(kicad_pcb
	(version 20260206)
	(generator "pcbnew")
	(generator_version "10.0")
	(general
		(thickness 1.6)
		(legacy_teardrops no)
	)
	(paper "A4")
	(layers
		(0 "F.Cu" signal "TOP")
		(4 "In1.Cu" signal "GND")
		(6 "In2.Cu" signal "IN1")
		(8 "In3.Cu" signal "GND1")
		(10 "In4.Cu" signal "IN2")
		(12 "In5.Cu" signal "GND2")
		(14 "In6.Cu" signal "IN3")
		(16 "In7.Cu" signal "GND3")
		(18 "In8.Cu" signal "VCC")
		(20 "In9.Cu" signal "VCC1")
		(22 "In10.Cu" signal "GND4")
		(24 "In11.Cu" signal "IN4")
		(26 "In12.Cu" signal "GND5")
		(28 "In13.Cu" signal "IN5")
		(30 "In14.Cu" signal "GND6")
		(32 "In15.Cu" signal "IN6")
		(34 "In16.Cu" signal "GND7")
		(2 "B.Cu" signal "BOTTOM")
		(9 "F.Adhes" user "F.Adhesive")
		(11 "B.Adhes" user "B.Adhesive")
		(13 "F.Paste" user "Package Geometry/Pastemask Top")
		(15 "B.Paste" user "Package Geometry/Pastemask Bottom")
		(5 "F.SilkS" user "Ref Des/Silkscreen Top")
		(7 "B.SilkS" user "Ref Des/Silkscreen Bottom")
		(1 "F.Mask" user "Board Geometry/Soldermask Top")
		(3 "B.Mask" user "Board Geometry/Soldermask Bottom")
		(17 "Dwgs.User" user "User.Drawings")
		(19 "Cmts.User" user "User.Comments")
		(21 "Eco1.User" user "User.Eco1")
		(23 "Eco2.User" user "User.Eco2")
		(25 "Edge.Cuts" user "Board Geometry/Outline")
		(27 "Margin" user)
		(31 "F.CrtYd" user "Package Geometry/Place Bound Top")
		(29 "B.CrtYd" user "Package Geometry/Place Bound Bottom")
		(35 "F.Fab" user "Ref Des/Assembly Top")
		(33 "B.Fab" user "Ref Des/Assembly Bottom")
	)
	(setup
		(pad_to_mask_clearance 0)
		(allow_soldermask_bridges_in_footprints no)
		(tenting
			(front yes)
			(back yes)
		)
		(covering
			(front no)
			(back no)
		)
		(plugging
			(front no)
			(back no)
		)
		(capping no)
		(filling no)
		(pcbplotparams
			(layerselection 0x00000000_00000000_55555555_5755f5ff)
			(plot_on_all_layers_selection 0x00000000_00000000_00000000_00000000)
			(disableapertmacros no)
			(usegerberextensions no)
			(usegerberattributes yes)
			(usegerberadvancedattributes yes)
			(creategerberjobfile yes)
			(dashed_line_dash_ratio 12)
			(dashed_line_gap_ratio 3)
			(svgprecision 4)
			(plotframeref no)
			(mode 1)
			(useauxorigin no)
			(pdf_front_fp_property_popups yes)
			(pdf_back_fp_property_popups yes)
			(pdf_metadata yes)
			(pdf_single_document no)
			(dxfpolygonmode yes)
			(dxfimperialunits yes)
			(dxfusepcbnewfont yes)
			(psnegative no)
			(psa4output no)
			(plot_black_and_white yes)
			(sketchpadsonfab no)
			(plotpadnumbers no)
			(hidednponfab no)
			(sketchdnponfab yes)
			(crossoutdnponfab yes)
			(subtractmaskfromsilk no)
			(outputformat 1)
			(mirror no)
			(drillshape 1)
			(scaleselection 1)
			(outputdirectory "")
		)
	)
	(gr_poly
		(pts
			(xy 213.5124 -330.83246) (xy 213.526085 -330.831978) (xy 213.552455 -330.824638) (xy 213.575932 -330.810564)
			(xy 213.594834 -330.790765) (xy 213.607806 -330.766661) (xy 213.613917 -330.73998) (xy 213.613746 -330.726288)
			(xy 213.613746 -330.724764) (xy 213.613238 -330.708) (xy 213.613724 -330.680731) (xy 213.621486 -330.626747)
			(xy 213.636851 -330.574417) (xy 213.659508 -330.524807) (xy 213.688994 -330.478926) (xy 213.724709 -330.437709)
			(xy 213.765926 -330.401994) (xy 213.811807 -330.372508) (xy 213.861417 -330.349851) (xy 213.913747 -330.334486)
			(xy 213.967731 -330.326724) (xy 214.022269 -330.326724) (xy 214.076253 -330.334486) (xy 214.128583 -330.349851)
			(xy 214.178193 -330.372508) (xy 214.224074 -330.401994) (xy 214.265291 -330.437709) (xy 214.301006 -330.478926)
			(xy 214.330492 -330.524807) (xy 214.353149 -330.574417) (xy 214.368514 -330.626747) (xy 214.376276 -330.680731)
			(xy 214.376762 -330.708) (xy 214.376254 -330.724764) (xy 214.376254 -330.726288) (xy 214.376077 -330.739986)
			(xy 214.382154 -330.766687) (xy 214.395114 -330.79081) (xy 214.414022 -330.810618) (xy 214.437518 -330.824683)
			(xy 214.463909 -330.831992) (xy 214.4776 -330.83246) (xy 214.65667 -330.83246) (xy 214.665052 -330.831698)
			(xy 214.67266 -330.83019) (xy 214.686503 -330.823212) (xy 214.69223 -330.817982) (xy 219.2147 -326.295512)
			(xy 219.221548 -326.288114) (xy 219.229287 -326.269516) (xy 219.229686 -326.259444) (xy 219.229686 -308.527704)
			(xy 219.230108 -308.517633) (xy 219.23782 -308.499026) (xy 219.244672 -308.491636) (xy 221.725744 -306.010564)
			(xy 221.733142 -306.003718) (xy 221.751741 -305.995989) (xy 221.761812 -305.995578) (xy 252.222 -305.995578)
			(xy 252.232071 -305.996) (xy 252.250677 -306.003712) (xy 252.258068 -306.010564) (xy 254.053594 -307.80609)
			(xy 254.060443 -307.813488) (xy 254.068182 -307.832086) (xy 254.06858 -307.842158) (xy 254.06858 -321.459352)
			(xy 254.086868 -321.485514) (xy 254.102108 -321.491102) (xy 254.127845 -321.500852) (xy 254.176433 -321.526696)
			(xy 254.220802 -321.559257) (xy 254.260028 -321.597858) (xy 254.293298 -321.641698) (xy 254.31992 -321.689865)
			(xy 254.33934 -321.741359) (xy 254.351157 -321.79511) (xy 254.355123 -321.850001) (xy 254.351156 -321.904893)
			(xy 254.33934 -321.958644) (xy 254.319919 -322.010137) (xy 254.293297 -322.058304) (xy 254.260027 -322.102144)
			(xy 254.2208 -322.140745) (xy 254.176431 -322.173305) (xy 254.127842 -322.199149) (xy 254.102108 -322.208906)
			(xy 254.086868 -322.214494) (xy 254.06858 -322.240656) (xy 254.06858 -322.376038) (xy 315.288168 -322.376038)
			(xy 315.288635 -322.345342) (xy 315.296039 -322.284397) (xy 315.310733 -322.224788) (xy 315.332503 -322.167384)
			(xy 315.36103 -322.113021) (xy 315.378084 -322.087494) (xy 315.383525 -322.078725) (xy 315.387666 -322.058532)
			(xy 315.38355 -322.038333) (xy 315.378084 -322.029582) (xy 315.361053 -322.004041) (xy 315.332541 -321.949675)
			(xy 315.310776 -321.892273) (xy 315.296074 -321.832671) (xy 315.288649 -321.771732) (xy 315.288168 -321.741038)
			(xy 315.288635 -321.710342) (xy 315.296039 -321.649397) (xy 315.310733 -321.589788) (xy 315.332503 -321.532384)
			(xy 315.36103 -321.478021) (xy 315.378084 -321.452494) (xy 315.383525 -321.443725) (xy 315.387666 -321.423532)
			(xy 315.38355 -321.403333) (xy 315.378084 -321.394582) (xy 315.361053 -321.369041) (xy 315.332541 -321.314675)
			(xy 315.310776 -321.257273) (xy 315.296074 -321.197671) (xy 315.288649 -321.136732) (xy 315.288168 -321.106038)
			(xy 315.288635 -321.075342) (xy 315.296039 -321.014397) (xy 315.310733 -320.954788) (xy 315.332503 -320.897384)
			(xy 315.36103 -320.843021) (xy 315.378084 -320.817494) (xy 315.383525 -320.808725) (xy 315.387666 -320.788532)
			(xy 315.38355 -320.768333) (xy 315.378084 -320.759582) (xy 315.361053 -320.734041) (xy 315.332541 -320.679675)
			(xy 315.310776 -320.622273) (xy 315.296074 -320.562671) (xy 315.288649 -320.501732) (xy 315.288168 -320.471038)
			(xy 315.288673 -320.440308) (xy 315.296077 -320.379294) (xy 315.310781 -320.319619) (xy 315.332572 -320.26215)
			(xy 315.36113 -320.207728) (xy 315.396041 -320.157144) (xy 315.436794 -320.111138) (xy 315.482796 -320.070379)
			(xy 315.533375 -320.035462) (xy 315.587794 -320.006897) (xy 315.645259 -319.9851) (xy 315.704933 -319.970388)
			(xy 315.765946 -319.962977) (xy 315.796676 -319.96253) (xy 315.817758 -319.963038) (xy 315.82868 -319.963546)
			(xy 315.848238 -319.955926) (xy 315.916564 -319.8876) (xy 315.924184 -319.868042) (xy 315.923676 -319.85712)
			(xy 315.923168 -319.836038) (xy 315.923673 -319.805308) (xy 315.931077 -319.744294) (xy 315.945781 -319.684619)
			(xy 315.967572 -319.62715) (xy 315.99613 -319.572728) (xy 316.031041 -319.522144) (xy 316.071794 -319.476138)
			(xy 316.117796 -319.435379) (xy 316.168375 -319.400462) (xy 316.222794 -319.371897) (xy 316.280259 -319.3501)
			(xy 316.339933 -319.335388) (xy 316.400946 -319.327977) (xy 316.431676 -319.32753) (xy 316.452758 -319.328038)
			(xy 316.46368 -319.328546) (xy 316.483238 -319.320926) (xy 316.551564 -319.2526) (xy 316.559184 -319.233042)
			(xy 316.558676 -319.22212) (xy 316.558168 -319.201038) (xy 316.55867 -319.169077) (xy 316.566681 -319.105659)
			(xy 316.582578 -319.043745) (xy 316.60611 -318.984312) (xy 316.636904 -318.928297) (xy 316.674477 -318.876582)
			(xy 316.718234 -318.829985) (xy 316.767487 -318.78924) (xy 316.821458 -318.754989) (xy 316.879297 -318.727772)
			(xy 316.94009 -318.708019) (xy 317.00288 -318.696041) (xy 317.066676 -318.692028) (xy 317.130472 -318.696041)
			(xy 317.193262 -318.708019) (xy 317.254055 -318.727772) (xy 317.311894 -318.754989) (xy 317.365865 -318.78924)
			(xy 317.415118 -318.829985) (xy 317.458875 -318.876582) (xy 317.496448 -318.928297) (xy 317.527242 -318.984312)
			(xy 317.550774 -319.043745) (xy 317.566671 -319.105659) (xy 317.574682 -319.169077) (xy 317.575184 -319.201038)
			(xy 317.574714 -319.231734) (xy 317.567311 -319.292679) (xy 317.552618 -319.352288) (xy 317.53085 -319.409692)
			(xy 317.502322 -319.464055) (xy 317.485268 -319.489582) (xy 317.479766 -319.498317) (xy 317.475651 -319.518532)
			(xy 317.479791 -319.538741) (xy 317.485268 -319.547494) (xy 317.502295 -319.573037) (xy 317.530806 -319.627403)
			(xy 317.552571 -319.684804) (xy 317.567274 -319.744406) (xy 317.574702 -319.805344) (xy 317.575184 -319.836038)
			(xy 317.574728 -319.864991) (xy 317.568123 -319.922518) (xy 317.555036 -319.978926) (xy 317.535637 -320.033485)
			(xy 317.510175 -320.085493) (xy 317.49492 -320.110104) (xy 317.48975 -320.119113) (xy 317.486334 -320.139577)
			(xy 317.491318 -320.159715) (xy 317.497206 -320.16827) (xy 317.516749 -320.194884) (xy 317.549506 -320.252215)
			(xy 317.574569 -320.313303) (xy 317.591515 -320.377121) (xy 317.600059 -320.442595) (xy 317.600584 -320.47561)
			(xy 317.600099 -320.506306) (xy 317.5927 -320.56725) (xy 317.578011 -320.626859) (xy 317.556245 -320.684263)
			(xy 317.527721 -320.738626) (xy 317.510668 -320.764154) (xy 317.50519 -320.772902) (xy 317.501067 -320.793108)
			(xy 317.505196 -320.813313) (xy 317.510668 -320.822066) (xy 317.527726 -320.847589) (xy 317.556232 -320.901961)
			(xy 317.577991 -320.959367) (xy 317.592687 -321.018973) (xy 317.600106 -321.079915) (xy 317.600584 -321.11061)
			(xy 317.600099 -321.141306) (xy 317.5927 -321.20225) (xy 317.578011 -321.261859) (xy 317.556245 -321.319263)
			(xy 317.527721 -321.373626) (xy 317.510668 -321.399154) (xy 317.50519 -321.407902) (xy 317.501067 -321.428108)
			(xy 317.505196 -321.448313) (xy 317.510668 -321.457066) (xy 317.527726 -321.482589) (xy 317.556232 -321.536961)
			(xy 317.577991 -321.594367) (xy 317.592687 -321.653973) (xy 317.600106 -321.714915) (xy 317.600584 -321.74561)
			(xy 317.600099 -321.776306) (xy 317.5927 -321.83725) (xy 317.578011 -321.896859) (xy 317.556245 -321.954263)
			(xy 317.527721 -322.008626) (xy 317.510668 -322.034154) (xy 317.50519 -322.042902) (xy 317.501067 -322.063108)
			(xy 317.505196 -322.083313) (xy 317.510668 -322.092066) (xy 317.527726 -322.117589) (xy 317.556232 -322.171961)
			(xy 317.577991 -322.229367) (xy 317.592687 -322.288973) (xy 317.600106 -322.349915) (xy 317.600584 -322.38061)
			(xy 317.600076 -322.413625) (xy 317.591527 -322.479099) (xy 317.574576 -322.542917) (xy 317.549507 -322.604003)
			(xy 317.516742 -322.66133) (xy 317.497206 -322.68795) (xy 317.491334 -322.696567) (xy 317.486434 -322.716818)
			(xy 317.489927 -322.737358) (xy 317.495174 -322.74637) (xy 317.511035 -322.771318) (xy 317.537545 -322.82416)
			(xy 317.557758 -322.879717) (xy 317.571401 -322.93724) (xy 317.578291 -322.995957) (xy 317.57874 -323.025516)
			(xy 319.304924 -323.025516) (xy 319.305445 -322.992501) (xy 319.31399 -322.927027) (xy 319.330938 -322.86321)
			(xy 319.356005 -322.802124) (xy 319.388767 -322.744796) (xy 319.408302 -322.718176) (xy 319.414152 -322.709546)
			(xy 319.419058 -322.689303) (xy 319.415576 -322.668768) (xy 319.410334 -322.659756) (xy 319.394442 -322.634827)
			(xy 319.367938 -322.581979) (xy 319.347731 -322.526418) (xy 319.334095 -322.46889) (xy 319.327212 -322.410171)
			(xy 319.326768 -322.38061) (xy 319.32722 -322.349913) (xy 319.334628 -322.288968) (xy 319.349326 -322.229359)
			(xy 319.371098 -322.171955) (xy 319.399629 -322.117593) (xy 319.416684 -322.092066) (xy 319.422149 -322.08331)
			(xy 319.426282 -322.063108) (xy 319.422155 -322.042905) (xy 319.416684 -322.034154) (xy 319.399641 -322.008621)
			(xy 319.371131 -321.954252) (xy 319.349369 -321.896849) (xy 319.334669 -321.837245) (xy 319.327247 -321.776305)
			(xy 319.326768 -321.74561) (xy 319.32722 -321.714913) (xy 319.334628 -321.653968) (xy 319.349326 -321.594359)
			(xy 319.371098 -321.536955) (xy 319.399629 -321.482593) (xy 319.416684 -321.457066) (xy 319.422149 -321.44831)
			(xy 319.426282 -321.428108) (xy 319.422155 -321.407905) (xy 319.416684 -321.399154) (xy 319.399641 -321.373621)
			(xy 319.371131 -321.319252) (xy 319.349369 -321.261849) (xy 319.334669 -321.202245) (xy 319.327247 -321.141305)
			(xy 319.326768 -321.11061) (xy 319.32722 -321.079913) (xy 319.334628 -321.018968) (xy 319.349326 -320.959359)
			(xy 319.371098 -320.901955) (xy 319.399629 -320.847593) (xy 319.416684 -320.822066) (xy 319.422149 -320.81331)
			(xy 319.426282 -320.793108) (xy 319.422155 -320.772905) (xy 319.416684 -320.764154) (xy 319.399641 -320.738621)
			(xy 319.371131 -320.684252) (xy 319.349369 -320.626849) (xy 319.334669 -320.567245) (xy 319.327247 -320.506305)
			(xy 319.326768 -320.47561) (xy 319.327254 -320.444637) (xy 319.33478 -320.383151) (xy 319.349723 -320.323036)
			(xy 319.371861 -320.265181) (xy 319.400865 -320.210446) (xy 319.418208 -320.18478) (xy 319.423659 -320.176017)
			(xy 319.427794 -320.15582) (xy 319.423675 -320.13562) (xy 319.418208 -320.126868) (xy 319.400833 -320.101222)
			(xy 319.371826 -320.046483) (xy 319.349688 -319.988624) (xy 319.334748 -319.928504) (xy 319.327225 -319.867013)
			(xy 319.326768 -319.836038) (xy 319.327235 -319.805342) (xy 319.334639 -319.744397) (xy 319.349333 -319.684788)
			(xy 319.371103 -319.627384) (xy 319.39963 -319.573021) (xy 319.416684 -319.547494) (xy 319.422125 -319.538725)
			(xy 319.426266 -319.518532) (xy 319.42215 -319.498333) (xy 319.416684 -319.489582) (xy 319.399653 -319.464041)
			(xy 319.371141 -319.409675) (xy 319.349376 -319.352273) (xy 319.334674 -319.292671) (xy 319.327249 -319.231732)
			(xy 319.326768 -319.201038) (xy 319.327235 -319.170342) (xy 319.334639 -319.109397) (xy 319.349333 -319.049788)
			(xy 319.371103 -318.992384) (xy 319.39963 -318.938021) (xy 319.416684 -318.912494) (xy 319.422125 -318.903725)
			(xy 319.426266 -318.883532) (xy 319.42215 -318.863333) (xy 319.416684 -318.854582) (xy 319.399653 -318.829041)
			(xy 319.371141 -318.774675) (xy 319.349376 -318.717273) (xy 319.334674 -318.657671) (xy 319.327249 -318.596732)
			(xy 319.326768 -318.566038) (xy 319.327235 -318.535342) (xy 319.334639 -318.474397) (xy 319.349333 -318.414788)
			(xy 319.371103 -318.357384) (xy 319.39963 -318.303021) (xy 319.416684 -318.277494) (xy 319.422125 -318.268725)
			(xy 319.426266 -318.248532) (xy 319.42215 -318.228333) (xy 319.416684 -318.219582) (xy 319.399653 -318.194041)
			(xy 319.371141 -318.139675) (xy 319.349376 -318.082273) (xy 319.334674 -318.022671) (xy 319.327249 -317.961732)
			(xy 319.326768 -317.931038) (xy 319.327235 -317.900342) (xy 319.334639 -317.839397) (xy 319.349333 -317.779788)
			(xy 319.371103 -317.722384) (xy 319.39963 -317.668021) (xy 319.416684 -317.642494) (xy 319.422125 -317.633725)
			(xy 319.426266 -317.613532) (xy 319.42215 -317.593333) (xy 319.416684 -317.584582) (xy 319.399653 -317.559041)
			(xy 319.371141 -317.504675) (xy 319.349376 -317.447273) (xy 319.334674 -317.387671) (xy 319.327249 -317.326732)
			(xy 319.326768 -317.296038) (xy 319.327235 -317.265342) (xy 319.334639 -317.204397) (xy 319.349333 -317.144788)
			(xy 319.371103 -317.087384) (xy 319.39963 -317.033021) (xy 319.416684 -317.007494) (xy 319.422125 -316.998725)
			(xy 319.426266 -316.978532) (xy 319.42215 -316.958333) (xy 319.416684 -316.949582) (xy 319.399653 -316.924041)
			(xy 319.371141 -316.869675) (xy 319.349376 -316.812273) (xy 319.334674 -316.752671) (xy 319.327249 -316.691732)
			(xy 319.326768 -316.661038) (xy 319.327273 -316.630308) (xy 319.334677 -316.569294) (xy 319.349381 -316.509619)
			(xy 319.371172 -316.45215) (xy 319.39973 -316.397728) (xy 319.434641 -316.347144) (xy 319.475394 -316.301138)
			(xy 319.521396 -316.260379) (xy 319.571975 -316.225462) (xy 319.626394 -316.196897) (xy 319.683859 -316.1751)
			(xy 319.743533 -316.160388) (xy 319.804546 -316.152977) (xy 319.835276 -316.15253) (xy 319.865973 -316.152979)
			(xy 319.926919 -316.160386) (xy 319.986528 -316.175083) (xy 320.043932 -316.196857) (xy 320.098293 -316.225389)
			(xy 320.12382 -316.242446) (xy 320.132572 -316.247917) (xy 320.152776 -316.252045) (xy 320.17298 -316.247917)
			(xy 320.181732 -316.242446) (xy 320.207266 -316.225404) (xy 320.261635 -316.196895) (xy 320.319038 -316.175133)
			(xy 320.378642 -316.160433) (xy 320.439581 -316.15301) (xy 320.470276 -316.15253) (xy 320.500973 -316.152979)
			(xy 320.561919 -316.160386) (xy 320.621528 -316.175083) (xy 320.678932 -316.196857) (xy 320.733293 -316.225389)
			(xy 320.75882 -316.242446) (xy 320.767572 -316.247917) (xy 320.787776 -316.252045) (xy 320.80798 -316.247917)
			(xy 320.816732 -316.242446) (xy 320.842266 -316.225404) (xy 320.896635 -316.196895) (xy 320.954038 -316.175133)
			(xy 321.013642 -316.160433) (xy 321.074581 -316.15301) (xy 321.105276 -316.15253) (xy 321.136009 -316.15296)
			(xy 321.197027 -316.160367) (xy 321.256708 -316.175075) (xy 321.31418 -316.19687) (xy 321.368606 -316.225434)
			(xy 321.419191 -316.260351) (xy 321.465199 -316.301111) (xy 321.505958 -316.34712) (xy 321.540873 -316.397706)
			(xy 321.569436 -316.452133) (xy 321.591229 -316.509606) (xy 321.605936 -316.569287) (xy 321.613341 -316.630305)
			(xy 321.613784 -316.661038) (xy 321.613314 -316.691734) (xy 321.605911 -316.752679) (xy 321.591218 -316.812288)
			(xy 321.56945 -316.869692) (xy 321.540922 -316.924055) (xy 321.523868 -316.949582) (xy 321.518366 -316.958317)
			(xy 321.514251 -316.978532) (xy 321.518391 -316.998741) (xy 321.523868 -317.007494) (xy 321.540895 -317.033037)
			(xy 321.569406 -317.087403) (xy 321.591171 -317.144804) (xy 321.605874 -317.204406) (xy 321.613302 -317.265344)
			(xy 321.613784 -317.296038) (xy 321.613314 -317.326734) (xy 321.605911 -317.387679) (xy 321.591218 -317.447288)
			(xy 321.56945 -317.504692) (xy 321.540922 -317.559055) (xy 321.523868 -317.584582) (xy 321.518366 -317.593317)
			(xy 321.514251 -317.613532) (xy 321.518391 -317.633741) (xy 321.523868 -317.642494) (xy 321.540895 -317.668037)
			(xy 321.569406 -317.722403) (xy 321.591171 -317.779804) (xy 321.605874 -317.839406) (xy 321.613302 -317.900344)
			(xy 321.613784 -317.931038) (xy 321.613314 -317.961734) (xy 321.605911 -318.022679) (xy 321.591218 -318.082288)
			(xy 321.56945 -318.139692) (xy 321.540922 -318.194055) (xy 321.523868 -318.219582) (xy 321.518366 -318.228317)
			(xy 321.514251 -318.248532) (xy 321.518391 -318.268741) (xy 321.523868 -318.277494) (xy 321.540895 -318.303037)
			(xy 321.569406 -318.357403) (xy 321.591171 -318.414804) (xy 321.605874 -318.474406) (xy 321.613302 -318.535344)
			(xy 321.613784 -318.566038) (xy 321.613314 -318.596734) (xy 321.605911 -318.657679) (xy 321.591218 -318.717288)
			(xy 321.56945 -318.774692) (xy 321.540922 -318.829055) (xy 321.523868 -318.854582) (xy 321.518366 -318.863317)
			(xy 321.514251 -318.883532) (xy 321.518391 -318.903741) (xy 321.523868 -318.912494) (xy 321.540895 -318.938037)
			(xy 321.569406 -318.992403) (xy 321.591171 -319.049804) (xy 321.605874 -319.109406) (xy 321.613302 -319.170344)
			(xy 321.613784 -319.201038) (xy 321.613314 -319.231734) (xy 321.605911 -319.292679) (xy 321.591218 -319.352288)
			(xy 321.56945 -319.409692) (xy 321.540922 -319.464055) (xy 321.523868 -319.489582) (xy 321.518366 -319.498317)
			(xy 321.514251 -319.518532) (xy 321.518391 -319.538741) (xy 321.523868 -319.547494) (xy 321.540895 -319.573037)
			(xy 321.569406 -319.627403) (xy 321.591171 -319.684804) (xy 321.605874 -319.744406) (xy 321.613302 -319.805344)
			(xy 321.613784 -319.836038) (xy 321.613314 -319.866734) (xy 321.605911 -319.927679) (xy 321.591218 -319.987288)
			(xy 321.56945 -320.044692) (xy 321.540922 -320.099055) (xy 321.523868 -320.124582) (xy 321.518366 -320.133317)
			(xy 321.514251 -320.153532) (xy 321.518391 -320.173741) (xy 321.523868 -320.182494) (xy 321.540895 -320.208037)
			(xy 321.569406 -320.262403) (xy 321.591171 -320.319804) (xy 321.605874 -320.379406) (xy 321.613302 -320.440344)
			(xy 321.613784 -320.471038) (xy 321.613314 -320.501734) (xy 321.605911 -320.562679) (xy 321.591218 -320.622288)
			(xy 321.56945 -320.679692) (xy 321.540922 -320.734055) (xy 321.523868 -320.759582) (xy 321.518366 -320.768317)
			(xy 321.514251 -320.788532) (xy 321.518391 -320.808741) (xy 321.523868 -320.817494) (xy 321.540895 -320.843037)
			(xy 321.569406 -320.897403) (xy 321.591171 -320.954804) (xy 321.605874 -321.014406) (xy 321.613302 -321.075344)
			(xy 321.613784 -321.106038) (xy 321.613314 -321.136734) (xy 321.605911 -321.197679) (xy 321.591218 -321.257288)
			(xy 321.56945 -321.314692) (xy 321.540922 -321.369055) (xy 321.523868 -321.394582) (xy 321.518366 -321.403317)
			(xy 321.514251 -321.423532) (xy 321.518391 -321.443741) (xy 321.523868 -321.452494) (xy 321.540895 -321.478037)
			(xy 321.569406 -321.532403) (xy 321.591171 -321.589804) (xy 321.605874 -321.649406) (xy 321.613302 -321.710344)
			(xy 321.613784 -321.741038) (xy 321.613314 -321.771734) (xy 321.605911 -321.832679) (xy 321.591218 -321.892288)
			(xy 321.56945 -321.949692) (xy 321.540922 -322.004055) (xy 321.523868 -322.029582) (xy 321.518366 -322.038317)
			(xy 321.514251 -322.058532) (xy 321.518391 -322.078741) (xy 321.523868 -322.087494) (xy 321.540895 -322.113037)
			(xy 321.569406 -322.167403) (xy 321.591171 -322.224804) (xy 321.605874 -322.284406) (xy 321.613302 -322.345344)
			(xy 321.613445 -322.354448) (xy 323.643752 -322.354448) (xy 323.644209 -322.323751) (xy 323.651614 -322.262805)
			(xy 323.666309 -322.203196) (xy 323.688081 -322.145792) (xy 323.716612 -322.091431) (xy 323.733668 -322.065904)
			(xy 323.739102 -322.057131) (xy 323.743247 -322.03694) (xy 323.739133 -322.016742) (xy 323.733668 -322.007992)
			(xy 323.71664 -321.98245) (xy 323.688128 -321.928084) (xy 323.666362 -321.870683) (xy 323.65166 -321.81108)
			(xy 323.644234 -321.750142) (xy 323.643752 -321.719448) (xy 323.644209 -321.688751) (xy 323.651614 -321.627805)
			(xy 323.666309 -321.568196) (xy 323.688081 -321.510792) (xy 323.716612 -321.456431) (xy 323.733668 -321.430904)
			(xy 323.739102 -321.422131) (xy 323.743247 -321.40194) (xy 323.739133 -321.381742) (xy 323.733668 -321.372992)
			(xy 323.71664 -321.34745) (xy 323.688128 -321.293084) (xy 323.666362 -321.235683) (xy 323.65166 -321.17608)
			(xy 323.644234 -321.115142) (xy 323.643752 -321.084448) (xy 323.644209 -321.053751) (xy 323.651614 -320.992805)
			(xy 323.666309 -320.933196) (xy 323.688081 -320.875792) (xy 323.716612 -320.821431) (xy 323.733668 -320.795904)
			(xy 323.739102 -320.787131) (xy 323.743247 -320.76694) (xy 323.739133 -320.746742) (xy 323.733668 -320.737992)
			(xy 323.71664 -320.71245) (xy 323.688128 -320.658084) (xy 323.666362 -320.600683) (xy 323.65166 -320.54108)
			(xy 323.644234 -320.480142) (xy 323.643752 -320.449448) (xy 323.644209 -320.418751) (xy 323.651614 -320.357805)
			(xy 323.666309 -320.298196) (xy 323.688081 -320.240792) (xy 323.716612 -320.186431) (xy 323.733668 -320.160904)
			(xy 323.739102 -320.152131) (xy 323.743247 -320.13194) (xy 323.739133 -320.111742) (xy 323.733668 -320.102992)
			(xy 323.71664 -320.07745) (xy 323.688128 -320.023084) (xy 323.666362 -319.965683) (xy 323.65166 -319.90608)
			(xy 323.644234 -319.845142) (xy 323.643752 -319.814448) (xy 323.644209 -319.783751) (xy 323.651614 -319.722805)
			(xy 323.666309 -319.663196) (xy 323.688081 -319.605792) (xy 323.716612 -319.551431) (xy 323.733668 -319.525904)
			(xy 323.739102 -319.517131) (xy 323.743247 -319.49694) (xy 323.739133 -319.476742) (xy 323.733668 -319.467992)
			(xy 323.71664 -319.44245) (xy 323.688128 -319.388084) (xy 323.666362 -319.330683) (xy 323.65166 -319.27108)
			(xy 323.644234 -319.210142) (xy 323.643752 -319.179448) (xy 323.644209 -319.148751) (xy 323.651614 -319.087805)
			(xy 323.666309 -319.028196) (xy 323.688081 -318.970792) (xy 323.716612 -318.916431) (xy 323.733668 -318.890904)
			(xy 323.739102 -318.882131) (xy 323.743247 -318.86194) (xy 323.739133 -318.841742) (xy 323.733668 -318.832992)
			(xy 323.71664 -318.80745) (xy 323.688128 -318.753084) (xy 323.666362 -318.695683) (xy 323.65166 -318.63608)
			(xy 323.644234 -318.575142) (xy 323.643752 -318.544448) (xy 323.644209 -318.513751) (xy 323.651614 -318.452805)
			(xy 323.666309 -318.393196) (xy 323.688081 -318.335792) (xy 323.716612 -318.281431) (xy 323.733668 -318.255904)
			(xy 323.739102 -318.247131) (xy 323.743247 -318.22694) (xy 323.739133 -318.206742) (xy 323.733668 -318.197992)
			(xy 323.71664 -318.17245) (xy 323.688128 -318.118084) (xy 323.666362 -318.060683) (xy 323.65166 -318.00108)
			(xy 323.644234 -317.940142) (xy 323.643752 -317.909448) (xy 323.644209 -317.878751) (xy 323.651614 -317.817805)
			(xy 323.666309 -317.758196) (xy 323.688081 -317.700792) (xy 323.716612 -317.646431) (xy 323.733668 -317.620904)
			(xy 323.739102 -317.612131) (xy 323.743247 -317.59194) (xy 323.739133 -317.571742) (xy 323.733668 -317.562992)
			(xy 323.71664 -317.53745) (xy 323.688128 -317.483084) (xy 323.666362 -317.425683) (xy 323.65166 -317.36608)
			(xy 323.644234 -317.305142) (xy 323.643752 -317.274448) (xy 323.644209 -317.243751) (xy 323.651614 -317.182805)
			(xy 323.666309 -317.123196) (xy 323.688081 -317.065792) (xy 323.716612 -317.011431) (xy 323.733668 -316.985904)
			(xy 323.739102 -316.977131) (xy 323.743247 -316.95694) (xy 323.739133 -316.936742) (xy 323.733668 -316.927992)
			(xy 323.71664 -316.90245) (xy 323.688128 -316.848084) (xy 323.666362 -316.790683) (xy 323.65166 -316.73108)
			(xy 323.644234 -316.670142) (xy 323.643752 -316.639448) (xy 323.644283 -316.608718) (xy 323.651685 -316.547707)
			(xy 323.666388 -316.488032) (xy 323.688176 -316.430565) (xy 323.716733 -316.376143) (xy 323.751641 -316.32556)
			(xy 323.792392 -316.279554) (xy 323.838391 -316.238795) (xy 323.888968 -316.203878) (xy 323.943385 -316.175312)
			(xy 324.000848 -316.153514) (xy 324.06052 -316.138801) (xy 324.121531 -316.131388) (xy 324.15226 -316.13094)
			(xy 324.182957 -316.131395) (xy 324.243903 -316.138801) (xy 324.303512 -316.153497) (xy 324.360916 -316.175269)
			(xy 324.415277 -316.2038) (xy 324.440804 -316.220856) (xy 324.449556 -316.226327) (xy 324.46976 -316.230455)
			(xy 324.489964 -316.226327) (xy 324.498716 -316.220856) (xy 324.524255 -316.203823) (xy 324.578622 -316.175312)
			(xy 324.636024 -316.153548) (xy 324.695627 -316.138846) (xy 324.756566 -316.131421) (xy 324.78726 -316.13094)
			(xy 324.817957 -316.131395) (xy 324.878903 -316.138801) (xy 324.938512 -316.153497) (xy 324.995916 -316.175269)
			(xy 325.050277 -316.2038) (xy 325.075804 -316.220856) (xy 325.084556 -316.226327) (xy 325.10476 -316.230455)
			(xy 325.124964 -316.226327) (xy 325.133716 -316.220856) (xy 325.159255 -316.203823) (xy 325.213622 -316.175312)
			(xy 325.271024 -316.153548) (xy 325.330627 -316.138846) (xy 325.391566 -316.131421) (xy 325.42226 -316.13094)
			(xy 325.452993 -316.131375) (xy 325.514012 -316.13878) (xy 325.573692 -316.153487) (xy 325.631165 -316.175281)
			(xy 325.685591 -316.203844) (xy 325.736178 -316.23876) (xy 325.782186 -316.27952) (xy 325.822944 -316.325529)
			(xy 325.85786 -316.376115) (xy 325.886422 -316.430542) (xy 325.908215 -316.488015) (xy 325.922921 -316.547696)
			(xy 325.930325 -316.608715) (xy 325.930768 -316.639448) (xy 325.930306 -316.670145) (xy 325.922902 -316.73109)
			(xy 325.908207 -316.790699) (xy 325.886437 -316.848103) (xy 325.857907 -316.902465) (xy 325.840852 -316.927992)
			(xy 325.835343 -316.936723) (xy 325.831232 -316.95694) (xy 325.835374 -316.97715) (xy 325.840852 -316.985904)
			(xy 325.857881 -317.011446) (xy 325.886393 -317.065812) (xy 325.908157 -317.123213) (xy 325.92286 -317.182816)
			(xy 325.930286 -317.243754) (xy 325.930768 -317.274448) (xy 325.930306 -317.305145) (xy 325.922902 -317.36609)
			(xy 325.908207 -317.425699) (xy 325.886437 -317.483103) (xy 325.857907 -317.537465) (xy 325.840852 -317.562992)
			(xy 325.835343 -317.571723) (xy 325.831232 -317.59194) (xy 325.835374 -317.61215) (xy 325.840852 -317.620904)
			(xy 325.857881 -317.646446) (xy 325.886393 -317.700812) (xy 325.908157 -317.758213) (xy 325.92286 -317.817816)
			(xy 325.930286 -317.878754) (xy 325.930768 -317.909448) (xy 325.930306 -317.940145) (xy 325.922902 -318.00109)
			(xy 325.908207 -318.060699) (xy 325.886437 -318.118103) (xy 325.857907 -318.172465) (xy 325.840852 -318.197992)
			(xy 325.835343 -318.206723) (xy 325.831232 -318.22694) (xy 325.835374 -318.24715) (xy 325.840852 -318.255904)
			(xy 325.857881 -318.281446) (xy 325.886393 -318.335812) (xy 325.908157 -318.393213) (xy 325.92286 -318.452816)
			(xy 325.930286 -318.513754) (xy 325.930768 -318.544448) (xy 325.930306 -318.575145) (xy 325.922902 -318.63609)
			(xy 325.908207 -318.695699) (xy 325.886437 -318.753103) (xy 325.857907 -318.807465) (xy 325.840852 -318.832992)
			(xy 325.835343 -318.841723) (xy 325.831232 -318.86194) (xy 325.835374 -318.88215) (xy 325.840852 -318.890904)
			(xy 325.857881 -318.916446) (xy 325.886393 -318.970812) (xy 325.908157 -319.028213) (xy 325.92286 -319.087816)
			(xy 325.930286 -319.148754) (xy 325.930768 -319.179448) (xy 325.930306 -319.210145) (xy 325.922902 -319.27109)
			(xy 325.908207 -319.330699) (xy 325.886437 -319.388103) (xy 325.857907 -319.442465) (xy 325.840852 -319.467992)
			(xy 325.835343 -319.476723) (xy 325.831232 -319.49694) (xy 325.835374 -319.51715) (xy 325.840852 -319.525904)
			(xy 325.857881 -319.551446) (xy 325.886393 -319.605812) (xy 325.908157 -319.663213) (xy 325.92286 -319.722816)
			(xy 325.930286 -319.783754) (xy 325.930768 -319.814448) (xy 325.930319 -319.843401) (xy 325.923713 -319.900929)
			(xy 325.910624 -319.957337) (xy 325.891223 -320.011896) (xy 325.86576 -320.063903) (xy 325.850504 -320.088514)
			(xy 325.845327 -320.097519) (xy 325.841915 -320.117985) (xy 325.846901 -320.138125) (xy 325.85279 -320.14668)
			(xy 325.872335 -320.173293) (xy 325.905093 -320.230624) (xy 325.930155 -320.291712) (xy 325.9471 -320.35553)
			(xy 325.955643 -320.421005) (xy 325.956168 -320.45402) (xy 325.955691 -320.484716) (xy 325.948291 -320.545661)
			(xy 325.9336 -320.60527) (xy 325.911832 -320.662674) (xy 325.883306 -320.717037) (xy 325.866252 -320.742564)
			(xy 325.860767 -320.751308) (xy 325.856648 -320.771517) (xy 325.86078 -320.791723) (xy 325.866252 -320.800476)
			(xy 325.883312 -320.825998) (xy 325.911818 -320.88037) (xy 325.933577 -320.937776) (xy 325.948272 -320.997383)
			(xy 325.95569 -321.058325) (xy 325.956168 -321.08902) (xy 325.955691 -321.119716) (xy 325.948291 -321.180661)
			(xy 325.9336 -321.24027) (xy 325.911832 -321.297674) (xy 325.883306 -321.352037) (xy 325.866252 -321.377564)
			(xy 325.860767 -321.386308) (xy 325.856648 -321.406517) (xy 325.86078 -321.426723) (xy 325.866252 -321.435476)
			(xy 325.883312 -321.460998) (xy 325.911818 -321.51537) (xy 325.933577 -321.572776) (xy 325.948272 -321.632383)
			(xy 325.95569 -321.693325) (xy 325.956168 -321.72402) (xy 325.955691 -321.754716) (xy 325.948291 -321.815661)
			(xy 325.9336 -321.87527) (xy 325.911832 -321.932674) (xy 325.883306 -321.987037) (xy 325.866252 -322.012564)
			(xy 325.860767 -322.021308) (xy 325.856648 -322.041517) (xy 325.86078 -322.061723) (xy 325.866252 -322.070476)
			(xy 325.883312 -322.095998) (xy 325.911818 -322.15037) (xy 325.933577 -322.207776) (xy 325.948272 -322.267383)
			(xy 325.95569 -322.328325) (xy 325.956168 -322.35902) (xy 325.955614 -322.392034) (xy 325.947077 -322.457506)
			(xy 325.930137 -322.521323) (xy 325.905078 -322.58241) (xy 325.872322 -322.639739) (xy 325.85279 -322.66636)
			(xy 325.84691 -322.674972) (xy 325.842015 -322.695226) (xy 325.845509 -322.715767) (xy 325.850758 -322.72478)
			(xy 325.866621 -322.749726) (xy 325.893131 -322.802569) (xy 325.913344 -322.858126) (xy 325.926986 -322.91565)
			(xy 325.933876 -322.974367) (xy 325.934324 -323.003926) (xy 327.660508 -323.003926) (xy 327.661017 -322.970911)
			(xy 327.669562 -322.905436) (xy 327.686512 -322.841618) (xy 327.711582 -322.780532) (xy 327.744349 -322.723205)
			(xy 327.763886 -322.696586) (xy 327.769729 -322.687951) (xy 327.774638 -322.667711) (xy 327.771159 -322.647178)
			(xy 327.765918 -322.638166) (xy 327.750029 -322.613235) (xy 327.723524 -322.560388) (xy 327.703317 -322.504827)
			(xy 327.68968 -322.4473) (xy 327.682797 -322.38858) (xy 327.682352 -322.35902) (xy 327.682795 -322.328323)
			(xy 327.690203 -322.267376) (xy 327.704902 -322.207767) (xy 327.726677 -322.150363) (xy 327.75521 -322.096002)
			(xy 327.772268 -322.070476) (xy 327.777726 -322.061716) (xy 327.781863 -322.041517) (xy 327.777739 -322.021315)
			(xy 327.772268 -322.012564) (xy 327.755227 -321.987029) (xy 327.726717 -321.932661) (xy 327.704955 -321.875258)
			(xy 327.690255 -321.815654) (xy 327.682832 -321.754715) (xy 327.682352 -321.72402) (xy 327.682795 -321.693323)
			(xy 327.690203 -321.632376) (xy 327.704902 -321.572767) (xy 327.726677 -321.515363) (xy 327.75521 -321.461002)
			(xy 327.772268 -321.435476) (xy 327.777726 -321.426716) (xy 327.781863 -321.406517) (xy 327.777739 -321.386315)
			(xy 327.772268 -321.377564) (xy 327.755227 -321.352029) (xy 327.726717 -321.297661) (xy 327.704955 -321.240258)
			(xy 327.690255 -321.180654) (xy 327.682832 -321.119715) (xy 327.682352 -321.08902) (xy 327.682795 -321.058323)
			(xy 327.690203 -320.997376) (xy 327.704902 -320.937767) (xy 327.726677 -320.880363) (xy 327.75521 -320.826002)
			(xy 327.772268 -320.800476) (xy 327.777726 -320.791716) (xy 327.781863 -320.771517) (xy 327.777739 -320.751315)
			(xy 327.772268 -320.742564) (xy 327.755227 -320.717029) (xy 327.726717 -320.662661) (xy 327.704955 -320.605258)
			(xy 327.690255 -320.545654) (xy 327.682832 -320.484715) (xy 327.682352 -320.45402) (xy 327.682846 -320.423048)
			(xy 327.690371 -320.361562) (xy 327.705312 -320.301446) (xy 327.727448 -320.243592) (xy 327.75645 -320.188856)
			(xy 327.773792 -320.16319) (xy 327.779236 -320.154423) (xy 327.783375 -320.134228) (xy 327.779258 -320.114029)
			(xy 327.773792 -320.105278) (xy 327.756431 -320.079622) (xy 327.72742 -320.024887) (xy 327.705279 -319.967031)
			(xy 327.690334 -319.906912) (xy 327.68281 -319.845422) (xy 327.682352 -319.814448) (xy 327.682809 -319.783751)
			(xy 327.690214 -319.722805) (xy 327.704909 -319.663196) (xy 327.726681 -319.605792) (xy 327.755212 -319.551431)
			(xy 327.772268 -319.525904) (xy 327.777702 -319.517131) (xy 327.781847 -319.49694) (xy 327.777733 -319.476742)
			(xy 327.772268 -319.467992) (xy 327.75524 -319.44245) (xy 327.726728 -319.388084) (xy 327.704962 -319.330683)
			(xy 327.69026 -319.27108) (xy 327.682834 -319.210142) (xy 327.682352 -319.179448) (xy 327.682809 -319.148751)
			(xy 327.690214 -319.087805) (xy 327.704909 -319.028196) (xy 327.726681 -318.970792) (xy 327.755212 -318.916431)
			(xy 327.772268 -318.890904) (xy 327.777702 -318.882131) (xy 327.781847 -318.86194) (xy 327.777733 -318.841742)
			(xy 327.772268 -318.832992) (xy 327.75524 -318.80745) (xy 327.726728 -318.753084) (xy 327.704962 -318.695683)
			(xy 327.69026 -318.63608) (xy 327.682834 -318.575142) (xy 327.682352 -318.544448) (xy 327.682809 -318.513751)
			(xy 327.690214 -318.452805) (xy 327.704909 -318.393196) (xy 327.726681 -318.335792) (xy 327.755212 -318.281431)
			(xy 327.772268 -318.255904) (xy 327.777702 -318.247131) (xy 327.781847 -318.22694) (xy 327.777733 -318.206742)
			(xy 327.772268 -318.197992) (xy 327.75524 -318.17245) (xy 327.726728 -318.118084) (xy 327.704962 -318.060683)
			(xy 327.69026 -318.00108) (xy 327.682834 -317.940142) (xy 327.682352 -317.909448) (xy 327.682809 -317.878751)
			(xy 327.690214 -317.817805) (xy 327.704909 -317.758196) (xy 327.726681 -317.700792) (xy 327.755212 -317.646431)
			(xy 327.772268 -317.620904) (xy 327.777702 -317.612131) (xy 327.781847 -317.59194) (xy 327.777733 -317.571742)
			(xy 327.772268 -317.562992) (xy 327.75524 -317.53745) (xy 327.726728 -317.483084) (xy 327.704962 -317.425683)
			(xy 327.69026 -317.36608) (xy 327.682834 -317.305142) (xy 327.682352 -317.274448) (xy 327.682809 -317.243751)
			(xy 327.690214 -317.182805) (xy 327.704909 -317.123196) (xy 327.726681 -317.065792) (xy 327.755212 -317.011431)
			(xy 327.772268 -316.985904) (xy 327.777702 -316.977131) (xy 327.781847 -316.95694) (xy 327.777733 -316.936742)
			(xy 327.772268 -316.927992) (xy 327.75524 -316.90245) (xy 327.726728 -316.848084) (xy 327.704962 -316.790683)
			(xy 327.69026 -316.73108) (xy 327.682834 -316.670142) (xy 327.682352 -316.639448) (xy 327.682883 -316.608718)
			(xy 327.690285 -316.547707) (xy 327.704988 -316.488032) (xy 327.726776 -316.430565) (xy 327.755333 -316.376143)
			(xy 327.790241 -316.32556) (xy 327.830992 -316.279554) (xy 327.876991 -316.238795) (xy 327.927568 -316.203878)
			(xy 327.981985 -316.175312) (xy 328.039448 -316.153514) (xy 328.09912 -316.138801) (xy 328.160131 -316.131388)
			(xy 328.19086 -316.13094) (xy 328.221557 -316.131395) (xy 328.282503 -316.138801) (xy 328.342112 -316.153497)
			(xy 328.399516 -316.175269) (xy 328.453877 -316.2038) (xy 328.479404 -316.220856) (xy 328.488156 -316.226327)
			(xy 328.50836 -316.230455) (xy 328.528564 -316.226327) (xy 328.537316 -316.220856) (xy 328.562855 -316.203823)
			(xy 328.617222 -316.175312) (xy 328.674624 -316.153548) (xy 328.734227 -316.138846) (xy 328.795166 -316.131421)
			(xy 328.82586 -316.13094) (xy 328.856557 -316.131395) (xy 328.917503 -316.138801) (xy 328.977112 -316.153497)
			(xy 329.034516 -316.175269) (xy 329.088877 -316.2038) (xy 329.114404 -316.220856) (xy 329.123156 -316.226327)
			(xy 329.14336 -316.230455) (xy 329.163564 -316.226327) (xy 329.172316 -316.220856) (xy 329.197855 -316.203823)
			(xy 329.252222 -316.175312) (xy 329.309624 -316.153548) (xy 329.369227 -316.138846) (xy 329.430166 -316.131421)
			(xy 329.46086 -316.13094) (xy 329.491593 -316.131375) (xy 329.552612 -316.13878) (xy 329.612292 -316.153487)
			(xy 329.669765 -316.175281) (xy 329.724191 -316.203844) (xy 329.774778 -316.23876) (xy 329.820786 -316.27952)
			(xy 329.861544 -316.325529) (xy 329.89646 -316.376115) (xy 329.925022 -316.430542) (xy 329.946815 -316.488015)
			(xy 329.961521 -316.547696) (xy 329.968925 -316.608715) (xy 329.969368 -316.639448) (xy 329.968906 -316.670145)
			(xy 329.961502 -316.73109) (xy 329.946807 -316.790699) (xy 329.925037 -316.848103) (xy 329.896507 -316.902465)
			(xy 329.879452 -316.927992) (xy 329.873943 -316.936723) (xy 329.869832 -316.95694) (xy 329.873974 -316.97715)
			(xy 329.879452 -316.985904) (xy 329.896481 -317.011446) (xy 329.924993 -317.065812) (xy 329.946757 -317.123213)
			(xy 329.96146 -317.182816) (xy 329.968886 -317.243754) (xy 329.969368 -317.274448) (xy 329.968906 -317.305145)
			(xy 329.961502 -317.36609) (xy 329.946807 -317.425699) (xy 329.925037 -317.483103) (xy 329.896507 -317.537465)
			(xy 329.879452 -317.562992) (xy 329.873943 -317.571723) (xy 329.869832 -317.59194) (xy 329.873974 -317.61215)
			(xy 329.879452 -317.620904) (xy 329.896481 -317.646446) (xy 329.924993 -317.700812) (xy 329.946757 -317.758213)
			(xy 329.96146 -317.817816) (xy 329.968886 -317.878754) (xy 329.969368 -317.909448) (xy 329.968906 -317.940145)
			(xy 329.961502 -318.00109) (xy 329.946807 -318.060699) (xy 329.925037 -318.118103) (xy 329.896507 -318.172465)
			(xy 329.879452 -318.197992) (xy 329.873943 -318.206723) (xy 329.869832 -318.22694) (xy 329.873974 -318.24715)
			(xy 329.879452 -318.255904) (xy 329.896481 -318.281446) (xy 329.924993 -318.335812) (xy 329.946757 -318.393213)
			(xy 329.96146 -318.452816) (xy 329.968886 -318.513754) (xy 329.969368 -318.544448) (xy 329.968906 -318.575145)
			(xy 329.961502 -318.63609) (xy 329.946807 -318.695699) (xy 329.925037 -318.753103) (xy 329.896507 -318.807465)
			(xy 329.879452 -318.832992) (xy 329.873943 -318.841723) (xy 329.869832 -318.86194) (xy 329.873974 -318.88215)
			(xy 329.879452 -318.890904) (xy 329.896481 -318.916446) (xy 329.924993 -318.970812) (xy 329.946757 -319.028213)
			(xy 329.96146 -319.087816) (xy 329.968886 -319.148754) (xy 329.969368 -319.179448) (xy 329.968906 -319.210145)
			(xy 329.961502 -319.27109) (xy 329.946807 -319.330699) (xy 329.925037 -319.388103) (xy 329.896507 -319.442465)
			(xy 329.879452 -319.467992) (xy 329.873943 -319.476723) (xy 329.869832 -319.49694) (xy 329.873974 -319.51715)
			(xy 329.879452 -319.525904) (xy 329.896481 -319.551446) (xy 329.924993 -319.605812) (xy 329.946757 -319.663213)
			(xy 329.96146 -319.722816) (xy 329.968886 -319.783754) (xy 329.969368 -319.814448) (xy 329.968906 -319.845145)
			(xy 329.961502 -319.90609) (xy 329.946807 -319.965699) (xy 329.925037 -320.023103) (xy 329.896507 -320.077465)
			(xy 329.879452 -320.102992) (xy 329.873943 -320.111723) (xy 329.869832 -320.13194) (xy 329.873974 -320.15215)
			(xy 329.879452 -320.160904) (xy 329.896481 -320.186446) (xy 329.924993 -320.240812) (xy 329.946757 -320.298213)
			(xy 329.96146 -320.357816) (xy 329.968886 -320.418754) (xy 329.969368 -320.449448) (xy 329.968906 -320.480145)
			(xy 329.961502 -320.54109) (xy 329.946807 -320.600699) (xy 329.925037 -320.658103) (xy 329.896507 -320.712465)
			(xy 329.879452 -320.737992) (xy 329.873943 -320.746723) (xy 329.869832 -320.76694) (xy 329.873974 -320.78715)
			(xy 329.879452 -320.795904) (xy 329.896481 -320.821446) (xy 329.924993 -320.875812) (xy 329.946757 -320.933213)
			(xy 329.96146 -320.992816) (xy 329.968886 -321.053754) (xy 329.969368 -321.084448) (xy 329.968906 -321.115145)
			(xy 329.961502 -321.17609) (xy 329.946807 -321.235699) (xy 329.925037 -321.293103) (xy 329.896507 -321.347465)
			(xy 329.879452 -321.372992) (xy 329.873943 -321.381723) (xy 329.869832 -321.40194) (xy 329.873974 -321.42215)
			(xy 329.879452 -321.430904) (xy 329.896481 -321.456446) (xy 329.924993 -321.510812) (xy 329.946757 -321.568213)
			(xy 329.96146 -321.627816) (xy 329.968886 -321.688754) (xy 329.969368 -321.719448) (xy 329.968906 -321.750145)
			(xy 329.961502 -321.81109) (xy 329.946807 -321.870699) (xy 329.925037 -321.928103) (xy 329.896507 -321.982465)
			(xy 329.879452 -322.007992) (xy 329.873943 -322.016723) (xy 329.869832 -322.03694) (xy 329.873974 -322.05715)
			(xy 329.879452 -322.065904) (xy 329.896481 -322.091446) (xy 329.924993 -322.145812) (xy 329.946757 -322.203213)
			(xy 329.96146 -322.262816) (xy 329.968886 -322.323754) (xy 329.969368 -322.354448) (xy 329.968841 -322.387685)
			(xy 329.960215 -322.453595) (xy 329.943063 -322.517816) (xy 329.917678 -322.57925) (xy 329.884496 -322.636848)
			(xy 329.86472 -322.663566) (xy 329.858781 -322.672265) (xy 329.853762 -322.692694) (xy 329.857336 -322.713425)
			(xy 329.862688 -322.722494) (xy 329.878842 -322.747574) (xy 329.905795 -322.800798) (xy 329.926331 -322.856811)
			(xy 329.940168 -322.914843) (xy 329.947115 -322.974096) (xy 329.947524 -323.003926) (xy 332.000352 -323.003926)
			(xy 332.000798 -322.973229) (xy 332.008205 -322.912283) (xy 332.022903 -322.852673) (xy 332.044678 -322.79527)
			(xy 332.073211 -322.740908) (xy 332.090268 -322.715382) (xy 332.095721 -322.706619) (xy 332.099859 -322.686422)
			(xy 332.095738 -322.666221) (xy 332.090268 -322.65747) (xy 332.07323 -322.631934) (xy 332.04472 -322.577566)
			(xy 332.022956 -322.520163) (xy 332.008256 -322.46056) (xy 332.000832 -322.399621) (xy 332.000352 -322.368926)
			(xy 332.000798 -322.338229) (xy 332.008205 -322.277283) (xy 332.022903 -322.217673) (xy 332.044678 -322.16027)
			(xy 332.073211 -322.105908) (xy 332.090268 -322.080382) (xy 332.095721 -322.071619) (xy 332.099859 -322.051422)
			(xy 332.095738 -322.031221) (xy 332.090268 -322.02247) (xy 332.07323 -321.996934) (xy 332.04472 -321.942566)
			(xy 332.022956 -321.885163) (xy 332.008256 -321.82556) (xy 332.000832 -321.764621) (xy 332.000352 -321.733926)
			(xy 332.000798 -321.703229) (xy 332.008205 -321.642283) (xy 332.022903 -321.582673) (xy 332.044678 -321.52527)
			(xy 332.073211 -321.470908) (xy 332.090268 -321.445382) (xy 332.095721 -321.436619) (xy 332.099859 -321.416422)
			(xy 332.095738 -321.396221) (xy 332.090268 -321.38747) (xy 332.07323 -321.361934) (xy 332.04472 -321.307566)
			(xy 332.022956 -321.250163) (xy 332.008256 -321.19056) (xy 332.000832 -321.129621) (xy 332.000352 -321.098926)
			(xy 332.000798 -321.068229) (xy 332.008205 -321.007283) (xy 332.022903 -320.947673) (xy 332.044678 -320.89027)
			(xy 332.073211 -320.835908) (xy 332.090268 -320.810382) (xy 332.095721 -320.801619) (xy 332.099859 -320.781422)
			(xy 332.095738 -320.761221) (xy 332.090268 -320.75247) (xy 332.07323 -320.726934) (xy 332.04472 -320.672566)
			(xy 332.022956 -320.615163) (xy 332.008256 -320.55556) (xy 332.000832 -320.494621) (xy 332.000352 -320.463926)
			(xy 332.000837 -320.432331) (xy 332.008658 -320.369626) (xy 332.024196 -320.308376) (xy 332.047209 -320.249526)
			(xy 332.077344 -320.193984) (xy 332.095348 -320.168016) (xy 332.101061 -320.159166) (xy 332.10535 -320.13856)
			(xy 332.101029 -320.117962) (xy 332.095348 -320.109088) (xy 332.07754 -320.08318) (xy 332.047729 -320.02783)
			(xy 332.024963 -319.969229) (xy 332.009588 -319.90827) (xy 332.001839 -319.845882) (xy 332.001368 -319.814448)
			(xy 332.00184 -319.783752) (xy 332.009243 -319.722807) (xy 332.023936 -319.663198) (xy 332.045704 -319.605794)
			(xy 332.07423 -319.551432) (xy 332.091284 -319.525904) (xy 332.096717 -319.517131) (xy 332.10086 -319.49694)
			(xy 332.096748 -319.476743) (xy 332.091284 -319.467992) (xy 332.074258 -319.442448) (xy 332.045745 -319.388083)
			(xy 332.023979 -319.330682) (xy 332.009276 -319.27108) (xy 332.00185 -319.210142) (xy 332.001368 -319.179448)
			(xy 332.00184 -319.148752) (xy 332.009243 -319.087807) (xy 332.023936 -319.028198) (xy 332.045704 -318.970794)
			(xy 332.07423 -318.916432) (xy 332.091284 -318.890904) (xy 332.096717 -318.882131) (xy 332.10086 -318.86194)
			(xy 332.096748 -318.841743) (xy 332.091284 -318.832992) (xy 332.074258 -318.807448) (xy 332.045745 -318.753083)
			(xy 332.023979 -318.695682) (xy 332.009276 -318.63608) (xy 332.00185 -318.575142) (xy 332.001368 -318.544448)
			(xy 332.00184 -318.513752) (xy 332.009243 -318.452807) (xy 332.023936 -318.393198) (xy 332.045704 -318.335794)
			(xy 332.07423 -318.281432) (xy 332.091284 -318.255904) (xy 332.096717 -318.247131) (xy 332.10086 -318.22694)
			(xy 332.096748 -318.206743) (xy 332.091284 -318.197992) (xy 332.074258 -318.172448) (xy 332.045745 -318.118083)
			(xy 332.023979 -318.060682) (xy 332.009276 -318.00108) (xy 332.00185 -317.940142) (xy 332.001368 -317.909448)
			(xy 332.00184 -317.878752) (xy 332.009243 -317.817807) (xy 332.023936 -317.758198) (xy 332.045704 -317.700794)
			(xy 332.07423 -317.646432) (xy 332.091284 -317.620904) (xy 332.096717 -317.612131) (xy 332.10086 -317.59194)
			(xy 332.096748 -317.571743) (xy 332.091284 -317.562992) (xy 332.074258 -317.537448) (xy 332.045745 -317.483083)
			(xy 332.023979 -317.425682) (xy 332.009276 -317.36608) (xy 332.00185 -317.305142) (xy 332.001368 -317.274448)
			(xy 332.00184 -317.243752) (xy 332.009243 -317.182807) (xy 332.023936 -317.123198) (xy 332.045704 -317.065794)
			(xy 332.07423 -317.011432) (xy 332.091284 -316.985904) (xy 332.096717 -316.977131) (xy 332.10086 -316.95694)
			(xy 332.096748 -316.936743) (xy 332.091284 -316.927992) (xy 332.074258 -316.902448) (xy 332.045745 -316.848083)
			(xy 332.023979 -316.790682) (xy 332.009276 -316.73108) (xy 332.00185 -316.670142) (xy 332.001368 -316.639448)
			(xy 332.001883 -316.608718) (xy 332.009285 -316.547705) (xy 332.023989 -316.488029) (xy 332.045778 -316.430561)
			(xy 332.074336 -316.376139) (xy 332.109245 -316.325555) (xy 332.149997 -316.279548) (xy 332.195998 -316.23879)
			(xy 332.246577 -316.203873) (xy 332.300995 -316.175307) (xy 332.358461 -316.15351) (xy 332.418134 -316.138798)
			(xy 332.479146 -316.131387) (xy 332.509876 -316.13094) (xy 332.540573 -316.131387) (xy 332.601519 -316.138794)
			(xy 332.661128 -316.153492) (xy 332.718532 -316.175266) (xy 332.772894 -316.203799) (xy 332.79842 -316.220856)
			(xy 332.807172 -316.226327) (xy 332.827376 -316.230455) (xy 332.84758 -316.226327) (xy 332.856332 -316.220856)
			(xy 332.881867 -316.203816) (xy 332.936235 -316.175306) (xy 332.993638 -316.153543) (xy 333.053242 -316.138843)
			(xy 333.114181 -316.13142) (xy 333.144876 -316.13094) (xy 333.175573 -316.131387) (xy 333.236519 -316.138794)
			(xy 333.296128 -316.153492) (xy 333.353532 -316.175266) (xy 333.407894 -316.203799) (xy 333.43342 -316.220856)
			(xy 333.442172 -316.226327) (xy 333.462376 -316.230455) (xy 333.48258 -316.226327) (xy 333.491332 -316.220856)
			(xy 333.516867 -316.203816) (xy 333.571235 -316.175306) (xy 333.628638 -316.153543) (xy 333.688242 -316.138843)
			(xy 333.749181 -316.13142) (xy 333.779876 -316.13094) (xy 333.810609 -316.13136) (xy 333.871628 -316.138767)
			(xy 333.93131 -316.153476) (xy 333.988782 -316.175271) (xy 334.043209 -316.203836) (xy 334.093795 -316.238754)
			(xy 334.139803 -316.279514) (xy 334.180561 -316.325524) (xy 334.215476 -316.376112) (xy 334.244039 -316.43054)
			(xy 334.265832 -316.488013) (xy 334.280537 -316.547695) (xy 334.287941 -316.608715) (xy 334.288384 -316.639448)
			(xy 334.287919 -316.670145) (xy 334.280515 -316.73109) (xy 334.265821 -316.790699) (xy 334.244051 -316.848103)
			(xy 334.215523 -316.902465) (xy 334.198468 -316.927992) (xy 334.192957 -316.936723) (xy 334.188845 -316.95694)
			(xy 334.192989 -316.977151) (xy 334.198468 -316.985904) (xy 334.215499 -317.011445) (xy 334.24401 -317.065811)
			(xy 334.265774 -317.123213) (xy 334.280476 -317.182816) (xy 334.287902 -317.243754) (xy 334.288384 -317.274448)
			(xy 334.287919 -317.305145) (xy 334.280515 -317.36609) (xy 334.265821 -317.425699) (xy 334.244051 -317.483103)
			(xy 334.215523 -317.537465) (xy 334.198468 -317.562992) (xy 334.192957 -317.571723) (xy 334.188845 -317.59194)
			(xy 334.192989 -317.612151) (xy 334.198468 -317.620904) (xy 334.215499 -317.646445) (xy 334.24401 -317.700811)
			(xy 334.265774 -317.758213) (xy 334.280476 -317.817816) (xy 334.287902 -317.878754) (xy 334.288384 -317.909448)
			(xy 334.287919 -317.940145) (xy 334.280515 -318.00109) (xy 334.265821 -318.060699) (xy 334.244051 -318.118103)
			(xy 334.215523 -318.172465) (xy 334.198468 -318.197992) (xy 334.192957 -318.206723) (xy 334.188845 -318.22694)
			(xy 334.192989 -318.247151) (xy 334.198468 -318.255904) (xy 334.215499 -318.281445) (xy 334.24401 -318.335811)
			(xy 334.265774 -318.393213) (xy 334.280476 -318.452816) (xy 334.287902 -318.513754) (xy 334.288384 -318.544448)
			(xy 334.287919 -318.575145) (xy 334.280515 -318.63609) (xy 334.265821 -318.695699) (xy 334.244051 -318.753103)
			(xy 334.215523 -318.807465) (xy 334.198468 -318.832992) (xy 334.192957 -318.841723) (xy 334.188845 -318.86194)
			(xy 334.192989 -318.882151) (xy 334.198468 -318.890904) (xy 334.215499 -318.916445) (xy 334.24401 -318.970811)
			(xy 334.265774 -319.028213) (xy 334.280476 -319.087816) (xy 334.287902 -319.148754) (xy 334.288384 -319.179448)
			(xy 334.287919 -319.210145) (xy 334.280515 -319.27109) (xy 334.265821 -319.330699) (xy 334.244051 -319.388103)
			(xy 334.215523 -319.442465) (xy 334.198468 -319.467992) (xy 334.192957 -319.476723) (xy 334.188845 -319.49694)
			(xy 334.192989 -319.517151) (xy 334.198468 -319.525904) (xy 334.215499 -319.551445) (xy 334.24401 -319.605811)
			(xy 334.265774 -319.663213) (xy 334.280476 -319.722816) (xy 334.287902 -319.783754) (xy 334.288384 -319.814448)
			(xy 334.287933 -319.843401) (xy 334.281326 -319.900929) (xy 334.268239 -319.957336) (xy 334.248838 -320.011896)
			(xy 334.223375 -320.063903) (xy 334.20812 -320.088514) (xy 334.202941 -320.097519) (xy 334.199528 -320.117985)
			(xy 334.204516 -320.138125) (xy 334.210406 -320.14668) (xy 334.229953 -320.173291) (xy 334.26271 -320.230623)
			(xy 334.287772 -320.291712) (xy 334.304716 -320.35553) (xy 334.313259 -320.421005) (xy 334.313784 -320.45402)
			(xy 334.313305 -320.484716) (xy 334.305904 -320.545661) (xy 334.291214 -320.60527) (xy 334.269447 -320.662674)
			(xy 334.240921 -320.717037) (xy 334.223868 -320.742564) (xy 334.218381 -320.751307) (xy 334.214261 -320.771517)
			(xy 334.218394 -320.791723) (xy 334.223868 -320.800476) (xy 334.24093 -320.825997) (xy 334.269436 -320.880369)
			(xy 334.291194 -320.937776) (xy 334.305888 -320.997383) (xy 334.313307 -321.058324) (xy 334.313784 -321.08902)
			(xy 334.313305 -321.119716) (xy 334.305904 -321.180661) (xy 334.291214 -321.24027) (xy 334.269447 -321.297674)
			(xy 334.240921 -321.352037) (xy 334.223868 -321.377564) (xy 334.218381 -321.386307) (xy 334.214261 -321.406517)
			(xy 334.218394 -321.426723) (xy 334.223868 -321.435476) (xy 334.24093 -321.460997) (xy 334.269436 -321.515369)
			(xy 334.291194 -321.572776) (xy 334.305888 -321.632383) (xy 334.313307 -321.693324) (xy 334.313784 -321.72402)
			(xy 334.313305 -321.754716) (xy 334.305904 -321.815661) (xy 334.291214 -321.87527) (xy 334.269447 -321.932674)
			(xy 334.240921 -321.987037) (xy 334.223868 -322.012564) (xy 334.218381 -322.021307) (xy 334.214261 -322.041517)
			(xy 334.218394 -322.061723) (xy 334.223868 -322.070476) (xy 334.24093 -322.095997) (xy 334.269436 -322.150369)
			(xy 334.291194 -322.207776) (xy 334.305888 -322.267383) (xy 334.313307 -322.328324) (xy 334.313784 -322.35902)
			(xy 334.313223 -322.392392) (xy 334.304482 -322.458561) (xy 334.287154 -322.523017) (xy 334.261537 -322.584649)
			(xy 334.228071 -322.642397) (xy 334.20812 -322.669154) (xy 334.202149 -322.677773) (xy 334.197101 -322.698104)
			(xy 334.20056 -322.718764) (xy 334.205834 -322.727828) (xy 334.221366 -322.752554) (xy 334.247257 -322.804895)
			(xy 334.266979 -322.859858) (xy 334.280272 -322.916719) (xy 334.286961 -322.974729) (xy 334.287368 -323.003926)
			(xy 336.038952 -323.003926) (xy 336.03942 -322.972584) (xy 336.047128 -322.910377) (xy 336.06242 -322.849588)
			(xy 336.085062 -322.791137) (xy 336.114712 -322.73591) (xy 336.132424 -322.710048) (xy 336.137984 -322.701224)
			(xy 336.142231 -322.680831) (xy 336.138009 -322.660434) (xy 336.132424 -322.651628) (xy 336.114873 -322.625849)
			(xy 336.085524 -322.57082) (xy 336.063127 -322.512614) (xy 336.048018 -322.452106) (xy 336.040424 -322.390203)
			(xy 336.039968 -322.35902) (xy 336.040425 -322.328323) (xy 336.047832 -322.267378) (xy 336.062528 -322.207769)
			(xy 336.0843 -322.150366) (xy 336.112829 -322.096003) (xy 336.129884 -322.070476) (xy 336.13534 -322.061715)
			(xy 336.139476 -322.041517) (xy 336.135353 -322.021315) (xy 336.129884 -322.012564) (xy 336.112845 -321.987028)
			(xy 336.084335 -321.93266) (xy 336.062571 -321.875258) (xy 336.047871 -321.815654) (xy 336.040448 -321.754715)
			(xy 336.039968 -321.72402) (xy 336.040425 -321.693323) (xy 336.047832 -321.632378) (xy 336.062528 -321.572769)
			(xy 336.0843 -321.515366) (xy 336.112829 -321.461003) (xy 336.129884 -321.435476) (xy 336.13534 -321.426715)
			(xy 336.139476 -321.406517) (xy 336.135353 -321.386315) (xy 336.129884 -321.377564) (xy 336.112845 -321.352028)
			(xy 336.084335 -321.29766) (xy 336.062571 -321.240258) (xy 336.047871 -321.180654) (xy 336.040448 -321.119715)
			(xy 336.039968 -321.08902) (xy 336.040425 -321.058323) (xy 336.047832 -320.997378) (xy 336.062528 -320.937769)
			(xy 336.0843 -320.880366) (xy 336.112829 -320.826003) (xy 336.129884 -320.800476) (xy 336.13534 -320.791715)
			(xy 336.139476 -320.771517) (xy 336.135353 -320.751315) (xy 336.129884 -320.742564) (xy 336.112845 -320.717028)
			(xy 336.084335 -320.66266) (xy 336.062571 -320.605258) (xy 336.047871 -320.545654) (xy 336.040448 -320.484715)
			(xy 336.039968 -320.45402) (xy 336.040459 -320.423048) (xy 336.047984 -320.361562) (xy 336.062926 -320.301446)
			(xy 336.085063 -320.243592) (xy 336.114066 -320.188856) (xy 336.131408 -320.16319) (xy 336.136851 -320.154422)
			(xy 336.140988 -320.134228) (xy 336.136873 -320.11403) (xy 336.131408 -320.105278) (xy 336.114037 -320.079629)
			(xy 336.08503 -320.024891) (xy 336.062891 -319.967033) (xy 336.047949 -319.906913) (xy 336.040426 -319.845423)
			(xy 336.039968 -319.814448) (xy 336.04044 -319.783752) (xy 336.047843 -319.722807) (xy 336.062536 -319.663198)
			(xy 336.084304 -319.605794) (xy 336.11283 -319.551432) (xy 336.129884 -319.525904) (xy 336.135317 -319.517131)
			(xy 336.13946 -319.49694) (xy 336.135348 -319.476743) (xy 336.129884 -319.467992) (xy 336.112858 -319.442448)
			(xy 336.084345 -319.388083) (xy 336.062579 -319.330682) (xy 336.047876 -319.27108) (xy 336.04045 -319.210142)
			(xy 336.039968 -319.179448) (xy 336.04044 -319.148752) (xy 336.047843 -319.087807) (xy 336.062536 -319.028198)
			(xy 336.084304 -318.970794) (xy 336.11283 -318.916432) (xy 336.129884 -318.890904) (xy 336.135317 -318.882131)
			(xy 336.13946 -318.86194) (xy 336.135348 -318.841743) (xy 336.129884 -318.832992) (xy 336.112858 -318.807448)
			(xy 336.084345 -318.753083) (xy 336.062579 -318.695682) (xy 336.047876 -318.63608) (xy 336.04045 -318.575142)
			(xy 336.039968 -318.544448) (xy 336.04044 -318.513752) (xy 336.047843 -318.452807) (xy 336.062536 -318.393198)
			(xy 336.084304 -318.335794) (xy 336.11283 -318.281432) (xy 336.129884 -318.255904) (xy 336.135317 -318.247131)
			(xy 336.13946 -318.22694) (xy 336.135348 -318.206743) (xy 336.129884 -318.197992) (xy 336.112858 -318.172448)
			(xy 336.084345 -318.118083) (xy 336.062579 -318.060682) (xy 336.047876 -318.00108) (xy 336.04045 -317.940142)
			(xy 336.039968 -317.909448) (xy 336.04044 -317.878752) (xy 336.047843 -317.817807) (xy 336.062536 -317.758198)
			(xy 336.084304 -317.700794) (xy 336.11283 -317.646432) (xy 336.129884 -317.620904) (xy 336.135317 -317.612131)
			(xy 336.13946 -317.59194) (xy 336.135348 -317.571743) (xy 336.129884 -317.562992) (xy 336.112858 -317.537448)
			(xy 336.084345 -317.483083) (xy 336.062579 -317.425682) (xy 336.047876 -317.36608) (xy 336.04045 -317.305142)
			(xy 336.039968 -317.274448) (xy 336.04044 -317.243752) (xy 336.047843 -317.182807) (xy 336.062536 -317.123198)
			(xy 336.084304 -317.065794) (xy 336.11283 -317.011432) (xy 336.129884 -316.985904) (xy 336.135317 -316.977131)
			(xy 336.13946 -316.95694) (xy 336.135348 -316.936743) (xy 336.129884 -316.927992) (xy 336.112858 -316.902448)
			(xy 336.084345 -316.848083) (xy 336.062579 -316.790682) (xy 336.047876 -316.73108) (xy 336.04045 -316.670142)
			(xy 336.039968 -316.639448) (xy 336.040483 -316.608718) (xy 336.047885 -316.547705) (xy 336.062589 -316.488029)
			(xy 336.084378 -316.430561) (xy 336.112936 -316.376139) (xy 336.147845 -316.325555) (xy 336.188597 -316.279548)
			(xy 336.234598 -316.23879) (xy 336.285177 -316.203873) (xy 336.339595 -316.175307) (xy 336.397061 -316.15351)
			(xy 336.456734 -316.138798) (xy 336.517746 -316.131387) (xy 336.548476 -316.13094) (xy 336.579173 -316.131387)
			(xy 336.640119 -316.138794) (xy 336.699728 -316.153492) (xy 336.757132 -316.175266) (xy 336.811494 -316.203799)
			(xy 336.83702 -316.220856) (xy 336.845772 -316.226327) (xy 336.865976 -316.230455) (xy 336.88618 -316.226327)
			(xy 336.894932 -316.220856) (xy 336.920467 -316.203816) (xy 336.974835 -316.175306) (xy 337.032238 -316.153543)
			(xy 337.091842 -316.138843) (xy 337.152781 -316.13142) (xy 337.183476 -316.13094) (xy 337.214173 -316.131387)
			(xy 337.275119 -316.138794) (xy 337.334728 -316.153492) (xy 337.392132 -316.175266) (xy 337.446494 -316.203799)
			(xy 337.47202 -316.220856) (xy 337.480772 -316.226327) (xy 337.500976 -316.230455) (xy 337.52118 -316.226327)
			(xy 337.529932 -316.220856) (xy 337.555467 -316.203816) (xy 337.609835 -316.175306) (xy 337.667238 -316.153543)
			(xy 337.726842 -316.138843) (xy 337.787781 -316.13142) (xy 337.818476 -316.13094) (xy 337.849209 -316.13136)
			(xy 337.910228 -316.138767) (xy 337.96991 -316.153476) (xy 338.027382 -316.175271) (xy 338.081809 -316.203836)
			(xy 338.132395 -316.238754) (xy 338.178403 -316.279514) (xy 338.219161 -316.325524) (xy 338.254076 -316.376112)
			(xy 338.282639 -316.43054) (xy 338.304432 -316.488013) (xy 338.319137 -316.547695) (xy 338.326541 -316.608715)
			(xy 338.326984 -316.639448) (xy 338.326519 -316.670145) (xy 338.319115 -316.73109) (xy 338.304421 -316.790699)
			(xy 338.282651 -316.848103) (xy 338.254123 -316.902465) (xy 338.237068 -316.927992) (xy 338.231557 -316.936723)
			(xy 338.227445 -316.95694) (xy 338.231589 -316.977151) (xy 338.237068 -316.985904) (xy 338.254099 -317.011445)
			(xy 338.28261 -317.065811) (xy 338.304374 -317.123213) (xy 338.319076 -317.182816) (xy 338.326502 -317.243754)
			(xy 338.326984 -317.274448) (xy 338.326519 -317.305145) (xy 338.319115 -317.36609) (xy 338.304421 -317.425699)
			(xy 338.282651 -317.483103) (xy 338.254123 -317.537465) (xy 338.237068 -317.562992) (xy 338.231557 -317.571723)
			(xy 338.227445 -317.59194) (xy 338.231589 -317.612151) (xy 338.237068 -317.620904) (xy 338.254099 -317.646445)
			(xy 338.28261 -317.700811) (xy 338.304374 -317.758213) (xy 338.319076 -317.817816) (xy 338.326502 -317.878754)
			(xy 338.326984 -317.909448) (xy 338.326519 -317.940145) (xy 338.319115 -318.00109) (xy 338.304421 -318.060699)
			(xy 338.282651 -318.118103) (xy 338.254123 -318.172465) (xy 338.237068 -318.197992) (xy 338.231557 -318.206723)
			(xy 338.227445 -318.22694) (xy 338.231589 -318.247151) (xy 338.237068 -318.255904) (xy 338.254099 -318.281445)
			(xy 338.28261 -318.335811) (xy 338.304374 -318.393213) (xy 338.319076 -318.452816) (xy 338.326502 -318.513754)
			(xy 338.326984 -318.544448) (xy 338.326519 -318.575145) (xy 338.319115 -318.63609) (xy 338.304421 -318.695699)
			(xy 338.282651 -318.753103) (xy 338.254123 -318.807465) (xy 338.237068 -318.832992) (xy 338.231557 -318.841723)
			(xy 338.227445 -318.86194) (xy 338.231589 -318.882151) (xy 338.237068 -318.890904) (xy 338.254099 -318.916445)
			(xy 338.28261 -318.970811) (xy 338.304374 -319.028213) (xy 338.319076 -319.087816) (xy 338.326502 -319.148754)
			(xy 338.326984 -319.179448) (xy 338.326519 -319.210145) (xy 338.319115 -319.27109) (xy 338.304421 -319.330699)
			(xy 338.282651 -319.388103) (xy 338.254123 -319.442465) (xy 338.237068 -319.467992) (xy 338.231557 -319.476723)
			(xy 338.227445 -319.49694) (xy 338.231589 -319.517151) (xy 338.237068 -319.525904) (xy 338.254099 -319.551445)
			(xy 338.28261 -319.605811) (xy 338.304374 -319.663213) (xy 338.319076 -319.722816) (xy 338.326502 -319.783754)
			(xy 338.326984 -319.814448) (xy 338.326765 -319.828926) (xy 340.255352 -319.828926) (xy 340.255798 -319.798229)
			(xy 340.263205 -319.737283) (xy 340.277903 -319.677673) (xy 340.299678 -319.62027) (xy 340.328211 -319.565908)
			(xy 340.345268 -319.540382) (xy 340.350721 -319.531619) (xy 340.354859 -319.511422) (xy 340.350738 -319.491221)
			(xy 340.345268 -319.48247) (xy 340.32823 -319.456934) (xy 340.29972 -319.402566) (xy 340.277956 -319.345163)
			(xy 340.263256 -319.28556) (xy 340.255832 -319.224621) (xy 340.255352 -319.193926) (xy 340.255798 -319.163229)
			(xy 340.263205 -319.102283) (xy 340.277903 -319.042673) (xy 340.299678 -318.98527) (xy 340.328211 -318.930908)
			(xy 340.345268 -318.905382) (xy 340.350721 -318.896619) (xy 340.354859 -318.876422) (xy 340.350738 -318.856221)
			(xy 340.345268 -318.84747) (xy 340.32823 -318.821934) (xy 340.29972 -318.767566) (xy 340.277956 -318.710163)
			(xy 340.263256 -318.65056) (xy 340.255832 -318.589621) (xy 340.255352 -318.558926) (xy 340.255798 -318.528229)
			(xy 340.263205 -318.467283) (xy 340.277903 -318.407673) (xy 340.299678 -318.35027) (xy 340.328211 -318.295908)
			(xy 340.345268 -318.270382) (xy 340.350721 -318.261619) (xy 340.354859 -318.241422) (xy 340.350738 -318.221221)
			(xy 340.345268 -318.21247) (xy 340.32823 -318.186934) (xy 340.29972 -318.132566) (xy 340.277956 -318.075163)
			(xy 340.263256 -318.01556) (xy 340.255832 -317.954621) (xy 340.255352 -317.923926) (xy 340.255798 -317.893229)
			(xy 340.263205 -317.832283) (xy 340.277903 -317.772673) (xy 340.299678 -317.71527) (xy 340.328211 -317.660908)
			(xy 340.345268 -317.635382) (xy 340.350721 -317.626619) (xy 340.354859 -317.606422) (xy 340.350738 -317.586221)
			(xy 340.345268 -317.57747) (xy 340.32823 -317.551934) (xy 340.29972 -317.497566) (xy 340.277956 -317.440163)
			(xy 340.263256 -317.38056) (xy 340.255832 -317.319621) (xy 340.255352 -317.288926) (xy 340.255798 -317.258229)
			(xy 340.263205 -317.197283) (xy 340.277903 -317.137673) (xy 340.299678 -317.08027) (xy 340.328211 -317.025908)
			(xy 340.345268 -317.000382) (xy 340.350721 -316.991619) (xy 340.354859 -316.971422) (xy 340.350738 -316.951221)
			(xy 340.345268 -316.94247) (xy 340.32823 -316.916934) (xy 340.29972 -316.862566) (xy 340.277956 -316.805163)
			(xy 340.263256 -316.74556) (xy 340.255832 -316.684621) (xy 340.255352 -316.653926) (xy 340.25588 -316.623197)
			(xy 340.263285 -316.562187) (xy 340.27799 -316.502514) (xy 340.29978 -316.445049) (xy 340.328337 -316.390629)
			(xy 340.363246 -316.340048) (xy 340.403997 -316.294044) (xy 340.449996 -316.253287) (xy 340.500573 -316.218371)
			(xy 340.554989 -316.189807) (xy 340.612451 -316.168009) (xy 340.672122 -316.153297) (xy 340.733131 -316.145884)
			(xy 340.76386 -316.145418) (xy 340.794557 -316.145877) (xy 340.855502 -316.153282) (xy 340.915111 -316.167977)
			(xy 340.972515 -316.189749) (xy 341.026877 -316.218279) (xy 341.052404 -316.235334) (xy 341.061156 -316.240805)
			(xy 341.08136 -316.244933) (xy 341.101564 -316.240805) (xy 341.110316 -316.235334) (xy 341.135853 -316.218298)
			(xy 341.190221 -316.189788) (xy 341.247623 -316.168025) (xy 341.307227 -316.153324) (xy 341.368166 -316.145899)
			(xy 341.39886 -316.145418) (xy 341.429557 -316.145877) (xy 341.490502 -316.153282) (xy 341.550111 -316.167977)
			(xy 341.607515 -316.189749) (xy 341.661877 -316.218279) (xy 341.687404 -316.235334) (xy 341.696156 -316.240805)
			(xy 341.71636 -316.244933) (xy 341.736564 -316.240805) (xy 341.745316 -316.235334) (xy 341.770853 -316.218298)
			(xy 341.825221 -316.189788) (xy 341.882623 -316.168025) (xy 341.942227 -316.153324) (xy 342.003166 -316.145899)
			(xy 342.03386 -316.145418) (xy 342.064592 -316.145875) (xy 342.125609 -316.15328) (xy 342.185288 -316.167986)
			(xy 342.24276 -316.189779) (xy 342.297185 -316.21834) (xy 342.34777 -316.253255) (xy 342.393778 -316.294012)
			(xy 342.434537 -316.340019) (xy 342.469452 -316.390603) (xy 342.498016 -316.445028) (xy 342.51981 -316.502498)
			(xy 342.534518 -316.562177) (xy 342.541924 -316.623194) (xy 342.542368 -316.653926) (xy 342.541894 -316.684622)
			(xy 342.534493 -316.745567) (xy 342.519801 -316.805176) (xy 342.498033 -316.86258) (xy 342.469506 -316.916943)
			(xy 342.452452 -316.94247) (xy 342.446962 -316.951211) (xy 342.442844 -316.971422) (xy 342.446979 -316.991629)
			(xy 342.452452 -317.000382) (xy 342.469472 -317.02593) (xy 342.497985 -317.080295) (xy 342.519752 -317.137694)
			(xy 342.534456 -317.197295) (xy 342.541885 -317.258232) (xy 342.542368 -317.288926) (xy 342.541894 -317.319622)
			(xy 342.534493 -317.380567) (xy 342.519801 -317.440176) (xy 342.498033 -317.49758) (xy 342.469506 -317.551943)
			(xy 342.452452 -317.57747) (xy 342.446962 -317.586211) (xy 342.442844 -317.606422) (xy 342.446979 -317.626629)
			(xy 342.452452 -317.635382) (xy 342.469472 -317.66093) (xy 342.497985 -317.715295) (xy 342.519752 -317.772694)
			(xy 342.534456 -317.832295) (xy 342.541885 -317.893232) (xy 342.542368 -317.923926) (xy 342.541894 -317.954622)
			(xy 342.534493 -318.015567) (xy 342.519801 -318.075176) (xy 342.498033 -318.13258) (xy 342.469506 -318.186943)
			(xy 342.452452 -318.21247) (xy 342.446962 -318.221211) (xy 342.442844 -318.241422) (xy 342.446979 -318.261629)
			(xy 342.452452 -318.270382) (xy 342.469472 -318.29593) (xy 342.497985 -318.350295) (xy 342.519752 -318.407694)
			(xy 342.534456 -318.467295) (xy 342.541885 -318.528232) (xy 342.542368 -318.558926) (xy 342.541894 -318.589622)
			(xy 342.534493 -318.650567) (xy 342.519801 -318.710176) (xy 342.498033 -318.76758) (xy 342.469506 -318.821943)
			(xy 342.452452 -318.84747) (xy 342.446962 -318.856211) (xy 342.442844 -318.876422) (xy 342.446979 -318.896629)
			(xy 342.452452 -318.905382) (xy 342.469472 -318.93093) (xy 342.497985 -318.985295) (xy 342.519752 -319.042694)
			(xy 342.534456 -319.102295) (xy 342.541885 -319.163232) (xy 342.542368 -319.193926) (xy 342.541894 -319.224622)
			(xy 342.534493 -319.285567) (xy 342.519801 -319.345176) (xy 342.498033 -319.40258) (xy 342.469506 -319.456943)
			(xy 342.452452 -319.48247) (xy 342.446962 -319.491211) (xy 342.442844 -319.511422) (xy 342.446979 -319.531629)
			(xy 342.452452 -319.540382) (xy 342.469472 -319.56593) (xy 342.497985 -319.620295) (xy 342.519752 -319.677694)
			(xy 342.534456 -319.737295) (xy 342.541885 -319.798232) (xy 342.542368 -319.828926) (xy 342.541957 -319.85788)
			(xy 342.535341 -319.915409) (xy 342.522245 -319.971817) (xy 342.502835 -320.026376) (xy 342.477364 -320.078382)
			(xy 342.462104 -320.102992) (xy 342.456858 -320.111964) (xy 342.45347 -320.132451) (xy 342.458486 -320.152603)
			(xy 342.46439 -320.161158) (xy 342.483925 -320.187778) (xy 342.516684 -320.245107) (xy 342.541749 -320.306193)
			(xy 342.558696 -320.37001) (xy 342.567242 -320.435484) (xy 342.567768 -320.468498) (xy 342.567331 -320.499195)
			(xy 342.559921 -320.560142) (xy 342.545221 -320.619751) (xy 342.523445 -320.677155) (xy 342.49491 -320.731516)
			(xy 342.477852 -320.757042) (xy 342.472385 -320.765796) (xy 342.46826 -320.785998) (xy 342.472384 -320.806201)
			(xy 342.477852 -320.814954) (xy 342.494903 -320.840482) (xy 342.52341 -320.894852) (xy 342.545171 -320.952257)
			(xy 342.559868 -321.011862) (xy 342.567289 -321.072803) (xy 342.567768 -321.103498) (xy 342.567331 -321.134195)
			(xy 342.559921 -321.195142) (xy 342.545221 -321.254751) (xy 342.523445 -321.312155) (xy 342.49491 -321.366516)
			(xy 342.477852 -321.392042) (xy 342.472385 -321.400796) (xy 342.46826 -321.420998) (xy 342.472384 -321.441201)
			(xy 342.477852 -321.449954) (xy 342.494903 -321.475482) (xy 342.52341 -321.529852) (xy 342.545171 -321.587257)
			(xy 342.559868 -321.646862) (xy 342.567289 -321.707803) (xy 342.567768 -321.738498) (xy 342.567331 -321.769195)
			(xy 342.559921 -321.830142) (xy 342.545221 -321.889751) (xy 342.523445 -321.947155) (xy 342.49491 -322.001516)
			(xy 342.477852 -322.027042) (xy 342.472385 -322.035796) (xy 342.46826 -322.055998) (xy 342.472384 -322.076201)
			(xy 342.477852 -322.084954) (xy 342.494903 -322.110482) (xy 342.52341 -322.164852) (xy 342.545171 -322.222257)
			(xy 342.559868 -322.281862) (xy 342.567289 -322.342803) (xy 342.567768 -322.373498) (xy 342.567307 -322.405372)
			(xy 342.559366 -322.468624) (xy 342.543573 -322.530384) (xy 342.520175 -322.589682) (xy 342.48954 -322.645586)
			(xy 342.471248 -322.671694) (xy 342.465459 -322.680619) (xy 342.461065 -322.70141) (xy 342.465467 -322.722199)
			(xy 342.471248 -322.73113) (xy 342.489538 -322.757235) (xy 342.520133 -322.813155) (xy 342.543511 -322.872456)
			(xy 342.559305 -322.934211) (xy 342.56727 -322.997455) (xy 342.567768 -323.029326) (xy 344.293952 -323.029326)
			(xy 344.294422 -322.997452) (xy 344.30236 -322.934201) (xy 344.318151 -322.87244) (xy 344.341547 -322.813142)
			(xy 344.372181 -322.757238) (xy 344.390472 -322.73113) (xy 344.396238 -322.722192) (xy 344.400637 -322.70141)
			(xy 344.396246 -322.680626) (xy 344.390472 -322.671694) (xy 344.372196 -322.64558) (xy 344.341597 -322.589662)
			(xy 344.318216 -322.530364) (xy 344.302419 -322.468611) (xy 344.294452 -322.405369) (xy 344.293952 -322.373498)
			(xy 344.294434 -322.342802) (xy 344.301833 -322.281857) (xy 344.316523 -322.222248) (xy 344.338289 -322.164844)
			(xy 344.366814 -322.110481) (xy 344.383868 -322.084954) (xy 344.389344 -322.076204) (xy 344.393475 -322.055998)
			(xy 344.389343 -322.035793) (xy 344.383868 -322.027042) (xy 344.366818 -322.001514) (xy 344.33831 -321.947144)
			(xy 344.316549 -321.889739) (xy 344.301851 -321.830134) (xy 344.294431 -321.769193) (xy 344.293952 -321.738498)
			(xy 344.294434 -321.707802) (xy 344.301833 -321.646857) (xy 344.316523 -321.587248) (xy 344.338289 -321.529844)
			(xy 344.366814 -321.475481) (xy 344.383868 -321.449954) (xy 344.389344 -321.441204) (xy 344.393475 -321.420998)
			(xy 344.389343 -321.400793) (xy 344.383868 -321.392042) (xy 344.366818 -321.366514) (xy 344.33831 -321.312144)
			(xy 344.316549 -321.254739) (xy 344.301851 -321.195134) (xy 344.294431 -321.134193) (xy 344.293952 -321.103498)
			(xy 344.294434 -321.072802) (xy 344.301833 -321.011857) (xy 344.316523 -320.952248) (xy 344.338289 -320.894844)
			(xy 344.366814 -320.840481) (xy 344.383868 -320.814954) (xy 344.389344 -320.806204) (xy 344.393475 -320.785998)
			(xy 344.389343 -320.765793) (xy 344.383868 -320.757042) (xy 344.366818 -320.731514) (xy 344.33831 -320.677144)
			(xy 344.316549 -320.619739) (xy 344.301851 -320.560134) (xy 344.294431 -320.499193) (xy 344.293952 -320.468498)
			(xy 344.294434 -320.437525) (xy 344.301962 -320.376039) (xy 344.316906 -320.315923) (xy 344.339044 -320.258069)
			(xy 344.368049 -320.203334) (xy 344.385392 -320.177668) (xy 344.390855 -320.168911) (xy 344.394988 -320.14871)
			(xy 344.390863 -320.128507) (xy 344.385392 -320.119756) (xy 344.368065 -320.094078) (xy 344.339049 -320.039349)
			(xy 344.3169 -319.981499) (xy 344.301948 -319.921385) (xy 344.294414 -319.859899) (xy 344.293952 -319.828926)
			(xy 344.294398 -319.798229) (xy 344.301805 -319.737283) (xy 344.316503 -319.677673) (xy 344.338278 -319.62027)
			(xy 344.366811 -319.565908) (xy 344.383868 -319.540382) (xy 344.389321 -319.531619) (xy 344.393459 -319.511422)
			(xy 344.389338 -319.491221) (xy 344.383868 -319.48247) (xy 344.36683 -319.456934) (xy 344.33832 -319.402566)
			(xy 344.316556 -319.345163) (xy 344.301856 -319.28556) (xy 344.294432 -319.224621) (xy 344.293952 -319.193926)
			(xy 344.294398 -319.163229) (xy 344.301805 -319.102283) (xy 344.316503 -319.042673) (xy 344.338278 -318.98527)
			(xy 344.366811 -318.930908) (xy 344.383868 -318.905382) (xy 344.389321 -318.896619) (xy 344.393459 -318.876422)
			(xy 344.389338 -318.856221) (xy 344.383868 -318.84747) (xy 344.36683 -318.821934) (xy 344.33832 -318.767566)
			(xy 344.316556 -318.710163) (xy 344.301856 -318.65056) (xy 344.294432 -318.589621) (xy 344.293952 -318.558926)
			(xy 344.294398 -318.528229) (xy 344.301805 -318.467283) (xy 344.316503 -318.407673) (xy 344.338278 -318.35027)
			(xy 344.366811 -318.295908) (xy 344.383868 -318.270382) (xy 344.389321 -318.261619) (xy 344.393459 -318.241422)
			(xy 344.389338 -318.221221) (xy 344.383868 -318.21247) (xy 344.36683 -318.186934) (xy 344.33832 -318.132566)
			(xy 344.316556 -318.075163) (xy 344.301856 -318.01556) (xy 344.294432 -317.954621) (xy 344.293952 -317.923926)
			(xy 344.294398 -317.893229) (xy 344.301805 -317.832283) (xy 344.316503 -317.772673) (xy 344.338278 -317.71527)
			(xy 344.366811 -317.660908) (xy 344.383868 -317.635382) (xy 344.389321 -317.626619) (xy 344.393459 -317.606422)
			(xy 344.389338 -317.586221) (xy 344.383868 -317.57747) (xy 344.36683 -317.551934) (xy 344.33832 -317.497566)
			(xy 344.316556 -317.440163) (xy 344.301856 -317.38056) (xy 344.294432 -317.319621) (xy 344.293952 -317.288926)
			(xy 344.294398 -317.258229) (xy 344.301805 -317.197283) (xy 344.316503 -317.137673) (xy 344.338278 -317.08027)
			(xy 344.366811 -317.025908) (xy 344.383868 -317.000382) (xy 344.389321 -316.991619) (xy 344.393459 -316.971422)
			(xy 344.389338 -316.951221) (xy 344.383868 -316.94247) (xy 344.36683 -316.916934) (xy 344.33832 -316.862566)
			(xy 344.316556 -316.805163) (xy 344.301856 -316.74556) (xy 344.294432 -316.684621) (xy 344.293952 -316.653926)
			(xy 344.29448 -316.623197) (xy 344.301885 -316.562187) (xy 344.31659 -316.502514) (xy 344.33838 -316.445049)
			(xy 344.366937 -316.390629) (xy 344.401846 -316.340048) (xy 344.442597 -316.294044) (xy 344.488596 -316.253287)
			(xy 344.539173 -316.218371) (xy 344.593589 -316.189807) (xy 344.651051 -316.168009) (xy 344.710722 -316.153297)
			(xy 344.771731 -316.145884) (xy 344.80246 -316.145418) (xy 344.833157 -316.145877) (xy 344.894102 -316.153282)
			(xy 344.953711 -316.167977) (xy 345.011115 -316.189749) (xy 345.065477 -316.218279) (xy 345.091004 -316.235334)
			(xy 345.099756 -316.240805) (xy 345.11996 -316.244933) (xy 345.140164 -316.240805) (xy 345.148916 -316.235334)
			(xy 345.174453 -316.218298) (xy 345.228821 -316.189788) (xy 345.286223 -316.168025) (xy 345.345827 -316.153324)
			(xy 345.406766 -316.145899) (xy 345.43746 -316.145418) (xy 345.468157 -316.145877) (xy 345.529102 -316.153282)
			(xy 345.588711 -316.167977) (xy 345.646115 -316.189749) (xy 345.700477 -316.218279) (xy 345.726004 -316.235334)
			(xy 345.734756 -316.240805) (xy 345.75496 -316.244933) (xy 345.775164 -316.240805) (xy 345.783916 -316.235334)
			(xy 345.809453 -316.218298) (xy 345.863821 -316.189788) (xy 345.921223 -316.168025) (xy 345.980827 -316.153324)
			(xy 346.041766 -316.145899) (xy 346.07246 -316.145418) (xy 346.103192 -316.145875) (xy 346.164209 -316.15328)
			(xy 346.223888 -316.167986) (xy 346.28136 -316.189779) (xy 346.335785 -316.21834) (xy 346.38637 -316.253255)
			(xy 346.432378 -316.294012) (xy 346.473137 -316.340019) (xy 346.508052 -316.390603) (xy 346.536616 -316.445028)
			(xy 346.55841 -316.502498) (xy 346.573118 -316.562177) (xy 346.580524 -316.623194) (xy 346.580968 -316.653926)
			(xy 346.580494 -316.684622) (xy 346.573093 -316.745567) (xy 346.558401 -316.805176) (xy 346.536633 -316.86258)
			(xy 346.508106 -316.916943) (xy 346.491052 -316.94247) (xy 346.485562 -316.951211) (xy 346.481444 -316.971422)
			(xy 346.485579 -316.991629) (xy 346.491052 -317.000382) (xy 346.508072 -317.02593) (xy 346.536585 -317.080295)
			(xy 346.558352 -317.137694) (xy 346.573056 -317.197295) (xy 346.580485 -317.258232) (xy 346.580968 -317.288926)
			(xy 346.580494 -317.319622) (xy 346.573093 -317.380567) (xy 346.558401 -317.440176) (xy 346.536633 -317.49758)
			(xy 346.508106 -317.551943) (xy 346.491052 -317.57747) (xy 346.485562 -317.586211) (xy 346.481444 -317.606422)
			(xy 346.485579 -317.626629) (xy 346.491052 -317.635382) (xy 346.508072 -317.66093) (xy 346.536585 -317.715295)
			(xy 346.558352 -317.772694) (xy 346.573056 -317.832295) (xy 346.580485 -317.893232) (xy 346.580968 -317.923926)
			(xy 346.580494 -317.954622) (xy 346.573093 -318.015567) (xy 346.558401 -318.075176) (xy 346.536633 -318.13258)
			(xy 346.508106 -318.186943) (xy 346.491052 -318.21247) (xy 346.485562 -318.221211) (xy 346.481444 -318.241422)
			(xy 346.485579 -318.261629) (xy 346.491052 -318.270382) (xy 346.508072 -318.29593) (xy 346.536585 -318.350295)
			(xy 346.558352 -318.407694) (xy 346.573056 -318.467295) (xy 346.580485 -318.528232) (xy 346.580968 -318.558926)
			(xy 346.580494 -318.589622) (xy 346.573093 -318.650567) (xy 346.558401 -318.710176) (xy 346.536633 -318.76758)
			(xy 346.508106 -318.821943) (xy 346.491052 -318.84747) (xy 346.485562 -318.856211) (xy 346.481444 -318.876422)
			(xy 346.485579 -318.896629) (xy 346.491052 -318.905382) (xy 346.508072 -318.93093) (xy 346.536585 -318.985295)
			(xy 346.558352 -319.042694) (xy 346.573056 -319.102295) (xy 346.580485 -319.163232) (xy 346.580968 -319.193926)
			(xy 346.580494 -319.224622) (xy 346.573093 -319.285567) (xy 346.558401 -319.345176) (xy 346.536633 -319.40258)
			(xy 346.508106 -319.456943) (xy 346.491052 -319.48247) (xy 346.485562 -319.491211) (xy 346.481444 -319.511422)
			(xy 346.485579 -319.531629) (xy 346.491052 -319.540382) (xy 346.508072 -319.56593) (xy 346.536585 -319.620295)
			(xy 346.558352 -319.677694) (xy 346.573056 -319.737295) (xy 346.580485 -319.798232) (xy 346.580968 -319.828926)
			(xy 346.580459 -319.861051) (xy 346.572368 -319.924788) (xy 346.556318 -319.987) (xy 346.532564 -320.046697)
			(xy 346.501484 -320.102929) (xy 346.482924 -320.129154) (xy 346.476938 -320.138095) (xy 346.472446 -320.159121)
			(xy 346.476955 -320.180144) (xy 346.482924 -320.189098) (xy 346.501496 -320.215316) (xy 346.532582 -320.271547)
			(xy 346.55634 -320.331245) (xy 346.572391 -320.39346) (xy 346.580479 -320.4572) (xy 346.580968 -320.489326)
			(xy 346.580494 -320.520022) (xy 346.573093 -320.580967) (xy 346.558401 -320.640576) (xy 346.536633 -320.69798)
			(xy 346.508106 -320.752343) (xy 346.491052 -320.77787) (xy 346.485562 -320.786611) (xy 346.481444 -320.806822)
			(xy 346.485579 -320.827029) (xy 346.491052 -320.835782) (xy 346.508072 -320.86133) (xy 346.536585 -320.915695)
			(xy 346.558352 -320.973094) (xy 346.573056 -321.032695) (xy 346.580485 -321.093632) (xy 346.580968 -321.124326)
			(xy 346.580494 -321.155022) (xy 346.573093 -321.215967) (xy 346.558401 -321.275576) (xy 346.536633 -321.33298)
			(xy 346.508106 -321.387343) (xy 346.491052 -321.41287) (xy 346.485562 -321.421611) (xy 346.481444 -321.441822)
			(xy 346.485579 -321.462029) (xy 346.491052 -321.470782) (xy 346.508072 -321.49633) (xy 346.536585 -321.550695)
			(xy 346.558352 -321.608094) (xy 346.573056 -321.667695) (xy 346.580485 -321.728632) (xy 346.580968 -321.759326)
			(xy 346.580494 -321.790022) (xy 346.573093 -321.850967) (xy 346.558401 -321.910576) (xy 346.536633 -321.96798)
			(xy 346.508106 -322.022343) (xy 346.491052 -322.04787) (xy 346.485562 -322.056611) (xy 346.481444 -322.076822)
			(xy 346.485579 -322.097029) (xy 346.491052 -322.105782) (xy 346.508072 -322.13133) (xy 346.536585 -322.185695)
			(xy 346.558352 -322.243094) (xy 346.573056 -322.302695) (xy 346.580485 -322.363632) (xy 346.580968 -322.394326)
			(xy 346.580494 -322.425022) (xy 346.573093 -322.485967) (xy 346.558401 -322.545576) (xy 346.536633 -322.60298)
			(xy 346.508106 -322.657343) (xy 346.491052 -322.68287) (xy 346.485562 -322.691611) (xy 346.481444 -322.711822)
			(xy 346.485579 -322.732029) (xy 346.491052 -322.740782) (xy 346.508072 -322.76633) (xy 346.536585 -322.820695)
			(xy 346.558352 -322.878094) (xy 346.573056 -322.937695) (xy 346.580485 -322.998632) (xy 346.580968 -323.029326)
			(xy 346.580587 -323.06006) (xy 346.573174 -323.12108) (xy 346.558461 -323.180762) (xy 346.53666 -323.238234)
			(xy 346.508091 -323.29266) (xy 346.47317 -323.343246) (xy 346.432406 -323.389253) (xy 346.386394 -323.430011)
			(xy 346.335804 -323.464925) (xy 346.281374 -323.493487) (xy 346.223898 -323.51528) (xy 346.164215 -323.529986)
			(xy 346.103194 -323.537391) (xy 346.07246 -323.537834) (xy 346.041764 -323.537356) (xy 345.980819 -323.529954)
			(xy 345.921211 -323.515262) (xy 345.863807 -323.493496) (xy 345.809444 -323.464971) (xy 345.783916 -323.447918)
			(xy 345.775164 -323.442447) (xy 345.75496 -323.438319) (xy 345.734756 -323.442447) (xy 345.726004 -323.447918)
			(xy 345.700457 -323.46494) (xy 345.646093 -323.493453) (xy 345.588693 -323.51522) (xy 345.529091 -323.529924)
			(xy 345.468154 -323.537352) (xy 345.43746 -323.537834) (xy 345.406764 -323.537356) (xy 345.345819 -323.529954)
			(xy 345.286211 -323.515262) (xy 345.228807 -323.493496) (xy 345.174444 -323.464971) (xy 345.148916 -323.447918)
			(xy 345.140164 -323.442447) (xy 345.11996 -323.438319) (xy 345.099756 -323.442447) (xy 345.091004 -323.447918)
			(xy 345.065457 -323.46494) (xy 345.011093 -323.493453) (xy 344.953693 -323.51522) (xy 344.894091 -323.529924)
			(xy 344.833154 -323.537352) (xy 344.80246 -323.537834) (xy 344.771729 -323.537382) (xy 344.710716 -323.529969)
			(xy 344.651041 -323.515257) (xy 344.593574 -323.49346) (xy 344.539154 -323.464895) (xy 344.488573 -323.429979)
			(xy 344.442569 -323.389222) (xy 344.401812 -323.343216) (xy 344.366898 -323.292634) (xy 344.338335 -323.238213)
			(xy 344.316539 -323.180746) (xy 344.301828 -323.12107) (xy 344.294417 -323.060057) (xy 344.293952 -323.029326)
			(xy 342.567768 -323.029326) (xy 342.567387 -323.06006) (xy 342.559974 -323.12108) (xy 342.545261 -323.180762)
			(xy 342.52346 -323.238234) (xy 342.494891 -323.29266) (xy 342.45997 -323.343246) (xy 342.419206 -323.389253)
			(xy 342.373194 -323.430011) (xy 342.322604 -323.464925) (xy 342.268174 -323.493487) (xy 342.210698 -323.51528)
			(xy 342.151015 -323.529986) (xy 342.089994 -323.537391) (xy 342.05926 -323.537834) (xy 342.028564 -323.537356)
			(xy 341.967619 -323.529954) (xy 341.908011 -323.515262) (xy 341.850607 -323.493496) (xy 341.796244 -323.464971)
			(xy 341.770716 -323.447918) (xy 341.761964 -323.442447) (xy 341.74176 -323.438319) (xy 341.721556 -323.442447)
			(xy 341.712804 -323.447918) (xy 341.687257 -323.46494) (xy 341.632893 -323.493453) (xy 341.575493 -323.51522)
			(xy 341.515891 -323.529924) (xy 341.454954 -323.537352) (xy 341.42426 -323.537834) (xy 341.393564 -323.537356)
			(xy 341.332619 -323.529954) (xy 341.273011 -323.515262) (xy 341.215607 -323.493496) (xy 341.161244 -323.464971)
			(xy 341.135716 -323.447918) (xy 341.126964 -323.442447) (xy 341.10676 -323.438319) (xy 341.086556 -323.442447)
			(xy 341.077804 -323.447918) (xy 341.052257 -323.46494) (xy 340.997893 -323.493453) (xy 340.940493 -323.51522)
			(xy 340.880891 -323.529924) (xy 340.819954 -323.537352) (xy 340.78926 -323.537834) (xy 340.758529 -323.537382)
			(xy 340.697516 -323.529969) (xy 340.637841 -323.515257) (xy 340.580374 -323.49346) (xy 340.525954 -323.464895)
			(xy 340.475373 -323.429979) (xy 340.429369 -323.389222) (xy 340.388612 -323.343216) (xy 340.353698 -323.292634)
			(xy 340.325135 -323.238213) (xy 340.303339 -323.180746) (xy 340.288628 -323.12107) (xy 340.281217 -323.060057)
			(xy 340.280752 -323.029326) (xy 340.281198 -322.998629) (xy 340.288605 -322.937683) (xy 340.303303 -322.878073)
			(xy 340.325078 -322.82067) (xy 340.353611 -322.766308) (xy 340.370668 -322.740782) (xy 340.376121 -322.732019)
			(xy 340.380259 -322.711822) (xy 340.376138 -322.691621) (xy 340.370668 -322.68287) (xy 340.35363 -322.657334)
			(xy 340.32512 -322.602966) (xy 340.303356 -322.545563) (xy 340.288656 -322.48596) (xy 340.281232 -322.425021)
			(xy 340.280752 -322.394326) (xy 340.281198 -322.363629) (xy 340.288605 -322.302683) (xy 340.303303 -322.243073)
			(xy 340.325078 -322.18567) (xy 340.353611 -322.131308) (xy 340.370668 -322.105782) (xy 340.376121 -322.097019)
			(xy 340.380259 -322.076822) (xy 340.376138 -322.056621) (xy 340.370668 -322.04787) (xy 340.35363 -322.022334)
			(xy 340.32512 -321.967966) (xy 340.303356 -321.910563) (xy 340.288656 -321.85096) (xy 340.281232 -321.790021)
			(xy 340.280752 -321.759326) (xy 340.281198 -321.728629) (xy 340.288605 -321.667683) (xy 340.303303 -321.608073)
			(xy 340.325078 -321.55067) (xy 340.353611 -321.496308) (xy 340.370668 -321.470782) (xy 340.376121 -321.462019)
			(xy 340.380259 -321.441822) (xy 340.376138 -321.421621) (xy 340.370668 -321.41287) (xy 340.35363 -321.387334)
			(xy 340.32512 -321.332966) (xy 340.303356 -321.275563) (xy 340.288656 -321.21596) (xy 340.281232 -321.155021)
			(xy 340.280752 -321.124326) (xy 340.281198 -321.093629) (xy 340.288605 -321.032683) (xy 340.303303 -320.973073)
			(xy 340.325078 -320.91567) (xy 340.353611 -320.861308) (xy 340.370668 -320.835782) (xy 340.376121 -320.827019)
			(xy 340.380259 -320.806822) (xy 340.376138 -320.786621) (xy 340.370668 -320.77787) (xy 340.35363 -320.752334)
			(xy 340.32512 -320.697966) (xy 340.303356 -320.640563) (xy 340.288656 -320.58096) (xy 340.281232 -320.520021)
			(xy 340.280752 -320.489326) (xy 340.281194 -320.459131) (xy 340.288318 -320.399163) (xy 340.302493 -320.34046)
			(xy 340.32352 -320.283849) (xy 340.351103 -320.230126) (xy 340.36762 -320.204846) (xy 340.373212 -320.195649)
			(xy 340.37692 -320.17447) (xy 340.371632 -320.153629) (xy 340.365334 -320.144902) (xy 340.344594 -320.117824)
			(xy 340.309772 -320.059173) (xy 340.283092 -319.996399) (xy 340.265029 -319.930626) (xy 340.255907 -319.86303)
			(xy 340.255352 -319.828926) (xy 338.326765 -319.828926) (xy 338.326519 -319.845145) (xy 338.319115 -319.90609)
			(xy 338.304421 -319.965699) (xy 338.282651 -320.023103) (xy 338.254123 -320.077465) (xy 338.237068 -320.102992)
			(xy 338.231557 -320.111723) (xy 338.227445 -320.13194) (xy 338.231589 -320.152151) (xy 338.237068 -320.160904)
			(xy 338.254099 -320.186445) (xy 338.28261 -320.240811) (xy 338.304374 -320.298213) (xy 338.319076 -320.357816)
			(xy 338.326502 -320.418754) (xy 338.326984 -320.449448) (xy 338.326519 -320.480145) (xy 338.319115 -320.54109)
			(xy 338.304421 -320.600699) (xy 338.282651 -320.658103) (xy 338.254123 -320.712465) (xy 338.237068 -320.737992)
			(xy 338.231557 -320.746723) (xy 338.227445 -320.76694) (xy 338.231589 -320.787151) (xy 338.237068 -320.795904)
			(xy 338.254099 -320.821445) (xy 338.28261 -320.875811) (xy 338.304374 -320.933213) (xy 338.319076 -320.992816)
			(xy 338.326502 -321.053754) (xy 338.326984 -321.084448) (xy 338.326519 -321.115145) (xy 338.319115 -321.17609)
			(xy 338.304421 -321.235699) (xy 338.282651 -321.293103) (xy 338.254123 -321.347465) (xy 338.237068 -321.372992)
			(xy 338.231557 -321.381723) (xy 338.227445 -321.40194) (xy 338.231589 -321.422151) (xy 338.237068 -321.430904)
			(xy 338.254099 -321.456445) (xy 338.28261 -321.510811) (xy 338.304374 -321.568213) (xy 338.319076 -321.627816)
			(xy 338.326502 -321.688754) (xy 338.326984 -321.719448) (xy 338.326519 -321.750145) (xy 338.319115 -321.81109)
			(xy 338.304421 -321.870699) (xy 338.282651 -321.928103) (xy 338.254123 -321.982465) (xy 338.237068 -322.007992)
			(xy 338.231557 -322.016723) (xy 338.227445 -322.03694) (xy 338.231589 -322.057151) (xy 338.237068 -322.065904)
			(xy 338.254099 -322.091445) (xy 338.28261 -322.145811) (xy 338.304374 -322.203213) (xy 338.319076 -322.262816)
			(xy 338.326502 -322.323754) (xy 338.326984 -322.354448) (xy 338.326479 -322.386043) (xy 338.318662 -322.448746)
			(xy 338.303129 -322.509996) (xy 338.28012 -322.568847) (xy 338.24999 -322.62439) (xy 338.231988 -322.650358)
			(xy 338.226295 -322.65922) (xy 338.221995 -322.679818) (xy 338.226309 -322.700414) (xy 338.231988 -322.709286)
			(xy 338.249789 -322.735198) (xy 338.2796 -322.790548) (xy 338.302367 -322.849147) (xy 338.317744 -322.910105)
			(xy 338.325496 -322.972492) (xy 338.325968 -323.003926) (xy 338.325587 -323.03466) (xy 338.318174 -323.09568)
			(xy 338.303461 -323.155362) (xy 338.28166 -323.212834) (xy 338.253091 -323.26726) (xy 338.21817 -323.317846)
			(xy 338.177406 -323.363853) (xy 338.131394 -323.404611) (xy 338.080804 -323.439525) (xy 338.026374 -323.468087)
			(xy 337.968898 -323.48988) (xy 337.909215 -323.504586) (xy 337.848194 -323.511991) (xy 337.81746 -323.512434)
			(xy 337.786764 -323.511956) (xy 337.725819 -323.504554) (xy 337.666211 -323.489862) (xy 337.608807 -323.468096)
			(xy 337.554444 -323.439571) (xy 337.528916 -323.422518) (xy 337.520164 -323.417047) (xy 337.49996 -323.412919)
			(xy 337.479756 -323.417047) (xy 337.471004 -323.422518) (xy 337.445457 -323.43954) (xy 337.391093 -323.468053)
			(xy 337.333693 -323.48982) (xy 337.274091 -323.504524) (xy 337.213154 -323.511952) (xy 337.18246 -323.512434)
			(xy 337.151764 -323.511956) (xy 337.090819 -323.504554) (xy 337.031211 -323.489862) (xy 336.973807 -323.468096)
			(xy 336.919444 -323.439571) (xy 336.893916 -323.422518) (xy 336.885164 -323.417047) (xy 336.86496 -323.412919)
			(xy 336.844756 -323.417047) (xy 336.836004 -323.422518) (xy 336.810457 -323.43954) (xy 336.756093 -323.468053)
			(xy 336.698693 -323.48982) (xy 336.639091 -323.504524) (xy 336.578154 -323.511952) (xy 336.54746 -323.512434)
			(xy 336.516729 -323.511982) (xy 336.455716 -323.504569) (xy 336.396041 -323.489857) (xy 336.338574 -323.46806)
			(xy 336.284154 -323.439495) (xy 336.233573 -323.404579) (xy 336.187569 -323.363822) (xy 336.146812 -323.317816)
			(xy 336.111898 -323.267234) (xy 336.083335 -323.212813) (xy 336.061539 -323.155346) (xy 336.046828 -323.09567)
			(xy 336.039417 -323.034657) (xy 336.038952 -323.003926) (xy 334.287368 -323.003926) (xy 334.286987 -323.03466)
			(xy 334.279574 -323.09568) (xy 334.264861 -323.155362) (xy 334.24306 -323.212834) (xy 334.214491 -323.26726)
			(xy 334.17957 -323.317846) (xy 334.138806 -323.363853) (xy 334.092794 -323.404611) (xy 334.042204 -323.439525)
			(xy 333.987774 -323.468087) (xy 333.930298 -323.48988) (xy 333.870615 -323.504586) (xy 333.809594 -323.511991)
			(xy 333.77886 -323.512434) (xy 333.748164 -323.511956) (xy 333.687219 -323.504554) (xy 333.627611 -323.489862)
			(xy 333.570207 -323.468096) (xy 333.515844 -323.439571) (xy 333.490316 -323.422518) (xy 333.481564 -323.417047)
			(xy 333.46136 -323.412919) (xy 333.441156 -323.417047) (xy 333.432404 -323.422518) (xy 333.406857 -323.43954)
			(xy 333.352493 -323.468053) (xy 333.295093 -323.48982) (xy 333.235491 -323.504524) (xy 333.174554 -323.511952)
			(xy 333.14386 -323.512434) (xy 333.113164 -323.511956) (xy 333.052219 -323.504554) (xy 332.992611 -323.489862)
			(xy 332.935207 -323.468096) (xy 332.880844 -323.439571) (xy 332.855316 -323.422518) (xy 332.846564 -323.417047)
			(xy 332.82636 -323.412919) (xy 332.806156 -323.417047) (xy 332.797404 -323.422518) (xy 332.771857 -323.43954)
			(xy 332.717493 -323.468053) (xy 332.660093 -323.48982) (xy 332.600491 -323.504524) (xy 332.539554 -323.511952)
			(xy 332.50886 -323.512434) (xy 332.478129 -323.511982) (xy 332.417116 -323.504569) (xy 332.357441 -323.489857)
			(xy 332.299974 -323.46806) (xy 332.245554 -323.439495) (xy 332.194973 -323.404579) (xy 332.148969 -323.363822)
			(xy 332.108212 -323.317816) (xy 332.073298 -323.267234) (xy 332.044735 -323.212813) (xy 332.022939 -323.155346)
			(xy 332.008228 -323.09567) (xy 332.000817 -323.034657) (xy 332.000352 -323.003926) (xy 329.947524 -323.003926)
			(xy 329.947068 -323.034657) (xy 329.939657 -323.09567) (xy 329.924946 -323.155346) (xy 329.90315 -323.212813)
			(xy 329.874585 -323.267234) (xy 329.83967 -323.317815) (xy 329.798913 -323.36382) (xy 329.752908 -323.404576)
			(xy 329.702325 -323.439491) (xy 329.647904 -323.468054) (xy 329.590436 -323.489849) (xy 329.530761 -323.504559)
			(xy 329.469747 -323.511969) (xy 329.439016 -323.512434) (xy 329.408319 -323.511978) (xy 329.347374 -323.504571)
			(xy 329.287765 -323.489874) (xy 329.230361 -323.468103) (xy 329.175999 -323.439573) (xy 329.150472 -323.422518)
			(xy 329.14172 -323.417047) (xy 329.121516 -323.412919) (xy 329.101312 -323.417047) (xy 329.09256 -323.422518)
			(xy 329.067025 -323.439559) (xy 329.012657 -323.468069) (xy 328.955254 -323.489832) (xy 328.89565 -323.504532)
			(xy 328.834711 -323.511954) (xy 328.804016 -323.512434) (xy 328.773319 -323.511978) (xy 328.712374 -323.504571)
			(xy 328.652765 -323.489874) (xy 328.595361 -323.468103) (xy 328.540999 -323.439573) (xy 328.515472 -323.422518)
			(xy 328.50672 -323.417047) (xy 328.486516 -323.412919) (xy 328.466312 -323.417047) (xy 328.45756 -323.422518)
			(xy 328.432025 -323.439559) (xy 328.377657 -323.468069) (xy 328.320254 -323.489832) (xy 328.26065 -323.504532)
			(xy 328.199711 -323.511954) (xy 328.169016 -323.512434) (xy 328.138286 -323.511929) (xy 328.077275 -323.504523)
			(xy 328.017601 -323.489817) (xy 327.960135 -323.468025) (xy 327.905714 -323.439466) (xy 327.855133 -323.404555)
			(xy 327.809128 -323.363801) (xy 327.768371 -323.3178) (xy 327.733456 -323.267222) (xy 327.704892 -323.212804)
			(xy 327.683096 -323.155339) (xy 327.668385 -323.095666) (xy 327.660974 -323.034656) (xy 327.660508 -323.003926)
			(xy 325.934324 -323.003926) (xy 325.933868 -323.034657) (xy 325.926457 -323.09567) (xy 325.911746 -323.155346)
			(xy 325.88995 -323.212813) (xy 325.861385 -323.267234) (xy 325.82647 -323.317815) (xy 325.785713 -323.36382)
			(xy 325.739708 -323.404576) (xy 325.689125 -323.439491) (xy 325.634704 -323.468054) (xy 325.577236 -323.489849)
			(xy 325.517561 -323.504559) (xy 325.456547 -323.511969) (xy 325.425816 -323.512434) (xy 325.395119 -323.511978)
			(xy 325.334174 -323.504571) (xy 325.274565 -323.489874) (xy 325.217161 -323.468103) (xy 325.162799 -323.439573)
			(xy 325.137272 -323.422518) (xy 325.12852 -323.417047) (xy 325.108316 -323.412919) (xy 325.088112 -323.417047)
			(xy 325.07936 -323.422518) (xy 325.053825 -323.439559) (xy 324.999457 -323.468069) (xy 324.942054 -323.489832)
			(xy 324.88245 -323.504532) (xy 324.821511 -323.511954) (xy 324.790816 -323.512434) (xy 324.760119 -323.511978)
			(xy 324.699174 -323.504571) (xy 324.639565 -323.489874) (xy 324.582161 -323.468103) (xy 324.527799 -323.439573)
			(xy 324.502272 -323.422518) (xy 324.49352 -323.417047) (xy 324.473316 -323.412919) (xy 324.453112 -323.417047)
			(xy 324.44436 -323.422518) (xy 324.418825 -323.439559) (xy 324.364457 -323.468069) (xy 324.307054 -323.489832)
			(xy 324.24745 -323.504532) (xy 324.186511 -323.511954) (xy 324.155816 -323.512434) (xy 324.125086 -323.511929)
			(xy 324.064075 -323.504523) (xy 324.004401 -323.489817) (xy 323.946935 -323.468025) (xy 323.892514 -323.439466)
			(xy 323.841933 -323.404555) (xy 323.795928 -323.363801) (xy 323.755171 -323.3178) (xy 323.720256 -323.267222)
			(xy 323.691692 -323.212804) (xy 323.669896 -323.155339) (xy 323.655185 -323.095666) (xy 323.647774 -323.034656)
			(xy 323.647308 -323.003926) (xy 323.647806 -322.972702) (xy 323.655477 -322.910727) (xy 323.670681 -322.850158)
			(xy 323.693189 -322.791908) (xy 323.722663 -322.736853) (xy 323.740272 -322.711064) (xy 323.745894 -322.702099)
			(xy 323.750073 -322.681382) (xy 323.745557 -322.660735) (xy 323.739764 -322.651882) (xy 323.721566 -322.625824)
			(xy 323.691118 -322.570032) (xy 323.667859 -322.510881) (xy 323.652151 -322.449293) (xy 323.644239 -322.386228)
			(xy 323.643752 -322.354448) (xy 321.613445 -322.354448) (xy 321.613784 -322.376038) (xy 321.613249 -322.409274)
			(xy 321.604624 -322.475184) (xy 321.587473 -322.539405) (xy 321.562091 -322.60084) (xy 321.528911 -322.658438)
			(xy 321.509136 -322.685156) (xy 321.503204 -322.69386) (xy 321.498181 -322.714286) (xy 321.501752 -322.735015)
			(xy 321.507104 -322.744084) (xy 321.523256 -322.769166) (xy 321.550209 -322.822389) (xy 321.570745 -322.878402)
			(xy 321.584582 -322.936434) (xy 321.59153 -322.995686) (xy 321.59194 -323.025516) (xy 321.591459 -323.056246)
			(xy 321.584049 -323.117258) (xy 321.56934 -323.176932) (xy 321.547545 -323.234398) (xy 321.518983 -323.288818)
			(xy 321.48407 -323.339399) (xy 321.443315 -323.385404) (xy 321.397312 -323.42616) (xy 321.346732 -323.461075)
			(xy 321.292313 -323.489639) (xy 321.234847 -323.511435) (xy 321.175174 -323.526146) (xy 321.114162 -323.533558)
			(xy 321.083432 -323.534024) (xy 321.052735 -323.533562) (xy 320.99179 -323.526156) (xy 320.932182 -323.511461)
			(xy 320.874778 -323.489691) (xy 320.820415 -323.461163) (xy 320.794888 -323.444108) (xy 320.786136 -323.438637)
			(xy 320.765932 -323.434509) (xy 320.745728 -323.438637) (xy 320.736976 -323.444108) (xy 320.711444 -323.461153)
			(xy 320.657074 -323.48966) (xy 320.599671 -323.511421) (xy 320.540066 -323.52612) (xy 320.479127 -323.533544)
			(xy 320.448432 -323.534024) (xy 320.417735 -323.533562) (xy 320.35679 -323.526156) (xy 320.297182 -323.511461)
			(xy 320.239778 -323.489691) (xy 320.185415 -323.461163) (xy 320.159888 -323.444108) (xy 320.151136 -323.438637)
			(xy 320.130932 -323.434509) (xy 320.110728 -323.438637) (xy 320.101976 -323.444108) (xy 320.076444 -323.461153)
			(xy 320.022074 -323.48966) (xy 319.964671 -323.511421) (xy 319.905066 -323.52612) (xy 319.844127 -323.533544)
			(xy 319.813432 -323.534024) (xy 319.782701 -323.533532) (xy 319.721687 -323.526128) (xy 319.662011 -323.511422)
			(xy 319.604542 -323.489631) (xy 319.550119 -323.461071) (xy 319.499535 -323.42616) (xy 319.453529 -323.385405)
			(xy 319.41277 -323.339403) (xy 319.377854 -323.288822) (xy 319.349289 -323.234402) (xy 319.327492 -323.176935)
			(xy 319.312781 -323.11726) (xy 319.305371 -323.056247) (xy 319.304924 -323.025516) (xy 317.57874 -323.025516)
			(xy 317.578259 -323.056246) (xy 317.570849 -323.117258) (xy 317.55614 -323.176932) (xy 317.534345 -323.234398)
			(xy 317.505783 -323.288818) (xy 317.47087 -323.339399) (xy 317.430115 -323.385404) (xy 317.384112 -323.42616)
			(xy 317.333532 -323.461075) (xy 317.279113 -323.489639) (xy 317.221647 -323.511435) (xy 317.161974 -323.526146)
			(xy 317.100962 -323.533558) (xy 317.070232 -323.534024) (xy 317.039535 -323.533562) (xy 316.97859 -323.526156)
			(xy 316.918982 -323.511461) (xy 316.861578 -323.489691) (xy 316.807215 -323.461163) (xy 316.781688 -323.444108)
			(xy 316.772936 -323.438637) (xy 316.752732 -323.434509) (xy 316.732528 -323.438637) (xy 316.723776 -323.444108)
			(xy 316.698244 -323.461153) (xy 316.643874 -323.48966) (xy 316.586471 -323.511421) (xy 316.526866 -323.52612)
			(xy 316.465927 -323.533544) (xy 316.435232 -323.534024) (xy 316.404535 -323.533562) (xy 316.34359 -323.526156)
			(xy 316.283982 -323.511461) (xy 316.226578 -323.489691) (xy 316.172215 -323.461163) (xy 316.146688 -323.444108)
			(xy 316.137936 -323.438637) (xy 316.117732 -323.434509) (xy 316.097528 -323.438637) (xy 316.088776 -323.444108)
			(xy 316.063244 -323.461153) (xy 316.008874 -323.48966) (xy 315.951471 -323.511421) (xy 315.891866 -323.52612)
			(xy 315.830927 -323.533544) (xy 315.800232 -323.534024) (xy 315.769501 -323.533532) (xy 315.708487 -323.526128)
			(xy 315.648811 -323.511422) (xy 315.591342 -323.489631) (xy 315.536919 -323.461071) (xy 315.486335 -323.42616)
			(xy 315.440329 -323.385405) (xy 315.39957 -323.339403) (xy 315.364654 -323.288822) (xy 315.336089 -323.234402)
			(xy 315.314292 -323.176935) (xy 315.299581 -323.11726) (xy 315.292171 -323.056247) (xy 315.291724 -323.025516)
			(xy 315.292214 -322.994292) (xy 315.299886 -322.932317) (xy 315.315092 -322.871748) (xy 315.337602 -322.813497)
			(xy 315.367078 -322.758443) (xy 315.384688 -322.732654) (xy 315.390317 -322.723693) (xy 315.394491 -322.702974)
			(xy 315.389974 -322.682326) (xy 315.38418 -322.673472) (xy 315.36598 -322.647416) (xy 315.335532 -322.591623)
			(xy 315.312273 -322.532472) (xy 315.296566 -322.470884) (xy 315.288654 -322.407818) (xy 315.288168 -322.376038)
			(xy 254.06858 -322.376038) (xy 254.06858 -323.022722) (xy 256.385058 -323.022722) (xy 256.389129 -322.9671)
			(xy 256.401255 -322.912663) (xy 256.421178 -322.860572) (xy 256.448474 -322.811937) (xy 256.48256 -322.767794)
			(xy 256.522709 -322.729085) (xy 256.568067 -322.696634) (xy 256.617667 -322.671133) (xy 256.670451 -322.653126)
			(xy 256.725294 -322.642996) (xy 256.781028 -322.640959) (xy 256.836465 -322.647059) (xy 256.890422 -322.661165)
			(xy 256.941751 -322.682977) (xy 256.989357 -322.712031) (xy 257.032225 -322.747706) (xy 257.069442 -322.789243)
			(xy 257.100215 -322.835756) (xy 257.123887 -322.886253) (xy 257.139955 -322.93966) (xy 257.148075 -322.994836)
			(xy 257.148584 -323.022722) (xy 257.148075 -323.050608) (xy 257.139955 -323.105784) (xy 257.123887 -323.159191)
			(xy 257.100215 -323.209688) (xy 257.069442 -323.256201) (xy 257.032225 -323.297738) (xy 256.989357 -323.333413)
			(xy 256.941751 -323.362467) (xy 256.890422 -323.384279) (xy 256.836465 -323.398385) (xy 256.781028 -323.404485)
			(xy 256.725294 -323.402448) (xy 256.670451 -323.392318) (xy 256.617667 -323.374311) (xy 256.568067 -323.34881)
			(xy 256.522709 -323.316359) (xy 256.48256 -323.27765) (xy 256.448474 -323.233507) (xy 256.421178 -323.184872)
			(xy 256.401255 -323.132781) (xy 256.389129 -323.078344) (xy 256.385058 -323.022722) (xy 254.06858 -323.022722)
			(xy 254.06858 -324.045072) (xy 256.377692 -324.045072) (xy 256.381763 -323.98945) (xy 256.393889 -323.935013)
			(xy 256.413812 -323.882922) (xy 256.441108 -323.834287) (xy 256.475194 -323.790144) (xy 256.515343 -323.751435)
			(xy 256.560701 -323.718984) (xy 256.610301 -323.693483) (xy 256.663085 -323.675476) (xy 256.717928 -323.665346)
			(xy 256.773662 -323.663309) (xy 256.829099 -323.669409) (xy 256.883056 -323.683515) (xy 256.934385 -323.705327)
			(xy 256.981991 -323.734381) (xy 257.024859 -323.770056) (xy 257.062076 -323.811593) (xy 257.092849 -323.858106)
			(xy 257.116521 -323.908603) (xy 257.132589 -323.96201) (xy 257.140709 -324.017186) (xy 257.141218 -324.045072)
			(xy 257.140709 -324.072958) (xy 257.132589 -324.128134) (xy 257.116521 -324.181541) (xy 257.092849 -324.232038)
			(xy 257.062076 -324.278551) (xy 257.024859 -324.320088) (xy 256.981991 -324.355763) (xy 256.934385 -324.384817)
			(xy 256.883056 -324.406629) (xy 256.829099 -324.420735) (xy 256.773662 -324.426835) (xy 256.717928 -324.424798)
			(xy 256.663085 -324.414668) (xy 256.610301 -324.396661) (xy 256.560701 -324.37116) (xy 256.515343 -324.338709)
			(xy 256.475194 -324.3) (xy 256.441108 -324.255857) (xy 256.413812 -324.207222) (xy 256.393889 -324.155131)
			(xy 256.381763 -324.100694) (xy 256.377692 -324.045072) (xy 254.06858 -324.045072) (xy 254.06858 -324.535)
			(xy 265.73047 -324.535) (xy 265.734461 -324.446135) (xy 265.746402 -324.357986) (xy 265.766197 -324.271262)
			(xy 265.793686 -324.186662) (xy 265.828648 -324.104867) (xy 265.870802 -324.026535) (xy 265.919808 -323.952297)
			(xy 265.975271 -323.88275) (xy 266.036745 -323.818456) (xy 266.103736 -323.759931) (xy 266.175702 -323.707647)
			(xy 266.252066 -323.662025) (xy 266.332213 -323.623432) (xy 266.415496 -323.592178) (xy 266.501245 -323.568516)
			(xy 266.58877 -323.552636) (xy 266.677367 -323.544666) (xy 266.721844 -323.544184) (xy 268.474444 -323.544184)
			(xy 268.518921 -323.544609) (xy 268.607518 -323.552586) (xy 268.695042 -323.568473) (xy 268.78079 -323.592142)
			(xy 268.864072 -323.623401) (xy 268.944216 -323.661999) (xy 269.020578 -323.707626) (xy 269.092542 -323.759915)
			(xy 269.15953 -323.818443) (xy 269.221002 -323.88274) (xy 269.276463 -323.952289) (xy 269.325467 -324.026529)
			(xy 269.367618 -324.104863) (xy 269.402579 -324.186659) (xy 269.430067 -324.271261) (xy 269.44986 -324.357985)
			(xy 269.461801 -324.446135) (xy 269.465792 -324.535) (xy 273.274584 -324.535) (xy 273.278575 -324.446139)
			(xy 273.290515 -324.357994) (xy 273.310309 -324.271274) (xy 273.337796 -324.186677) (xy 273.372755 -324.104885)
			(xy 273.414906 -324.026556) (xy 273.463908 -323.95232) (xy 273.519368 -323.882776) (xy 273.580838 -323.818483)
			(xy 273.647824 -323.759959) (xy 273.719786 -323.707675) (xy 273.796145 -323.662053) (xy 273.876287 -323.623458)
			(xy 273.959565 -323.592203) (xy 274.04531 -323.568539) (xy 274.132831 -323.552656) (xy 274.221423 -323.544683)
			(xy 274.265898 -323.544184) (xy 276.018498 -323.544184) (xy 276.062977 -323.544592) (xy 276.151578 -323.552566)
			(xy 276.239107 -323.56845) (xy 276.32486 -323.592116) (xy 276.408146 -323.623374) (xy 276.488295 -323.661972)
			(xy 276.564662 -323.707598) (xy 276.636631 -323.759887) (xy 276.703623 -323.818416) (xy 276.765099 -323.882715)
			(xy 276.820564 -323.952266) (xy 276.869571 -324.026508) (xy 276.911726 -324.104845) (xy 276.946689 -324.186644)
			(xy 276.974178 -324.271249) (xy 276.993974 -324.357977) (xy 277.005915 -324.446131) (xy 277.009906 -324.535)
			(xy 280.818384 -324.535) (xy 280.822375 -324.446139) (xy 280.834315 -324.357994) (xy 280.854109 -324.271274)
			(xy 280.881596 -324.186677) (xy 280.916555 -324.104885) (xy 280.958706 -324.026556) (xy 281.007708 -323.95232)
			(xy 281.063168 -323.882776) (xy 281.124638 -323.818483) (xy 281.191624 -323.759959) (xy 281.263586 -323.707675)
			(xy 281.339945 -323.662053) (xy 281.420087 -323.623458) (xy 281.503365 -323.592203) (xy 281.58911 -323.568539)
			(xy 281.676631 -323.552656) (xy 281.765223 -323.544683) (xy 281.809698 -323.544184) (xy 283.562298 -323.544184)
			(xy 283.606777 -323.544592) (xy 283.695378 -323.552566) (xy 283.782907 -323.56845) (xy 283.86866 -323.592116)
			(xy 283.951946 -323.623374) (xy 284.032095 -323.661972) (xy 284.108462 -323.707598) (xy 284.180431 -323.759887)
			(xy 284.247423 -323.818416) (xy 284.308899 -323.882715) (xy 284.364364 -323.952266) (xy 284.413371 -324.026508)
			(xy 284.455526 -324.104845) (xy 284.490489 -324.186644) (xy 284.517978 -324.271249) (xy 284.537774 -324.357977)
			(xy 284.549715 -324.446131) (xy 284.553706 -324.535) (xy 288.362484 -324.535) (xy 288.366475 -324.446142)
			(xy 288.378414 -324.357999) (xy 288.398206 -324.271281) (xy 288.425692 -324.186687) (xy 288.46065 -324.104897)
			(xy 288.502798 -324.026569) (xy 288.551798 -323.952335) (xy 288.607254 -323.882792) (xy 288.668721 -323.818499)
			(xy 288.735703 -323.759975) (xy 288.807662 -323.707691) (xy 288.884018 -323.662068) (xy 288.964155 -323.623472)
			(xy 289.04743 -323.592215) (xy 289.133171 -323.568548) (xy 289.220689 -323.552662) (xy 289.309278 -323.544685)
			(xy 289.353752 -323.544184) (xy 291.106352 -323.544184) (xy 291.150833 -323.54459) (xy 291.239436 -323.552561)
			(xy 291.326968 -323.568441) (xy 291.412725 -323.592105) (xy 291.496015 -323.623361) (xy 291.576167 -323.661957)
			(xy 291.652537 -323.707582) (xy 291.72451 -323.75987) (xy 291.791506 -323.8184) (xy 291.852985 -323.882699)
			(xy 291.908453 -323.952251) (xy 291.957463 -324.026494) (xy 291.99962 -324.104833) (xy 292.034585 -324.186635)
			(xy 292.062076 -324.271242) (xy 292.081873 -324.357972) (xy 292.093815 -324.446128) (xy 292.097806 -324.535)
			(xy 295.90647 -324.535) (xy 295.910461 -324.446138) (xy 295.922401 -324.357991) (xy 295.942195 -324.271269)
			(xy 295.969683 -324.18667) (xy 296.004643 -324.104876) (xy 296.046795 -324.026546) (xy 296.095799 -323.952309)
			(xy 296.151259 -323.882764) (xy 296.212731 -323.81847) (xy 296.279719 -323.759945) (xy 296.351682 -323.70766)
			(xy 296.428043 -323.662037) (xy 296.508187 -323.623443) (xy 296.591467 -323.592188) (xy 296.677213 -323.568524)
			(xy 296.764736 -323.552641) (xy 296.85333 -323.544668) (xy 296.897806 -323.544184) (xy 298.650406 -323.544184)
			(xy 298.694884 -323.544607) (xy 298.783483 -323.552582) (xy 298.87101 -323.568466) (xy 298.956761 -323.592132)
			(xy 299.040046 -323.62339) (xy 299.120193 -323.661987) (xy 299.196558 -323.707613) (xy 299.268525 -323.759901)
			(xy 299.335516 -323.818429) (xy 299.39699 -323.882727) (xy 299.452454 -323.952277) (xy 299.50146 -324.026518)
			(xy 299.543614 -324.104853) (xy 299.578576 -324.186651) (xy 299.606065 -324.271254) (xy 299.62586 -324.357981)
			(xy 299.6378 -324.446133) (xy 299.641792 -324.535) (xy 303.450584 -324.535) (xy 303.454575 -324.446141)
			(xy 303.466515 -324.357998) (xy 303.486307 -324.27128) (xy 303.513793 -324.186685) (xy 303.548751 -324.104895)
			(xy 303.590899 -324.026567) (xy 303.6399 -323.952332) (xy 303.695357 -323.882789) (xy 303.756824 -323.818496)
			(xy 303.823807 -323.759973) (xy 303.895766 -323.707688) (xy 303.972122 -323.662065) (xy 304.052261 -323.62347)
			(xy 304.135536 -323.592213) (xy 304.221278 -323.568546) (xy 304.308796 -323.552661) (xy 304.397386 -323.544684)
			(xy 304.44186 -323.544184) (xy 306.19446 -323.544184) (xy 306.23894 -323.544591) (xy 306.327543 -323.552562)
			(xy 306.415075 -323.568443) (xy 306.500831 -323.592107) (xy 306.58412 -323.623363) (xy 306.664272 -323.661959)
			(xy 306.740642 -323.707585) (xy 306.812614 -323.759873) (xy 306.879609 -323.818403) (xy 306.941088 -323.882702)
			(xy 306.996555 -323.952253) (xy 307.045564 -324.026497) (xy 307.087721 -324.104835) (xy 307.122686 -324.186636)
			(xy 307.150177 -324.271243) (xy 307.169973 -324.357973) (xy 307.181915 -324.446129) (xy 307.185906 -324.535)
			(xy 307.181915 -324.623871) (xy 307.169973 -324.712027) (xy 307.150177 -324.798757) (xy 307.122686 -324.883364)
			(xy 307.087721 -324.965165) (xy 307.045564 -325.043503) (xy 306.996555 -325.117747) (xy 306.941088 -325.187298)
			(xy 306.879609 -325.251597) (xy 306.812614 -325.310127) (xy 306.740642 -325.362415) (xy 306.664272 -325.408041)
			(xy 306.58412 -325.446637) (xy 306.500831 -325.477893) (xy 306.415075 -325.501557) (xy 306.327543 -325.517438)
			(xy 306.23894 -325.525409) (xy 306.19446 -325.525892) (xy 304.44186 -325.525892) (xy 304.397386 -325.525316)
			(xy 304.308796 -325.517339) (xy 304.221278 -325.501454) (xy 304.135536 -325.477787) (xy 304.052261 -325.44653)
			(xy 303.972122 -325.407935) (xy 303.895766 -325.362312) (xy 303.823807 -325.310027) (xy 303.756824 -325.251504)
			(xy 303.695357 -325.187211) (xy 303.6399 -325.117668) (xy 303.590899 -325.043433) (xy 303.548751 -324.965105)
			(xy 303.513793 -324.883315) (xy 303.486307 -324.79872) (xy 303.466515 -324.712002) (xy 303.454575 -324.623859)
			(xy 303.450584 -324.535) (xy 299.641792 -324.535) (xy 299.6378 -324.623867) (xy 299.62586 -324.712019)
			(xy 299.606065 -324.798746) (xy 299.578576 -324.883349) (xy 299.543614 -324.965147) (xy 299.50146 -325.043482)
			(xy 299.452454 -325.117723) (xy 299.39699 -325.187273) (xy 299.335516 -325.251571) (xy 299.268525 -325.310099)
			(xy 299.196558 -325.362387) (xy 299.120193 -325.408013) (xy 299.040046 -325.44661) (xy 298.956761 -325.477868)
			(xy 298.87101 -325.501534) (xy 298.783483 -325.517418) (xy 298.694884 -325.525393) (xy 298.650406 -325.525892)
			(xy 296.897806 -325.525892) (xy 296.85333 -325.525332) (xy 296.764736 -325.517359) (xy 296.677213 -325.501476)
			(xy 296.591467 -325.477812) (xy 296.508187 -325.446557) (xy 296.428043 -325.407963) (xy 296.351682 -325.36234)
			(xy 296.279719 -325.310055) (xy 296.212731 -325.25153) (xy 296.151259 -325.187236) (xy 296.095799 -325.117691)
			(xy 296.046795 -325.043454) (xy 296.004643 -324.965124) (xy 295.969683 -324.88333) (xy 295.942195 -324.798731)
			(xy 295.922401 -324.712009) (xy 295.910461 -324.623862) (xy 295.90647 -324.535) (xy 292.097806 -324.535)
			(xy 292.093815 -324.623872) (xy 292.081873 -324.712028) (xy 292.062076 -324.798758) (xy 292.034585 -324.883365)
			(xy 291.99962 -324.965167) (xy 291.957463 -325.043506) (xy 291.908453 -325.117749) (xy 291.852985 -325.187301)
			(xy 291.791506 -325.2516) (xy 291.72451 -325.31013) (xy 291.652537 -325.362418) (xy 291.576167 -325.408043)
			(xy 291.496015 -325.446639) (xy 291.412725 -325.477895) (xy 291.326968 -325.501559) (xy 291.239436 -325.517439)
			(xy 291.150833 -325.52541) (xy 291.106352 -325.525892) (xy 289.353752 -325.525892) (xy 289.309278 -325.525315)
			(xy 289.220689 -325.517338) (xy 289.133171 -325.501452) (xy 289.04743 -325.477785) (xy 288.964155 -325.446528)
			(xy 288.884018 -325.407932) (xy 288.807662 -325.362309) (xy 288.735703 -325.310025) (xy 288.668721 -325.251501)
			(xy 288.607254 -325.187208) (xy 288.551798 -325.117665) (xy 288.502798 -325.043431) (xy 288.46065 -324.965103)
			(xy 288.425692 -324.883313) (xy 288.398206 -324.798719) (xy 288.378414 -324.712001) (xy 288.366475 -324.623858)
			(xy 288.362484 -324.535) (xy 284.553706 -324.535) (xy 284.549715 -324.623869) (xy 284.537774 -324.712023)
			(xy 284.517978 -324.798751) (xy 284.490489 -324.883356) (xy 284.455526 -324.965155) (xy 284.413371 -325.043492)
			(xy 284.364364 -325.117734) (xy 284.308899 -325.187285) (xy 284.247423 -325.251584) (xy 284.180431 -325.310113)
			(xy 284.108462 -325.362402) (xy 284.032095 -325.408028) (xy 283.951946 -325.446626) (xy 283.86866 -325.477884)
			(xy 283.782907 -325.50155) (xy 283.695378 -325.517434) (xy 283.606777 -325.525408) (xy 283.562298 -325.525892)
			(xy 281.809698 -325.525892) (xy 281.765223 -325.525317) (xy 281.676631 -325.517344) (xy 281.58911 -325.501461)
			(xy 281.503365 -325.477797) (xy 281.420087 -325.446542) (xy 281.339945 -325.407947) (xy 281.263586 -325.362325)
			(xy 281.191624 -325.310041) (xy 281.124638 -325.251517) (xy 281.063168 -325.187224) (xy 281.007708 -325.11768)
			(xy 280.958706 -325.043444) (xy 280.916555 -324.965115) (xy 280.881596 -324.883323) (xy 280.854109 -324.798726)
			(xy 280.834315 -324.712006) (xy 280.822375 -324.623861) (xy 280.818384 -324.535) (xy 277.009906 -324.535)
			(xy 277.005915 -324.623869) (xy 276.993974 -324.712023) (xy 276.974178 -324.798751) (xy 276.946689 -324.883356)
			(xy 276.911726 -324.965155) (xy 276.869571 -325.043492) (xy 276.820564 -325.117734) (xy 276.765099 -325.187285)
			(xy 276.703623 -325.251584) (xy 276.636631 -325.310113) (xy 276.564662 -325.362402) (xy 276.488295 -325.408028)
			(xy 276.408146 -325.446626) (xy 276.32486 -325.477884) (xy 276.239107 -325.50155) (xy 276.151578 -325.517434)
			(xy 276.062977 -325.525408) (xy 276.018498 -325.525892) (xy 274.265898 -325.525892) (xy 274.221423 -325.525317)
			(xy 274.132831 -325.517344) (xy 274.04531 -325.501461) (xy 273.959565 -325.477797) (xy 273.876287 -325.446542)
			(xy 273.796145 -325.407947) (xy 273.719786 -325.362325) (xy 273.647824 -325.310041) (xy 273.580838 -325.251517)
			(xy 273.519368 -325.187224) (xy 273.463908 -325.11768) (xy 273.414906 -325.043444) (xy 273.372755 -324.965115)
			(xy 273.337796 -324.883323) (xy 273.310309 -324.798726) (xy 273.290515 -324.712006) (xy 273.278575 -324.623861)
			(xy 273.274584 -324.535) (xy 269.465792 -324.535) (xy 269.461801 -324.623865) (xy 269.44986 -324.712015)
			(xy 269.430067 -324.798739) (xy 269.402579 -324.883341) (xy 269.367618 -324.965137) (xy 269.325467 -325.043471)
			(xy 269.276463 -325.117711) (xy 269.221002 -325.18726) (xy 269.15953 -325.251557) (xy 269.092542 -325.310085)
			(xy 269.020578 -325.362374) (xy 268.944216 -325.408001) (xy 268.864072 -325.446599) (xy 268.78079 -325.477858)
			(xy 268.695042 -325.501527) (xy 268.607518 -325.517414) (xy 268.518921 -325.525391) (xy 268.474444 -325.525892)
			(xy 266.721844 -325.525892) (xy 266.677367 -325.525334) (xy 266.58877 -325.517364) (xy 266.501245 -325.501484)
			(xy 266.415496 -325.477822) (xy 266.332213 -325.446568) (xy 266.252066 -325.407975) (xy 266.175702 -325.362353)
			(xy 266.103736 -325.310069) (xy 266.036745 -325.251544) (xy 265.975271 -325.18725) (xy 265.919808 -325.117703)
			(xy 265.870802 -325.043465) (xy 265.828648 -324.965133) (xy 265.793686 -324.883338) (xy 265.766197 -324.798738)
			(xy 265.746402 -324.712014) (xy 265.734461 -324.623865) (xy 265.73047 -324.535) (xy 254.06858 -324.535)
			(xy 254.06858 -325.056754) (xy 256.397758 -325.056754) (xy 256.401829 -325.001132) (xy 256.413955 -324.946695)
			(xy 256.433878 -324.894604) (xy 256.461174 -324.845969) (xy 256.49526 -324.801826) (xy 256.535409 -324.763117)
			(xy 256.580767 -324.730666) (xy 256.630367 -324.705165) (xy 256.683151 -324.687158) (xy 256.737994 -324.677028)
			(xy 256.793728 -324.674991) (xy 256.849165 -324.681091) (xy 256.903122 -324.695197) (xy 256.954451 -324.717009)
			(xy 257.002057 -324.746063) (xy 257.044925 -324.781738) (xy 257.082142 -324.823275) (xy 257.112915 -324.869788)
			(xy 257.136587 -324.920285) (xy 257.152655 -324.973692) (xy 257.160775 -325.028868) (xy 257.161284 -325.056754)
			(xy 257.160775 -325.08464) (xy 257.152655 -325.139816) (xy 257.136587 -325.193223) (xy 257.112915 -325.24372)
			(xy 257.082142 -325.290233) (xy 257.044925 -325.33177) (xy 257.002057 -325.367445) (xy 256.954451 -325.396499)
			(xy 256.903122 -325.418311) (xy 256.849165 -325.432417) (xy 256.793728 -325.438517) (xy 256.737994 -325.43648)
			(xy 256.683151 -325.42635) (xy 256.630367 -325.408343) (xy 256.580767 -325.382842) (xy 256.535409 -325.350391)
			(xy 256.49526 -325.311682) (xy 256.461174 -325.267539) (xy 256.433878 -325.218904) (xy 256.413955 -325.166813)
			(xy 256.401829 -325.112376) (xy 256.397758 -325.056754) (xy 254.06858 -325.056754) (xy 254.06858 -325.458836)
			(xy 254.069079 -325.469262) (xy 254.077332 -325.488412) (xy 254.084582 -325.49592) (xy 254.104852 -325.515694)
			(xy 254.13991 -325.560162) (xy 254.16801 -325.609323) (xy 254.188534 -325.662098) (xy 254.201032 -325.717327)
			(xy 254.205229 -325.773797) (xy 254.201033 -325.830267) (xy 254.188536 -325.885496) (xy 254.168012 -325.938272)
			(xy 254.139913 -325.987434) (xy 254.104855 -326.031902) (xy 254.084582 -326.051672) (xy 254.07731 -326.05917)
			(xy 254.069031 -326.078322) (xy 254.06858 -326.088756) (xy 254.06858 -326.251316) (xy 254.069094 -326.261735)
			(xy 254.077367 -326.280863) (xy 254.084582 -326.2884) (xy 254.104811 -326.308167) (xy 254.139795 -326.352607)
			(xy 254.167832 -326.401726) (xy 254.18831 -326.454446) (xy 254.200777 -326.509613) (xy 254.204962 -326.566015)
			(xy 254.200773 -326.622417) (xy 254.188301 -326.677583) (xy 254.167819 -326.730301) (xy 254.139778 -326.779418)
			(xy 254.104791 -326.823855) (xy 254.084582 -326.843644) (xy 254.077321 -326.851146) (xy 254.069069 -326.870298)
			(xy 254.06858 -326.880728) (xy 254.06858 -327.14565) (xy 254.069081 -327.156075) (xy 254.077338 -327.175221)
			(xy 254.084582 -327.182734) (xy 254.104851 -327.202508) (xy 254.139907 -327.246976) (xy 254.168005 -327.296136)
			(xy 254.188527 -327.348911) (xy 254.201024 -327.404138) (xy 254.205219 -327.460607) (xy 254.201022 -327.517075)
			(xy 254.188523 -327.572303) (xy 254.167999 -327.625076) (xy 254.139899 -327.674236) (xy 254.104841 -327.718702)
			(xy 254.084582 -327.738486) (xy 254.077312 -327.745984) (xy 254.069038 -327.765137) (xy 254.068598 -327.775155)
			(xy 257.954439 -327.775155) (xy 257.954439 -327.720645) (xy 257.962197 -327.666689) (xy 257.977555 -327.614387)
			(xy 258.0002 -327.564803) (xy 258.029672 -327.518947) (xy 258.06537 -327.477752) (xy 258.106568 -327.442056)
			(xy 258.152426 -327.412588) (xy 258.202011 -327.389946) (xy 258.254315 -327.374591) (xy 258.308271 -327.366837)
			(xy 258.335526 -327.366376) (xy 258.358882 -327.366733) (xy 258.405241 -327.372469) (xy 258.427982 -327.377806)
			(xy 258.437126 -327.380092) (xy 258.455414 -327.377806) (xy 258.532376 -327.337166) (xy 258.544568 -327.323196)
			(xy 258.54787 -327.314306) (xy 258.558409 -327.287241) (xy 258.586538 -327.236428) (xy 258.622045 -327.190466)
			(xy 258.66411 -327.150419) (xy 258.711761 -327.117213) (xy 258.763894 -327.091614) (xy 258.819307 -327.074215)
			(xy 258.876716 -327.065418) (xy 258.905756 -327.064878) (xy 258.93388 -327.065364) (xy 258.989516 -327.073639)
			(xy 259.043331 -327.09) (xy 259.094157 -327.114094) (xy 259.140891 -327.145395) (xy 259.162042 -327.163938)
			(xy 259.169408 -327.170542) (xy 259.187188 -327.177146) (xy 259.276088 -327.175876) (xy 259.293614 -327.168764)
			(xy 259.300726 -327.161906) (xy 259.322162 -327.142138) (xy 259.369933 -327.108705) (xy 259.422234 -327.082926)
			(xy 259.477846 -327.065401) (xy 259.535478 -327.056537) (xy 259.564632 -327.055988) (xy 259.591881 -327.056484)
			(xy 259.645825 -327.064244) (xy 259.698116 -327.079602) (xy 259.747688 -327.102245) (xy 259.793534 -327.131711)
			(xy 259.83472 -327.167403) (xy 259.870408 -327.208592) (xy 259.899871 -327.25444) (xy 259.922509 -327.304014)
			(xy 259.937863 -327.356306) (xy 259.945618 -327.41025) (xy 259.945618 -327.46475) (xy 259.937863 -327.518694)
			(xy 259.922509 -327.570986) (xy 259.899871 -327.62056) (xy 259.870408 -327.666408) (xy 259.83472 -327.707597)
			(xy 259.793534 -327.743289) (xy 259.747688 -327.772755) (xy 259.698116 -327.795398) (xy 259.645825 -327.810756)
			(xy 259.591881 -327.818516) (xy 259.564632 -327.819004) (xy 259.536509 -327.818504) (xy 259.480875 -327.81023)
			(xy 259.42706 -327.79387) (xy 259.376234 -327.76978) (xy 259.329499 -327.738484) (xy 259.308346 -327.719944)
			(xy 259.30098 -327.71334) (xy 259.2832 -327.706736) (xy 259.1943 -327.708006) (xy 259.176774 -327.715118)
			(xy 259.169662 -327.721976) (xy 259.148228 -327.741746) (xy 259.100457 -327.77518) (xy 259.048156 -327.800959)
			(xy 258.992542 -327.818484) (xy 258.934911 -327.827345) (xy 258.905756 -327.827894) (xy 258.8824 -327.827523)
			(xy 258.836042 -327.821796) (xy 258.8133 -327.816464) (xy 258.804156 -327.814178) (xy 258.785868 -327.816464)
			(xy 258.708906 -327.857104) (xy 258.696714 -327.871074) (xy 258.693412 -327.879964) (xy 258.682872 -327.907029)
			(xy 258.654745 -327.957844) (xy 258.619239 -328.003807) (xy 258.577174 -328.043855) (xy 258.529524 -328.077062)
			(xy 258.477389 -328.10266) (xy 258.421976 -328.120058) (xy 258.364566 -328.128853) (xy 258.335526 -328.129392)
			(xy 258.308271 -328.128963) (xy 258.254315 -328.121209) (xy 258.202011 -328.105854) (xy 258.152426 -328.083212)
			(xy 258.106568 -328.053744) (xy 258.06537 -328.018048) (xy 258.029672 -327.976853) (xy 258.0002 -327.930997)
			(xy 257.977555 -327.881413) (xy 257.962197 -327.829111) (xy 257.954439 -327.775155) (xy 254.068598 -327.775155)
			(xy 254.06858 -327.77557) (xy 254.06858 -328.334116) (xy 254.069005 -328.344185) (xy 254.076722 -328.362788)
			(xy 254.083566 -328.370184) (xy 255.44653 -329.733148) (xy 255.453943 -329.739822) (xy 255.472379 -329.747386)
			(xy 255.482344 -329.74788) (xy 256.043938 -329.74788) (xy 256.049442 -329.747762) (xy 256.060207 -329.745461)
			(xy 256.065274 -329.743308) (xy 256.093214 -329.730354) (xy 256.100326 -329.72248) (xy 256.121053 -329.699885)
			(xy 256.16703 -329.659317) (xy 256.217551 -329.62457) (xy 256.271882 -329.596148) (xy 256.329236 -329.574464)
			(xy 256.38878 -329.55983) (xy 256.449652 -329.552461) (xy 256.48031 -329.552046) (xy 256.511687 -329.552511)
			(xy 256.573964 -329.560232) (xy 256.634818 -329.575556) (xy 256.693325 -329.598249) (xy 256.748596 -329.627967)
			(xy 256.799791 -329.664258) (xy 256.846133 -329.706572) (xy 256.866898 -329.7301) (xy 256.87447 -329.738124)
			(xy 256.894487 -329.747345) (xy 256.905506 -329.74788) (xy 257.162808 -329.74788) (xy 257.185448 -329.748296)
			(xy 257.230252 -329.754852) (xy 257.273643 -329.767798) (xy 257.314715 -329.786862) (xy 257.352611 -329.811647)
			(xy 257.369818 -329.826366) (xy 257.377034 -329.832162) (xy 257.394352 -329.838654) (xy 257.4036 -329.839066)
			(xy 261.788148 -329.839066) (xy 261.801864 -329.837288) (xy 261.80923 -329.835002) (xy 261.815072 -329.831446)
			(xy 261.821126 -329.828009) (xy 261.834529 -329.824268) (xy 261.841488 -329.82408) (xy 271.809718 -329.82408)
			(xy 271.819116 -329.82027) (xy 271.849523 -329.808502) (xy 271.912597 -329.791977) (xy 271.977268 -329.78367)
			(xy 272.00987 -329.783186) (xy 272.042468 -329.783714) (xy 272.107128 -329.792047) (xy 272.170199 -329.808556)
			(xy 272.200624 -329.82027) (xy 272.210022 -329.82408) (xy 272.444718 -329.82408) (xy 272.454116 -329.82027)
			(xy 272.484483 -329.808515) (xy 272.547472 -329.792002) (xy 272.612057 -329.783684) (xy 272.644616 -329.783186)
			(xy 272.64487 -329.783186) (xy 272.673705 -329.78363) (xy 272.730994 -329.79025) (xy 272.75917 -329.796394)
			(xy 272.764887 -329.797594) (xy 272.776567 -329.797594) (xy 272.782284 -329.796394) (xy 272.810765 -329.790121)
			(xy 272.868694 -329.783375) (xy 272.897854 -329.782932) (xy 272.898616 -329.782932) (xy 272.927457 -329.783352)
			(xy 272.984765 -329.789908) (xy 273.040964 -329.802902) (xy 273.068288 -329.812142) (xy 273.072098 -329.813412)
			(xy 273.08048 -329.814936) (xy 273.084899 -329.815626) (xy 273.093841 -329.815626) (xy 273.09826 -329.814936)
			(xy 273.106642 -329.813412) (xy 273.110452 -329.812142) (xy 273.137574 -329.802986) (xy 273.193357 -329.790123)
			(xy 273.250231 -329.783608) (xy 273.278854 -329.783186) (xy 273.27987 -329.783186) (xy 273.308705 -329.78363)
			(xy 273.365994 -329.79025) (xy 273.39417 -329.796394) (xy 273.399887 -329.797594) (xy 273.411567 -329.797594)
			(xy 273.417284 -329.796394) (xy 273.445765 -329.790121) (xy 273.503694 -329.783375) (xy 273.532854 -329.782932)
			(xy 273.533616 -329.782932) (xy 273.566352 -329.783422) (xy 273.631286 -329.791793) (xy 273.694607 -329.808433)
			(xy 273.725132 -329.82027) (xy 273.734276 -329.82408) (xy 273.967448 -329.82408) (xy 273.976592 -329.82027)
			(xy 274.007117 -329.808433) (xy 274.07044 -329.791801) (xy 274.135372 -329.783422) (xy 274.168108 -329.782932)
			(xy 274.168616 -329.782932) (xy 274.201352 -329.783422) (xy 274.266286 -329.791793) (xy 274.329607 -329.808433)
			(xy 274.360132 -329.82027) (xy 274.369276 -329.82408) (xy 275.822918 -329.82408) (xy 275.832316 -329.82027)
			(xy 275.862723 -329.808502) (xy 275.925797 -329.791977) (xy 275.990468 -329.78367) (xy 276.02307 -329.783186)
			(xy 276.055668 -329.783714) (xy 276.120328 -329.792047) (xy 276.183399 -329.808556) (xy 276.213824 -329.82027)
			(xy 276.223222 -329.82408) (xy 276.457918 -329.82408) (xy 276.467316 -329.82027) (xy 276.497683 -329.808515)
			(xy 276.560672 -329.792002) (xy 276.625257 -329.783684) (xy 276.657816 -329.783186) (xy 276.65807 -329.783186)
			(xy 276.686905 -329.78363) (xy 276.744194 -329.79025) (xy 276.77237 -329.796394) (xy 276.778087 -329.797594)
			(xy 276.789767 -329.797594) (xy 276.795484 -329.796394) (xy 276.823965 -329.790121) (xy 276.881894 -329.783375)
			(xy 276.911054 -329.782932) (xy 276.911816 -329.782932) (xy 276.940657 -329.783352) (xy 276.997965 -329.789908)
			(xy 277.054164 -329.802902) (xy 277.081488 -329.812142) (xy 277.085298 -329.813412) (xy 277.09368 -329.814936)
			(xy 277.098099 -329.815626) (xy 277.107041 -329.815626) (xy 277.11146 -329.814936) (xy 277.119842 -329.813412)
			(xy 277.123652 -329.812142) (xy 277.150774 -329.802986) (xy 277.206557 -329.790123) (xy 277.263431 -329.783608)
			(xy 277.292054 -329.783186) (xy 277.29307 -329.783186) (xy 277.321905 -329.78363) (xy 277.379194 -329.79025)
			(xy 277.40737 -329.796394) (xy 277.413087 -329.797594) (xy 277.424767 -329.797594) (xy 277.430484 -329.796394)
			(xy 277.458965 -329.790121) (xy 277.516894 -329.783375) (xy 277.546054 -329.782932) (xy 277.546816 -329.782932)
			(xy 277.579552 -329.783422) (xy 277.644486 -329.791793) (xy 277.707807 -329.808433) (xy 277.738332 -329.82027)
			(xy 277.747476 -329.82408) (xy 277.980648 -329.82408) (xy 277.989792 -329.82027) (xy 278.020317 -329.808433)
			(xy 278.08364 -329.791801) (xy 278.148572 -329.783422) (xy 278.181308 -329.782932) (xy 278.181816 -329.782932)
			(xy 278.214552 -329.783422) (xy 278.279486 -329.791793) (xy 278.342807 -329.808433) (xy 278.373332 -329.82027)
			(xy 278.382476 -329.82408) (xy 280.090118 -329.82408) (xy 280.099516 -329.82027) (xy 280.129923 -329.808502)
			(xy 280.192997 -329.791977) (xy 280.257668 -329.78367) (xy 280.29027 -329.783186) (xy 280.322868 -329.783714)
			(xy 280.387528 -329.792047) (xy 280.450599 -329.808556) (xy 280.481024 -329.82027) (xy 280.490422 -329.82408)
			(xy 280.725118 -329.82408) (xy 280.734516 -329.82027) (xy 280.764883 -329.808515) (xy 280.827872 -329.792002)
			(xy 280.892457 -329.783684) (xy 280.925016 -329.783186) (xy 280.92527 -329.783186) (xy 280.954105 -329.78363)
			(xy 281.011394 -329.79025) (xy 281.03957 -329.796394) (xy 281.045287 -329.797594) (xy 281.056967 -329.797594)
			(xy 281.062684 -329.796394) (xy 281.091165 -329.790121) (xy 281.149094 -329.783375) (xy 281.178254 -329.782932)
			(xy 281.179016 -329.782932) (xy 281.207857 -329.783352) (xy 281.265165 -329.789908) (xy 281.321364 -329.802902)
			(xy 281.348688 -329.812142) (xy 281.352498 -329.813412) (xy 281.36088 -329.814936) (xy 281.365299 -329.815626)
			(xy 281.374241 -329.815626) (xy 281.37866 -329.814936) (xy 281.387042 -329.813412) (xy 281.390852 -329.812142)
			(xy 281.417974 -329.802986) (xy 281.473757 -329.790123) (xy 281.530631 -329.783608) (xy 281.559254 -329.783186)
			(xy 281.56027 -329.783186) (xy 281.589105 -329.78363) (xy 281.646394 -329.79025) (xy 281.67457 -329.796394)
			(xy 281.680287 -329.797594) (xy 281.691967 -329.797594) (xy 281.697684 -329.796394) (xy 281.726165 -329.790121)
			(xy 281.784094 -329.783375) (xy 281.813254 -329.782932) (xy 281.814016 -329.782932) (xy 281.846752 -329.783422)
			(xy 281.911686 -329.791793) (xy 281.975007 -329.808433) (xy 282.005532 -329.82027) (xy 282.014676 -329.82408)
			(xy 282.247848 -329.82408) (xy 282.256992 -329.82027) (xy 282.287517 -329.808433) (xy 282.35084 -329.791801)
			(xy 282.415772 -329.783422) (xy 282.448508 -329.782932) (xy 282.449016 -329.782932) (xy 282.481752 -329.783422)
			(xy 282.546686 -329.791793) (xy 282.610007 -329.808433) (xy 282.640532 -329.82027) (xy 282.649676 -329.82408)
			(xy 284.103318 -329.82408) (xy 284.112716 -329.82027) (xy 284.143123 -329.808502) (xy 284.206197 -329.791977)
			(xy 284.270868 -329.78367) (xy 284.30347 -329.783186) (xy 284.336068 -329.783714) (xy 284.400728 -329.792047)
			(xy 284.463799 -329.808556) (xy 284.494224 -329.82027) (xy 284.503622 -329.82408) (xy 284.738318 -329.82408)
			(xy 284.747716 -329.82027) (xy 284.778083 -329.808515) (xy 284.841072 -329.792002) (xy 284.905657 -329.783684)
			(xy 284.938216 -329.783186) (xy 284.93847 -329.783186) (xy 284.967305 -329.78363) (xy 285.024594 -329.79025)
			(xy 285.05277 -329.796394) (xy 285.058487 -329.797594) (xy 285.070167 -329.797594) (xy 285.075884 -329.796394)
			(xy 285.104365 -329.790121) (xy 285.162294 -329.783375) (xy 285.191454 -329.782932) (xy 285.192216 -329.782932)
			(xy 285.221057 -329.783352) (xy 285.278365 -329.789908) (xy 285.334564 -329.802902) (xy 285.361888 -329.812142)
			(xy 285.365698 -329.813412) (xy 285.37408 -329.814936) (xy 285.378499 -329.815626) (xy 285.387441 -329.815626)
			(xy 285.39186 -329.814936) (xy 285.400242 -329.813412) (xy 285.404052 -329.812142) (xy 285.431174 -329.802986)
			(xy 285.486957 -329.790123) (xy 285.543831 -329.783608) (xy 285.572454 -329.783186) (xy 285.57347 -329.783186)
			(xy 285.602305 -329.78363) (xy 285.659594 -329.79025) (xy 285.68777 -329.796394) (xy 285.693487 -329.797594)
			(xy 285.705167 -329.797594) (xy 285.710884 -329.796394) (xy 285.739365 -329.790121) (xy 285.797294 -329.783375)
			(xy 285.826454 -329.782932) (xy 285.827216 -329.782932) (xy 285.859952 -329.783422) (xy 285.924886 -329.791793)
			(xy 285.988207 -329.808433) (xy 286.018732 -329.82027) (xy 286.027876 -329.82408) (xy 286.261048 -329.82408)
			(xy 286.270192 -329.82027) (xy 286.300717 -329.808433) (xy 286.36404 -329.791801) (xy 286.428972 -329.783422)
			(xy 286.461708 -329.782932) (xy 286.462216 -329.782932) (xy 286.494952 -329.783422) (xy 286.559886 -329.791793)
			(xy 286.623207 -329.808433) (xy 286.653732 -329.82027) (xy 286.662876 -329.82408) (xy 288.395918 -329.82408)
			(xy 288.405316 -329.82027) (xy 288.435723 -329.808502) (xy 288.498797 -329.791977) (xy 288.563468 -329.78367)
			(xy 288.59607 -329.783186) (xy 288.628668 -329.783714) (xy 288.693328 -329.792047) (xy 288.756399 -329.808556)
			(xy 288.786824 -329.82027) (xy 288.796222 -329.82408) (xy 289.030918 -329.82408) (xy 289.040316 -329.82027)
			(xy 289.070683 -329.808515) (xy 289.133672 -329.792002) (xy 289.198257 -329.783684) (xy 289.230816 -329.783186)
			(xy 289.23107 -329.783186) (xy 289.259905 -329.78363) (xy 289.317194 -329.79025) (xy 289.34537 -329.796394)
			(xy 289.351087 -329.797594) (xy 289.362767 -329.797594) (xy 289.368484 -329.796394) (xy 289.396965 -329.790121)
			(xy 289.454894 -329.783375) (xy 289.484054 -329.782932) (xy 289.484816 -329.782932) (xy 289.513657 -329.783352)
			(xy 289.570965 -329.789908) (xy 289.627164 -329.802902) (xy 289.654488 -329.812142) (xy 289.658298 -329.813412)
			(xy 289.66668 -329.814936) (xy 289.671099 -329.815626) (xy 289.680041 -329.815626) (xy 289.68446 -329.814936)
			(xy 289.692842 -329.813412) (xy 289.696652 -329.812142) (xy 289.723774 -329.802986) (xy 289.779557 -329.790123)
			(xy 289.836431 -329.783608) (xy 289.865054 -329.783186) (xy 289.86607 -329.783186) (xy 289.894905 -329.78363)
			(xy 289.952194 -329.79025) (xy 289.98037 -329.796394) (xy 289.986087 -329.797594) (xy 289.997767 -329.797594)
			(xy 290.003484 -329.796394) (xy 290.031965 -329.790121) (xy 290.089894 -329.783375) (xy 290.119054 -329.782932)
			(xy 290.119816 -329.782932) (xy 290.152552 -329.783422) (xy 290.217486 -329.791793) (xy 290.280807 -329.808433)
			(xy 290.311332 -329.82027) (xy 290.320476 -329.82408) (xy 290.553648 -329.82408) (xy 290.562792 -329.82027)
			(xy 290.593317 -329.808433) (xy 290.65664 -329.791801) (xy 290.721572 -329.783422) (xy 290.754308 -329.782932)
			(xy 290.754816 -329.782932) (xy 290.787552 -329.783422) (xy 290.852486 -329.791793) (xy 290.915807 -329.808433)
			(xy 290.946332 -329.82027) (xy 290.955476 -329.82408) (xy 292.409118 -329.82408) (xy 292.418516 -329.82027)
			(xy 292.448923 -329.808502) (xy 292.511997 -329.791977) (xy 292.576668 -329.78367) (xy 292.60927 -329.783186)
			(xy 292.641868 -329.783714) (xy 292.706528 -329.792047) (xy 292.769599 -329.808556) (xy 292.800024 -329.82027)
			(xy 292.809422 -329.82408) (xy 293.044118 -329.82408) (xy 293.053516 -329.82027) (xy 293.083883 -329.808515)
			(xy 293.146872 -329.792002) (xy 293.211457 -329.783684) (xy 293.244016 -329.783186) (xy 293.24427 -329.783186)
			(xy 293.273105 -329.78363) (xy 293.330394 -329.79025) (xy 293.35857 -329.796394) (xy 293.364287 -329.797594)
			(xy 293.375967 -329.797594) (xy 293.381684 -329.796394) (xy 293.410165 -329.790121) (xy 293.468094 -329.783375)
			(xy 293.497254 -329.782932) (xy 293.498016 -329.782932) (xy 293.526857 -329.783352) (xy 293.584165 -329.789908)
			(xy 293.640364 -329.802902) (xy 293.667688 -329.812142) (xy 293.671498 -329.813412) (xy 293.67988 -329.814936)
			(xy 293.684299 -329.815626) (xy 293.693241 -329.815626) (xy 293.69766 -329.814936) (xy 293.706042 -329.813412)
			(xy 293.709852 -329.812142) (xy 293.736974 -329.802986) (xy 293.792757 -329.790123) (xy 293.849631 -329.783608)
			(xy 293.878254 -329.783186) (xy 293.87927 -329.783186) (xy 293.908105 -329.78363) (xy 293.965394 -329.79025)
			(xy 293.99357 -329.796394) (xy 293.999287 -329.797594) (xy 294.010967 -329.797594) (xy 294.016684 -329.796394)
			(xy 294.045165 -329.790121) (xy 294.103094 -329.783375) (xy 294.132254 -329.782932) (xy 294.133016 -329.782932)
			(xy 294.165752 -329.783422) (xy 294.230686 -329.791793) (xy 294.294007 -329.808433) (xy 294.324532 -329.82027)
			(xy 294.333676 -329.82408) (xy 294.566848 -329.82408) (xy 294.575992 -329.82027) (xy 294.606517 -329.808433)
			(xy 294.66984 -329.791801) (xy 294.734772 -329.783422) (xy 294.767508 -329.782932) (xy 294.768016 -329.782932)
			(xy 294.800752 -329.783422) (xy 294.865686 -329.791793) (xy 294.929007 -329.808433) (xy 294.959532 -329.82027)
			(xy 294.968676 -329.82408) (xy 296.752518 -329.82408) (xy 296.761916 -329.82027) (xy 296.792323 -329.808502)
			(xy 296.855397 -329.791977) (xy 296.920068 -329.78367) (xy 296.95267 -329.783186) (xy 296.985268 -329.783714)
			(xy 297.049928 -329.792047) (xy 297.112999 -329.808556) (xy 297.143424 -329.82027) (xy 297.152822 -329.82408)
			(xy 297.387518 -329.82408) (xy 297.396916 -329.82027) (xy 297.427283 -329.808515) (xy 297.490272 -329.792002)
			(xy 297.554857 -329.783684) (xy 297.587416 -329.783186) (xy 297.58767 -329.783186) (xy 297.616505 -329.78363)
			(xy 297.673794 -329.79025) (xy 297.70197 -329.796394) (xy 297.707687 -329.797594) (xy 297.719367 -329.797594)
			(xy 297.725084 -329.796394) (xy 297.753565 -329.790121) (xy 297.811494 -329.783375) (xy 297.840654 -329.782932)
			(xy 297.841416 -329.782932) (xy 297.870257 -329.783352) (xy 297.927565 -329.789908) (xy 297.983764 -329.802902)
			(xy 298.011088 -329.812142) (xy 298.014898 -329.813412) (xy 298.02328 -329.814936) (xy 298.027699 -329.815626)
			(xy 298.036641 -329.815626) (xy 298.04106 -329.814936) (xy 298.049442 -329.813412) (xy 298.053252 -329.812142)
			(xy 298.080374 -329.802986) (xy 298.136157 -329.790123) (xy 298.193031 -329.783608) (xy 298.221654 -329.783186)
			(xy 298.22267 -329.783186) (xy 298.251505 -329.78363) (xy 298.308794 -329.79025) (xy 298.33697 -329.796394)
			(xy 298.342687 -329.797594) (xy 298.354367 -329.797594) (xy 298.360084 -329.796394) (xy 298.388565 -329.790121)
			(xy 298.446494 -329.783375) (xy 298.475654 -329.782932) (xy 298.476416 -329.782932) (xy 298.509152 -329.783422)
			(xy 298.574086 -329.791793) (xy 298.637407 -329.808433) (xy 298.667932 -329.82027) (xy 298.677076 -329.82408)
			(xy 298.910248 -329.82408) (xy 298.919392 -329.82027) (xy 298.949917 -329.808433) (xy 299.01324 -329.791801)
			(xy 299.078172 -329.783422) (xy 299.110908 -329.782932) (xy 299.111416 -329.782932) (xy 299.144152 -329.783422)
			(xy 299.209086 -329.791793) (xy 299.272407 -329.808433) (xy 299.302932 -329.82027) (xy 299.312076 -329.82408)
			(xy 300.765718 -329.82408) (xy 300.775116 -329.82027) (xy 300.805523 -329.808502) (xy 300.868597 -329.791977)
			(xy 300.933268 -329.78367) (xy 300.96587 -329.783186) (xy 300.998468 -329.783714) (xy 301.063128 -329.792047)
			(xy 301.126199 -329.808556) (xy 301.156624 -329.82027) (xy 301.166022 -329.82408) (xy 301.400718 -329.82408)
			(xy 301.410116 -329.82027) (xy 301.440483 -329.808515) (xy 301.503472 -329.792002) (xy 301.568057 -329.783684)
			(xy 301.600616 -329.783186) (xy 301.60087 -329.783186) (xy 301.629705 -329.78363) (xy 301.686994 -329.79025)
			(xy 301.71517 -329.796394) (xy 301.720887 -329.797594) (xy 301.732567 -329.797594) (xy 301.738284 -329.796394)
			(xy 301.766765 -329.790121) (xy 301.824694 -329.783375) (xy 301.853854 -329.782932) (xy 301.854616 -329.782932)
			(xy 301.883457 -329.783352) (xy 301.940765 -329.789908) (xy 301.996964 -329.802902) (xy 302.024288 -329.812142)
			(xy 302.028098 -329.813412) (xy 302.03648 -329.814936) (xy 302.040899 -329.815626) (xy 302.049841 -329.815626)
			(xy 302.05426 -329.814936) (xy 302.062642 -329.813412) (xy 302.066452 -329.812142) (xy 302.093574 -329.802986)
			(xy 302.149357 -329.790123) (xy 302.206231 -329.783608) (xy 302.234854 -329.783186) (xy 302.23587 -329.783186)
			(xy 302.264705 -329.78363) (xy 302.321994 -329.79025) (xy 302.35017 -329.796394) (xy 302.355887 -329.797594)
			(xy 302.367567 -329.797594) (xy 302.373284 -329.796394) (xy 302.401765 -329.790121) (xy 302.459694 -329.783375)
			(xy 302.488854 -329.782932) (xy 302.489616 -329.782932) (xy 302.522352 -329.783422) (xy 302.587286 -329.791793)
			(xy 302.650607 -329.808433) (xy 302.681132 -329.82027) (xy 302.690276 -329.82408) (xy 302.923448 -329.82408)
			(xy 302.932592 -329.82027) (xy 302.963117 -329.808433) (xy 303.02644 -329.791801) (xy 303.091372 -329.783422)
			(xy 303.124108 -329.782932) (xy 303.124616 -329.782932) (xy 303.157352 -329.783422) (xy 303.222286 -329.791793)
			(xy 303.285607 -329.808433) (xy 303.316132 -329.82027) (xy 303.325276 -329.82408) (xy 305.083718 -329.82408)
			(xy 305.093116 -329.82027) (xy 305.123523 -329.808502) (xy 305.186597 -329.791977) (xy 305.251268 -329.78367)
			(xy 305.28387 -329.783186) (xy 305.316468 -329.783714) (xy 305.381128 -329.792047) (xy 305.444199 -329.808556)
			(xy 305.474624 -329.82027) (xy 305.484022 -329.82408) (xy 305.718718 -329.82408) (xy 305.728116 -329.82027)
			(xy 305.758483 -329.808515) (xy 305.821472 -329.792002) (xy 305.886057 -329.783684) (xy 305.918616 -329.783186)
			(xy 305.91887 -329.783186) (xy 305.947705 -329.78363) (xy 306.004994 -329.79025) (xy 306.03317 -329.796394)
			(xy 306.038887 -329.797594) (xy 306.050567 -329.797594) (xy 306.056284 -329.796394) (xy 306.084765 -329.790121)
			(xy 306.142694 -329.783375) (xy 306.171854 -329.782932) (xy 306.172616 -329.782932) (xy 306.201457 -329.783352)
			(xy 306.258765 -329.789908) (xy 306.314964 -329.802902) (xy 306.342288 -329.812142) (xy 306.346098 -329.813412)
			(xy 306.35448 -329.814936) (xy 306.358899 -329.815626) (xy 306.367841 -329.815626) (xy 306.37226 -329.814936)
			(xy 306.380642 -329.813412) (xy 306.384452 -329.812142) (xy 306.411574 -329.802986) (xy 306.467357 -329.790123)
			(xy 306.524231 -329.783608) (xy 306.552854 -329.783186) (xy 306.55387 -329.783186) (xy 306.582705 -329.78363)
			(xy 306.639994 -329.79025) (xy 306.66817 -329.796394) (xy 306.673887 -329.797594) (xy 306.685567 -329.797594)
			(xy 306.691284 -329.796394) (xy 306.719765 -329.790121) (xy 306.777694 -329.783375) (xy 306.806854 -329.782932)
			(xy 306.807616 -329.782932) (xy 306.840352 -329.783422) (xy 306.905286 -329.791793) (xy 306.968607 -329.808433)
			(xy 306.999132 -329.82027) (xy 307.008276 -329.82408) (xy 307.241448 -329.82408) (xy 307.250592 -329.82027)
			(xy 307.281117 -329.808433) (xy 307.34444 -329.791801) (xy 307.409372 -329.783422) (xy 307.442108 -329.782932)
			(xy 307.442616 -329.782932) (xy 307.475352 -329.783422) (xy 307.540286 -329.791793) (xy 307.603607 -329.808433)
			(xy 307.634132 -329.82027) (xy 307.643276 -329.82408) (xy 309.096918 -329.82408) (xy 309.106316 -329.82027)
			(xy 309.136723 -329.808502) (xy 309.199797 -329.791977) (xy 309.264468 -329.78367) (xy 309.29707 -329.783186)
			(xy 309.329668 -329.783714) (xy 309.394328 -329.792047) (xy 309.457399 -329.808556) (xy 309.487824 -329.82027)
			(xy 309.497222 -329.82408) (xy 309.731918 -329.82408) (xy 309.741316 -329.82027) (xy 309.771683 -329.808515)
			(xy 309.834672 -329.792002) (xy 309.899257 -329.783684) (xy 309.931816 -329.783186) (xy 309.93207 -329.783186)
			(xy 309.960905 -329.78363) (xy 310.018194 -329.79025) (xy 310.04637 -329.796394) (xy 310.052087 -329.797594)
			(xy 310.063767 -329.797594) (xy 310.069484 -329.796394) (xy 310.097965 -329.790121) (xy 310.155894 -329.783375)
			(xy 310.185054 -329.782932) (xy 310.185816 -329.782932) (xy 310.218552 -329.783422) (xy 310.283486 -329.791793)
			(xy 310.346807 -329.808433) (xy 310.377332 -329.82027) (xy 310.386476 -329.82408) (xy 310.619648 -329.82408)
			(xy 310.628792 -329.82027) (xy 310.659317 -329.808433) (xy 310.72264 -329.791801) (xy 310.787572 -329.783422)
			(xy 310.820308 -329.782932) (xy 310.820816 -329.782932) (xy 310.853552 -329.783422) (xy 310.918486 -329.791793)
			(xy 310.981807 -329.808433) (xy 311.012332 -329.82027) (xy 311.021476 -329.82408) (xy 314.453016 -329.82408)
			(xy 314.461652 -329.823318) (xy 314.469169 -329.821715) (xy 314.482856 -329.814737) (xy 314.488576 -329.809602)
			(xy 318.36995 -325.928228) (xy 318.37735 -325.921387) (xy 318.395948 -325.913666) (xy 318.406018 -325.913242)
			(xy 347.606874 -325.913242) (xy 347.616937 -325.912804) (xy 347.635516 -325.905064) (xy 347.642942 -325.898256)
			(xy 348.474284 -325.066914) (xy 348.481119 -325.059512) (xy 348.488824 -325.040913) (xy 348.48927 -325.030846)
			(xy 348.48927 -312.077354) (xy 348.488675 -312.064733) (xy 348.476813 -312.042461) (xy 348.466664 -312.034936)
			(xy 348.385638 -311.980834) (xy 348.360746 -311.978548) (xy 348.348808 -311.983374) (xy 348.317821 -311.995683)
			(xy 348.253431 -312.012993) (xy 348.187328 -312.021722) (xy 348.15399 -312.022236) (xy 348.122937 -312.02175)
			(xy 348.061297 -312.014156) (xy 348.001036 -311.999131) (xy 347.971872 -311.988454) (xy 347.962982 -311.985152)
			(xy 347.94444 -311.985152) (xy 347.863668 -312.015886) (xy 347.849698 -312.028078) (xy 347.84538 -312.03646)
			(xy 347.832984 -312.059372) (xy 347.802913 -312.101908) (xy 347.767335 -312.139958) (xy 347.726912 -312.172815)
			(xy 347.682395 -312.199868) (xy 347.634611 -312.220614) (xy 347.58445 -312.234667) (xy 347.532844 -312.241767)
			(xy 347.506798 -312.2422) (xy 347.479547 -312.241714) (xy 347.425601 -312.233958) (xy 347.373308 -312.218603)
			(xy 347.323732 -312.195962) (xy 347.277882 -312.166496) (xy 347.236693 -312.130805) (xy 347.201003 -312.089616)
			(xy 347.171537 -312.043767) (xy 347.148897 -311.994191) (xy 347.133542 -311.941897) (xy 347.125786 -311.887951)
			(xy 347.125786 -311.833449) (xy 347.133542 -311.779503) (xy 347.148897 -311.727209) (xy 347.171537 -311.677633)
			(xy 347.201003 -311.631784) (xy 347.236693 -311.590595) (xy 347.277882 -311.554904) (xy 347.323732 -311.525438)
			(xy 347.373308 -311.502797) (xy 347.425601 -311.487442) (xy 347.479547 -311.479686) (xy 347.506798 -311.479184)
			(xy 347.517043 -311.479272) (xy 347.537501 -311.480415) (xy 347.547692 -311.48147) (xy 347.55709 -311.482486)
			(xy 347.575124 -311.47766) (xy 347.645482 -311.427368) (xy 347.655642 -311.411874) (xy 347.657674 -311.402476)
			(xy 347.664567 -311.373613) (xy 347.684196 -311.317609) (xy 347.710221 -311.264276) (xy 347.742286 -311.214341)
			(xy 347.760798 -311.191148) (xy 347.766024 -311.184127) (xy 347.771853 -311.167636) (xy 347.772228 -311.15889)
			(xy 347.772228 -311.004966) (xy 347.771917 -310.996209) (xy 347.766072 -310.979705) (xy 347.760798 -310.972708)
			(xy 347.741909 -310.948955) (xy 347.70931 -310.897763) (xy 347.695774 -310.8706) (xy 347.691508 -310.862713)
			(xy 347.678638 -310.850248) (xy 347.670628 -310.846216) (xy 347.643196 -310.834024) (xy 347.634972 -310.830704)
			(xy 347.617307 -310.82929) (xy 347.608652 -310.83123) (xy 347.583692 -310.837739) (xy 347.532589 -310.844745)
			(xy 347.506798 -310.8452) (xy 347.479547 -310.844714) (xy 347.425601 -310.836958) (xy 347.373308 -310.821603)
			(xy 347.323732 -310.798962) (xy 347.277882 -310.769496) (xy 347.236693 -310.733805) (xy 347.201003 -310.692616)
			(xy 347.171537 -310.646767) (xy 347.148897 -310.597191) (xy 347.133542 -310.544897) (xy 347.125786 -310.490951)
			(xy 347.125786 -310.436449) (xy 347.133542 -310.382503) (xy 347.148897 -310.330209) (xy 347.171537 -310.280633)
			(xy 347.201003 -310.234784) (xy 347.236693 -310.193595) (xy 347.277882 -310.157904) (xy 347.323732 -310.128438)
			(xy 347.373308 -310.105797) (xy 347.425601 -310.090442) (xy 347.479547 -310.082686) (xy 347.506798 -310.082184)
			(xy 347.533247 -310.082634) (xy 347.585638 -310.08994) (xy 347.636517 -310.104412) (xy 347.684911 -310.125772)
			(xy 347.72989 -310.153611) (xy 347.770594 -310.187395) (xy 347.788738 -310.206644) (xy 347.79497 -310.212868)
			(xy 347.810557 -310.221045) (xy 347.819218 -310.222646) (xy 347.84919 -310.226964) (xy 347.858066 -310.227773)
			(xy 347.87547 -310.223993) (xy 347.883226 -310.219598) (xy 347.91378 -310.201118) (xy 347.978963 -310.17196)
			(xy 348.047581 -310.152198) (xy 348.118287 -310.142218) (xy 348.15399 -310.14162) (xy 348.187324 -310.14219)
			(xy 348.253416 -310.150936) (xy 348.317803 -310.168229) (xy 348.348808 -310.180482) (xy 348.360746 -310.185308)
			(xy 348.385638 -310.183022) (xy 348.466664 -310.12892) (xy 348.47677 -310.121356) (xy 348.488634 -310.099108)
			(xy 348.48927 -310.086502) (xy 348.48927 -305.478942) (xy 348.488956 -305.470186) (xy 348.483109 -305.453684)
			(xy 348.47784 -305.446684) (xy 344.904822 -301.092616) (xy 344.861968 -301.039719) (xy 344.78083 -300.930383)
			(xy 344.705086 -300.817243) (xy 344.634913 -300.700566) (xy 344.570478 -300.580626) (xy 344.54084 -300.519338)
			(xy 344.53703 -300.511464) (xy 343.80551 -299.779944) (xy 343.798671 -299.772543) (xy 343.790955 -299.753945)
			(xy 343.790524 -299.743876) (xy 343.790524 -296.431716) (xy 343.790983 -296.399926) (xy 343.798001 -296.336734)
			(xy 343.811899 -296.274691) (xy 343.83251 -296.214545) (xy 343.845642 -296.18559) (xy 343.850468 -296.17543)
			(xy 343.850468 -295.869868) (xy 343.850898 -295.838141) (xy 343.858007 -295.775086) (xy 343.872132 -295.713223)
			(xy 343.893095 -295.653331) (xy 343.920632 -295.596163) (xy 343.954398 -295.542438) (xy 343.993967 -295.492832)
			(xy 344.016076 -295.470072) (xy 344.214704 -295.27119) (xy 344.221562 -295.24452) (xy 344.217752 -295.231058)
			(xy 344.212162 -295.210361) (xy 344.206172 -295.167911) (xy 344.205814 -295.146476) (xy 344.205814 -295.145968)
			(xy 344.206283 -295.121624) (xy 344.214003 -295.073552) (xy 344.229257 -295.027315) (xy 344.251658 -294.984086)
			(xy 344.280639 -294.944963) (xy 344.315464 -294.910937) (xy 344.3351 -294.89654) (xy 344.341958 -294.891714)
			(xy 344.35161 -294.878506) (xy 344.354912 -294.868346) (xy 344.355166 -294.867076) (xy 344.367049 -294.822439)
			(xy 344.39715 -294.735102) (xy 344.434276 -294.650512) (xy 344.47818 -294.569232) (xy 344.502994 -294.530272)
			(xy 344.507058 -294.523922) (xy 344.511122 -294.509952) (xy 344.511122 -294.16248) (xy 344.507058 -294.14851)
			(xy 344.502994 -294.14216) (xy 344.479536 -294.10531) (xy 344.437715 -294.028609) (xy 344.401942 -293.948908)
			(xy 344.372431 -293.866682) (xy 344.3605 -293.82466) (xy 344.355166 -293.804848) (xy 344.354912 -293.803578)
			(xy 344.35161 -293.793418) (xy 344.341958 -293.78021) (xy 344.3351 -293.775384) (xy 344.315488 -293.760963)
			(xy 344.280676 -293.726939) (xy 344.251705 -293.687821) (xy 344.22931 -293.644601) (xy 344.214059 -293.598375)
			(xy 344.206337 -293.550313) (xy 344.206341 -293.501636) (xy 344.214071 -293.453576) (xy 344.22933 -293.407352)
			(xy 344.251732 -293.364136) (xy 344.280709 -293.325023) (xy 344.315527 -293.291004) (xy 344.3351 -293.276528)
			(xy 344.341958 -293.271702) (xy 344.35161 -293.258494) (xy 344.354912 -293.24808) (xy 344.35542 -293.246302)
			(xy 344.367275 -293.201701) (xy 344.397315 -293.114431) (xy 344.434377 -293.029904) (xy 344.478212 -292.948683)
			(xy 344.502994 -292.909752) (xy 344.507058 -292.903402) (xy 344.511122 -292.889432) (xy 344.511122 -292.542468)
			(xy 344.507058 -292.528498) (xy 344.502994 -292.522148) (xy 344.479536 -292.485298) (xy 344.437716 -292.408597)
			(xy 344.401944 -292.328895) (xy 344.372434 -292.246669) (xy 344.3605 -292.204648) (xy 344.355166 -292.184836)
			(xy 344.354912 -292.183566) (xy 344.35161 -292.173406) (xy 344.341958 -292.160198) (xy 344.3351 -292.155372)
			(xy 344.315481 -292.140951) (xy 344.280655 -292.106925) (xy 344.251671 -292.067802) (xy 344.229264 -292.024576)
			(xy 344.214001 -291.978341) (xy 344.206269 -291.93027) (xy 344.206265 -291.881581) (xy 344.213989 -291.833508)
			(xy 344.229244 -291.787271) (xy 344.251644 -291.744041) (xy 344.280622 -291.704914) (xy 344.315442 -291.670882)
			(xy 344.3351 -291.656516) (xy 344.341958 -291.65169) (xy 344.35161 -291.638482) (xy 344.354912 -291.628068)
			(xy 344.35542 -291.62629) (xy 344.367275 -291.581689) (xy 344.397317 -291.49442) (xy 344.434379 -291.409894)
			(xy 344.478215 -291.328673) (xy 344.502994 -291.28974) (xy 344.507058 -291.28339) (xy 344.511122 -291.26942)
			(xy 344.511122 -290.922456) (xy 344.507058 -290.908486) (xy 344.502994 -290.902136) (xy 344.479537 -290.865286)
			(xy 344.437717 -290.788584) (xy 344.401946 -290.708882) (xy 344.372436 -290.626656) (xy 344.3605 -290.584636)
			(xy 344.355166 -290.564824) (xy 344.354912 -290.563554) (xy 344.35161 -290.553394) (xy 344.341958 -290.540186)
			(xy 344.3351 -290.53536) (xy 344.315482 -290.520939) (xy 344.280658 -290.486913) (xy 344.251676 -290.447791)
			(xy 344.22927 -290.404566) (xy 344.214009 -290.358332) (xy 344.206278 -290.310262) (xy 344.206275 -290.261575)
			(xy 344.214 -290.213504) (xy 344.229256 -290.167268) (xy 344.251656 -290.12404) (xy 344.280634 -290.084915)
			(xy 344.315453 -290.050885) (xy 344.3351 -290.036504) (xy 344.341958 -290.031678) (xy 344.35161 -290.01847)
			(xy 344.354912 -290.008056) (xy 344.35542 -290.006278) (xy 344.367276 -289.961677) (xy 344.397318 -289.874409)
			(xy 344.434381 -289.789883) (xy 344.478218 -289.708663) (xy 344.502994 -289.669728) (xy 344.507058 -289.663378)
			(xy 344.511122 -289.649408) (xy 344.511122 -289.302444) (xy 344.507058 -289.288474) (xy 344.502994 -289.282124)
			(xy 344.479537 -289.245274) (xy 344.437719 -289.168572) (xy 344.401948 -289.08887) (xy 344.372439 -289.006643)
			(xy 344.3605 -288.964624) (xy 344.355166 -288.944812) (xy 344.354912 -288.943542) (xy 344.35161 -288.933382)
			(xy 344.341958 -288.920174) (xy 344.3351 -288.915348) (xy 344.315483 -288.900927) (xy 344.280661 -288.866901)
			(xy 344.25168 -288.82778) (xy 344.229276 -288.784556) (xy 344.214016 -288.738323) (xy 344.206288 -288.690254)
			(xy 344.206286 -288.641569) (xy 344.214011 -288.593499) (xy 344.229267 -288.547266) (xy 344.251668 -288.504039)
			(xy 344.280646 -288.464916) (xy 344.315465 -288.430888) (xy 344.3351 -288.416492) (xy 344.341958 -288.411666)
			(xy 344.35161 -288.398458) (xy 344.354912 -288.388044) (xy 344.35542 -288.386266) (xy 344.367276 -288.341665)
			(xy 344.397319 -288.254397) (xy 344.434383 -288.169872) (xy 344.47822 -288.088652) (xy 344.502994 -288.049716)
			(xy 344.507058 -288.043366) (xy 344.511122 -288.029396) (xy 344.511122 -287.682432) (xy 344.507058 -287.668462)
			(xy 344.502994 -287.662112) (xy 344.479348 -287.624987) (xy 344.437238 -287.547685) (xy 344.401271 -287.46734)
			(xy 344.371666 -287.384441) (xy 344.359738 -287.342072) (xy 344.355166 -287.3248) (xy 344.354912 -287.32353)
			(xy 344.35161 -287.31337) (xy 344.341958 -287.300162) (xy 344.3351 -287.295336) (xy 344.315484 -287.280915)
			(xy 344.280664 -287.24689) (xy 344.251685 -287.207769) (xy 344.229283 -287.164545) (xy 344.214024 -287.118314)
			(xy 344.206297 -287.070247) (xy 344.206296 -287.021562) (xy 344.214022 -286.973495) (xy 344.229279 -286.927263)
			(xy 344.25168 -286.884039) (xy 344.280658 -286.844917) (xy 344.315477 -286.810891) (xy 344.3351 -286.79648)
			(xy 344.341958 -286.791654) (xy 344.35161 -286.778446) (xy 344.354912 -286.768032) (xy 344.35542 -286.766254)
			(xy 344.367277 -286.721654) (xy 344.397321 -286.634386) (xy 344.434385 -286.549861) (xy 344.478223 -286.468642)
			(xy 344.502994 -286.429704) (xy 344.507058 -286.423354) (xy 344.511122 -286.409384) (xy 344.511122 -286.062674)
			(xy 344.507058 -286.048704) (xy 344.502994 -286.042354) (xy 344.479536 -286.005504) (xy 344.437716 -285.928803)
			(xy 344.401943 -285.849101) (xy 344.372432 -285.766875) (xy 344.3605 -285.724854) (xy 344.355166 -285.705042)
			(xy 344.354912 -285.703772) (xy 344.35161 -285.693612) (xy 344.341958 -285.680404) (xy 344.3351 -285.675578)
			(xy 344.31548 -285.661157) (xy 344.280654 -285.62713) (xy 344.251669 -285.588008) (xy 344.22926 -285.544781)
			(xy 344.213997 -285.498546) (xy 344.206265 -285.450474) (xy 344.20626 -285.401784) (xy 344.213983 -285.353711)
			(xy 344.229238 -285.307472) (xy 344.251638 -285.264241) (xy 344.280616 -285.225113) (xy 344.315436 -285.19108)
			(xy 344.3351 -285.176722) (xy 344.341958 -285.171896) (xy 344.35161 -285.158688) (xy 344.354912 -285.148274)
			(xy 344.35542 -285.146496) (xy 344.367275 -285.101895) (xy 344.397316 -285.014626) (xy 344.434378 -284.930099)
			(xy 344.478214 -284.848878) (xy 344.502994 -284.809946) (xy 344.507058 -284.803596) (xy 344.511122 -284.789626)
			(xy 344.511122 -284.442662) (xy 344.507058 -284.428692) (xy 344.502994 -284.422342) (xy 344.479537 -284.385492)
			(xy 344.437717 -284.308791) (xy 344.401945 -284.229089) (xy 344.372435 -284.146863) (xy 344.3605 -284.104842)
			(xy 344.355166 -284.08503) (xy 344.354912 -284.08376) (xy 344.35161 -284.0736) (xy 344.341958 -284.060392)
			(xy 344.3351 -284.055566) (xy 344.315481 -284.041145) (xy 344.280657 -284.007119) (xy 344.251673 -283.967997)
			(xy 344.229267 -283.924771) (xy 344.214005 -283.878537) (xy 344.206274 -283.830466) (xy 344.20627 -283.781778)
			(xy 344.213994 -283.733706) (xy 344.22925 -283.68747) (xy 344.25165 -283.64424) (xy 344.280628 -283.605114)
			(xy 344.315448 -283.571083) (xy 344.3351 -283.55671) (xy 344.341958 -283.551884) (xy 344.35161 -283.538676)
			(xy 344.354912 -283.528262) (xy 344.35542 -283.526484) (xy 344.367276 -283.481883) (xy 344.397317 -283.394614)
			(xy 344.43438 -283.310088) (xy 344.478216 -283.228868) (xy 344.502994 -283.189934) (xy 344.507058 -283.183584)
			(xy 344.511122 -283.169614) (xy 344.511122 -282.82265) (xy 344.507058 -282.80868) (xy 344.502994 -282.80233)
			(xy 344.479537 -282.76548) (xy 344.437718 -282.688778) (xy 344.401947 -282.609076) (xy 344.372438 -282.52685)
			(xy 344.3605 -282.48483) (xy 344.355166 -282.465018) (xy 344.354912 -282.463748) (xy 344.35161 -282.453588)
			(xy 344.341958 -282.44038) (xy 344.3351 -282.435554) (xy 344.315482 -282.421133) (xy 344.280659 -282.387107)
			(xy 344.251678 -282.347986) (xy 344.229273 -282.304761) (xy 344.214013 -282.258527) (xy 344.206283 -282.210458)
			(xy 344.206281 -282.161772) (xy 344.214005 -282.113702) (xy 344.229262 -282.067467) (xy 344.251662 -282.02424)
			(xy 344.28064 -281.985116) (xy 344.315459 -281.951086) (xy 344.3351 -281.936698) (xy 344.341958 -281.931872)
			(xy 344.35161 -281.918664) (xy 344.354912 -281.90825) (xy 344.35542 -281.906472) (xy 344.367276 -281.861871)
			(xy 344.397319 -281.774603) (xy 344.434382 -281.690077) (xy 344.478219 -281.608858) (xy 344.502994 -281.569922)
			(xy 344.507058 -281.563572) (xy 344.511122 -281.549602) (xy 344.511122 -281.202638) (xy 344.507058 -281.188668)
			(xy 344.502994 -281.182318) (xy 344.479537 -281.145468) (xy 344.437719 -281.068766) (xy 344.401949 -280.989063)
			(xy 344.372441 -280.906837) (xy 344.3605 -280.864818) (xy 344.355166 -280.845006) (xy 344.354912 -280.843736)
			(xy 344.35161 -280.833576) (xy 344.341958 -280.820368) (xy 344.3351 -280.815542) (xy 344.314767 -280.800547)
			(xy 344.278856 -280.765016) (xy 344.24928 -280.724061) (xy 344.226845 -280.678798) (xy 344.212163 -280.63046)
			(xy 344.208354 -280.605484) (xy 344.207592 -280.600658) (xy 344.207592 -280.600404) (xy 344.206576 -280.592276)
			(xy 344.192606 -280.561288) (xy 344.186256 -280.554938) (xy 344.15476 -280.521156) (xy 344.152982 -280.519378)
			(xy 344.15222 -280.518616) (xy 344.123052 -280.48537) (xy 344.06935 -280.415089) (xy 344.021232 -280.340872)
			(xy 343.978986 -280.263163) (xy 343.942864 -280.182425) (xy 343.913081 -280.099139) (xy 343.901014 -280.05659)
			(xy 343.898072 -280.047338) (xy 343.886448 -280.031806) (xy 343.878408 -280.026364) (xy 343.855503 -280.011927)
			(xy 343.814558 -279.976505) (xy 343.780255 -279.934619) (xy 343.753597 -279.887497) (xy 343.735367 -279.836518)
			(xy 343.726098 -279.783178) (xy 343.7255 -279.756108) (xy 343.725981 -279.731657) (xy 343.733564 -279.683345)
			(xy 343.748504 -279.636779) (xy 343.770444 -279.593074) (xy 343.798859 -279.553273) (xy 343.83307 -279.518327)
			(xy 343.872258 -279.489074) (xy 343.893648 -279.477216) (xy 343.897204 -279.46985) (xy 343.898982 -279.464262)
			(xy 343.912016 -279.416861) (xy 343.945136 -279.324293) (xy 343.986078 -279.234909) (xy 344.034542 -279.149369)
			(xy 344.09017 -279.068306) (xy 344.152551 -278.992316) (xy 344.18651 -278.95677) (xy 344.192606 -278.950674)
			(xy 344.20683 -278.919686) (xy 344.207846 -278.911558) (xy 344.211293 -278.886041) (xy 344.225623 -278.836589)
			(xy 344.248039 -278.790238) (xy 344.277907 -278.748301) (xy 344.314382 -278.711963) (xy 344.3351 -278.696674)
			(xy 344.341958 -278.691848) (xy 344.35161 -278.67864) (xy 344.354912 -278.668226) (xy 344.366772 -278.623387)
			(xy 344.396876 -278.535649) (xy 344.434068 -278.450674) (xy 344.478098 -278.369031) (xy 344.502994 -278.329898)
			(xy 344.507058 -278.323548) (xy 344.511122 -278.309578) (xy 344.511122 -277.962614) (xy 344.507058 -277.948644)
			(xy 344.502994 -277.942294) (xy 344.478141 -277.903218) (xy 344.434182 -277.821699) (xy 344.397049 -277.736852)
			(xy 344.366992 -277.649249) (xy 344.355166 -277.604474) (xy 344.35257 -277.595822) (xy 344.342292 -277.580983)
			(xy 344.3351 -277.575518) (xy 344.315485 -277.561097) (xy 344.280668 -277.527072) (xy 344.251692 -277.487953)
			(xy 344.229292 -277.44473) (xy 344.214036 -277.3985) (xy 344.206311 -277.350435) (xy 344.206312 -277.301753)
			(xy 344.214039 -277.253688) (xy 344.229297 -277.207459) (xy 344.251698 -277.164238) (xy 344.280675 -277.125119)
			(xy 344.315494 -277.091096) (xy 344.3351 -277.076662) (xy 344.342273 -277.071181) (xy 344.352532 -277.056342)
			(xy 344.355166 -277.047706) (xy 344.367022 -277.002941) (xy 344.397094 -276.915345) (xy 344.434222 -276.8305)
			(xy 344.478159 -276.748972) (xy 344.502994 -276.709886) (xy 344.507058 -276.703536) (xy 344.511122 -276.689566)
			(xy 344.511122 -276.342602) (xy 344.507058 -276.328632) (xy 344.502994 -276.322282) (xy 344.478141 -276.283205)
			(xy 344.434183 -276.201686) (xy 344.397051 -276.116839) (xy 344.366995 -276.029236) (xy 344.355166 -275.984462)
			(xy 344.352568 -275.975811) (xy 344.342288 -275.960975) (xy 344.3351 -275.955506) (xy 344.315486 -275.941085)
			(xy 344.280671 -275.90706) (xy 344.251697 -275.867941) (xy 344.229299 -275.82472) (xy 344.214044 -275.778491)
			(xy 344.20632 -275.730428) (xy 344.206322 -275.681747) (xy 344.21405 -275.633684) (xy 344.229308 -275.587457)
			(xy 344.25171 -275.544237) (xy 344.280687 -275.50512) (xy 344.315506 -275.471099) (xy 344.3351 -275.45665)
			(xy 344.342282 -275.451175) (xy 344.352566 -275.436343) (xy 344.355166 -275.427694) (xy 344.367023 -275.382929)
			(xy 344.397096 -275.295334) (xy 344.434224 -275.210489) (xy 344.478161 -275.128962) (xy 344.502994 -275.089874)
			(xy 344.507058 -275.083524) (xy 344.511122 -275.069554) (xy 344.511122 -274.72259) (xy 344.507058 -274.70862)
			(xy 344.502994 -274.70227) (xy 344.478141 -274.663193) (xy 344.434184 -274.581674) (xy 344.397053 -274.496827)
			(xy 344.366998 -274.409223) (xy 344.355166 -274.36445) (xy 344.352567 -274.355801) (xy 344.342284 -274.340967)
			(xy 344.3351 -274.335494) (xy 344.315487 -274.321073) (xy 344.280674 -274.287049) (xy 344.251701 -274.24793)
			(xy 344.229305 -274.20471) (xy 344.214052 -274.158482) (xy 344.206329 -274.11042) (xy 344.206332 -274.061741)
			(xy 344.214061 -274.01368) (xy 344.22932 -273.967454) (xy 344.251722 -273.924236) (xy 344.280699 -273.885122)
			(xy 344.315517 -273.851102) (xy 344.3351 -273.836638) (xy 344.342281 -273.831162) (xy 344.352561 -273.816329)
			(xy 344.355166 -273.807682) (xy 344.367023 -273.762917) (xy 344.397097 -273.675323) (xy 344.434226 -273.590478)
			(xy 344.478164 -273.508951) (xy 344.502994 -273.469862) (xy 344.506791 -273.463583) (xy 344.51093 -273.449511)
			(xy 344.511122 -273.442176) (xy 344.511122 -272.799556) (xy 344.486484 -272.771108) (xy 344.467688 -272.768314)
			(xy 344.443762 -272.764407) (xy 344.39747 -272.750018) (xy 344.354034 -272.728496) (xy 344.314544 -272.70038)
			(xy 344.279993 -272.666377) (xy 344.251249 -272.627342) (xy 344.229035 -272.584255) (xy 344.213908 -272.538199)
			(xy 344.206249 -272.490332) (xy 344.20625 -272.441855) (xy 344.213911 -272.393988) (xy 344.22904 -272.347933)
			(xy 344.251256 -272.304847) (xy 344.280002 -272.265813) (xy 344.314554 -272.231812) (xy 344.354045 -272.203697)
			(xy 344.397483 -272.182177) (xy 344.443775 -272.16779) (xy 344.467688 -272.163794) (xy 344.486484 -272.161)
			(xy 344.511122 -272.132552) (xy 344.511122 -271.179544) (xy 344.486484 -271.151096) (xy 344.467688 -271.148302)
			(xy 344.443755 -271.144395) (xy 344.39745 -271.130004) (xy 344.354 -271.108477) (xy 344.314497 -271.080355)
			(xy 344.279935 -271.046344) (xy 344.251181 -271.007299) (xy 344.228959 -270.9642) (xy 344.213826 -270.918132)
			(xy 344.206163 -270.870251) (xy 344.206162 -270.821761) (xy 344.213823 -270.77388) (xy 344.228954 -270.727811)
			(xy 344.251175 -270.684712) (xy 344.279927 -270.645665) (xy 344.314488 -270.611653) (xy 344.353989 -270.583529)
			(xy 344.397438 -270.562) (xy 344.443744 -270.547608) (xy 344.467688 -270.543782) (xy 344.486484 -270.540988)
			(xy 344.511122 -270.51254) (xy 344.511122 -269.559532) (xy 344.486484 -269.531084) (xy 344.467688 -269.52829)
			(xy 344.443756 -269.524383) (xy 344.397452 -269.509993) (xy 344.354004 -269.488466) (xy 344.314504 -269.460345)
			(xy 344.279943 -269.426335) (xy 344.251191 -269.387291) (xy 344.228969 -269.344194) (xy 344.213837 -269.298128)
			(xy 344.206174 -269.250248) (xy 344.206174 -269.20176) (xy 344.213835 -269.153881) (xy 344.228966 -269.107814)
			(xy 344.251186 -269.064716) (xy 344.279937 -269.025672) (xy 344.314497 -268.991661) (xy 344.353997 -268.963538)
			(xy 344.397444 -268.94201) (xy 344.443748 -268.927619) (xy 344.467688 -268.92377) (xy 344.486484 -268.920976)
			(xy 344.511122 -268.892528) (xy 344.511122 -268.56436) (xy 344.511553 -268.554293) (xy 344.51928 -268.535702)
			(xy 344.526108 -268.528292) (xy 344.661998 -268.392402) (xy 344.670126 -268.38148) (xy 344.680032 -268.364208)
			(xy 344.681556 -268.356334) (xy 344.687156 -268.330914) (xy 344.705835 -268.282334) (xy 344.732487 -268.237627)
			(xy 344.766339 -268.198092) (xy 344.806409 -268.164875) (xy 344.851534 -268.138939) (xy 344.900407 -268.121037)
			(xy 344.925904 -268.115796) (xy 344.933778 -268.114272) (xy 344.946986 -268.107414) (xy 345.1987 -267.8557)
			(xy 345.204993 -267.848756) (xy 345.212526 -267.831616) (xy 345.213404 -267.812914) (xy 345.210892 -267.803884)
			(xy 345.205558 -267.787882) (xy 345.20124 -267.781786) (xy 345.188201 -267.762414) (xy 345.167525 -267.720546)
			(xy 345.153456 -267.67602) (xy 345.146321 -267.629873) (xy 345.145868 -267.606526) (xy 345.145868 -267.606018)
			(xy 345.146337 -267.582025) (xy 345.153841 -267.53463) (xy 345.168666 -267.488992) (xy 345.190449 -267.446235)
			(xy 345.218651 -267.407412) (xy 345.25258 -267.373479) (xy 345.291399 -267.345271) (xy 345.334153 -267.323483)
			(xy 345.379789 -267.308651) (xy 345.427183 -267.301141) (xy 345.451176 -267.30071) (xy 345.474968 -267.301163)
			(xy 345.521976 -267.308539) (xy 345.567272 -267.323118) (xy 345.609758 -267.344545) (xy 345.648406 -267.372303)
			(xy 345.682282 -267.405719) (xy 345.710565 -267.443985) (xy 345.732571 -267.486174) (xy 345.747766 -267.531266)
			(xy 345.755784 -267.57817) (xy 345.756484 -267.601954) (xy 345.756484 -267.606272) (xy 345.755791 -267.635108)
			(xy 345.744922 -267.691749) (xy 345.734894 -267.718794) (xy 345.734894 -267.719048) (xy 345.73086 -267.730852)
			(xy 345.733505 -267.755629) (xy 345.739974 -267.766292) (xy 345.787218 -267.835888) (xy 345.79475 -267.845903)
			(xy 345.816866 -267.857618) (xy 345.829382 -267.85824) (xy 346.013024 -267.85824) (xy 346.025436 -267.857615)
			(xy 346.047387 -267.846019) (xy 346.054934 -267.836142) (xy 346.102432 -267.766546) (xy 346.1089 -267.755809)
			(xy 346.111558 -267.730913) (xy 346.107512 -267.719048) (xy 346.107512 -267.718794) (xy 346.097549 -267.691995)
			(xy 346.086678 -267.635869) (xy 346.085922 -267.607288) (xy 346.085922 -267.601954) (xy 346.086759 -267.576919)
			(xy 346.095591 -267.527616) (xy 346.112352 -267.480415) (xy 346.136591 -267.436583) (xy 346.16766 -267.397295)
			(xy 346.204724 -267.363604) (xy 346.24679 -267.336414) (xy 346.292729 -267.316455) (xy 346.34131 -267.304261)
			(xy 346.39123 -267.30016) (xy 346.44115 -267.304261) (xy 346.489731 -267.316455) (xy 346.53567 -267.336414)
			(xy 346.577736 -267.363604) (xy 346.6148 -267.397295) (xy 346.645869 -267.436583) (xy 346.670108 -267.480415)
			(xy 346.686869 -267.527616) (xy 346.695701 -267.576919) (xy 346.696538 -267.601954) (xy 346.696538 -267.606272)
			(xy 346.695845 -267.635108) (xy 346.684974 -267.691748) (xy 346.674948 -267.718794) (xy 346.674948 -267.719048)
			(xy 346.670915 -267.730852) (xy 346.673559 -267.755629) (xy 346.680028 -267.766292) (xy 346.727272 -267.835888)
			(xy 346.734801 -267.84591) (xy 346.756916 -267.857645) (xy 346.769436 -267.85824) (xy 347.687138 -267.85824)
			(xy 347.695774 -267.857478) (xy 347.703289 -267.855871) (xy 347.716967 -267.848884) (xy 347.722698 -267.843762)
			(xy 347.95841 -267.60805) (xy 347.96603 -267.59154) (xy 347.966792 -267.582396) (xy 347.969105 -267.558473)
			(xy 347.980297 -267.511734) (xy 347.998673 -267.467325) (xy 348.023779 -267.426344) (xy 348.054995 -267.389801)
			(xy 348.091551 -267.358601) (xy 348.132544 -267.333512) (xy 348.17696 -267.315156) (xy 348.200218 -267.309092)
			(xy 348.217236 -267.305028) (xy 348.23908 -267.277342) (xy 348.23908 -266.349734) (xy 348.23908 -266.347702)
			(xy 348.238518 -266.339642) (xy 348.232963 -266.324478) (xy 348.228158 -266.317984) (xy 348.205552 -266.28979)
			(xy 348.192852 -266.281154) (xy 348.184978 -266.278868) (xy 348.161586 -266.27148) (xy 348.117344 -266.250294)
			(xy 348.07706 -266.222306) (xy 348.041769 -266.188236) (xy 348.012381 -266.148962) (xy 347.989651 -266.105493)
			(xy 347.974165 -266.058949) (xy 347.966321 -266.010528) (xy 347.96632 -265.961475) (xy 347.974164 -265.913054)
			(xy 347.98965 -265.86651) (xy 348.012379 -265.823041) (xy 348.041767 -265.783766) (xy 348.077057 -265.749696)
			(xy 348.117341 -265.721708) (xy 348.161583 -265.700521) (xy 348.184978 -265.693144) (xy 348.192852 -265.690858)
			(xy 348.205552 -265.682222) (xy 348.228158 -265.654028) (xy 348.232931 -265.647515) (xy 348.238492 -265.632364)
			(xy 348.23908 -265.62431) (xy 348.23908 -265.415522) (xy 348.238642 -265.405459) (xy 348.230906 -265.386877)
			(xy 348.224094 -265.379454) (xy 348.196154 -265.351514) (xy 348.188121 -265.34425) (xy 348.167868 -265.33663)
			(xy 348.157038 -265.336782) (xy 348.081346 -265.341608) (xy 348.072238 -265.342578) (xy 348.055569 -265.350133)
			(xy 348.048834 -265.35634) (xy 348.043754 -265.36142) (xy 348.041976 -265.36396) (xy 348.027402 -265.381911)
			(xy 347.99376 -265.41363) (xy 347.955722 -265.439917) (xy 347.914157 -265.460172) (xy 347.870015 -265.473931)
			(xy 347.824303 -265.480882) (xy 347.801184 -265.481308) (xy 347.776946 -265.480842) (xy 347.729079 -265.473182)
			(xy 347.683023 -265.458056) (xy 347.639935 -265.435845) (xy 347.600896 -265.407106) (xy 347.566888 -265.372561)
			(xy 347.538763 -265.333078) (xy 347.517229 -265.289647) (xy 347.502826 -265.24336) (xy 347.498924 -265.219434)
			(xy 347.49613 -265.200638) (xy 347.467682 -265.176) (xy 347.194632 -265.176) (xy 347.166184 -265.200638)
			(xy 347.16339 -265.219434) (xy 347.159481 -265.243362) (xy 347.145089 -265.289658) (xy 347.123563 -265.333099)
			(xy 347.095443 -265.372592) (xy 347.061436 -265.407147) (xy 347.022396 -265.435893) (xy 346.979304 -265.45811)
			(xy 346.933243 -265.473239) (xy 346.885371 -265.480899) (xy 346.836889 -265.480899) (xy 346.789017 -265.473239)
			(xy 346.742956 -265.45811) (xy 346.699864 -265.435893) (xy 346.660824 -265.407147) (xy 346.626817 -265.372592)
			(xy 346.598697 -265.333099) (xy 346.577171 -265.289658) (xy 346.562779 -265.243362) (xy 346.55887 -265.219434)
			(xy 346.556076 -265.200638) (xy 346.527628 -265.176) (xy 346.254578 -265.176) (xy 346.22613 -265.200638)
			(xy 346.223336 -265.219434) (xy 346.219427 -265.243362) (xy 346.205035 -265.289658) (xy 346.183509 -265.333099)
			(xy 346.155389 -265.372592) (xy 346.121382 -265.407147) (xy 346.082342 -265.435893) (xy 346.03925 -265.45811)
			(xy 345.993189 -265.473239) (xy 345.945317 -265.480899) (xy 345.896835 -265.480899) (xy 345.848963 -265.473239)
			(xy 345.802902 -265.45811) (xy 345.75981 -265.435893) (xy 345.72077 -265.407147) (xy 345.686763 -265.372592)
			(xy 345.658643 -265.333099) (xy 345.637117 -265.289658) (xy 345.622725 -265.243362) (xy 345.618816 -265.219434)
			(xy 345.616022 -265.200638) (xy 345.587574 -265.176) (xy 345.314524 -265.176) (xy 345.286076 -265.200638)
			(xy 345.283282 -265.219434) (xy 345.279373 -265.243362) (xy 345.264981 -265.289658) (xy 345.243455 -265.333099)
			(xy 345.215335 -265.372592) (xy 345.181328 -265.407147) (xy 345.142288 -265.435893) (xy 345.099196 -265.45811)
			(xy 345.053135 -265.473239) (xy 345.005263 -265.480899) (xy 344.956781 -265.480899) (xy 344.908909 -265.473239)
			(xy 344.862848 -265.45811) (xy 344.819756 -265.435893) (xy 344.780716 -265.407147) (xy 344.746709 -265.372592)
			(xy 344.718589 -265.333099) (xy 344.697063 -265.289658) (xy 344.682671 -265.243362) (xy 344.678762 -265.219434)
			(xy 344.675968 -265.200638) (xy 344.64752 -265.176) (xy 344.374724 -265.176) (xy 344.346276 -265.200638)
			(xy 344.343482 -265.219434) (xy 344.339573 -265.243362) (xy 344.325181 -265.289658) (xy 344.303655 -265.333099)
			(xy 344.275535 -265.372592) (xy 344.241528 -265.407147) (xy 344.202488 -265.435893) (xy 344.159396 -265.45811)
			(xy 344.113335 -265.473239) (xy 344.065463 -265.480899) (xy 344.016981 -265.480899) (xy 343.969109 -265.473239)
			(xy 343.923048 -265.45811) (xy 343.879956 -265.435893) (xy 343.840916 -265.407147) (xy 343.806909 -265.372592)
			(xy 343.778789 -265.333099) (xy 343.757263 -265.289658) (xy 343.742871 -265.243362) (xy 343.738962 -265.219434)
			(xy 343.736168 -265.200638) (xy 343.70772 -265.176) (xy 343.43467 -265.176) (xy 343.406222 -265.200638)
			(xy 343.403428 -265.219434) (xy 343.399519 -265.243362) (xy 343.385127 -265.289658) (xy 343.363601 -265.333099)
			(xy 343.335481 -265.372592) (xy 343.301474 -265.407147) (xy 343.262434 -265.435893) (xy 343.219342 -265.45811)
			(xy 343.173281 -265.473239) (xy 343.125409 -265.480899) (xy 343.076927 -265.480899) (xy 343.029055 -265.473239)
			(xy 342.982994 -265.45811) (xy 342.939902 -265.435893) (xy 342.900862 -265.407147) (xy 342.866855 -265.372592)
			(xy 342.838735 -265.333099) (xy 342.817209 -265.289658) (xy 342.802817 -265.243362) (xy 342.798908 -265.219434)
			(xy 342.796114 -265.200638) (xy 342.767666 -265.176) (xy 342.50503 -265.176) (xy 342.476328 -265.200892)
			(xy 342.473788 -265.219688) (xy 342.469811 -265.244495) (xy 342.45503 -265.29251) (xy 342.432832 -265.337578)
			(xy 342.403778 -265.378563) (xy 342.3686 -265.41443) (xy 342.328186 -265.444274) (xy 342.283557 -265.467342)
			(xy 342.235838 -265.483052) (xy 342.186233 -265.491007) (xy 342.135995 -265.491007) (xy 342.08639 -265.483052)
			(xy 342.038671 -265.467342) (xy 341.994042 -265.444274) (xy 341.953628 -265.41443) (xy 341.91845 -265.378563)
			(xy 341.889396 -265.337578) (xy 341.867198 -265.29251) (xy 341.852417 -265.244495) (xy 341.84844 -265.219688)
			(xy 341.8459 -265.200892) (xy 341.817198 -265.176) (xy 341.554562 -265.176) (xy 341.526114 -265.200638)
			(xy 341.52332 -265.219434) (xy 341.519411 -265.243362) (xy 341.505019 -265.289658) (xy 341.483493 -265.333099)
			(xy 341.455373 -265.372592) (xy 341.421366 -265.407147) (xy 341.382326 -265.435893) (xy 341.339234 -265.45811)
			(xy 341.293173 -265.473239) (xy 341.245301 -265.480899) (xy 341.196819 -265.480899) (xy 341.148947 -265.473239)
			(xy 341.102886 -265.45811) (xy 341.059794 -265.435893) (xy 341.020754 -265.407147) (xy 340.986747 -265.372592)
			(xy 340.958627 -265.333099) (xy 340.937101 -265.289658) (xy 340.922709 -265.243362) (xy 340.9188 -265.219434)
			(xy 340.916006 -265.200638) (xy 340.887558 -265.176) (xy 340.614508 -265.176) (xy 340.58606 -265.200638)
			(xy 340.583266 -265.219434) (xy 340.579357 -265.243362) (xy 340.564965 -265.289658) (xy 340.543439 -265.333099)
			(xy 340.515319 -265.372592) (xy 340.481312 -265.407147) (xy 340.442272 -265.435893) (xy 340.39918 -265.45811)
			(xy 340.353119 -265.473239) (xy 340.305247 -265.480899) (xy 340.256765 -265.480899) (xy 340.208893 -265.473239)
			(xy 340.162832 -265.45811) (xy 340.11974 -265.435893) (xy 340.0807 -265.407147) (xy 340.046693 -265.372592)
			(xy 340.018573 -265.333099) (xy 339.997047 -265.289658) (xy 339.982655 -265.243362) (xy 339.978746 -265.219434)
			(xy 339.975952 -265.200638) (xy 339.947504 -265.176) (xy 339.685122 -265.176) (xy 339.65642 -265.200892)
			(xy 339.65388 -265.219688) (xy 339.649903 -265.244495) (xy 339.635122 -265.29251) (xy 339.612924 -265.337578)
			(xy 339.58387 -265.378563) (xy 339.548692 -265.41443) (xy 339.508278 -265.444274) (xy 339.463649 -265.467342)
			(xy 339.41593 -265.483052) (xy 339.366325 -265.491007) (xy 339.316087 -265.491007) (xy 339.266482 -265.483052)
			(xy 339.218763 -265.467342) (xy 339.174134 -265.444274) (xy 339.13372 -265.41443) (xy 339.098542 -265.378563)
			(xy 339.069488 -265.337578) (xy 339.04729 -265.29251) (xy 339.032509 -265.244495) (xy 339.028532 -265.219688)
			(xy 339.025992 -265.200892) (xy 338.99729 -265.176) (xy 338.762086 -265.176) (xy 338.752017 -265.176426)
			(xy 338.733416 -265.184144) (xy 338.726018 -265.190986) (xy 338.710524 -265.20648) (xy 338.703412 -265.220196)
			(xy 338.701888 -265.22807) (xy 338.697469 -265.251091) (xy 338.682506 -265.295515) (xy 338.660928 -265.337128)
			(xy 338.633243 -265.374954) (xy 338.6001 -265.408104) (xy 338.562279 -265.435797) (xy 338.52067 -265.457383)
			(xy 338.47625 -265.472354) (xy 338.453222 -265.476736) (xy 338.445348 -265.47826) (xy 338.431632 -265.485372)
			(xy 338.180172 -265.736832) (xy 338.174054 -265.743541) (xy 338.166559 -265.760066) (xy 338.165243 -265.778163)
			(xy 338.170269 -265.795598) (xy 338.175346 -265.803126) (xy 338.189667 -265.823047) (xy 338.212428 -265.866507)
			(xy 338.227936 -265.91305) (xy 338.235791 -265.961476) (xy 338.236306 -265.986006) (xy 338.565248 -265.986006)
			(xy 338.569208 -265.936952) (xy 338.580985 -265.889168) (xy 338.600276 -265.843892) (xy 338.626579 -265.802296)
			(xy 338.659214 -265.765459) (xy 338.697335 -265.734334) (xy 338.739956 -265.709727) (xy 338.785972 -265.692275)
			(xy 338.834191 -265.682431) (xy 338.883366 -265.68045) (xy 338.932221 -265.686382) (xy 338.979492 -265.700074)
			(xy 339.023954 -265.721172) (xy 339.064457 -265.749128) (xy 339.09995 -265.78322) (xy 339.129515 -265.822564)
			(xy 339.152386 -265.866141) (xy 339.16797 -265.912822) (xy 339.175865 -265.961399) (xy 339.17636 -265.986006)
			(xy 339.505302 -265.986006) (xy 339.509262 -265.936952) (xy 339.521039 -265.889168) (xy 339.54033 -265.843892)
			(xy 339.566633 -265.802296) (xy 339.599268 -265.765459) (xy 339.637389 -265.734334) (xy 339.68001 -265.709727)
			(xy 339.726026 -265.692275) (xy 339.774245 -265.682431) (xy 339.82342 -265.68045) (xy 339.872275 -265.686382)
			(xy 339.919546 -265.700074) (xy 339.964008 -265.721172) (xy 340.004511 -265.749128) (xy 340.040004 -265.78322)
			(xy 340.069569 -265.822564) (xy 340.09244 -265.866141) (xy 340.108024 -265.912822) (xy 340.115919 -265.961399)
			(xy 340.116414 -265.986006) (xy 340.434925 -265.986006) (xy 340.43902 -265.935278) (xy 340.451199 -265.885864)
			(xy 340.471147 -265.839044) (xy 340.498348 -265.79603) (xy 340.532096 -265.757936) (xy 340.571518 -265.725749)
			(xy 340.615592 -265.700303) (xy 340.663178 -265.682256) (xy 340.713042 -265.672076) (xy 340.763894 -265.670027)
			(xy 340.814415 -265.676161) (xy 340.863299 -265.690321) (xy 340.909278 -265.712138) (xy 340.951162 -265.741048)
			(xy 340.987866 -265.776303) (xy 341.018439 -265.816989) (xy 341.04209 -265.862052) (xy 341.058206 -265.910326)
			(xy 341.06637 -265.96056) (xy 341.066882 -265.986006) (xy 341.38541 -265.986006) (xy 341.38937 -265.936952)
			(xy 341.401147 -265.889168) (xy 341.420438 -265.843892) (xy 341.446741 -265.802296) (xy 341.479376 -265.765459)
			(xy 341.517497 -265.734334) (xy 341.560118 -265.709727) (xy 341.606134 -265.692275) (xy 341.654353 -265.682431)
			(xy 341.703528 -265.68045) (xy 341.752383 -265.686382) (xy 341.799654 -265.700074) (xy 341.844116 -265.721172)
			(xy 341.884619 -265.749128) (xy 341.920112 -265.78322) (xy 341.949677 -265.822564) (xy 341.972548 -265.866141)
			(xy 341.988132 -265.912822) (xy 341.996027 -265.961399) (xy 341.996522 -265.986006) (xy 342.32521 -265.986006)
			(xy 342.32917 -265.936952) (xy 342.340947 -265.889168) (xy 342.360238 -265.843892) (xy 342.386541 -265.802296)
			(xy 342.419176 -265.765459) (xy 342.457297 -265.734334) (xy 342.499918 -265.709727) (xy 342.545934 -265.692275)
			(xy 342.594153 -265.682431) (xy 342.643328 -265.68045) (xy 342.692183 -265.686382) (xy 342.739454 -265.700074)
			(xy 342.783916 -265.721172) (xy 342.824419 -265.749128) (xy 342.859912 -265.78322) (xy 342.889477 -265.822564)
			(xy 342.912348 -265.866141) (xy 342.927932 -265.912822) (xy 342.935827 -265.961399) (xy 342.936322 -265.986006)
			(xy 343.254833 -265.986006) (xy 343.258928 -265.935278) (xy 343.271107 -265.885864) (xy 343.291055 -265.839044)
			(xy 343.318256 -265.79603) (xy 343.352004 -265.757936) (xy 343.391426 -265.725749) (xy 343.4355 -265.700303)
			(xy 343.483086 -265.682256) (xy 343.53295 -265.672076) (xy 343.583802 -265.670027) (xy 343.634323 -265.676161)
			(xy 343.683207 -265.690321) (xy 343.729186 -265.712138) (xy 343.77107 -265.741048) (xy 343.807774 -265.776303)
			(xy 343.838347 -265.816989) (xy 343.861998 -265.862052) (xy 343.878114 -265.910326) (xy 343.886278 -265.96056)
			(xy 343.88679 -265.986006) (xy 344.205318 -265.986006) (xy 344.209278 -265.936952) (xy 344.221055 -265.889168)
			(xy 344.240346 -265.843892) (xy 344.266649 -265.802296) (xy 344.299284 -265.765459) (xy 344.337405 -265.734334)
			(xy 344.380026 -265.709727) (xy 344.426042 -265.692275) (xy 344.474261 -265.682431) (xy 344.523436 -265.68045)
			(xy 344.572291 -265.686382) (xy 344.619562 -265.700074) (xy 344.664024 -265.721172) (xy 344.704527 -265.749128)
			(xy 344.74002 -265.78322) (xy 344.769585 -265.822564) (xy 344.792456 -265.866141) (xy 344.80804 -265.912822)
			(xy 344.815935 -265.961399) (xy 344.81643 -265.986006) (xy 345.145372 -265.986006) (xy 345.149332 -265.936952)
			(xy 345.161109 -265.889168) (xy 345.1804 -265.843892) (xy 345.206703 -265.802296) (xy 345.239338 -265.765459)
			(xy 345.277459 -265.734334) (xy 345.32008 -265.709727) (xy 345.366096 -265.692275) (xy 345.414315 -265.682431)
			(xy 345.46349 -265.68045) (xy 345.512345 -265.686382) (xy 345.559616 -265.700074) (xy 345.604078 -265.721172)
			(xy 345.644581 -265.749128) (xy 345.680074 -265.78322) (xy 345.709639 -265.822564) (xy 345.73251 -265.866141)
			(xy 345.748094 -265.912822) (xy 345.755989 -265.961399) (xy 345.756484 -265.986006) (xy 346.085426 -265.986006)
			(xy 346.089386 -265.936952) (xy 346.101163 -265.889168) (xy 346.120454 -265.843892) (xy 346.146757 -265.802296)
			(xy 346.179392 -265.765459) (xy 346.217513 -265.734334) (xy 346.260134 -265.709727) (xy 346.30615 -265.692275)
			(xy 346.354369 -265.682431) (xy 346.403544 -265.68045) (xy 346.452399 -265.686382) (xy 346.49967 -265.700074)
			(xy 346.544132 -265.721172) (xy 346.584635 -265.749128) (xy 346.620128 -265.78322) (xy 346.649693 -265.822564)
			(xy 346.672564 -265.866141) (xy 346.688148 -265.912822) (xy 346.696043 -265.961399) (xy 346.696538 -265.986006)
			(xy 347.025226 -265.986006) (xy 347.029186 -265.936952) (xy 347.040963 -265.889168) (xy 347.060254 -265.843892)
			(xy 347.086557 -265.802296) (xy 347.119192 -265.765459) (xy 347.157313 -265.734334) (xy 347.199934 -265.709727)
			(xy 347.24595 -265.692275) (xy 347.294169 -265.682431) (xy 347.343344 -265.68045) (xy 347.392199 -265.686382)
			(xy 347.43947 -265.700074) (xy 347.483932 -265.721172) (xy 347.524435 -265.749128) (xy 347.559928 -265.78322)
			(xy 347.589493 -265.822564) (xy 347.612364 -265.866141) (xy 347.627948 -265.912822) (xy 347.635843 -265.961399)
			(xy 347.636338 -265.986006) (xy 347.635843 -266.010613) (xy 347.627948 -266.05919) (xy 347.612364 -266.105871)
			(xy 347.589493 -266.149448) (xy 347.559928 -266.188792) (xy 347.524435 -266.222884) (xy 347.483932 -266.25084)
			(xy 347.43947 -266.271938) (xy 347.392199 -266.28563) (xy 347.343344 -266.291562) (xy 347.294169 -266.289581)
			(xy 347.24595 -266.279737) (xy 347.199934 -266.262285) (xy 347.157313 -266.237678) (xy 347.119192 -266.206553)
			(xy 347.086557 -266.169716) (xy 347.060254 -266.12812) (xy 347.040963 -266.082844) (xy 347.029186 -266.03506)
			(xy 347.025226 -265.986006) (xy 346.696538 -265.986006) (xy 346.696043 -266.010613) (xy 346.688148 -266.05919)
			(xy 346.672564 -266.105871) (xy 346.649693 -266.149448) (xy 346.620128 -266.188792) (xy 346.584635 -266.222884)
			(xy 346.544132 -266.25084) (xy 346.49967 -266.271938) (xy 346.452399 -266.28563) (xy 346.403544 -266.291562)
			(xy 346.354369 -266.289581) (xy 346.30615 -266.279737) (xy 346.260134 -266.262285) (xy 346.217513 -266.237678)
			(xy 346.179392 -266.206553) (xy 346.146757 -266.169716) (xy 346.120454 -266.12812) (xy 346.101163 -266.082844)
			(xy 346.089386 -266.03506) (xy 346.085426 -265.986006) (xy 345.756484 -265.986006) (xy 345.755989 -266.010613)
			(xy 345.748094 -266.05919) (xy 345.73251 -266.105871) (xy 345.709639 -266.149448) (xy 345.680074 -266.188792)
			(xy 345.644581 -266.222884) (xy 345.604078 -266.25084) (xy 345.559616 -266.271938) (xy 345.512345 -266.28563)
			(xy 345.46349 -266.291562) (xy 345.414315 -266.289581) (xy 345.366096 -266.279737) (xy 345.32008 -266.262285)
			(xy 345.277459 -266.237678) (xy 345.239338 -266.206553) (xy 345.206703 -266.169716) (xy 345.1804 -266.12812)
			(xy 345.161109 -266.082844) (xy 345.149332 -266.03506) (xy 345.145372 -265.986006) (xy 344.81643 -265.986006)
			(xy 344.815935 -266.010613) (xy 344.80804 -266.05919) (xy 344.792456 -266.105871) (xy 344.769585 -266.149448)
			(xy 344.74002 -266.188792) (xy 344.704527 -266.222884) (xy 344.664024 -266.25084) (xy 344.619562 -266.271938)
			(xy 344.572291 -266.28563) (xy 344.523436 -266.291562) (xy 344.474261 -266.289581) (xy 344.426042 -266.279737)
			(xy 344.380026 -266.262285) (xy 344.337405 -266.237678) (xy 344.299284 -266.206553) (xy 344.266649 -266.169716)
			(xy 344.240346 -266.12812) (xy 344.221055 -266.082844) (xy 344.209278 -266.03506) (xy 344.205318 -265.986006)
			(xy 343.88679 -265.986006) (xy 343.886278 -266.011452) (xy 343.878114 -266.061686) (xy 343.861998 -266.10996)
			(xy 343.838347 -266.155023) (xy 343.807774 -266.195709) (xy 343.77107 -266.230964) (xy 343.729186 -266.259874)
			(xy 343.683207 -266.281691) (xy 343.634323 -266.295851) (xy 343.583802 -266.301985) (xy 343.53295 -266.299936)
			(xy 343.483086 -266.289756) (xy 343.4355 -266.271709) (xy 343.391426 -266.246263) (xy 343.352004 -266.214076)
			(xy 343.318256 -266.175982) (xy 343.291055 -266.132968) (xy 343.271107 -266.086148) (xy 343.258928 -266.036734)
			(xy 343.254833 -265.986006) (xy 342.936322 -265.986006) (xy 342.935827 -266.010613) (xy 342.927932 -266.05919)
			(xy 342.912348 -266.105871) (xy 342.889477 -266.149448) (xy 342.859912 -266.188792) (xy 342.824419 -266.222884)
			(xy 342.783916 -266.25084) (xy 342.739454 -266.271938) (xy 342.692183 -266.28563) (xy 342.643328 -266.291562)
			(xy 342.594153 -266.289581) (xy 342.545934 -266.279737) (xy 342.499918 -266.262285) (xy 342.457297 -266.237678)
			(xy 342.419176 -266.206553) (xy 342.386541 -266.169716) (xy 342.360238 -266.12812) (xy 342.340947 -266.082844)
			(xy 342.32917 -266.03506) (xy 342.32521 -265.986006) (xy 341.996522 -265.986006) (xy 341.996027 -266.010613)
			(xy 341.988132 -266.05919) (xy 341.972548 -266.105871) (xy 341.949677 -266.149448) (xy 341.920112 -266.188792)
			(xy 341.884619 -266.222884) (xy 341.844116 -266.25084) (xy 341.799654 -266.271938) (xy 341.752383 -266.28563)
			(xy 341.703528 -266.291562) (xy 341.654353 -266.289581) (xy 341.606134 -266.279737) (xy 341.560118 -266.262285)
			(xy 341.517497 -266.237678) (xy 341.479376 -266.206553) (xy 341.446741 -266.169716) (xy 341.420438 -266.12812)
			(xy 341.401147 -266.082844) (xy 341.38937 -266.03506) (xy 341.38541 -265.986006) (xy 341.066882 -265.986006)
			(xy 341.06637 -266.011452) (xy 341.058206 -266.061686) (xy 341.04209 -266.10996) (xy 341.018439 -266.155023)
			(xy 340.987866 -266.195709) (xy 340.951162 -266.230964) (xy 340.909278 -266.259874) (xy 340.863299 -266.281691)
			(xy 340.814415 -266.295851) (xy 340.763894 -266.301985) (xy 340.713042 -266.299936) (xy 340.663178 -266.289756)
			(xy 340.615592 -266.271709) (xy 340.571518 -266.246263) (xy 340.532096 -266.214076) (xy 340.498348 -266.175982)
			(xy 340.471147 -266.132968) (xy 340.451199 -266.086148) (xy 340.43902 -266.036734) (xy 340.434925 -265.986006)
			(xy 340.116414 -265.986006) (xy 340.115919 -266.010613) (xy 340.108024 -266.05919) (xy 340.09244 -266.105871)
			(xy 340.069569 -266.149448) (xy 340.040004 -266.188792) (xy 340.004511 -266.222884) (xy 339.964008 -266.25084)
			(xy 339.919546 -266.271938) (xy 339.872275 -266.28563) (xy 339.82342 -266.291562) (xy 339.774245 -266.289581)
			(xy 339.726026 -266.279737) (xy 339.68001 -266.262285) (xy 339.637389 -266.237678) (xy 339.599268 -266.206553)
			(xy 339.566633 -266.169716) (xy 339.54033 -266.12812) (xy 339.521039 -266.082844) (xy 339.509262 -266.03506)
			(xy 339.505302 -265.986006) (xy 339.17636 -265.986006) (xy 339.175865 -266.010613) (xy 339.16797 -266.05919)
			(xy 339.152386 -266.105871) (xy 339.129515 -266.149448) (xy 339.09995 -266.188792) (xy 339.064457 -266.222884)
			(xy 339.023954 -266.25084) (xy 338.979492 -266.271938) (xy 338.932221 -266.28563) (xy 338.883366 -266.291562)
			(xy 338.834191 -266.289581) (xy 338.785972 -266.279737) (xy 338.739956 -266.262285) (xy 338.697335 -266.237678)
			(xy 338.659214 -266.206553) (xy 338.626579 -266.169716) (xy 338.600276 -266.12812) (xy 338.580985 -266.082844)
			(xy 338.569208 -266.03506) (xy 338.565248 -265.986006) (xy 338.236306 -265.986006) (xy 338.23582 -266.010826)
			(xy 338.227788 -266.059812) (xy 338.211937 -266.106853) (xy 338.188685 -266.150711) (xy 338.158644 -266.190229)
			(xy 338.122606 -266.224366) (xy 338.08152 -266.252224) (xy 338.036468 -266.273068) (xy 337.988638 -266.286349)
			(xy 337.964018 -266.289536) (xy 337.950048 -266.29106) (xy 337.92795 -266.30757) (xy 337.888072 -266.402312)
			(xy 337.885072 -266.410154) (xy 337.883904 -266.426895) (xy 337.885786 -266.435078) (xy 337.88858 -266.445238)
			(xy 337.89493 -266.453366) (xy 337.919314 -266.48664) (xy 337.939126 -266.51839) (xy 337.945476 -266.529312)
			(xy 337.988402 -266.602718) (xy 337.989418 -266.604496) (xy 337.996474 -266.614304) (xy 338.017291 -266.626503)
			(xy 338.029296 -266.627864) (xy 338.126578 -266.633452) (xy 338.149438 -266.622784) (xy 338.157058 -266.612624)
			(xy 338.171574 -266.594029) (xy 338.205367 -266.561117) (xy 338.24382 -266.533794) (xy 338.286018 -266.512709)
			(xy 338.330956 -266.498365) (xy 338.377566 -266.491103) (xy 338.401152 -266.490704) (xy 338.426411 -266.491193)
			(xy 338.476242 -266.499501) (xy 338.524025 -266.515898) (xy 338.568458 -266.539938) (xy 338.608327 -266.570963)
			(xy 338.642545 -266.608128) (xy 338.670178 -266.650419) (xy 338.690473 -266.696682) (xy 338.702876 -266.745654)
			(xy 338.707048 -266.796) (xy 338.707047 -266.796012) (xy 339.024971 -266.796012) (xy 339.029066 -266.745284)
			(xy 339.041245 -266.69587) (xy 339.061193 -266.64905) (xy 339.088394 -266.606036) (xy 339.122142 -266.567942)
			(xy 339.161564 -266.535755) (xy 339.205638 -266.510309) (xy 339.253224 -266.492262) (xy 339.303088 -266.482082)
			(xy 339.35394 -266.480033) (xy 339.404461 -266.486167) (xy 339.453345 -266.500327) (xy 339.499324 -266.522144)
			(xy 339.541208 -266.551054) (xy 339.577912 -266.586309) (xy 339.608485 -266.626995) (xy 339.632136 -266.672058)
			(xy 339.648252 -266.720332) (xy 339.656416 -266.770566) (xy 339.656928 -266.796012) (xy 339.964771 -266.796012)
			(xy 339.968866 -266.745284) (xy 339.981045 -266.69587) (xy 340.000993 -266.64905) (xy 340.028194 -266.606036)
			(xy 340.061942 -266.567942) (xy 340.101364 -266.535755) (xy 340.145438 -266.510309) (xy 340.193024 -266.492262)
			(xy 340.242888 -266.482082) (xy 340.29374 -266.480033) (xy 340.344261 -266.486167) (xy 340.393145 -266.500327)
			(xy 340.439124 -266.522144) (xy 340.481008 -266.551054) (xy 340.517712 -266.586309) (xy 340.548285 -266.626995)
			(xy 340.571936 -266.672058) (xy 340.588052 -266.720332) (xy 340.596216 -266.770566) (xy 340.596728 -266.796012)
			(xy 340.915256 -266.796012) (xy 340.919216 -266.746958) (xy 340.930993 -266.699174) (xy 340.950284 -266.653898)
			(xy 340.976587 -266.612302) (xy 341.009222 -266.575465) (xy 341.047343 -266.54434) (xy 341.089964 -266.519733)
			(xy 341.13598 -266.502281) (xy 341.184199 -266.492437) (xy 341.233374 -266.490456) (xy 341.282229 -266.496388)
			(xy 341.3295 -266.51008) (xy 341.373962 -266.531178) (xy 341.414465 -266.559134) (xy 341.449958 -266.593226)
			(xy 341.479523 -266.63257) (xy 341.502394 -266.676147) (xy 341.517978 -266.722828) (xy 341.525873 -266.771405)
			(xy 341.526368 -266.796012) (xy 341.844879 -266.796012) (xy 341.848974 -266.745284) (xy 341.861153 -266.69587)
			(xy 341.881101 -266.64905) (xy 341.908302 -266.606036) (xy 341.94205 -266.567942) (xy 341.981472 -266.535755)
			(xy 342.025546 -266.510309) (xy 342.073132 -266.492262) (xy 342.122996 -266.482082) (xy 342.173848 -266.480033)
			(xy 342.224369 -266.486167) (xy 342.273253 -266.500327) (xy 342.319232 -266.522144) (xy 342.361116 -266.551054)
			(xy 342.39782 -266.586309) (xy 342.428393 -266.626995) (xy 342.452044 -266.672058) (xy 342.46816 -266.720332)
			(xy 342.476324 -266.770566) (xy 342.476836 -266.796012) (xy 342.795364 -266.796012) (xy 342.799324 -266.746958)
			(xy 342.811101 -266.699174) (xy 342.830392 -266.653898) (xy 342.856695 -266.612302) (xy 342.88933 -266.575465)
			(xy 342.927451 -266.54434) (xy 342.970072 -266.519733) (xy 343.016088 -266.502281) (xy 343.064307 -266.492437)
			(xy 343.113482 -266.490456) (xy 343.162337 -266.496388) (xy 343.209608 -266.51008) (xy 343.25407 -266.531178)
			(xy 343.294573 -266.559134) (xy 343.330066 -266.593226) (xy 343.359631 -266.63257) (xy 343.382502 -266.676147)
			(xy 343.398086 -266.722828) (xy 343.405981 -266.771405) (xy 343.406476 -266.796012) (xy 343.724987 -266.796012)
			(xy 343.729082 -266.745284) (xy 343.741261 -266.69587) (xy 343.761209 -266.64905) (xy 343.78841 -266.606036)
			(xy 343.822158 -266.567942) (xy 343.86158 -266.535755) (xy 343.905654 -266.510309) (xy 343.95324 -266.492262)
			(xy 344.003104 -266.482082) (xy 344.053956 -266.480033) (xy 344.104477 -266.486167) (xy 344.153361 -266.500327)
			(xy 344.19934 -266.522144) (xy 344.241224 -266.551054) (xy 344.277928 -266.586309) (xy 344.308501 -266.626995)
			(xy 344.332152 -266.672058) (xy 344.348268 -266.720332) (xy 344.356432 -266.770566) (xy 344.356944 -266.796012)
			(xy 344.675218 -266.796012) (xy 344.679178 -266.746958) (xy 344.690955 -266.699174) (xy 344.710246 -266.653898)
			(xy 344.736549 -266.612302) (xy 344.769184 -266.575465) (xy 344.807305 -266.54434) (xy 344.849926 -266.519733)
			(xy 344.895942 -266.502281) (xy 344.944161 -266.492437) (xy 344.993336 -266.490456) (xy 345.042191 -266.496388)
			(xy 345.089462 -266.51008) (xy 345.133924 -266.531178) (xy 345.174427 -266.559134) (xy 345.20992 -266.593226)
			(xy 345.239485 -266.63257) (xy 345.262356 -266.676147) (xy 345.27794 -266.722828) (xy 345.285835 -266.771405)
			(xy 345.28633 -266.796012) (xy 345.615272 -266.796012) (xy 345.619232 -266.746958) (xy 345.631009 -266.699174)
			(xy 345.6503 -266.653898) (xy 345.676603 -266.612302) (xy 345.709238 -266.575465) (xy 345.747359 -266.54434)
			(xy 345.78998 -266.519733) (xy 345.835996 -266.502281) (xy 345.884215 -266.492437) (xy 345.93339 -266.490456)
			(xy 345.982245 -266.496388) (xy 346.029516 -266.51008) (xy 346.073978 -266.531178) (xy 346.114481 -266.559134)
			(xy 346.149974 -266.593226) (xy 346.179539 -266.63257) (xy 346.20241 -266.676147) (xy 346.217994 -266.722828)
			(xy 346.225889 -266.771405) (xy 346.226384 -266.796012) (xy 347.49538 -266.796012) (xy 347.49934 -266.746958)
			(xy 347.511117 -266.699174) (xy 347.530408 -266.653898) (xy 347.556711 -266.612302) (xy 347.589346 -266.575465)
			(xy 347.627467 -266.54434) (xy 347.670088 -266.519733) (xy 347.716104 -266.502281) (xy 347.764323 -266.492437)
			(xy 347.813498 -266.490456) (xy 347.862353 -266.496388) (xy 347.909624 -266.51008) (xy 347.954086 -266.531178)
			(xy 347.994589 -266.559134) (xy 348.030082 -266.593226) (xy 348.059647 -266.63257) (xy 348.082518 -266.676147)
			(xy 348.098102 -266.722828) (xy 348.105997 -266.771405) (xy 348.106492 -266.796012) (xy 348.105997 -266.820619)
			(xy 348.098102 -266.869196) (xy 348.082518 -266.915877) (xy 348.059647 -266.959454) (xy 348.030082 -266.998798)
			(xy 347.994589 -267.03289) (xy 347.954086 -267.060846) (xy 347.909624 -267.081944) (xy 347.862353 -267.095636)
			(xy 347.813498 -267.101568) (xy 347.764323 -267.099587) (xy 347.716104 -267.089743) (xy 347.670088 -267.072291)
			(xy 347.627467 -267.047684) (xy 347.589346 -267.016559) (xy 347.556711 -266.979722) (xy 347.530408 -266.938126)
			(xy 347.511117 -266.89285) (xy 347.49934 -266.845066) (xy 347.49538 -266.796012) (xy 346.226384 -266.796012)
			(xy 346.225889 -266.820619) (xy 346.217994 -266.869196) (xy 346.20241 -266.915877) (xy 346.179539 -266.959454)
			(xy 346.149974 -266.998798) (xy 346.114481 -267.03289) (xy 346.073978 -267.060846) (xy 346.029516 -267.081944)
			(xy 345.982245 -267.095636) (xy 345.93339 -267.101568) (xy 345.884215 -267.099587) (xy 345.835996 -267.089743)
			(xy 345.78998 -267.072291) (xy 345.747359 -267.047684) (xy 345.709238 -267.016559) (xy 345.676603 -266.979722)
			(xy 345.6503 -266.938126) (xy 345.631009 -266.89285) (xy 345.619232 -266.845066) (xy 345.615272 -266.796012)
			(xy 345.28633 -266.796012) (xy 345.285835 -266.820619) (xy 345.27794 -266.869196) (xy 345.262356 -266.915877)
			(xy 345.239485 -266.959454) (xy 345.20992 -266.998798) (xy 345.174427 -267.03289) (xy 345.133924 -267.060846)
			(xy 345.089462 -267.081944) (xy 345.042191 -267.095636) (xy 344.993336 -267.101568) (xy 344.944161 -267.099587)
			(xy 344.895942 -267.089743) (xy 344.849926 -267.072291) (xy 344.807305 -267.047684) (xy 344.769184 -267.016559)
			(xy 344.736549 -266.979722) (xy 344.710246 -266.938126) (xy 344.690955 -266.89285) (xy 344.679178 -266.845066)
			(xy 344.675218 -266.796012) (xy 344.356944 -266.796012) (xy 344.356432 -266.821458) (xy 344.348268 -266.871692)
			(xy 344.332152 -266.919966) (xy 344.308501 -266.965029) (xy 344.277928 -267.005715) (xy 344.241224 -267.04097)
			(xy 344.19934 -267.06988) (xy 344.153361 -267.091697) (xy 344.104477 -267.105857) (xy 344.053956 -267.111991)
			(xy 344.003104 -267.109942) (xy 343.95324 -267.099762) (xy 343.905654 -267.081715) (xy 343.86158 -267.056269)
			(xy 343.822158 -267.024082) (xy 343.78841 -266.985988) (xy 343.761209 -266.942974) (xy 343.741261 -266.896154)
			(xy 343.729082 -266.84674) (xy 343.724987 -266.796012) (xy 343.406476 -266.796012) (xy 343.405981 -266.820619)
			(xy 343.398086 -266.869196) (xy 343.382502 -266.915877) (xy 343.359631 -266.959454) (xy 343.330066 -266.998798)
			(xy 343.294573 -267.03289) (xy 343.25407 -267.060846) (xy 343.209608 -267.081944) (xy 343.162337 -267.095636)
			(xy 343.113482 -267.101568) (xy 343.064307 -267.099587) (xy 343.016088 -267.089743) (xy 342.970072 -267.072291)
			(xy 342.927451 -267.047684) (xy 342.88933 -267.016559) (xy 342.856695 -266.979722) (xy 342.830392 -266.938126)
			(xy 342.811101 -266.89285) (xy 342.799324 -266.845066) (xy 342.795364 -266.796012) (xy 342.476836 -266.796012)
			(xy 342.476324 -266.821458) (xy 342.46816 -266.871692) (xy 342.452044 -266.919966) (xy 342.428393 -266.965029)
			(xy 342.39782 -267.005715) (xy 342.361116 -267.04097) (xy 342.319232 -267.06988) (xy 342.273253 -267.091697)
			(xy 342.224369 -267.105857) (xy 342.173848 -267.111991) (xy 342.122996 -267.109942) (xy 342.073132 -267.099762)
			(xy 342.025546 -267.081715) (xy 341.981472 -267.056269) (xy 341.94205 -267.024082) (xy 341.908302 -266.985988)
			(xy 341.881101 -266.942974) (xy 341.861153 -266.896154) (xy 341.848974 -266.84674) (xy 341.844879 -266.796012)
			(xy 341.526368 -266.796012) (xy 341.525873 -266.820619) (xy 341.517978 -266.869196) (xy 341.502394 -266.915877)
			(xy 341.479523 -266.959454) (xy 341.449958 -266.998798) (xy 341.414465 -267.03289) (xy 341.373962 -267.060846)
			(xy 341.3295 -267.081944) (xy 341.282229 -267.095636) (xy 341.233374 -267.101568) (xy 341.184199 -267.099587)
			(xy 341.13598 -267.089743) (xy 341.089964 -267.072291) (xy 341.047343 -267.047684) (xy 341.009222 -267.016559)
			(xy 340.976587 -266.979722) (xy 340.950284 -266.938126) (xy 340.930993 -266.89285) (xy 340.919216 -266.845066)
			(xy 340.915256 -266.796012) (xy 340.596728 -266.796012) (xy 340.596216 -266.821458) (xy 340.588052 -266.871692)
			(xy 340.571936 -266.919966) (xy 340.548285 -266.965029) (xy 340.517712 -267.005715) (xy 340.481008 -267.04097)
			(xy 340.439124 -267.06988) (xy 340.393145 -267.091697) (xy 340.344261 -267.105857) (xy 340.29374 -267.111991)
			(xy 340.242888 -267.109942) (xy 340.193024 -267.099762) (xy 340.145438 -267.081715) (xy 340.101364 -267.056269)
			(xy 340.061942 -267.024082) (xy 340.028194 -266.985988) (xy 340.000993 -266.942974) (xy 339.981045 -266.896154)
			(xy 339.968866 -266.84674) (xy 339.964771 -266.796012) (xy 339.656928 -266.796012) (xy 339.656416 -266.821458)
			(xy 339.648252 -266.871692) (xy 339.632136 -266.919966) (xy 339.608485 -266.965029) (xy 339.577912 -267.005715)
			(xy 339.541208 -267.04097) (xy 339.499324 -267.06988) (xy 339.453345 -267.091697) (xy 339.404461 -267.105857)
			(xy 339.35394 -267.111991) (xy 339.303088 -267.109942) (xy 339.253224 -267.099762) (xy 339.205638 -267.081715)
			(xy 339.161564 -267.056269) (xy 339.122142 -267.024082) (xy 339.088394 -266.985988) (xy 339.061193 -266.942974)
			(xy 339.041245 -266.896154) (xy 339.029066 -266.84674) (xy 339.024971 -266.796012) (xy 338.707047 -266.796012)
			(xy 338.702876 -266.846346) (xy 338.690473 -266.895318) (xy 338.670178 -266.941581) (xy 338.642545 -266.983872)
			(xy 338.608327 -267.021037) (xy 338.568458 -267.052062) (xy 338.524025 -267.076102) (xy 338.476242 -267.092499)
			(xy 338.426411 -267.100807) (xy 338.401152 -267.10132) (xy 338.380335 -267.100966) (xy 338.339085 -267.095315)
			(xy 338.298983 -267.084123) (xy 338.27974 -267.076174) (xy 338.267294 -267.076936) (xy 338.255864 -267.077952)
			(xy 338.178648 -267.12037) (xy 338.173939 -267.123194) (xy 338.165741 -267.130496) (xy 338.162392 -267.134848)
			(xy 338.162138 -267.135102) (xy 338.155026 -267.144754) (xy 338.152994 -267.15593) (xy 338.144104 -267.194284)
			(xy 338.120736 -267.282168) (xy 338.110576 -267.316204) (xy 338.107801 -267.326022) (xy 338.109411 -267.346345)
			(xy 338.118784 -267.364448) (xy 338.126324 -267.371322) (xy 338.146557 -267.388887) (xy 338.181123 -267.429819)
			(xy 338.208016 -267.476155) (xy 338.22641 -267.526474) (xy 338.235739 -267.57923) (xy 338.236306 -267.606018)
			(xy 338.554817 -267.606018) (xy 338.558912 -267.55529) (xy 338.571091 -267.505876) (xy 338.591039 -267.459056)
			(xy 338.61824 -267.416042) (xy 338.651988 -267.377948) (xy 338.69141 -267.345761) (xy 338.735484 -267.320315)
			(xy 338.78307 -267.302268) (xy 338.832934 -267.292088) (xy 338.883786 -267.290039) (xy 338.934307 -267.296173)
			(xy 338.983191 -267.310333) (xy 339.02917 -267.33215) (xy 339.071054 -267.36106) (xy 339.107758 -267.396315)
			(xy 339.138331 -267.437001) (xy 339.161982 -267.482064) (xy 339.178098 -267.530338) (xy 339.186262 -267.580572)
			(xy 339.186774 -267.606018) (xy 339.505302 -267.606018) (xy 339.509262 -267.556964) (xy 339.521039 -267.50918)
			(xy 339.54033 -267.463904) (xy 339.566633 -267.422308) (xy 339.599268 -267.385471) (xy 339.637389 -267.354346)
			(xy 339.68001 -267.329739) (xy 339.726026 -267.312287) (xy 339.774245 -267.302443) (xy 339.82342 -267.300462)
			(xy 339.872275 -267.306394) (xy 339.919546 -267.320086) (xy 339.964008 -267.341184) (xy 340.004511 -267.36914)
			(xy 340.040004 -267.403232) (xy 340.069569 -267.442576) (xy 340.09244 -267.486153) (xy 340.108024 -267.532834)
			(xy 340.115919 -267.581411) (xy 340.116414 -267.606018) (xy 340.445356 -267.606018) (xy 340.449316 -267.556964)
			(xy 340.461093 -267.50918) (xy 340.480384 -267.463904) (xy 340.506687 -267.422308) (xy 340.539322 -267.385471)
			(xy 340.577443 -267.354346) (xy 340.620064 -267.329739) (xy 340.66608 -267.312287) (xy 340.714299 -267.302443)
			(xy 340.763474 -267.300462) (xy 340.812329 -267.306394) (xy 340.8596 -267.320086) (xy 340.904062 -267.341184)
			(xy 340.944565 -267.36914) (xy 340.980058 -267.403232) (xy 341.009623 -267.442576) (xy 341.032494 -267.486153)
			(xy 341.048078 -267.532834) (xy 341.055973 -267.581411) (xy 341.056468 -267.606018) (xy 341.38541 -267.606018)
			(xy 341.38937 -267.556964) (xy 341.401147 -267.50918) (xy 341.420438 -267.463904) (xy 341.446741 -267.422308)
			(xy 341.479376 -267.385471) (xy 341.517497 -267.354346) (xy 341.560118 -267.329739) (xy 341.606134 -267.312287)
			(xy 341.654353 -267.302443) (xy 341.703528 -267.300462) (xy 341.752383 -267.306394) (xy 341.799654 -267.320086)
			(xy 341.844116 -267.341184) (xy 341.884619 -267.36914) (xy 341.920112 -267.403232) (xy 341.949677 -267.442576)
			(xy 341.972548 -267.486153) (xy 341.988132 -267.532834) (xy 341.996027 -267.581411) (xy 341.996522 -267.606018)
			(xy 342.314779 -267.606018) (xy 342.318874 -267.55529) (xy 342.331053 -267.505876) (xy 342.351001 -267.459056)
			(xy 342.378202 -267.416042) (xy 342.41195 -267.377948) (xy 342.451372 -267.345761) (xy 342.495446 -267.320315)
			(xy 342.543032 -267.302268) (xy 342.592896 -267.292088) (xy 342.643748 -267.290039) (xy 342.694269 -267.296173)
			(xy 342.743153 -267.310333) (xy 342.789132 -267.33215) (xy 342.831016 -267.36106) (xy 342.86772 -267.396315)
			(xy 342.898293 -267.437001) (xy 342.921944 -267.482064) (xy 342.93806 -267.530338) (xy 342.946224 -267.580572)
			(xy 342.946736 -267.606018) (xy 343.265264 -267.606018) (xy 343.269224 -267.556964) (xy 343.281001 -267.50918)
			(xy 343.300292 -267.463904) (xy 343.326595 -267.422308) (xy 343.35923 -267.385471) (xy 343.397351 -267.354346)
			(xy 343.439972 -267.329739) (xy 343.485988 -267.312287) (xy 343.534207 -267.302443) (xy 343.583382 -267.300462)
			(xy 343.632237 -267.306394) (xy 343.679508 -267.320086) (xy 343.72397 -267.341184) (xy 343.764473 -267.36914)
			(xy 343.799966 -267.403232) (xy 343.829531 -267.442576) (xy 343.852402 -267.486153) (xy 343.867986 -267.532834)
			(xy 343.875881 -267.581411) (xy 343.876376 -267.606018) (xy 344.205318 -267.606018) (xy 344.209278 -267.556964)
			(xy 344.221055 -267.50918) (xy 344.240346 -267.463904) (xy 344.266649 -267.422308) (xy 344.299284 -267.385471)
			(xy 344.337405 -267.354346) (xy 344.380026 -267.329739) (xy 344.426042 -267.312287) (xy 344.474261 -267.302443)
			(xy 344.523436 -267.300462) (xy 344.572291 -267.306394) (xy 344.619562 -267.320086) (xy 344.664024 -267.341184)
			(xy 344.704527 -267.36914) (xy 344.74002 -267.403232) (xy 344.769585 -267.442576) (xy 344.792456 -267.486153)
			(xy 344.80804 -267.532834) (xy 344.815935 -267.581411) (xy 344.81643 -267.606018) (xy 344.815935 -267.630625)
			(xy 344.80804 -267.679202) (xy 344.792456 -267.725883) (xy 344.769585 -267.76946) (xy 344.74002 -267.808804)
			(xy 344.704527 -267.842896) (xy 344.664024 -267.870852) (xy 344.619562 -267.89195) (xy 344.572291 -267.905642)
			(xy 344.523436 -267.911574) (xy 344.474261 -267.909593) (xy 344.426042 -267.899749) (xy 344.380026 -267.882297)
			(xy 344.337405 -267.85769) (xy 344.299284 -267.826565) (xy 344.266649 -267.789728) (xy 344.240346 -267.748132)
			(xy 344.221055 -267.702856) (xy 344.209278 -267.655072) (xy 344.205318 -267.606018) (xy 343.876376 -267.606018)
			(xy 343.875881 -267.630625) (xy 343.867986 -267.679202) (xy 343.852402 -267.725883) (xy 343.829531 -267.76946)
			(xy 343.799966 -267.808804) (xy 343.764473 -267.842896) (xy 343.72397 -267.870852) (xy 343.679508 -267.89195)
			(xy 343.632237 -267.905642) (xy 343.583382 -267.911574) (xy 343.534207 -267.909593) (xy 343.485988 -267.899749)
			(xy 343.439972 -267.882297) (xy 343.397351 -267.85769) (xy 343.35923 -267.826565) (xy 343.326595 -267.789728)
			(xy 343.300292 -267.748132) (xy 343.281001 -267.702856) (xy 343.269224 -267.655072) (xy 343.265264 -267.606018)
			(xy 342.946736 -267.606018) (xy 342.946224 -267.631464) (xy 342.93806 -267.681698) (xy 342.921944 -267.729972)
			(xy 342.898293 -267.775035) (xy 342.86772 -267.815721) (xy 342.831016 -267.850976) (xy 342.789132 -267.879886)
			(xy 342.743153 -267.901703) (xy 342.694269 -267.915863) (xy 342.643748 -267.921997) (xy 342.592896 -267.919948)
			(xy 342.543032 -267.909768) (xy 342.495446 -267.891721) (xy 342.451372 -267.866275) (xy 342.41195 -267.834088)
			(xy 342.378202 -267.795994) (xy 342.351001 -267.75298) (xy 342.331053 -267.70616) (xy 342.318874 -267.656746)
			(xy 342.314779 -267.606018) (xy 341.996522 -267.606018) (xy 341.996027 -267.630625) (xy 341.988132 -267.679202)
			(xy 341.972548 -267.725883) (xy 341.949677 -267.76946) (xy 341.920112 -267.808804) (xy 341.884619 -267.842896)
			(xy 341.844116 -267.870852) (xy 341.799654 -267.89195) (xy 341.752383 -267.905642) (xy 341.703528 -267.911574)
			(xy 341.654353 -267.909593) (xy 341.606134 -267.899749) (xy 341.560118 -267.882297) (xy 341.517497 -267.85769)
			(xy 341.479376 -267.826565) (xy 341.446741 -267.789728) (xy 341.420438 -267.748132) (xy 341.401147 -267.702856)
			(xy 341.38937 -267.655072) (xy 341.38541 -267.606018) (xy 341.056468 -267.606018) (xy 341.055973 -267.630625)
			(xy 341.048078 -267.679202) (xy 341.032494 -267.725883) (xy 341.009623 -267.76946) (xy 340.980058 -267.808804)
			(xy 340.944565 -267.842896) (xy 340.904062 -267.870852) (xy 340.8596 -267.89195) (xy 340.812329 -267.905642)
			(xy 340.763474 -267.911574) (xy 340.714299 -267.909593) (xy 340.66608 -267.899749) (xy 340.620064 -267.882297)
			(xy 340.577443 -267.85769) (xy 340.539322 -267.826565) (xy 340.506687 -267.789728) (xy 340.480384 -267.748132)
			(xy 340.461093 -267.702856) (xy 340.449316 -267.655072) (xy 340.445356 -267.606018) (xy 340.116414 -267.606018)
			(xy 340.115919 -267.630625) (xy 340.108024 -267.679202) (xy 340.09244 -267.725883) (xy 340.069569 -267.76946)
			(xy 340.040004 -267.808804) (xy 340.004511 -267.842896) (xy 339.964008 -267.870852) (xy 339.919546 -267.89195)
			(xy 339.872275 -267.905642) (xy 339.82342 -267.911574) (xy 339.774245 -267.909593) (xy 339.726026 -267.899749)
			(xy 339.68001 -267.882297) (xy 339.637389 -267.85769) (xy 339.599268 -267.826565) (xy 339.566633 -267.789728)
			(xy 339.54033 -267.748132) (xy 339.521039 -267.702856) (xy 339.509262 -267.655072) (xy 339.505302 -267.606018)
			(xy 339.186774 -267.606018) (xy 339.186262 -267.631464) (xy 339.178098 -267.681698) (xy 339.161982 -267.729972)
			(xy 339.138331 -267.775035) (xy 339.107758 -267.815721) (xy 339.071054 -267.850976) (xy 339.02917 -267.879886)
			(xy 338.983191 -267.901703) (xy 338.934307 -267.915863) (xy 338.883786 -267.921997) (xy 338.832934 -267.919948)
			(xy 338.78307 -267.909768) (xy 338.735484 -267.891721) (xy 338.69141 -267.866275) (xy 338.651988 -267.834088)
			(xy 338.61824 -267.795994) (xy 338.591039 -267.75298) (xy 338.571091 -267.70616) (xy 338.558912 -267.656746)
			(xy 338.554817 -267.606018) (xy 338.236306 -267.606018) (xy 338.235834 -267.630008) (xy 338.228326 -267.677398)
			(xy 338.213497 -267.723029) (xy 338.191712 -267.765779) (xy 338.163508 -267.804595) (xy 338.12958 -267.838521)
			(xy 338.090762 -267.866723) (xy 338.048011 -267.888504) (xy 338.002378 -267.90333) (xy 337.954988 -267.910836)
			(xy 337.930998 -267.911326) (xy 337.906126 -267.910835) (xy 337.85704 -267.902769) (xy 337.809911 -267.886849)
			(xy 337.765988 -267.863498) (xy 337.726433 -267.833333) (xy 337.692293 -267.797154) (xy 337.664472 -267.755917)
			(xy 337.65363 -267.733526) (xy 337.648544 -267.723773) (xy 337.631856 -267.709478) (xy 337.610726 -267.703449)
			(xy 337.599782 -267.70457) (xy 337.582014 -267.707216) (xy 337.546316 -267.711281) (xy 337.528408 -267.712698)
			(xy 337.51901 -267.71346) (xy 337.501738 -267.721588) (xy 337.474814 -267.75029) (xy 337.468531 -267.757581)
			(xy 337.461476 -267.775471) (xy 337.461098 -267.785088) (xy 337.461098 -268.082522) (xy 337.485736 -268.11097)
			(xy 337.504532 -268.113764) (xy 337.528458 -268.117673) (xy 337.574751 -268.132064) (xy 337.618188 -268.153589)
			(xy 337.657679 -268.181707) (xy 337.69223 -268.215712) (xy 337.720974 -268.254749) (xy 337.743189 -268.297838)
			(xy 337.758316 -268.343895) (xy 337.765975 -268.391764) (xy 337.765975 -268.416024) (xy 338.095348 -268.416024)
			(xy 338.099308 -268.36697) (xy 338.111085 -268.319186) (xy 338.130376 -268.27391) (xy 338.156679 -268.232314)
			(xy 338.189314 -268.195477) (xy 338.227435 -268.164352) (xy 338.270056 -268.139745) (xy 338.316072 -268.122293)
			(xy 338.364291 -268.112449) (xy 338.413466 -268.110468) (xy 338.462321 -268.1164) (xy 338.509592 -268.130092)
			(xy 338.554054 -268.15119) (xy 338.594557 -268.179146) (xy 338.63005 -268.213238) (xy 338.659615 -268.252582)
			(xy 338.682486 -268.296159) (xy 338.69807 -268.34284) (xy 338.705965 -268.391417) (xy 338.70646 -268.416024)
			(xy 339.035402 -268.416024) (xy 339.039362 -268.36697) (xy 339.051139 -268.319186) (xy 339.07043 -268.27391)
			(xy 339.096733 -268.232314) (xy 339.129368 -268.195477) (xy 339.167489 -268.164352) (xy 339.21011 -268.139745)
			(xy 339.256126 -268.122293) (xy 339.304345 -268.112449) (xy 339.35352 -268.110468) (xy 339.402375 -268.1164)
			(xy 339.449646 -268.130092) (xy 339.494108 -268.15119) (xy 339.534611 -268.179146) (xy 339.570104 -268.213238)
			(xy 339.599669 -268.252582) (xy 339.62254 -268.296159) (xy 339.638124 -268.34284) (xy 339.646019 -268.391417)
			(xy 339.646514 -268.416024) (xy 339.975202 -268.416024) (xy 339.979162 -268.36697) (xy 339.990939 -268.319186)
			(xy 340.01023 -268.27391) (xy 340.036533 -268.232314) (xy 340.069168 -268.195477) (xy 340.107289 -268.164352)
			(xy 340.14991 -268.139745) (xy 340.195926 -268.122293) (xy 340.244145 -268.112449) (xy 340.29332 -268.110468)
			(xy 340.342175 -268.1164) (xy 340.389446 -268.130092) (xy 340.433908 -268.15119) (xy 340.474411 -268.179146)
			(xy 340.509904 -268.213238) (xy 340.539469 -268.252582) (xy 340.56234 -268.296159) (xy 340.577924 -268.34284)
			(xy 340.585819 -268.391417) (xy 340.586314 -268.416024) (xy 340.915256 -268.416024) (xy 340.919216 -268.36697)
			(xy 340.930993 -268.319186) (xy 340.950284 -268.27391) (xy 340.976587 -268.232314) (xy 341.009222 -268.195477)
			(xy 341.047343 -268.164352) (xy 341.089964 -268.139745) (xy 341.13598 -268.122293) (xy 341.184199 -268.112449)
			(xy 341.233374 -268.110468) (xy 341.282229 -268.1164) (xy 341.3295 -268.130092) (xy 341.373962 -268.15119)
			(xy 341.414465 -268.179146) (xy 341.449958 -268.213238) (xy 341.479523 -268.252582) (xy 341.502394 -268.296159)
			(xy 341.517978 -268.34284) (xy 341.525873 -268.391417) (xy 341.526368 -268.416024) (xy 341.85531 -268.416024)
			(xy 341.85927 -268.36697) (xy 341.871047 -268.319186) (xy 341.890338 -268.27391) (xy 341.916641 -268.232314)
			(xy 341.949276 -268.195477) (xy 341.987397 -268.164352) (xy 342.030018 -268.139745) (xy 342.076034 -268.122293)
			(xy 342.124253 -268.112449) (xy 342.173428 -268.110468) (xy 342.222283 -268.1164) (xy 342.269554 -268.130092)
			(xy 342.314016 -268.15119) (xy 342.354519 -268.179146) (xy 342.390012 -268.213238) (xy 342.419577 -268.252582)
			(xy 342.442448 -268.296159) (xy 342.458032 -268.34284) (xy 342.465927 -268.391417) (xy 342.466422 -268.416024)
			(xy 342.795364 -268.416024) (xy 342.799324 -268.36697) (xy 342.811101 -268.319186) (xy 342.830392 -268.27391)
			(xy 342.856695 -268.232314) (xy 342.88933 -268.195477) (xy 342.927451 -268.164352) (xy 342.970072 -268.139745)
			(xy 343.016088 -268.122293) (xy 343.064307 -268.112449) (xy 343.113482 -268.110468) (xy 343.162337 -268.1164)
			(xy 343.209608 -268.130092) (xy 343.25407 -268.15119) (xy 343.294573 -268.179146) (xy 343.330066 -268.213238)
			(xy 343.359631 -268.252582) (xy 343.382502 -268.296159) (xy 343.398086 -268.34284) (xy 343.405981 -268.391417)
			(xy 343.406476 -268.416024) (xy 343.735418 -268.416024) (xy 343.739378 -268.36697) (xy 343.751155 -268.319186)
			(xy 343.770446 -268.27391) (xy 343.796749 -268.232314) (xy 343.829384 -268.195477) (xy 343.867505 -268.164352)
			(xy 343.910126 -268.139745) (xy 343.956142 -268.122293) (xy 344.004361 -268.112449) (xy 344.053536 -268.110468)
			(xy 344.102391 -268.1164) (xy 344.149662 -268.130092) (xy 344.194124 -268.15119) (xy 344.234627 -268.179146)
			(xy 344.27012 -268.213238) (xy 344.299685 -268.252582) (xy 344.322556 -268.296159) (xy 344.33814 -268.34284)
			(xy 344.346035 -268.391417) (xy 344.34653 -268.416024) (xy 344.346035 -268.440631) (xy 344.33814 -268.489208)
			(xy 344.322556 -268.535889) (xy 344.299685 -268.579466) (xy 344.27012 -268.61881) (xy 344.234627 -268.652902)
			(xy 344.194124 -268.680858) (xy 344.149662 -268.701956) (xy 344.102391 -268.715648) (xy 344.053536 -268.72158)
			(xy 344.004361 -268.719599) (xy 343.956142 -268.709755) (xy 343.910126 -268.692303) (xy 343.867505 -268.667696)
			(xy 343.829384 -268.636571) (xy 343.796749 -268.599734) (xy 343.770446 -268.558138) (xy 343.751155 -268.512862)
			(xy 343.739378 -268.465078) (xy 343.735418 -268.416024) (xy 343.406476 -268.416024) (xy 343.405981 -268.440631)
			(xy 343.398086 -268.489208) (xy 343.382502 -268.535889) (xy 343.359631 -268.579466) (xy 343.330066 -268.61881)
			(xy 343.294573 -268.652902) (xy 343.25407 -268.680858) (xy 343.209608 -268.701956) (xy 343.162337 -268.715648)
			(xy 343.113482 -268.72158) (xy 343.064307 -268.719599) (xy 343.016088 -268.709755) (xy 342.970072 -268.692303)
			(xy 342.927451 -268.667696) (xy 342.88933 -268.636571) (xy 342.856695 -268.599734) (xy 342.830392 -268.558138)
			(xy 342.811101 -268.512862) (xy 342.799324 -268.465078) (xy 342.795364 -268.416024) (xy 342.466422 -268.416024)
			(xy 342.465927 -268.440631) (xy 342.458032 -268.489208) (xy 342.442448 -268.535889) (xy 342.419577 -268.579466)
			(xy 342.390012 -268.61881) (xy 342.354519 -268.652902) (xy 342.314016 -268.680858) (xy 342.269554 -268.701956)
			(xy 342.222283 -268.715648) (xy 342.173428 -268.72158) (xy 342.124253 -268.719599) (xy 342.076034 -268.709755)
			(xy 342.030018 -268.692303) (xy 341.987397 -268.667696) (xy 341.949276 -268.636571) (xy 341.916641 -268.599734)
			(xy 341.890338 -268.558138) (xy 341.871047 -268.512862) (xy 341.85927 -268.465078) (xy 341.85531 -268.416024)
			(xy 341.526368 -268.416024) (xy 341.525873 -268.440631) (xy 341.517978 -268.489208) (xy 341.502394 -268.535889)
			(xy 341.479523 -268.579466) (xy 341.449958 -268.61881) (xy 341.414465 -268.652902) (xy 341.373962 -268.680858)
			(xy 341.3295 -268.701956) (xy 341.282229 -268.715648) (xy 341.233374 -268.72158) (xy 341.184199 -268.719599)
			(xy 341.13598 -268.709755) (xy 341.089964 -268.692303) (xy 341.047343 -268.667696) (xy 341.009222 -268.636571)
			(xy 340.976587 -268.599734) (xy 340.950284 -268.558138) (xy 340.930993 -268.512862) (xy 340.919216 -268.465078)
			(xy 340.915256 -268.416024) (xy 340.586314 -268.416024) (xy 340.585819 -268.440631) (xy 340.577924 -268.489208)
			(xy 340.56234 -268.535889) (xy 340.539469 -268.579466) (xy 340.509904 -268.61881) (xy 340.474411 -268.652902)
			(xy 340.433908 -268.680858) (xy 340.389446 -268.701956) (xy 340.342175 -268.715648) (xy 340.29332 -268.72158)
			(xy 340.244145 -268.719599) (xy 340.195926 -268.709755) (xy 340.14991 -268.692303) (xy 340.107289 -268.667696)
			(xy 340.069168 -268.636571) (xy 340.036533 -268.599734) (xy 340.01023 -268.558138) (xy 339.990939 -268.512862)
			(xy 339.979162 -268.465078) (xy 339.975202 -268.416024) (xy 339.646514 -268.416024) (xy 339.646019 -268.440631)
			(xy 339.638124 -268.489208) (xy 339.62254 -268.535889) (xy 339.599669 -268.579466) (xy 339.570104 -268.61881)
			(xy 339.534611 -268.652902) (xy 339.494108 -268.680858) (xy 339.449646 -268.701956) (xy 339.402375 -268.715648)
			(xy 339.35352 -268.72158) (xy 339.304345 -268.719599) (xy 339.256126 -268.709755) (xy 339.21011 -268.692303)
			(xy 339.167489 -268.667696) (xy 339.129368 -268.636571) (xy 339.096733 -268.599734) (xy 339.07043 -268.558138)
			(xy 339.051139 -268.512862) (xy 339.039362 -268.465078) (xy 339.035402 -268.416024) (xy 338.70646 -268.416024)
			(xy 338.705965 -268.440631) (xy 338.69807 -268.489208) (xy 338.682486 -268.535889) (xy 338.659615 -268.579466)
			(xy 338.63005 -268.61881) (xy 338.594557 -268.652902) (xy 338.554054 -268.680858) (xy 338.509592 -268.701956)
			(xy 338.462321 -268.715648) (xy 338.413466 -268.72158) (xy 338.364291 -268.719599) (xy 338.316072 -268.709755)
			(xy 338.270056 -268.692303) (xy 338.227435 -268.667696) (xy 338.189314 -268.636571) (xy 338.156679 -268.599734)
			(xy 338.130376 -268.558138) (xy 338.111085 -268.512862) (xy 338.099308 -268.465078) (xy 338.095348 -268.416024)
			(xy 337.765975 -268.416024) (xy 337.765975 -268.440242) (xy 337.758314 -268.488111) (xy 337.743186 -268.534169)
			(xy 337.72097 -268.577257) (xy 337.692226 -268.616293) (xy 337.657673 -268.650297) (xy 337.618182 -268.678415)
			(xy 337.574745 -268.699939) (xy 337.528452 -268.714329) (xy 337.504532 -268.718284) (xy 337.485736 -268.721078)
			(xy 337.461098 -268.749526) (xy 337.461098 -269.414498) (xy 337.461435 -269.423668) (xy 337.467813 -269.44086)
			(xy 337.473544 -269.448026) (xy 337.474052 -269.448534) (xy 337.500976 -269.477744) (xy 337.516978 -269.485872)
			(xy 337.526122 -269.487142) (xy 337.54314 -269.489428) (xy 337.55711 -269.49146) (xy 337.58251 -269.481046)
			(xy 337.644994 -269.399258) (xy 337.650163 -269.391864) (xy 337.655414 -269.374617) (xy 337.654345 -269.35662)
			(xy 337.65109 -269.348204) (xy 337.65109 -269.34795) (xy 337.643141 -269.328835) (xy 337.631889 -269.288994)
			(xy 337.626122 -269.247998) (xy 337.62569 -269.2273) (xy 337.62569 -269.221712) (xy 337.626478 -269.197944)
			(xy 337.634512 -269.151074) (xy 337.649717 -269.106017) (xy 337.671725 -269.063863) (xy 337.700005 -269.025632)
			(xy 337.733871 -268.992249) (xy 337.772504 -268.964522) (xy 337.81497 -268.943122) (xy 337.860241 -268.928566)
			(xy 337.907221 -268.921206) (xy 337.930998 -268.920722) (xy 337.95499 -268.921168) (xy 338.002384 -268.928675)
			(xy 338.04802 -268.943503) (xy 338.090775 -268.965289) (xy 338.129594 -268.993495) (xy 338.163523 -269.027427)
			(xy 338.191725 -269.066249) (xy 338.213507 -269.109006) (xy 338.228332 -269.154643) (xy 338.235834 -269.202038)
			(xy 338.236306 -269.22603) (xy 338.554817 -269.22603) (xy 338.558912 -269.175302) (xy 338.571091 -269.125888)
			(xy 338.591039 -269.079068) (xy 338.61824 -269.036054) (xy 338.651988 -268.99796) (xy 338.69141 -268.965773)
			(xy 338.735484 -268.940327) (xy 338.78307 -268.92228) (xy 338.832934 -268.9121) (xy 338.883786 -268.910051)
			(xy 338.934307 -268.916185) (xy 338.983191 -268.930345) (xy 339.02917 -268.952162) (xy 339.071054 -268.981072)
			(xy 339.107758 -269.016327) (xy 339.138331 -269.057013) (xy 339.161982 -269.102076) (xy 339.178098 -269.15035)
			(xy 339.186262 -269.200584) (xy 339.186774 -269.22603) (xy 339.505302 -269.22603) (xy 339.509262 -269.176976)
			(xy 339.521039 -269.129192) (xy 339.54033 -269.083916) (xy 339.566633 -269.04232) (xy 339.599268 -269.005483)
			(xy 339.637389 -268.974358) (xy 339.68001 -268.949751) (xy 339.726026 -268.932299) (xy 339.774245 -268.922455)
			(xy 339.82342 -268.920474) (xy 339.872275 -268.926406) (xy 339.919546 -268.940098) (xy 339.964008 -268.961196)
			(xy 340.004511 -268.989152) (xy 340.040004 -269.023244) (xy 340.069569 -269.062588) (xy 340.09244 -269.106165)
			(xy 340.108024 -269.152846) (xy 340.115919 -269.201423) (xy 340.116414 -269.22603) (xy 340.445356 -269.22603)
			(xy 340.449316 -269.176976) (xy 340.461093 -269.129192) (xy 340.480384 -269.083916) (xy 340.506687 -269.04232)
			(xy 340.539322 -269.005483) (xy 340.577443 -268.974358) (xy 340.620064 -268.949751) (xy 340.66608 -268.932299)
			(xy 340.714299 -268.922455) (xy 340.763474 -268.920474) (xy 340.812329 -268.926406) (xy 340.8596 -268.940098)
			(xy 340.904062 -268.961196) (xy 340.944565 -268.989152) (xy 340.980058 -269.023244) (xy 341.009623 -269.062588)
			(xy 341.032494 -269.106165) (xy 341.048078 -269.152846) (xy 341.055973 -269.201423) (xy 341.056468 -269.22603)
			(xy 341.38541 -269.22603) (xy 341.38937 -269.176976) (xy 341.401147 -269.129192) (xy 341.420438 -269.083916)
			(xy 341.446741 -269.04232) (xy 341.479376 -269.005483) (xy 341.517497 -268.974358) (xy 341.560118 -268.949751)
			(xy 341.606134 -268.932299) (xy 341.654353 -268.922455) (xy 341.703528 -268.920474) (xy 341.752383 -268.926406)
			(xy 341.799654 -268.940098) (xy 341.844116 -268.961196) (xy 341.884619 -268.989152) (xy 341.920112 -269.023244)
			(xy 341.949677 -269.062588) (xy 341.972548 -269.106165) (xy 341.988132 -269.152846) (xy 341.996027 -269.201423)
			(xy 341.996522 -269.22603) (xy 342.314779 -269.22603) (xy 342.318874 -269.175302) (xy 342.331053 -269.125888)
			(xy 342.351001 -269.079068) (xy 342.378202 -269.036054) (xy 342.41195 -268.99796) (xy 342.451372 -268.965773)
			(xy 342.495446 -268.940327) (xy 342.543032 -268.92228) (xy 342.592896 -268.9121) (xy 342.643748 -268.910051)
			(xy 342.694269 -268.916185) (xy 342.743153 -268.930345) (xy 342.789132 -268.952162) (xy 342.831016 -268.981072)
			(xy 342.86772 -269.016327) (xy 342.898293 -269.057013) (xy 342.921944 -269.102076) (xy 342.93806 -269.15035)
			(xy 342.946224 -269.200584) (xy 342.946736 -269.22603) (xy 343.265264 -269.22603) (xy 343.269224 -269.176976)
			(xy 343.281001 -269.129192) (xy 343.300292 -269.083916) (xy 343.326595 -269.04232) (xy 343.35923 -269.005483)
			(xy 343.397351 -268.974358) (xy 343.439972 -268.949751) (xy 343.485988 -268.932299) (xy 343.534207 -268.922455)
			(xy 343.583382 -268.920474) (xy 343.632237 -268.926406) (xy 343.679508 -268.940098) (xy 343.72397 -268.961196)
			(xy 343.764473 -268.989152) (xy 343.799966 -269.023244) (xy 343.829531 -269.062588) (xy 343.852402 -269.106165)
			(xy 343.867986 -269.152846) (xy 343.875881 -269.201423) (xy 343.876376 -269.22603) (xy 343.875881 -269.250637)
			(xy 343.867986 -269.299214) (xy 343.852402 -269.345895) (xy 343.829531 -269.389472) (xy 343.799966 -269.428816)
			(xy 343.764473 -269.462908) (xy 343.72397 -269.490864) (xy 343.679508 -269.511962) (xy 343.632237 -269.525654)
			(xy 343.583382 -269.531586) (xy 343.534207 -269.529605) (xy 343.485988 -269.519761) (xy 343.439972 -269.502309)
			(xy 343.397351 -269.477702) (xy 343.35923 -269.446577) (xy 343.326595 -269.40974) (xy 343.300292 -269.368144)
			(xy 343.281001 -269.322868) (xy 343.269224 -269.275084) (xy 343.265264 -269.22603) (xy 342.946736 -269.22603)
			(xy 342.946224 -269.251476) (xy 342.93806 -269.30171) (xy 342.921944 -269.349984) (xy 342.898293 -269.395047)
			(xy 342.86772 -269.435733) (xy 342.831016 -269.470988) (xy 342.789132 -269.499898) (xy 342.743153 -269.521715)
			(xy 342.694269 -269.535875) (xy 342.643748 -269.542009) (xy 342.592896 -269.53996) (xy 342.543032 -269.52978)
			(xy 342.495446 -269.511733) (xy 342.451372 -269.486287) (xy 342.41195 -269.4541) (xy 342.378202 -269.416006)
			(xy 342.351001 -269.372992) (xy 342.331053 -269.326172) (xy 342.318874 -269.276758) (xy 342.314779 -269.22603)
			(xy 341.996522 -269.22603) (xy 341.996027 -269.250637) (xy 341.988132 -269.299214) (xy 341.972548 -269.345895)
			(xy 341.949677 -269.389472) (xy 341.920112 -269.428816) (xy 341.884619 -269.462908) (xy 341.844116 -269.490864)
			(xy 341.799654 -269.511962) (xy 341.752383 -269.525654) (xy 341.703528 -269.531586) (xy 341.654353 -269.529605)
			(xy 341.606134 -269.519761) (xy 341.560118 -269.502309) (xy 341.517497 -269.477702) (xy 341.479376 -269.446577)
			(xy 341.446741 -269.40974) (xy 341.420438 -269.368144) (xy 341.401147 -269.322868) (xy 341.38937 -269.275084)
			(xy 341.38541 -269.22603) (xy 341.056468 -269.22603) (xy 341.055973 -269.250637) (xy 341.048078 -269.299214)
			(xy 341.032494 -269.345895) (xy 341.009623 -269.389472) (xy 340.980058 -269.428816) (xy 340.944565 -269.462908)
			(xy 340.904062 -269.490864) (xy 340.8596 -269.511962) (xy 340.812329 -269.525654) (xy 340.763474 -269.531586)
			(xy 340.714299 -269.529605) (xy 340.66608 -269.519761) (xy 340.620064 -269.502309) (xy 340.577443 -269.477702)
			(xy 340.539322 -269.446577) (xy 340.506687 -269.40974) (xy 340.480384 -269.368144) (xy 340.461093 -269.322868)
			(xy 340.449316 -269.275084) (xy 340.445356 -269.22603) (xy 340.116414 -269.22603) (xy 340.115919 -269.250637)
			(xy 340.108024 -269.299214) (xy 340.09244 -269.345895) (xy 340.069569 -269.389472) (xy 340.040004 -269.428816)
			(xy 340.004511 -269.462908) (xy 339.964008 -269.490864) (xy 339.919546 -269.511962) (xy 339.872275 -269.525654)
			(xy 339.82342 -269.531586) (xy 339.774245 -269.529605) (xy 339.726026 -269.519761) (xy 339.68001 -269.502309)
			(xy 339.637389 -269.477702) (xy 339.599268 -269.446577) (xy 339.566633 -269.40974) (xy 339.54033 -269.368144)
			(xy 339.521039 -269.322868) (xy 339.509262 -269.275084) (xy 339.505302 -269.22603) (xy 339.186774 -269.22603)
			(xy 339.186262 -269.251476) (xy 339.178098 -269.30171) (xy 339.161982 -269.349984) (xy 339.138331 -269.395047)
			(xy 339.107758 -269.435733) (xy 339.071054 -269.470988) (xy 339.02917 -269.499898) (xy 338.983191 -269.521715)
			(xy 338.934307 -269.535875) (xy 338.883786 -269.542009) (xy 338.832934 -269.53996) (xy 338.78307 -269.52978)
			(xy 338.735484 -269.511733) (xy 338.69141 -269.486287) (xy 338.651988 -269.4541) (xy 338.61824 -269.416006)
			(xy 338.591039 -269.372992) (xy 338.571091 -269.326172) (xy 338.558912 -269.276758) (xy 338.554817 -269.22603)
			(xy 338.236306 -269.22603) (xy 338.235818 -269.250849) (xy 338.227783 -269.299832) (xy 338.21193 -269.34687)
			(xy 338.188677 -269.390724) (xy 338.158636 -269.430239) (xy 338.122598 -269.464373) (xy 338.081512 -269.492228)
			(xy 338.036462 -269.51307) (xy 337.988634 -269.526349) (xy 337.964018 -269.52956) (xy 337.950048 -269.531084)
			(xy 337.92795 -269.547594) (xy 337.888072 -269.642336) (xy 337.884928 -269.650863) (xy 337.884224 -269.66901)
			(xy 337.889867 -269.686272) (xy 337.895184 -269.693644) (xy 337.897724 -269.696946) (xy 337.921658 -269.72886)
			(xy 337.961057 -269.798221) (xy 337.97621 -269.835122) (xy 337.98129 -269.84833) (xy 338.00288 -269.865348)
			(xy 338.119466 -269.880334) (xy 338.144866 -269.869158) (xy 338.153248 -269.857728) (xy 338.167715 -269.83843)
			(xy 338.201705 -269.804217) (xy 338.240645 -269.775763) (xy 338.283569 -269.753776) (xy 338.329412 -269.738799)
			(xy 338.377038 -269.731205) (xy 338.401152 -269.730728) (xy 338.426409 -269.731217) (xy 338.476236 -269.739524)
			(xy 338.524016 -269.75592) (xy 338.568444 -269.779958) (xy 338.60831 -269.810981) (xy 338.642526 -269.848143)
			(xy 338.670157 -269.890431) (xy 338.69045 -269.93669) (xy 338.702852 -269.985658) (xy 338.707024 -270.036)
			(xy 338.707021 -270.036036) (xy 339.024971 -270.036036) (xy 339.029066 -269.985308) (xy 339.041245 -269.935894)
			(xy 339.061193 -269.889074) (xy 339.088394 -269.84606) (xy 339.122142 -269.807966) (xy 339.161564 -269.775779)
			(xy 339.205638 -269.750333) (xy 339.253224 -269.732286) (xy 339.303088 -269.722106) (xy 339.35394 -269.720057)
			(xy 339.404461 -269.726191) (xy 339.453345 -269.740351) (xy 339.499324 -269.762168) (xy 339.541208 -269.791078)
			(xy 339.577912 -269.826333) (xy 339.608485 -269.867019) (xy 339.632136 -269.912082) (xy 339.648252 -269.960356)
			(xy 339.656416 -270.01059) (xy 339.656928 -270.036036) (xy 339.964771 -270.036036) (xy 339.968866 -269.985308)
			(xy 339.981045 -269.935894) (xy 340.000993 -269.889074) (xy 340.028194 -269.84606) (xy 340.061942 -269.807966)
			(xy 340.101364 -269.775779) (xy 340.145438 -269.750333) (xy 340.193024 -269.732286) (xy 340.242888 -269.722106)
			(xy 340.29374 -269.720057) (xy 340.344261 -269.726191) (xy 340.393145 -269.740351) (xy 340.439124 -269.762168)
			(xy 340.481008 -269.791078) (xy 340.517712 -269.826333) (xy 340.548285 -269.867019) (xy 340.571936 -269.912082)
			(xy 340.588052 -269.960356) (xy 340.596216 -270.01059) (xy 340.596728 -270.036036) (xy 340.915256 -270.036036)
			(xy 340.919216 -269.986982) (xy 340.930993 -269.939198) (xy 340.950284 -269.893922) (xy 340.976587 -269.852326)
			(xy 341.009222 -269.815489) (xy 341.047343 -269.784364) (xy 341.089964 -269.759757) (xy 341.13598 -269.742305)
			(xy 341.184199 -269.732461) (xy 341.233374 -269.73048) (xy 341.282229 -269.736412) (xy 341.3295 -269.750104)
			(xy 341.373962 -269.771202) (xy 341.414465 -269.799158) (xy 341.449958 -269.83325) (xy 341.479523 -269.872594)
			(xy 341.502394 -269.916171) (xy 341.517978 -269.962852) (xy 341.525873 -270.011429) (xy 341.526368 -270.036036)
			(xy 341.844879 -270.036036) (xy 341.848974 -269.985308) (xy 341.861153 -269.935894) (xy 341.881101 -269.889074)
			(xy 341.908302 -269.84606) (xy 341.94205 -269.807966) (xy 341.981472 -269.775779) (xy 342.025546 -269.750333)
			(xy 342.073132 -269.732286) (xy 342.122996 -269.722106) (xy 342.173848 -269.720057) (xy 342.224369 -269.726191)
			(xy 342.273253 -269.740351) (xy 342.319232 -269.762168) (xy 342.361116 -269.791078) (xy 342.39782 -269.826333)
			(xy 342.428393 -269.867019) (xy 342.452044 -269.912082) (xy 342.46816 -269.960356) (xy 342.476324 -270.01059)
			(xy 342.476836 -270.036036) (xy 342.795364 -270.036036) (xy 342.799324 -269.986982) (xy 342.811101 -269.939198)
			(xy 342.830392 -269.893922) (xy 342.856695 -269.852326) (xy 342.88933 -269.815489) (xy 342.927451 -269.784364)
			(xy 342.970072 -269.759757) (xy 343.016088 -269.742305) (xy 343.064307 -269.732461) (xy 343.113482 -269.73048)
			(xy 343.162337 -269.736412) (xy 343.209608 -269.750104) (xy 343.25407 -269.771202) (xy 343.294573 -269.799158)
			(xy 343.330066 -269.83325) (xy 343.359631 -269.872594) (xy 343.382502 -269.916171) (xy 343.398086 -269.962852)
			(xy 343.405981 -270.011429) (xy 343.406476 -270.036036) (xy 343.724987 -270.036036) (xy 343.729082 -269.985308)
			(xy 343.741261 -269.935894) (xy 343.761209 -269.889074) (xy 343.78841 -269.84606) (xy 343.822158 -269.807966)
			(xy 343.86158 -269.775779) (xy 343.905654 -269.750333) (xy 343.95324 -269.732286) (xy 344.003104 -269.722106)
			(xy 344.053956 -269.720057) (xy 344.104477 -269.726191) (xy 344.153361 -269.740351) (xy 344.19934 -269.762168)
			(xy 344.241224 -269.791078) (xy 344.277928 -269.826333) (xy 344.308501 -269.867019) (xy 344.332152 -269.912082)
			(xy 344.348268 -269.960356) (xy 344.356432 -270.01059) (xy 344.356944 -270.036036) (xy 344.356432 -270.061482)
			(xy 344.348268 -270.111716) (xy 344.332152 -270.15999) (xy 344.308501 -270.205053) (xy 344.277928 -270.245739)
			(xy 344.241224 -270.280994) (xy 344.19934 -270.309904) (xy 344.153361 -270.331721) (xy 344.104477 -270.345881)
			(xy 344.053956 -270.352015) (xy 344.003104 -270.349966) (xy 343.95324 -270.339786) (xy 343.905654 -270.321739)
			(xy 343.86158 -270.296293) (xy 343.822158 -270.264106) (xy 343.78841 -270.226012) (xy 343.761209 -270.182998)
			(xy 343.741261 -270.136178) (xy 343.729082 -270.086764) (xy 343.724987 -270.036036) (xy 343.406476 -270.036036)
			(xy 343.405981 -270.060643) (xy 343.398086 -270.10922) (xy 343.382502 -270.155901) (xy 343.359631 -270.199478)
			(xy 343.330066 -270.238822) (xy 343.294573 -270.272914) (xy 343.25407 -270.30087) (xy 343.209608 -270.321968)
			(xy 343.162337 -270.33566) (xy 343.113482 -270.341592) (xy 343.064307 -270.339611) (xy 343.016088 -270.329767)
			(xy 342.970072 -270.312315) (xy 342.927451 -270.287708) (xy 342.88933 -270.256583) (xy 342.856695 -270.219746)
			(xy 342.830392 -270.17815) (xy 342.811101 -270.132874) (xy 342.799324 -270.08509) (xy 342.795364 -270.036036)
			(xy 342.476836 -270.036036) (xy 342.476324 -270.061482) (xy 342.46816 -270.111716) (xy 342.452044 -270.15999)
			(xy 342.428393 -270.205053) (xy 342.39782 -270.245739) (xy 342.361116 -270.280994) (xy 342.319232 -270.309904)
			(xy 342.273253 -270.331721) (xy 342.224369 -270.345881) (xy 342.173848 -270.352015) (xy 342.122996 -270.349966)
			(xy 342.073132 -270.339786) (xy 342.025546 -270.321739) (xy 341.981472 -270.296293) (xy 341.94205 -270.264106)
			(xy 341.908302 -270.226012) (xy 341.881101 -270.182998) (xy 341.861153 -270.136178) (xy 341.848974 -270.086764)
			(xy 341.844879 -270.036036) (xy 341.526368 -270.036036) (xy 341.525873 -270.060643) (xy 341.517978 -270.10922)
			(xy 341.502394 -270.155901) (xy 341.479523 -270.199478) (xy 341.449958 -270.238822) (xy 341.414465 -270.272914)
			(xy 341.373962 -270.30087) (xy 341.3295 -270.321968) (xy 341.282229 -270.33566) (xy 341.233374 -270.341592)
			(xy 341.184199 -270.339611) (xy 341.13598 -270.329767) (xy 341.089964 -270.312315) (xy 341.047343 -270.287708)
			(xy 341.009222 -270.256583) (xy 340.976587 -270.219746) (xy 340.950284 -270.17815) (xy 340.930993 -270.132874)
			(xy 340.919216 -270.08509) (xy 340.915256 -270.036036) (xy 340.596728 -270.036036) (xy 340.596216 -270.061482)
			(xy 340.588052 -270.111716) (xy 340.571936 -270.15999) (xy 340.548285 -270.205053) (xy 340.517712 -270.245739)
			(xy 340.481008 -270.280994) (xy 340.439124 -270.309904) (xy 340.393145 -270.331721) (xy 340.344261 -270.345881)
			(xy 340.29374 -270.352015) (xy 340.242888 -270.349966) (xy 340.193024 -270.339786) (xy 340.145438 -270.321739)
			(xy 340.101364 -270.296293) (xy 340.061942 -270.264106) (xy 340.028194 -270.226012) (xy 340.000993 -270.182998)
			(xy 339.981045 -270.136178) (xy 339.968866 -270.086764) (xy 339.964771 -270.036036) (xy 339.656928 -270.036036)
			(xy 339.656416 -270.061482) (xy 339.648252 -270.111716) (xy 339.632136 -270.15999) (xy 339.608485 -270.205053)
			(xy 339.577912 -270.245739) (xy 339.541208 -270.280994) (xy 339.499324 -270.309904) (xy 339.453345 -270.331721)
			(xy 339.404461 -270.345881) (xy 339.35394 -270.352015) (xy 339.303088 -270.349966) (xy 339.253224 -270.339786)
			(xy 339.205638 -270.321739) (xy 339.161564 -270.296293) (xy 339.122142 -270.264106) (xy 339.088394 -270.226012)
			(xy 339.061193 -270.182998) (xy 339.041245 -270.136178) (xy 339.029066 -270.086764) (xy 339.024971 -270.036036)
			(xy 338.707021 -270.036036) (xy 338.702852 -270.086342) (xy 338.69045 -270.13531) (xy 338.670157 -270.181569)
			(xy 338.642526 -270.223857) (xy 338.60831 -270.261019) (xy 338.568444 -270.292042) (xy 338.524016 -270.31608)
			(xy 338.476236 -270.332476) (xy 338.426409 -270.340783) (xy 338.401152 -270.341344) (xy 338.388389 -270.341205)
			(xy 338.362955 -270.339042) (xy 338.350352 -270.337026) (xy 338.350352 -270.33728) (xy 338.326896 -270.332856)
			(xy 338.281636 -270.317701) (xy 338.239278 -270.295703) (xy 338.200848 -270.267396) (xy 338.167279 -270.233466)
			(xy 338.152994 -270.214344) (xy 338.144866 -270.202914) (xy 338.119212 -270.191738) (xy 338.017104 -270.204946)
			(xy 338.003134 -270.206724) (xy 337.98129 -270.223742) (xy 337.97621 -270.23695) (xy 337.969352 -270.25346)
			(xy 337.962655 -270.268831) (xy 337.947659 -270.298824) (xy 337.93938 -270.313404) (xy 337.894168 -270.391382)
			(xy 337.892644 -270.394176) (xy 337.892644 -270.39443) (xy 337.887947 -270.405251) (xy 337.887962 -270.428813)
			(xy 337.892644 -270.439642) (xy 337.929474 -270.514064) (xy 337.935087 -270.524675) (xy 337.953917 -270.53951)
			(xy 337.965542 -270.542512) (xy 337.969098 -270.54302) (xy 337.993656 -270.54662) (xy 338.041239 -270.560735)
			(xy 338.085914 -270.582357) (xy 338.126507 -270.610915) (xy 338.161949 -270.64566) (xy 338.191308 -270.685677)
			(xy 338.213813 -270.729914) (xy 338.228871 -270.777207) (xy 338.236086 -270.826312) (xy 338.235761 -270.846042)
			(xy 338.554817 -270.846042) (xy 338.558912 -270.795314) (xy 338.571091 -270.7459) (xy 338.591039 -270.69908)
			(xy 338.61824 -270.656066) (xy 338.651988 -270.617972) (xy 338.69141 -270.585785) (xy 338.735484 -270.560339)
			(xy 338.78307 -270.542292) (xy 338.832934 -270.532112) (xy 338.883786 -270.530063) (xy 338.934307 -270.536197)
			(xy 338.983191 -270.550357) (xy 339.02917 -270.572174) (xy 339.071054 -270.601084) (xy 339.107758 -270.636339)
			(xy 339.138331 -270.677025) (xy 339.161982 -270.722088) (xy 339.178098 -270.770362) (xy 339.186262 -270.820596)
			(xy 339.186774 -270.846042) (xy 339.505302 -270.846042) (xy 339.509262 -270.796988) (xy 339.521039 -270.749204)
			(xy 339.54033 -270.703928) (xy 339.566633 -270.662332) (xy 339.599268 -270.625495) (xy 339.637389 -270.59437)
			(xy 339.68001 -270.569763) (xy 339.726026 -270.552311) (xy 339.774245 -270.542467) (xy 339.82342 -270.540486)
			(xy 339.872275 -270.546418) (xy 339.919546 -270.56011) (xy 339.964008 -270.581208) (xy 340.004511 -270.609164)
			(xy 340.040004 -270.643256) (xy 340.069569 -270.6826) (xy 340.09244 -270.726177) (xy 340.108024 -270.772858)
			(xy 340.115919 -270.821435) (xy 340.116414 -270.846042) (xy 340.434925 -270.846042) (xy 340.43902 -270.795314)
			(xy 340.451199 -270.7459) (xy 340.471147 -270.69908) (xy 340.498348 -270.656066) (xy 340.532096 -270.617972)
			(xy 340.571518 -270.585785) (xy 340.615592 -270.560339) (xy 340.663178 -270.542292) (xy 340.713042 -270.532112)
			(xy 340.763894 -270.530063) (xy 340.814415 -270.536197) (xy 340.863299 -270.550357) (xy 340.909278 -270.572174)
			(xy 340.951162 -270.601084) (xy 340.987866 -270.636339) (xy 341.018439 -270.677025) (xy 341.04209 -270.722088)
			(xy 341.058206 -270.770362) (xy 341.06637 -270.820596) (xy 341.066882 -270.846042) (xy 341.38541 -270.846042)
			(xy 341.38937 -270.796988) (xy 341.401147 -270.749204) (xy 341.420438 -270.703928) (xy 341.446741 -270.662332)
			(xy 341.479376 -270.625495) (xy 341.517497 -270.59437) (xy 341.560118 -270.569763) (xy 341.606134 -270.552311)
			(xy 341.654353 -270.542467) (xy 341.703528 -270.540486) (xy 341.752383 -270.546418) (xy 341.799654 -270.56011)
			(xy 341.844116 -270.581208) (xy 341.884619 -270.609164) (xy 341.920112 -270.643256) (xy 341.949677 -270.6826)
			(xy 341.972548 -270.726177) (xy 341.988132 -270.772858) (xy 341.996027 -270.821435) (xy 341.996522 -270.846042)
			(xy 342.314779 -270.846042) (xy 342.318874 -270.795314) (xy 342.331053 -270.7459) (xy 342.351001 -270.69908)
			(xy 342.378202 -270.656066) (xy 342.41195 -270.617972) (xy 342.451372 -270.585785) (xy 342.495446 -270.560339)
			(xy 342.543032 -270.542292) (xy 342.592896 -270.532112) (xy 342.643748 -270.530063) (xy 342.694269 -270.536197)
			(xy 342.743153 -270.550357) (xy 342.789132 -270.572174) (xy 342.831016 -270.601084) (xy 342.86772 -270.636339)
			(xy 342.898293 -270.677025) (xy 342.921944 -270.722088) (xy 342.93806 -270.770362) (xy 342.946224 -270.820596)
			(xy 342.946736 -270.846042) (xy 343.254833 -270.846042) (xy 343.258928 -270.795314) (xy 343.271107 -270.7459)
			(xy 343.291055 -270.69908) (xy 343.318256 -270.656066) (xy 343.352004 -270.617972) (xy 343.391426 -270.585785)
			(xy 343.4355 -270.560339) (xy 343.483086 -270.542292) (xy 343.53295 -270.532112) (xy 343.583802 -270.530063)
			(xy 343.634323 -270.536197) (xy 343.683207 -270.550357) (xy 343.729186 -270.572174) (xy 343.77107 -270.601084)
			(xy 343.807774 -270.636339) (xy 343.838347 -270.677025) (xy 343.861998 -270.722088) (xy 343.878114 -270.770362)
			(xy 343.886278 -270.820596) (xy 343.88679 -270.846042) (xy 343.886278 -270.871488) (xy 343.878114 -270.921722)
			(xy 343.861998 -270.969996) (xy 343.838347 -271.015059) (xy 343.807774 -271.055745) (xy 343.77107 -271.091)
			(xy 343.729186 -271.11991) (xy 343.683207 -271.141727) (xy 343.634323 -271.155887) (xy 343.583802 -271.162021)
			(xy 343.53295 -271.159972) (xy 343.483086 -271.149792) (xy 343.4355 -271.131745) (xy 343.391426 -271.106299)
			(xy 343.352004 -271.074112) (xy 343.318256 -271.036018) (xy 343.291055 -270.993004) (xy 343.271107 -270.946184)
			(xy 343.258928 -270.89677) (xy 343.254833 -270.846042) (xy 342.946736 -270.846042) (xy 342.946224 -270.871488)
			(xy 342.93806 -270.921722) (xy 342.921944 -270.969996) (xy 342.898293 -271.015059) (xy 342.86772 -271.055745)
			(xy 342.831016 -271.091) (xy 342.789132 -271.11991) (xy 342.743153 -271.141727) (xy 342.694269 -271.155887)
			(xy 342.643748 -271.162021) (xy 342.592896 -271.159972) (xy 342.543032 -271.149792) (xy 342.495446 -271.131745)
			(xy 342.451372 -271.106299) (xy 342.41195 -271.074112) (xy 342.378202 -271.036018) (xy 342.351001 -270.993004)
			(xy 342.331053 -270.946184) (xy 342.318874 -270.89677) (xy 342.314779 -270.846042) (xy 341.996522 -270.846042)
			(xy 341.996027 -270.870649) (xy 341.988132 -270.919226) (xy 341.972548 -270.965907) (xy 341.949677 -271.009484)
			(xy 341.920112 -271.048828) (xy 341.884619 -271.08292) (xy 341.844116 -271.110876) (xy 341.799654 -271.131974)
			(xy 341.752383 -271.145666) (xy 341.703528 -271.151598) (xy 341.654353 -271.149617) (xy 341.606134 -271.139773)
			(xy 341.560118 -271.122321) (xy 341.517497 -271.097714) (xy 341.479376 -271.066589) (xy 341.446741 -271.029752)
			(xy 341.420438 -270.988156) (xy 341.401147 -270.94288) (xy 341.38937 -270.895096) (xy 341.38541 -270.846042)
			(xy 341.066882 -270.846042) (xy 341.06637 -270.871488) (xy 341.058206 -270.921722) (xy 341.04209 -270.969996)
			(xy 341.018439 -271.015059) (xy 340.987866 -271.055745) (xy 340.951162 -271.091) (xy 340.909278 -271.11991)
			(xy 340.863299 -271.141727) (xy 340.814415 -271.155887) (xy 340.763894 -271.162021) (xy 340.713042 -271.159972)
			(xy 340.663178 -271.149792) (xy 340.615592 -271.131745) (xy 340.571518 -271.106299) (xy 340.532096 -271.074112)
			(xy 340.498348 -271.036018) (xy 340.471147 -270.993004) (xy 340.451199 -270.946184) (xy 340.43902 -270.89677)
			(xy 340.434925 -270.846042) (xy 340.116414 -270.846042) (xy 340.115919 -270.870649) (xy 340.108024 -270.919226)
			(xy 340.09244 -270.965907) (xy 340.069569 -271.009484) (xy 340.040004 -271.048828) (xy 340.004511 -271.08292)
			(xy 339.964008 -271.110876) (xy 339.919546 -271.131974) (xy 339.872275 -271.145666) (xy 339.82342 -271.151598)
			(xy 339.774245 -271.149617) (xy 339.726026 -271.139773) (xy 339.68001 -271.122321) (xy 339.637389 -271.097714)
			(xy 339.599268 -271.066589) (xy 339.566633 -271.029752) (xy 339.54033 -270.988156) (xy 339.521039 -270.94288)
			(xy 339.509262 -270.895096) (xy 339.505302 -270.846042) (xy 339.186774 -270.846042) (xy 339.186262 -270.871488)
			(xy 339.178098 -270.921722) (xy 339.161982 -270.969996) (xy 339.138331 -271.015059) (xy 339.107758 -271.055745)
			(xy 339.071054 -271.091) (xy 339.02917 -271.11991) (xy 338.983191 -271.141727) (xy 338.934307 -271.155887)
			(xy 338.883786 -271.162021) (xy 338.832934 -271.159972) (xy 338.78307 -271.149792) (xy 338.735484 -271.131745)
			(xy 338.69141 -271.106299) (xy 338.651988 -271.074112) (xy 338.61824 -271.036018) (xy 338.591039 -270.993004)
			(xy 338.571091 -270.946184) (xy 338.558912 -270.89677) (xy 338.554817 -270.846042) (xy 338.235761 -270.846042)
			(xy 338.235268 -270.875938) (xy 338.226439 -270.924778) (xy 338.209832 -270.971549) (xy 338.185882 -271.015021)
			(xy 338.15522 -271.054049) (xy 338.118653 -271.087607) (xy 338.09813 -271.101566) (xy 338.0783 -271.114049)
			(xy 338.035645 -271.133441) (xy 337.990529 -271.146094) (xy 337.96732 -271.149318) (xy 337.967066 -271.149318)
			(xy 337.958092 -271.150682) (xy 337.94188 -271.15882) (xy 337.929502 -271.17208) (xy 337.925664 -271.180306)
			(xy 337.886294 -271.275048) (xy 337.890104 -271.301972) (xy 337.898486 -271.312894) (xy 337.922857 -271.345133)
			(xy 337.963022 -271.41526) (xy 337.978496 -271.452594) (xy 337.983576 -271.465548) (xy 338.00542 -271.482566)
			(xy 338.075524 -271.491456) (xy 338.081874 -271.491964) (xy 338.11718 -271.491964) (xy 338.129003 -271.491416)
			(xy 338.150201 -271.480954) (xy 338.15782 -271.471898) (xy 338.172327 -271.453417) (xy 338.206062 -271.42072)
			(xy 338.244411 -271.393581) (xy 338.286468 -271.372642) (xy 338.331238 -271.3584) (xy 338.377662 -271.351189)
			(xy 338.401152 -271.35074) (xy 338.426408 -271.351229) (xy 338.476233 -271.359536) (xy 338.524011 -271.375931)
			(xy 338.568438 -271.399968) (xy 338.608302 -271.43099) (xy 338.642516 -271.46815) (xy 338.670146 -271.510436)
			(xy 338.690439 -271.556693) (xy 338.70284 -271.60566) (xy 338.707012 -271.656) (xy 338.707008 -271.656048)
			(xy 339.024971 -271.656048) (xy 339.029066 -271.60532) (xy 339.041245 -271.555906) (xy 339.061193 -271.509086)
			(xy 339.088394 -271.466072) (xy 339.122142 -271.427978) (xy 339.161564 -271.395791) (xy 339.205638 -271.370345)
			(xy 339.253224 -271.352298) (xy 339.303088 -271.342118) (xy 339.35394 -271.340069) (xy 339.404461 -271.346203)
			(xy 339.453345 -271.360363) (xy 339.499324 -271.38218) (xy 339.541208 -271.41109) (xy 339.577912 -271.446345)
			(xy 339.608485 -271.487031) (xy 339.632136 -271.532094) (xy 339.648252 -271.580368) (xy 339.656416 -271.630602)
			(xy 339.656928 -271.656048) (xy 339.964771 -271.656048) (xy 339.968866 -271.60532) (xy 339.981045 -271.555906)
			(xy 340.000993 -271.509086) (xy 340.028194 -271.466072) (xy 340.061942 -271.427978) (xy 340.101364 -271.395791)
			(xy 340.145438 -271.370345) (xy 340.193024 -271.352298) (xy 340.242888 -271.342118) (xy 340.29374 -271.340069)
			(xy 340.344261 -271.346203) (xy 340.393145 -271.360363) (xy 340.439124 -271.38218) (xy 340.481008 -271.41109)
			(xy 340.517712 -271.446345) (xy 340.548285 -271.487031) (xy 340.571936 -271.532094) (xy 340.588052 -271.580368)
			(xy 340.596216 -271.630602) (xy 340.596728 -271.656048) (xy 340.915256 -271.656048) (xy 340.919216 -271.606994)
			(xy 340.930993 -271.55921) (xy 340.950284 -271.513934) (xy 340.976587 -271.472338) (xy 341.009222 -271.435501)
			(xy 341.047343 -271.404376) (xy 341.089964 -271.379769) (xy 341.13598 -271.362317) (xy 341.184199 -271.352473)
			(xy 341.233374 -271.350492) (xy 341.282229 -271.356424) (xy 341.3295 -271.370116) (xy 341.373962 -271.391214)
			(xy 341.414465 -271.41917) (xy 341.449958 -271.453262) (xy 341.479523 -271.492606) (xy 341.502394 -271.536183)
			(xy 341.517978 -271.582864) (xy 341.525873 -271.631441) (xy 341.526368 -271.656048) (xy 341.844879 -271.656048)
			(xy 341.848974 -271.60532) (xy 341.861153 -271.555906) (xy 341.881101 -271.509086) (xy 341.908302 -271.466072)
			(xy 341.94205 -271.427978) (xy 341.981472 -271.395791) (xy 342.025546 -271.370345) (xy 342.073132 -271.352298)
			(xy 342.122996 -271.342118) (xy 342.173848 -271.340069) (xy 342.224369 -271.346203) (xy 342.273253 -271.360363)
			(xy 342.319232 -271.38218) (xy 342.361116 -271.41109) (xy 342.39782 -271.446345) (xy 342.428393 -271.487031)
			(xy 342.452044 -271.532094) (xy 342.46816 -271.580368) (xy 342.476324 -271.630602) (xy 342.476836 -271.656048)
			(xy 342.795364 -271.656048) (xy 342.799324 -271.606994) (xy 342.811101 -271.55921) (xy 342.830392 -271.513934)
			(xy 342.856695 -271.472338) (xy 342.88933 -271.435501) (xy 342.927451 -271.404376) (xy 342.970072 -271.379769)
			(xy 343.016088 -271.362317) (xy 343.064307 -271.352473) (xy 343.113482 -271.350492) (xy 343.162337 -271.356424)
			(xy 343.209608 -271.370116) (xy 343.25407 -271.391214) (xy 343.294573 -271.41917) (xy 343.330066 -271.453262)
			(xy 343.359631 -271.492606) (xy 343.382502 -271.536183) (xy 343.398086 -271.582864) (xy 343.405981 -271.631441)
			(xy 343.406476 -271.656048) (xy 343.724987 -271.656048) (xy 343.729082 -271.60532) (xy 343.741261 -271.555906)
			(xy 343.761209 -271.509086) (xy 343.78841 -271.466072) (xy 343.822158 -271.427978) (xy 343.86158 -271.395791)
			(xy 343.905654 -271.370345) (xy 343.95324 -271.352298) (xy 344.003104 -271.342118) (xy 344.053956 -271.340069)
			(xy 344.104477 -271.346203) (xy 344.153361 -271.360363) (xy 344.19934 -271.38218) (xy 344.241224 -271.41109)
			(xy 344.277928 -271.446345) (xy 344.308501 -271.487031) (xy 344.332152 -271.532094) (xy 344.348268 -271.580368)
			(xy 344.356432 -271.630602) (xy 344.356944 -271.656048) (xy 344.356432 -271.681494) (xy 344.348268 -271.731728)
			(xy 344.332152 -271.780002) (xy 344.308501 -271.825065) (xy 344.277928 -271.865751) (xy 344.241224 -271.901006)
			(xy 344.19934 -271.929916) (xy 344.153361 -271.951733) (xy 344.104477 -271.965893) (xy 344.053956 -271.972027)
			(xy 344.003104 -271.969978) (xy 343.95324 -271.959798) (xy 343.905654 -271.941751) (xy 343.86158 -271.916305)
			(xy 343.822158 -271.884118) (xy 343.78841 -271.846024) (xy 343.761209 -271.80301) (xy 343.741261 -271.75619)
			(xy 343.729082 -271.706776) (xy 343.724987 -271.656048) (xy 343.406476 -271.656048) (xy 343.405981 -271.680655)
			(xy 343.398086 -271.729232) (xy 343.382502 -271.775913) (xy 343.359631 -271.81949) (xy 343.330066 -271.858834)
			(xy 343.294573 -271.892926) (xy 343.25407 -271.920882) (xy 343.209608 -271.94198) (xy 343.162337 -271.955672)
			(xy 343.113482 -271.961604) (xy 343.064307 -271.959623) (xy 343.016088 -271.949779) (xy 342.970072 -271.932327)
			(xy 342.927451 -271.90772) (xy 342.88933 -271.876595) (xy 342.856695 -271.839758) (xy 342.830392 -271.798162)
			(xy 342.811101 -271.752886) (xy 342.799324 -271.705102) (xy 342.795364 -271.656048) (xy 342.476836 -271.656048)
			(xy 342.476324 -271.681494) (xy 342.46816 -271.731728) (xy 342.452044 -271.780002) (xy 342.428393 -271.825065)
			(xy 342.39782 -271.865751) (xy 342.361116 -271.901006) (xy 342.319232 -271.929916) (xy 342.273253 -271.951733)
			(xy 342.224369 -271.965893) (xy 342.173848 -271.972027) (xy 342.122996 -271.969978) (xy 342.073132 -271.959798)
			(xy 342.025546 -271.941751) (xy 341.981472 -271.916305) (xy 341.94205 -271.884118) (xy 341.908302 -271.846024)
			(xy 341.881101 -271.80301) (xy 341.861153 -271.75619) (xy 341.848974 -271.706776) (xy 341.844879 -271.656048)
			(xy 341.526368 -271.656048) (xy 341.525873 -271.680655) (xy 341.517978 -271.729232) (xy 341.502394 -271.775913)
			(xy 341.479523 -271.81949) (xy 341.449958 -271.858834) (xy 341.414465 -271.892926) (xy 341.373962 -271.920882)
			(xy 341.3295 -271.94198) (xy 341.282229 -271.955672) (xy 341.233374 -271.961604) (xy 341.184199 -271.959623)
			(xy 341.13598 -271.949779) (xy 341.089964 -271.932327) (xy 341.047343 -271.90772) (xy 341.009222 -271.876595)
			(xy 340.976587 -271.839758) (xy 340.950284 -271.798162) (xy 340.930993 -271.752886) (xy 340.919216 -271.705102)
			(xy 340.915256 -271.656048) (xy 340.596728 -271.656048) (xy 340.596216 -271.681494) (xy 340.588052 -271.731728)
			(xy 340.571936 -271.780002) (xy 340.548285 -271.825065) (xy 340.517712 -271.865751) (xy 340.481008 -271.901006)
			(xy 340.439124 -271.929916) (xy 340.393145 -271.951733) (xy 340.344261 -271.965893) (xy 340.29374 -271.972027)
			(xy 340.242888 -271.969978) (xy 340.193024 -271.959798) (xy 340.145438 -271.941751) (xy 340.101364 -271.916305)
			(xy 340.061942 -271.884118) (xy 340.028194 -271.846024) (xy 340.000993 -271.80301) (xy 339.981045 -271.75619)
			(xy 339.968866 -271.706776) (xy 339.964771 -271.656048) (xy 339.656928 -271.656048) (xy 339.656416 -271.681494)
			(xy 339.648252 -271.731728) (xy 339.632136 -271.780002) (xy 339.608485 -271.825065) (xy 339.577912 -271.865751)
			(xy 339.541208 -271.901006) (xy 339.499324 -271.929916) (xy 339.453345 -271.951733) (xy 339.404461 -271.965893)
			(xy 339.35394 -271.972027) (xy 339.303088 -271.969978) (xy 339.253224 -271.959798) (xy 339.205638 -271.941751)
			(xy 339.161564 -271.916305) (xy 339.122142 -271.884118) (xy 339.088394 -271.846024) (xy 339.061193 -271.80301)
			(xy 339.041245 -271.75619) (xy 339.029066 -271.706776) (xy 339.024971 -271.656048) (xy 338.707008 -271.656048)
			(xy 338.70284 -271.70634) (xy 338.690439 -271.755307) (xy 338.670146 -271.801564) (xy 338.642516 -271.84385)
			(xy 338.608302 -271.88101) (xy 338.568438 -271.912032) (xy 338.524011 -271.936069) (xy 338.476233 -271.952464)
			(xy 338.426408 -271.960771) (xy 338.401152 -271.961356) (xy 338.377666 -271.960899) (xy 338.331254 -271.953657)
			(xy 338.286497 -271.939398) (xy 338.24445 -271.918457) (xy 338.206102 -271.891328) (xy 338.172359 -271.858649)
			(xy 338.15782 -271.840198) (xy 338.150177 -271.831172) (xy 338.128993 -271.820718) (xy 338.11718 -271.820132)
			(xy 338.081874 -271.820132) (xy 338.075524 -271.82064) (xy 338.00542 -271.82953) (xy 337.983576 -271.846548)
			(xy 337.978496 -271.859502) (xy 337.965288 -271.89049) (xy 337.959955 -271.901829) (xy 337.948394 -271.924062)
			(xy 337.942174 -271.93494) (xy 337.912964 -271.985232) (xy 337.897724 -272.011648) (xy 337.891944 -272.022796)
			(xy 337.891001 -272.047858) (xy 337.895946 -272.0594) (xy 337.938618 -272.14703) (xy 337.958938 -272.161762)
			(xy 337.971892 -272.16354) (xy 337.995984 -272.167277) (xy 338.042646 -272.181401) (xy 338.086469 -272.202761)
			(xy 338.126342 -272.230813) (xy 338.161249 -272.264846) (xy 338.190305 -272.303993) (xy 338.212771 -272.34726)
			(xy 338.228076 -272.393547) (xy 338.235831 -272.441678) (xy 338.236306 -272.466054) (xy 338.554817 -272.466054)
			(xy 338.558912 -272.415326) (xy 338.571091 -272.365912) (xy 338.591039 -272.319092) (xy 338.61824 -272.276078)
			(xy 338.651988 -272.237984) (xy 338.69141 -272.205797) (xy 338.735484 -272.180351) (xy 338.78307 -272.162304)
			(xy 338.832934 -272.152124) (xy 338.883786 -272.150075) (xy 338.934307 -272.156209) (xy 338.983191 -272.170369)
			(xy 339.02917 -272.192186) (xy 339.071054 -272.221096) (xy 339.107758 -272.256351) (xy 339.138331 -272.297037)
			(xy 339.161982 -272.3421) (xy 339.178098 -272.390374) (xy 339.186262 -272.440608) (xy 339.186774 -272.466054)
			(xy 339.505302 -272.466054) (xy 339.509262 -272.417) (xy 339.521039 -272.369216) (xy 339.54033 -272.32394)
			(xy 339.566633 -272.282344) (xy 339.599268 -272.245507) (xy 339.637389 -272.214382) (xy 339.68001 -272.189775)
			(xy 339.726026 -272.172323) (xy 339.774245 -272.162479) (xy 339.82342 -272.160498) (xy 339.872275 -272.16643)
			(xy 339.919546 -272.180122) (xy 339.964008 -272.20122) (xy 340.004511 -272.229176) (xy 340.040004 -272.263268)
			(xy 340.069569 -272.302612) (xy 340.09244 -272.346189) (xy 340.108024 -272.39287) (xy 340.115919 -272.441447)
			(xy 340.116414 -272.466054) (xy 340.434925 -272.466054) (xy 340.43902 -272.415326) (xy 340.451199 -272.365912)
			(xy 340.471147 -272.319092) (xy 340.498348 -272.276078) (xy 340.532096 -272.237984) (xy 340.571518 -272.205797)
			(xy 340.615592 -272.180351) (xy 340.663178 -272.162304) (xy 340.713042 -272.152124) (xy 340.763894 -272.150075)
			(xy 340.814415 -272.156209) (xy 340.863299 -272.170369) (xy 340.909278 -272.192186) (xy 340.951162 -272.221096)
			(xy 340.987866 -272.256351) (xy 341.018439 -272.297037) (xy 341.04209 -272.3421) (xy 341.058206 -272.390374)
			(xy 341.06637 -272.440608) (xy 341.066882 -272.466054) (xy 341.38541 -272.466054) (xy 341.38937 -272.417)
			(xy 341.401147 -272.369216) (xy 341.420438 -272.32394) (xy 341.446741 -272.282344) (xy 341.479376 -272.245507)
			(xy 341.517497 -272.214382) (xy 341.560118 -272.189775) (xy 341.606134 -272.172323) (xy 341.654353 -272.162479)
			(xy 341.703528 -272.160498) (xy 341.752383 -272.16643) (xy 341.799654 -272.180122) (xy 341.844116 -272.20122)
			(xy 341.884619 -272.229176) (xy 341.920112 -272.263268) (xy 341.949677 -272.302612) (xy 341.972548 -272.346189)
			(xy 341.988132 -272.39287) (xy 341.996027 -272.441447) (xy 341.996522 -272.466054) (xy 342.314779 -272.466054)
			(xy 342.318874 -272.415326) (xy 342.331053 -272.365912) (xy 342.351001 -272.319092) (xy 342.378202 -272.276078)
			(xy 342.41195 -272.237984) (xy 342.451372 -272.205797) (xy 342.495446 -272.180351) (xy 342.543032 -272.162304)
			(xy 342.592896 -272.152124) (xy 342.643748 -272.150075) (xy 342.694269 -272.156209) (xy 342.743153 -272.170369)
			(xy 342.789132 -272.192186) (xy 342.831016 -272.221096) (xy 342.86772 -272.256351) (xy 342.898293 -272.297037)
			(xy 342.921944 -272.3421) (xy 342.93806 -272.390374) (xy 342.946224 -272.440608) (xy 342.946736 -272.466054)
			(xy 343.254833 -272.466054) (xy 343.258928 -272.415326) (xy 343.271107 -272.365912) (xy 343.291055 -272.319092)
			(xy 343.318256 -272.276078) (xy 343.352004 -272.237984) (xy 343.391426 -272.205797) (xy 343.4355 -272.180351)
			(xy 343.483086 -272.162304) (xy 343.53295 -272.152124) (xy 343.583802 -272.150075) (xy 343.634323 -272.156209)
			(xy 343.683207 -272.170369) (xy 343.729186 -272.192186) (xy 343.77107 -272.221096) (xy 343.807774 -272.256351)
			(xy 343.838347 -272.297037) (xy 343.861998 -272.3421) (xy 343.878114 -272.390374) (xy 343.886278 -272.440608)
			(xy 343.88679 -272.466054) (xy 343.886278 -272.4915) (xy 343.878114 -272.541734) (xy 343.861998 -272.590008)
			(xy 343.838347 -272.635071) (xy 343.807774 -272.675757) (xy 343.77107 -272.711012) (xy 343.729186 -272.739922)
			(xy 343.683207 -272.761739) (xy 343.634323 -272.775899) (xy 343.583802 -272.782033) (xy 343.53295 -272.779984)
			(xy 343.483086 -272.769804) (xy 343.4355 -272.751757) (xy 343.391426 -272.726311) (xy 343.352004 -272.694124)
			(xy 343.318256 -272.65603) (xy 343.291055 -272.613016) (xy 343.271107 -272.566196) (xy 343.258928 -272.516782)
			(xy 343.254833 -272.466054) (xy 342.946736 -272.466054) (xy 342.946224 -272.4915) (xy 342.93806 -272.541734)
			(xy 342.921944 -272.590008) (xy 342.898293 -272.635071) (xy 342.86772 -272.675757) (xy 342.831016 -272.711012)
			(xy 342.789132 -272.739922) (xy 342.743153 -272.761739) (xy 342.694269 -272.775899) (xy 342.643748 -272.782033)
			(xy 342.592896 -272.779984) (xy 342.543032 -272.769804) (xy 342.495446 -272.751757) (xy 342.451372 -272.726311)
			(xy 342.41195 -272.694124) (xy 342.378202 -272.65603) (xy 342.351001 -272.613016) (xy 342.331053 -272.566196)
			(xy 342.318874 -272.516782) (xy 342.314779 -272.466054) (xy 341.996522 -272.466054) (xy 341.996027 -272.490661)
			(xy 341.988132 -272.539238) (xy 341.972548 -272.585919) (xy 341.949677 -272.629496) (xy 341.920112 -272.66884)
			(xy 341.884619 -272.702932) (xy 341.844116 -272.730888) (xy 341.799654 -272.751986) (xy 341.752383 -272.765678)
			(xy 341.703528 -272.77161) (xy 341.654353 -272.769629) (xy 341.606134 -272.759785) (xy 341.560118 -272.742333)
			(xy 341.517497 -272.717726) (xy 341.479376 -272.686601) (xy 341.446741 -272.649764) (xy 341.420438 -272.608168)
			(xy 341.401147 -272.562892) (xy 341.38937 -272.515108) (xy 341.38541 -272.466054) (xy 341.066882 -272.466054)
			(xy 341.06637 -272.4915) (xy 341.058206 -272.541734) (xy 341.04209 -272.590008) (xy 341.018439 -272.635071)
			(xy 340.987866 -272.675757) (xy 340.951162 -272.711012) (xy 340.909278 -272.739922) (xy 340.863299 -272.761739)
			(xy 340.814415 -272.775899) (xy 340.763894 -272.782033) (xy 340.713042 -272.779984) (xy 340.663178 -272.769804)
			(xy 340.615592 -272.751757) (xy 340.571518 -272.726311) (xy 340.532096 -272.694124) (xy 340.498348 -272.65603)
			(xy 340.471147 -272.613016) (xy 340.451199 -272.566196) (xy 340.43902 -272.516782) (xy 340.434925 -272.466054)
			(xy 340.116414 -272.466054) (xy 340.115919 -272.490661) (xy 340.108024 -272.539238) (xy 340.09244 -272.585919)
			(xy 340.069569 -272.629496) (xy 340.040004 -272.66884) (xy 340.004511 -272.702932) (xy 339.964008 -272.730888)
			(xy 339.919546 -272.751986) (xy 339.872275 -272.765678) (xy 339.82342 -272.77161) (xy 339.774245 -272.769629)
			(xy 339.726026 -272.759785) (xy 339.68001 -272.742333) (xy 339.637389 -272.717726) (xy 339.599268 -272.686601)
			(xy 339.566633 -272.649764) (xy 339.54033 -272.608168) (xy 339.521039 -272.562892) (xy 339.509262 -272.515108)
			(xy 339.505302 -272.466054) (xy 339.186774 -272.466054) (xy 339.186262 -272.4915) (xy 339.178098 -272.541734)
			(xy 339.161982 -272.590008) (xy 339.138331 -272.635071) (xy 339.107758 -272.675757) (xy 339.071054 -272.711012)
			(xy 339.02917 -272.739922) (xy 338.983191 -272.761739) (xy 338.934307 -272.775899) (xy 338.883786 -272.782033)
			(xy 338.832934 -272.779984) (xy 338.78307 -272.769804) (xy 338.735484 -272.751757) (xy 338.69141 -272.726311)
			(xy 338.651988 -272.694124) (xy 338.61824 -272.65603) (xy 338.591039 -272.613016) (xy 338.571091 -272.566196)
			(xy 338.558912 -272.516782) (xy 338.554817 -272.466054) (xy 338.236306 -272.466054) (xy 338.235816 -272.490872)
			(xy 338.227778 -272.539852) (xy 338.211923 -272.586887) (xy 338.188668 -272.630737) (xy 338.158627 -272.670249)
			(xy 338.122589 -272.70438) (xy 338.081505 -272.732232) (xy 338.036457 -272.753072) (xy 337.98863 -272.76635)
			(xy 337.964018 -272.769584) (xy 337.950048 -272.771108) (xy 337.92795 -272.787618) (xy 337.888072 -272.88236)
			(xy 337.884914 -272.890889) (xy 337.884186 -272.909049) (xy 337.889812 -272.926331) (xy 337.895184 -272.933668)
			(xy 337.897724 -272.93697) (xy 337.921657 -272.968884) (xy 337.961053 -273.038247) (xy 337.97621 -273.075146)
			(xy 337.98129 -273.088354) (xy 338.00288 -273.105372) (xy 338.119466 -273.120358) (xy 338.144866 -273.109182)
			(xy 338.153248 -273.097752) (xy 338.167714 -273.078453) (xy 338.201703 -273.044237) (xy 338.240643 -273.015781)
			(xy 338.283567 -272.993792) (xy 338.329411 -272.978814) (xy 338.377038 -272.971219) (xy 338.401152 -272.970752)
			(xy 338.426416 -272.971241) (xy 338.476255 -272.979551) (xy 338.524046 -272.995951) (xy 338.568486 -273.019994)
			(xy 338.608362 -273.051025) (xy 338.642586 -273.088196) (xy 338.670224 -273.130494) (xy 338.690522 -273.176765)
			(xy 338.702927 -273.225746) (xy 338.707097 -273.27606) (xy 339.024971 -273.27606) (xy 339.029066 -273.225332)
			(xy 339.041245 -273.175918) (xy 339.061193 -273.129098) (xy 339.088394 -273.086084) (xy 339.122142 -273.04799)
			(xy 339.161564 -273.015803) (xy 339.205638 -272.990357) (xy 339.253224 -272.97231) (xy 339.303088 -272.96213)
			(xy 339.35394 -272.960081) (xy 339.404461 -272.966215) (xy 339.453345 -272.980375) (xy 339.499324 -273.002192)
			(xy 339.541208 -273.031102) (xy 339.577912 -273.066357) (xy 339.608485 -273.107043) (xy 339.632136 -273.152106)
			(xy 339.648252 -273.20038) (xy 339.656416 -273.250614) (xy 339.656928 -273.27606) (xy 339.964771 -273.27606)
			(xy 339.968866 -273.225332) (xy 339.981045 -273.175918) (xy 340.000993 -273.129098) (xy 340.028194 -273.086084)
			(xy 340.061942 -273.04799) (xy 340.101364 -273.015803) (xy 340.145438 -272.990357) (xy 340.193024 -272.97231)
			(xy 340.242888 -272.96213) (xy 340.29374 -272.960081) (xy 340.344261 -272.966215) (xy 340.393145 -272.980375)
			(xy 340.439124 -273.002192) (xy 340.481008 -273.031102) (xy 340.517712 -273.066357) (xy 340.548285 -273.107043)
			(xy 340.571936 -273.152106) (xy 340.588052 -273.20038) (xy 340.596216 -273.250614) (xy 340.596728 -273.27606)
			(xy 340.915256 -273.27606) (xy 340.919216 -273.227006) (xy 340.930993 -273.179222) (xy 340.950284 -273.133946)
			(xy 340.976587 -273.09235) (xy 341.009222 -273.055513) (xy 341.047343 -273.024388) (xy 341.089964 -272.999781)
			(xy 341.13598 -272.982329) (xy 341.184199 -272.972485) (xy 341.233374 -272.970504) (xy 341.282229 -272.976436)
			(xy 341.3295 -272.990128) (xy 341.373962 -273.011226) (xy 341.414465 -273.039182) (xy 341.449958 -273.073274)
			(xy 341.479523 -273.112618) (xy 341.502394 -273.156195) (xy 341.517978 -273.202876) (xy 341.525873 -273.251453)
			(xy 341.526368 -273.27606) (xy 341.844879 -273.27606) (xy 341.848974 -273.225332) (xy 341.861153 -273.175918)
			(xy 341.881101 -273.129098) (xy 341.908302 -273.086084) (xy 341.94205 -273.04799) (xy 341.981472 -273.015803)
			(xy 342.025546 -272.990357) (xy 342.073132 -272.97231) (xy 342.122996 -272.96213) (xy 342.173848 -272.960081)
			(xy 342.224369 -272.966215) (xy 342.273253 -272.980375) (xy 342.319232 -273.002192) (xy 342.361116 -273.031102)
			(xy 342.39782 -273.066357) (xy 342.428393 -273.107043) (xy 342.452044 -273.152106) (xy 342.46816 -273.20038)
			(xy 342.476324 -273.250614) (xy 342.476836 -273.27606) (xy 342.795364 -273.27606) (xy 342.799324 -273.227006)
			(xy 342.811101 -273.179222) (xy 342.830392 -273.133946) (xy 342.856695 -273.09235) (xy 342.88933 -273.055513)
			(xy 342.927451 -273.024388) (xy 342.970072 -272.999781) (xy 343.016088 -272.982329) (xy 343.064307 -272.972485)
			(xy 343.113482 -272.970504) (xy 343.162337 -272.976436) (xy 343.209608 -272.990128) (xy 343.25407 -273.011226)
			(xy 343.294573 -273.039182) (xy 343.330066 -273.073274) (xy 343.359631 -273.112618) (xy 343.382502 -273.156195)
			(xy 343.398086 -273.202876) (xy 343.405981 -273.251453) (xy 343.406476 -273.27606) (xy 343.724987 -273.27606)
			(xy 343.729082 -273.225332) (xy 343.741261 -273.175918) (xy 343.761209 -273.129098) (xy 343.78841 -273.086084)
			(xy 343.822158 -273.04799) (xy 343.86158 -273.015803) (xy 343.905654 -272.990357) (xy 343.95324 -272.97231)
			(xy 344.003104 -272.96213) (xy 344.053956 -272.960081) (xy 344.104477 -272.966215) (xy 344.153361 -272.980375)
			(xy 344.19934 -273.002192) (xy 344.241224 -273.031102) (xy 344.277928 -273.066357) (xy 344.308501 -273.107043)
			(xy 344.332152 -273.152106) (xy 344.348268 -273.20038) (xy 344.356432 -273.250614) (xy 344.356944 -273.27606)
			(xy 344.356432 -273.301506) (xy 344.348268 -273.35174) (xy 344.332152 -273.400014) (xy 344.308501 -273.445077)
			(xy 344.277928 -273.485763) (xy 344.241224 -273.521018) (xy 344.19934 -273.549928) (xy 344.153361 -273.571745)
			(xy 344.104477 -273.585905) (xy 344.053956 -273.592039) (xy 344.003104 -273.58999) (xy 343.95324 -273.57981)
			(xy 343.905654 -273.561763) (xy 343.86158 -273.536317) (xy 343.822158 -273.50413) (xy 343.78841 -273.466036)
			(xy 343.761209 -273.423022) (xy 343.741261 -273.376202) (xy 343.729082 -273.326788) (xy 343.724987 -273.27606)
			(xy 343.406476 -273.27606) (xy 343.405981 -273.300667) (xy 343.398086 -273.349244) (xy 343.382502 -273.395925)
			(xy 343.359631 -273.439502) (xy 343.330066 -273.478846) (xy 343.294573 -273.512938) (xy 343.25407 -273.540894)
			(xy 343.209608 -273.561992) (xy 343.162337 -273.575684) (xy 343.113482 -273.581616) (xy 343.064307 -273.579635)
			(xy 343.016088 -273.569791) (xy 342.970072 -273.552339) (xy 342.927451 -273.527732) (xy 342.88933 -273.496607)
			(xy 342.856695 -273.45977) (xy 342.830392 -273.418174) (xy 342.811101 -273.372898) (xy 342.799324 -273.325114)
			(xy 342.795364 -273.27606) (xy 342.476836 -273.27606) (xy 342.476324 -273.301506) (xy 342.46816 -273.35174)
			(xy 342.452044 -273.400014) (xy 342.428393 -273.445077) (xy 342.39782 -273.485763) (xy 342.361116 -273.521018)
			(xy 342.319232 -273.549928) (xy 342.273253 -273.571745) (xy 342.224369 -273.585905) (xy 342.173848 -273.592039)
			(xy 342.122996 -273.58999) (xy 342.073132 -273.57981) (xy 342.025546 -273.561763) (xy 341.981472 -273.536317)
			(xy 341.94205 -273.50413) (xy 341.908302 -273.466036) (xy 341.881101 -273.423022) (xy 341.861153 -273.376202)
			(xy 341.848974 -273.326788) (xy 341.844879 -273.27606) (xy 341.526368 -273.27606) (xy 341.525873 -273.300667)
			(xy 341.517978 -273.349244) (xy 341.502394 -273.395925) (xy 341.479523 -273.439502) (xy 341.449958 -273.478846)
			(xy 341.414465 -273.512938) (xy 341.373962 -273.540894) (xy 341.3295 -273.561992) (xy 341.282229 -273.575684)
			(xy 341.233374 -273.581616) (xy 341.184199 -273.579635) (xy 341.13598 -273.569791) (xy 341.089964 -273.552339)
			(xy 341.047343 -273.527732) (xy 341.009222 -273.496607) (xy 340.976587 -273.45977) (xy 340.950284 -273.418174)
			(xy 340.930993 -273.372898) (xy 340.919216 -273.325114) (xy 340.915256 -273.27606) (xy 340.596728 -273.27606)
			(xy 340.596216 -273.301506) (xy 340.588052 -273.35174) (xy 340.571936 -273.400014) (xy 340.548285 -273.445077)
			(xy 340.517712 -273.485763) (xy 340.481008 -273.521018) (xy 340.439124 -273.549928) (xy 340.393145 -273.571745)
			(xy 340.344261 -273.585905) (xy 340.29374 -273.592039) (xy 340.242888 -273.58999) (xy 340.193024 -273.57981)
			(xy 340.145438 -273.561763) (xy 340.101364 -273.536317) (xy 340.061942 -273.50413) (xy 340.028194 -273.466036)
			(xy 340.000993 -273.423022) (xy 339.981045 -273.376202) (xy 339.968866 -273.326788) (xy 339.964771 -273.27606)
			(xy 339.656928 -273.27606) (xy 339.656416 -273.301506) (xy 339.648252 -273.35174) (xy 339.632136 -273.400014)
			(xy 339.608485 -273.445077) (xy 339.577912 -273.485763) (xy 339.541208 -273.521018) (xy 339.499324 -273.549928)
			(xy 339.453345 -273.571745) (xy 339.404461 -273.585905) (xy 339.35394 -273.592039) (xy 339.303088 -273.58999)
			(xy 339.253224 -273.57981) (xy 339.205638 -273.561763) (xy 339.161564 -273.536317) (xy 339.122142 -273.50413)
			(xy 339.088394 -273.466036) (xy 339.061193 -273.423022) (xy 339.041245 -273.376202) (xy 339.029066 -273.326788)
			(xy 339.024971 -273.27606) (xy 338.707097 -273.27606) (xy 338.7071 -273.2761) (xy 338.702927 -273.326454)
			(xy 338.690522 -273.375435) (xy 338.670224 -273.421706) (xy 338.642586 -273.464004) (xy 338.608362 -273.501175)
			(xy 338.568486 -273.532206) (xy 338.524046 -273.556249) (xy 338.476255 -273.572649) (xy 338.426416 -273.580959)
			(xy 338.401152 -273.581368) (xy 338.388389 -273.581229) (xy 338.362955 -273.579066) (xy 338.350352 -273.57705)
			(xy 338.350352 -273.577304) (xy 338.326897 -273.572879) (xy 338.28164 -273.557721) (xy 338.239286 -273.53572)
			(xy 338.200862 -273.507408) (xy 338.167299 -273.473474) (xy 338.152994 -273.454368) (xy 338.144866 -273.442938)
			(xy 338.119212 -273.431762) (xy 338.017104 -273.44497) (xy 338.003134 -273.446748) (xy 337.98129 -273.463766)
			(xy 337.97621 -273.476974) (xy 337.969352 -273.493484) (xy 337.962654 -273.508855) (xy 337.947657 -273.538847)
			(xy 337.93938 -273.553428) (xy 337.894168 -273.631406) (xy 337.892644 -273.6342) (xy 337.892644 -273.634454)
			(xy 337.88793 -273.645276) (xy 337.887913 -273.668853) (xy 337.892644 -273.679666) (xy 337.929474 -273.754088)
			(xy 337.935078 -273.764711) (xy 337.953905 -273.779569) (xy 337.965542 -273.782536) (xy 337.969098 -273.783044)
			(xy 337.993389 -273.786586) (xy 338.040486 -273.800412) (xy 338.084764 -273.821597) (xy 338.125081 -273.849595)
			(xy 338.160398 -273.883684) (xy 338.189804 -273.922986) (xy 338.212542 -273.966487) (xy 338.228025 -274.013066)
			(xy 338.235854 -274.061523) (xy 338.236306 -274.086066) (xy 338.554817 -274.086066) (xy 338.558912 -274.035338)
			(xy 338.571091 -273.985924) (xy 338.591039 -273.939104) (xy 338.61824 -273.89609) (xy 338.651988 -273.857996)
			(xy 338.69141 -273.825809) (xy 338.735484 -273.800363) (xy 338.78307 -273.782316) (xy 338.832934 -273.772136)
			(xy 338.883786 -273.770087) (xy 338.934307 -273.776221) (xy 338.983191 -273.790381) (xy 339.02917 -273.812198)
			(xy 339.071054 -273.841108) (xy 339.107758 -273.876363) (xy 339.138331 -273.917049) (xy 339.161982 -273.962112)
			(xy 339.178098 -274.010386) (xy 339.186262 -274.06062) (xy 339.186774 -274.086066) (xy 339.505302 -274.086066)
			(xy 339.509262 -274.037012) (xy 339.521039 -273.989228) (xy 339.54033 -273.943952) (xy 339.566633 -273.902356)
			(xy 339.599268 -273.865519) (xy 339.637389 -273.834394) (xy 339.68001 -273.809787) (xy 339.726026 -273.792335)
			(xy 339.774245 -273.782491) (xy 339.82342 -273.78051) (xy 339.872275 -273.786442) (xy 339.919546 -273.800134)
			(xy 339.964008 -273.821232) (xy 340.004511 -273.849188) (xy 340.040004 -273.88328) (xy 340.069569 -273.922624)
			(xy 340.09244 -273.966201) (xy 340.108024 -274.012882) (xy 340.115919 -274.061459) (xy 340.116414 -274.086066)
			(xy 340.434925 -274.086066) (xy 340.43902 -274.035338) (xy 340.451199 -273.985924) (xy 340.471147 -273.939104)
			(xy 340.498348 -273.89609) (xy 340.532096 -273.857996) (xy 340.571518 -273.825809) (xy 340.615592 -273.800363)
			(xy 340.663178 -273.782316) (xy 340.713042 -273.772136) (xy 340.763894 -273.770087) (xy 340.814415 -273.776221)
			(xy 340.863299 -273.790381) (xy 340.909278 -273.812198) (xy 340.951162 -273.841108) (xy 340.987866 -273.876363)
			(xy 341.018439 -273.917049) (xy 341.04209 -273.962112) (xy 341.058206 -274.010386) (xy 341.06637 -274.06062)
			(xy 341.066882 -274.086066) (xy 341.38541 -274.086066) (xy 341.38937 -274.037012) (xy 341.401147 -273.989228)
			(xy 341.420438 -273.943952) (xy 341.446741 -273.902356) (xy 341.479376 -273.865519) (xy 341.517497 -273.834394)
			(xy 341.560118 -273.809787) (xy 341.606134 -273.792335) (xy 341.654353 -273.782491) (xy 341.703528 -273.78051)
			(xy 341.752383 -273.786442) (xy 341.799654 -273.800134) (xy 341.844116 -273.821232) (xy 341.884619 -273.849188)
			(xy 341.920112 -273.88328) (xy 341.949677 -273.922624) (xy 341.972548 -273.966201) (xy 341.988132 -274.012882)
			(xy 341.996027 -274.061459) (xy 341.996522 -274.086066) (xy 342.314779 -274.086066) (xy 342.318874 -274.035338)
			(xy 342.331053 -273.985924) (xy 342.351001 -273.939104) (xy 342.378202 -273.89609) (xy 342.41195 -273.857996)
			(xy 342.451372 -273.825809) (xy 342.495446 -273.800363) (xy 342.543032 -273.782316) (xy 342.592896 -273.772136)
			(xy 342.643748 -273.770087) (xy 342.694269 -273.776221) (xy 342.743153 -273.790381) (xy 342.789132 -273.812198)
			(xy 342.831016 -273.841108) (xy 342.86772 -273.876363) (xy 342.898293 -273.917049) (xy 342.921944 -273.962112)
			(xy 342.93806 -274.010386) (xy 342.946224 -274.06062) (xy 342.946736 -274.086066) (xy 343.254833 -274.086066)
			(xy 343.258928 -274.035338) (xy 343.271107 -273.985924) (xy 343.291055 -273.939104) (xy 343.318256 -273.89609)
			(xy 343.352004 -273.857996) (xy 343.391426 -273.825809) (xy 343.4355 -273.800363) (xy 343.483086 -273.782316)
			(xy 343.53295 -273.772136) (xy 343.583802 -273.770087) (xy 343.634323 -273.776221) (xy 343.683207 -273.790381)
			(xy 343.729186 -273.812198) (xy 343.77107 -273.841108) (xy 343.807774 -273.876363) (xy 343.838347 -273.917049)
			(xy 343.861998 -273.962112) (xy 343.878114 -274.010386) (xy 343.886278 -274.06062) (xy 343.88679 -274.086066)
			(xy 343.886278 -274.111512) (xy 343.878114 -274.161746) (xy 343.861998 -274.21002) (xy 343.838347 -274.255083)
			(xy 343.807774 -274.295769) (xy 343.77107 -274.331024) (xy 343.729186 -274.359934) (xy 343.683207 -274.381751)
			(xy 343.634323 -274.395911) (xy 343.583802 -274.402045) (xy 343.53295 -274.399996) (xy 343.483086 -274.389816)
			(xy 343.4355 -274.371769) (xy 343.391426 -274.346323) (xy 343.352004 -274.314136) (xy 343.318256 -274.276042)
			(xy 343.291055 -274.233028) (xy 343.271107 -274.186208) (xy 343.258928 -274.136794) (xy 343.254833 -274.086066)
			(xy 342.946736 -274.086066) (xy 342.946224 -274.111512) (xy 342.93806 -274.161746) (xy 342.921944 -274.21002)
			(xy 342.898293 -274.255083) (xy 342.86772 -274.295769) (xy 342.831016 -274.331024) (xy 342.789132 -274.359934)
			(xy 342.743153 -274.381751) (xy 342.694269 -274.395911) (xy 342.643748 -274.402045) (xy 342.592896 -274.399996)
			(xy 342.543032 -274.389816) (xy 342.495446 -274.371769) (xy 342.451372 -274.346323) (xy 342.41195 -274.314136)
			(xy 342.378202 -274.276042) (xy 342.351001 -274.233028) (xy 342.331053 -274.186208) (xy 342.318874 -274.136794)
			(xy 342.314779 -274.086066) (xy 341.996522 -274.086066) (xy 341.996027 -274.110673) (xy 341.988132 -274.15925)
			(xy 341.972548 -274.205931) (xy 341.949677 -274.249508) (xy 341.920112 -274.288852) (xy 341.884619 -274.322944)
			(xy 341.844116 -274.3509) (xy 341.799654 -274.371998) (xy 341.752383 -274.38569) (xy 341.703528 -274.391622)
			(xy 341.654353 -274.389641) (xy 341.606134 -274.379797) (xy 341.560118 -274.362345) (xy 341.517497 -274.337738)
			(xy 341.479376 -274.306613) (xy 341.446741 -274.269776) (xy 341.420438 -274.22818) (xy 341.401147 -274.182904)
			(xy 341.38937 -274.13512) (xy 341.38541 -274.086066) (xy 341.066882 -274.086066) (xy 341.06637 -274.111512)
			(xy 341.058206 -274.161746) (xy 341.04209 -274.21002) (xy 341.018439 -274.255083) (xy 340.987866 -274.295769)
			(xy 340.951162 -274.331024) (xy 340.909278 -274.359934) (xy 340.863299 -274.381751) (xy 340.814415 -274.395911)
			(xy 340.763894 -274.402045) (xy 340.713042 -274.399996) (xy 340.663178 -274.389816) (xy 340.615592 -274.371769)
			(xy 340.571518 -274.346323) (xy 340.532096 -274.314136) (xy 340.498348 -274.276042) (xy 340.471147 -274.233028)
			(xy 340.451199 -274.186208) (xy 340.43902 -274.136794) (xy 340.434925 -274.086066) (xy 340.116414 -274.086066)
			(xy 340.115919 -274.110673) (xy 340.108024 -274.15925) (xy 340.09244 -274.205931) (xy 340.069569 -274.249508)
			(xy 340.040004 -274.288852) (xy 340.004511 -274.322944) (xy 339.964008 -274.3509) (xy 339.919546 -274.371998)
			(xy 339.872275 -274.38569) (xy 339.82342 -274.391622) (xy 339.774245 -274.389641) (xy 339.726026 -274.379797)
			(xy 339.68001 -274.362345) (xy 339.637389 -274.337738) (xy 339.599268 -274.306613) (xy 339.566633 -274.269776)
			(xy 339.54033 -274.22818) (xy 339.521039 -274.182904) (xy 339.509262 -274.13512) (xy 339.505302 -274.086066)
			(xy 339.186774 -274.086066) (xy 339.186262 -274.111512) (xy 339.178098 -274.161746) (xy 339.161982 -274.21002)
			(xy 339.138331 -274.255083) (xy 339.107758 -274.295769) (xy 339.071054 -274.331024) (xy 339.02917 -274.359934)
			(xy 338.983191 -274.381751) (xy 338.934307 -274.395911) (xy 338.883786 -274.402045) (xy 338.832934 -274.399996)
			(xy 338.78307 -274.389816) (xy 338.735484 -274.371769) (xy 338.69141 -274.346323) (xy 338.651988 -274.314136)
			(xy 338.61824 -274.276042) (xy 338.591039 -274.233028) (xy 338.571091 -274.186208) (xy 338.558912 -274.136794)
			(xy 338.554817 -274.086066) (xy 338.236306 -274.086066) (xy 338.235823 -274.110888) (xy 338.227796 -274.159879)
			(xy 338.211949 -274.206926) (xy 338.1887 -274.250789) (xy 338.158659 -274.290312) (xy 338.12262 -274.324455)
			(xy 338.081532 -274.352317) (xy 338.036478 -274.373164) (xy 337.988644 -274.386447) (xy 337.964018 -274.389596)
			(xy 337.950048 -274.39112) (xy 337.92795 -274.40763) (xy 337.888072 -274.502372) (xy 337.884916 -274.510901)
			(xy 337.884192 -274.529059) (xy 337.88982 -274.546337) (xy 337.895184 -274.55368) (xy 337.897724 -274.556982)
			(xy 337.921661 -274.588894) (xy 337.961068 -274.658252) (xy 337.97621 -274.695158) (xy 337.98129 -274.708366)
			(xy 338.00288 -274.725384) (xy 338.119466 -274.74037) (xy 338.144866 -274.729194) (xy 338.153248 -274.717764)
			(xy 338.167713 -274.698464) (xy 338.201702 -274.664247) (xy 338.240641 -274.63579) (xy 338.283566 -274.6138)
			(xy 338.32941 -274.598821) (xy 338.377038 -274.591226) (xy 338.401152 -274.590764) (xy 338.426415 -274.591253)
			(xy 338.476252 -274.599562) (xy 338.524041 -274.615962) (xy 338.568479 -274.640004) (xy 338.608354 -274.671034)
			(xy 338.642576 -274.708204) (xy 338.670213 -274.7505) (xy 338.690511 -274.796769) (xy 338.702915 -274.845748)
			(xy 338.707086 -274.896072) (xy 339.024971 -274.896072) (xy 339.029066 -274.845344) (xy 339.041245 -274.79593)
			(xy 339.061193 -274.74911) (xy 339.088394 -274.706096) (xy 339.122142 -274.668002) (xy 339.161564 -274.635815)
			(xy 339.205638 -274.610369) (xy 339.253224 -274.592322) (xy 339.303088 -274.582142) (xy 339.35394 -274.580093)
			(xy 339.404461 -274.586227) (xy 339.453345 -274.600387) (xy 339.499324 -274.622204) (xy 339.541208 -274.651114)
			(xy 339.577912 -274.686369) (xy 339.608485 -274.727055) (xy 339.632136 -274.772118) (xy 339.648252 -274.820392)
			(xy 339.656416 -274.870626) (xy 339.656928 -274.896072) (xy 339.964771 -274.896072) (xy 339.968866 -274.845344)
			(xy 339.981045 -274.79593) (xy 340.000993 -274.74911) (xy 340.028194 -274.706096) (xy 340.061942 -274.668002)
			(xy 340.101364 -274.635815) (xy 340.145438 -274.610369) (xy 340.193024 -274.592322) (xy 340.242888 -274.582142)
			(xy 340.29374 -274.580093) (xy 340.344261 -274.586227) (xy 340.393145 -274.600387) (xy 340.439124 -274.622204)
			(xy 340.481008 -274.651114) (xy 340.517712 -274.686369) (xy 340.548285 -274.727055) (xy 340.571936 -274.772118)
			(xy 340.588052 -274.820392) (xy 340.596216 -274.870626) (xy 340.596728 -274.896072) (xy 340.915256 -274.896072)
			(xy 340.919216 -274.847018) (xy 340.930993 -274.799234) (xy 340.950284 -274.753958) (xy 340.976587 -274.712362)
			(xy 341.009222 -274.675525) (xy 341.047343 -274.6444) (xy 341.089964 -274.619793) (xy 341.13598 -274.602341)
			(xy 341.184199 -274.592497) (xy 341.233374 -274.590516) (xy 341.282229 -274.596448) (xy 341.3295 -274.61014)
			(xy 341.373962 -274.631238) (xy 341.414465 -274.659194) (xy 341.449958 -274.693286) (xy 341.479523 -274.73263)
			(xy 341.502394 -274.776207) (xy 341.517978 -274.822888) (xy 341.525873 -274.871465) (xy 341.526368 -274.896072)
			(xy 341.844879 -274.896072) (xy 341.848974 -274.845344) (xy 341.861153 -274.79593) (xy 341.881101 -274.74911)
			(xy 341.908302 -274.706096) (xy 341.94205 -274.668002) (xy 341.981472 -274.635815) (xy 342.025546 -274.610369)
			(xy 342.073132 -274.592322) (xy 342.122996 -274.582142) (xy 342.173848 -274.580093) (xy 342.224369 -274.586227)
			(xy 342.273253 -274.600387) (xy 342.319232 -274.622204) (xy 342.361116 -274.651114) (xy 342.39782 -274.686369)
			(xy 342.428393 -274.727055) (xy 342.452044 -274.772118) (xy 342.46816 -274.820392) (xy 342.476324 -274.870626)
			(xy 342.476836 -274.896072) (xy 342.795364 -274.896072) (xy 342.799324 -274.847018) (xy 342.811101 -274.799234)
			(xy 342.830392 -274.753958) (xy 342.856695 -274.712362) (xy 342.88933 -274.675525) (xy 342.927451 -274.6444)
			(xy 342.970072 -274.619793) (xy 343.016088 -274.602341) (xy 343.064307 -274.592497) (xy 343.113482 -274.590516)
			(xy 343.162337 -274.596448) (xy 343.209608 -274.61014) (xy 343.25407 -274.631238) (xy 343.294573 -274.659194)
			(xy 343.330066 -274.693286) (xy 343.359631 -274.73263) (xy 343.382502 -274.776207) (xy 343.398086 -274.822888)
			(xy 343.405981 -274.871465) (xy 343.406476 -274.896072) (xy 343.724987 -274.896072) (xy 343.729082 -274.845344)
			(xy 343.741261 -274.79593) (xy 343.761209 -274.74911) (xy 343.78841 -274.706096) (xy 343.822158 -274.668002)
			(xy 343.86158 -274.635815) (xy 343.905654 -274.610369) (xy 343.95324 -274.592322) (xy 344.003104 -274.582142)
			(xy 344.053956 -274.580093) (xy 344.104477 -274.586227) (xy 344.153361 -274.600387) (xy 344.19934 -274.622204)
			(xy 344.241224 -274.651114) (xy 344.277928 -274.686369) (xy 344.308501 -274.727055) (xy 344.332152 -274.772118)
			(xy 344.348268 -274.820392) (xy 344.356432 -274.870626) (xy 344.356944 -274.896072) (xy 344.356432 -274.921518)
			(xy 344.348268 -274.971752) (xy 344.332152 -275.020026) (xy 344.308501 -275.065089) (xy 344.277928 -275.105775)
			(xy 344.241224 -275.14103) (xy 344.19934 -275.16994) (xy 344.153361 -275.191757) (xy 344.104477 -275.205917)
			(xy 344.053956 -275.212051) (xy 344.003104 -275.210002) (xy 343.95324 -275.199822) (xy 343.905654 -275.181775)
			(xy 343.86158 -275.156329) (xy 343.822158 -275.124142) (xy 343.78841 -275.086048) (xy 343.761209 -275.043034)
			(xy 343.741261 -274.996214) (xy 343.729082 -274.9468) (xy 343.724987 -274.896072) (xy 343.406476 -274.896072)
			(xy 343.405981 -274.920679) (xy 343.398086 -274.969256) (xy 343.382502 -275.015937) (xy 343.359631 -275.059514)
			(xy 343.330066 -275.098858) (xy 343.294573 -275.13295) (xy 343.25407 -275.160906) (xy 343.209608 -275.182004)
			(xy 343.162337 -275.195696) (xy 343.113482 -275.201628) (xy 343.064307 -275.199647) (xy 343.016088 -275.189803)
			(xy 342.970072 -275.172351) (xy 342.927451 -275.147744) (xy 342.88933 -275.116619) (xy 342.856695 -275.079782)
			(xy 342.830392 -275.038186) (xy 342.811101 -274.99291) (xy 342.799324 -274.945126) (xy 342.795364 -274.896072)
			(xy 342.476836 -274.896072) (xy 342.476324 -274.921518) (xy 342.46816 -274.971752) (xy 342.452044 -275.020026)
			(xy 342.428393 -275.065089) (xy 342.39782 -275.105775) (xy 342.361116 -275.14103) (xy 342.319232 -275.16994)
			(xy 342.273253 -275.191757) (xy 342.224369 -275.205917) (xy 342.173848 -275.212051) (xy 342.122996 -275.210002)
			(xy 342.073132 -275.199822) (xy 342.025546 -275.181775) (xy 341.981472 -275.156329) (xy 341.94205 -275.124142)
			(xy 341.908302 -275.086048) (xy 341.881101 -275.043034) (xy 341.861153 -274.996214) (xy 341.848974 -274.9468)
			(xy 341.844879 -274.896072) (xy 341.526368 -274.896072) (xy 341.525873 -274.920679) (xy 341.517978 -274.969256)
			(xy 341.502394 -275.015937) (xy 341.479523 -275.059514) (xy 341.449958 -275.098858) (xy 341.414465 -275.13295)
			(xy 341.373962 -275.160906) (xy 341.3295 -275.182004) (xy 341.282229 -275.195696) (xy 341.233374 -275.201628)
			(xy 341.184199 -275.199647) (xy 341.13598 -275.189803) (xy 341.089964 -275.172351) (xy 341.047343 -275.147744)
			(xy 341.009222 -275.116619) (xy 340.976587 -275.079782) (xy 340.950284 -275.038186) (xy 340.930993 -274.99291)
			(xy 340.919216 -274.945126) (xy 340.915256 -274.896072) (xy 340.596728 -274.896072) (xy 340.596216 -274.921518)
			(xy 340.588052 -274.971752) (xy 340.571936 -275.020026) (xy 340.548285 -275.065089) (xy 340.517712 -275.105775)
			(xy 340.481008 -275.14103) (xy 340.439124 -275.16994) (xy 340.393145 -275.191757) (xy 340.344261 -275.205917)
			(xy 340.29374 -275.212051) (xy 340.242888 -275.210002) (xy 340.193024 -275.199822) (xy 340.145438 -275.181775)
			(xy 340.101364 -275.156329) (xy 340.061942 -275.124142) (xy 340.028194 -275.086048) (xy 340.000993 -275.043034)
			(xy 339.981045 -274.996214) (xy 339.968866 -274.9468) (xy 339.964771 -274.896072) (xy 339.656928 -274.896072)
			(xy 339.656416 -274.921518) (xy 339.648252 -274.971752) (xy 339.632136 -275.020026) (xy 339.608485 -275.065089)
			(xy 339.577912 -275.105775) (xy 339.541208 -275.14103) (xy 339.499324 -275.16994) (xy 339.453345 -275.191757)
			(xy 339.404461 -275.205917) (xy 339.35394 -275.212051) (xy 339.303088 -275.210002) (xy 339.253224 -275.199822)
			(xy 339.205638 -275.181775) (xy 339.161564 -275.156329) (xy 339.122142 -275.124142) (xy 339.088394 -275.086048)
			(xy 339.061193 -275.043034) (xy 339.041245 -274.996214) (xy 339.029066 -274.9468) (xy 339.024971 -274.896072)
			(xy 338.707086 -274.896072) (xy 338.707088 -274.8961) (xy 338.702915 -274.946453) (xy 338.690511 -274.995431)
			(xy 338.670213 -275.0417) (xy 338.642576 -275.083996) (xy 338.608354 -275.121166) (xy 338.568479 -275.152196)
			(xy 338.524041 -275.176238) (xy 338.476252 -275.192638) (xy 338.426415 -275.200947) (xy 338.401152 -275.20138)
			(xy 338.388389 -275.201241) (xy 338.362955 -275.199078) (xy 338.350352 -275.197062) (xy 338.350352 -275.197316)
			(xy 338.326897 -275.192891) (xy 338.28164 -275.177734) (xy 338.239285 -275.155733) (xy 338.200859 -275.127422)
			(xy 338.167296 -275.093489) (xy 338.152994 -275.07438) (xy 338.144866 -275.06295) (xy 338.119212 -275.051774)
			(xy 338.017104 -275.064982) (xy 338.003134 -275.06676) (xy 337.98129 -275.083778) (xy 337.97621 -275.096986)
			(xy 337.969352 -275.113496) (xy 337.962654 -275.128867) (xy 337.947656 -275.158858) (xy 337.93938 -275.17344)
			(xy 337.894168 -275.251418) (xy 337.892644 -275.254212) (xy 337.892644 -275.254466) (xy 337.887932 -275.265288)
			(xy 337.887921 -275.288863) (xy 337.892644 -275.299678) (xy 337.929474 -275.3741) (xy 337.935079 -275.384721)
			(xy 337.953906 -275.399576) (xy 337.965542 -275.402548) (xy 337.969098 -275.403056) (xy 337.993654 -275.406656)
			(xy 338.041232 -275.420771) (xy 338.085902 -275.442391) (xy 338.12649 -275.470948) (xy 338.161928 -275.505691)
			(xy 338.191283 -275.545705) (xy 338.213784 -275.589938) (xy 338.228839 -275.637227) (xy 338.236051 -275.686328)
			(xy 338.235725 -275.706078) (xy 338.554817 -275.706078) (xy 338.558912 -275.65535) (xy 338.571091 -275.605936)
			(xy 338.591039 -275.559116) (xy 338.61824 -275.516102) (xy 338.651988 -275.478008) (xy 338.69141 -275.445821)
			(xy 338.735484 -275.420375) (xy 338.78307 -275.402328) (xy 338.832934 -275.392148) (xy 338.883786 -275.390099)
			(xy 338.934307 -275.396233) (xy 338.983191 -275.410393) (xy 339.02917 -275.43221) (xy 339.071054 -275.46112)
			(xy 339.107758 -275.496375) (xy 339.138331 -275.537061) (xy 339.161982 -275.582124) (xy 339.178098 -275.630398)
			(xy 339.186262 -275.680632) (xy 339.186774 -275.706078) (xy 339.505302 -275.706078) (xy 339.509262 -275.657024)
			(xy 339.521039 -275.60924) (xy 339.54033 -275.563964) (xy 339.566633 -275.522368) (xy 339.599268 -275.485531)
			(xy 339.637389 -275.454406) (xy 339.68001 -275.429799) (xy 339.726026 -275.412347) (xy 339.774245 -275.402503)
			(xy 339.82342 -275.400522) (xy 339.872275 -275.406454) (xy 339.919546 -275.420146) (xy 339.964008 -275.441244)
			(xy 340.004511 -275.4692) (xy 340.040004 -275.503292) (xy 340.069569 -275.542636) (xy 340.09244 -275.586213)
			(xy 340.108024 -275.632894) (xy 340.115919 -275.681471) (xy 340.116414 -275.706078) (xy 340.434925 -275.706078)
			(xy 340.43902 -275.65535) (xy 340.451199 -275.605936) (xy 340.471147 -275.559116) (xy 340.498348 -275.516102)
			(xy 340.532096 -275.478008) (xy 340.571518 -275.445821) (xy 340.615592 -275.420375) (xy 340.663178 -275.402328)
			(xy 340.713042 -275.392148) (xy 340.763894 -275.390099) (xy 340.814415 -275.396233) (xy 340.863299 -275.410393)
			(xy 340.909278 -275.43221) (xy 340.951162 -275.46112) (xy 340.987866 -275.496375) (xy 341.018439 -275.537061)
			(xy 341.04209 -275.582124) (xy 341.058206 -275.630398) (xy 341.06637 -275.680632) (xy 341.066882 -275.706078)
			(xy 341.38541 -275.706078) (xy 341.38937 -275.657024) (xy 341.401147 -275.60924) (xy 341.420438 -275.563964)
			(xy 341.446741 -275.522368) (xy 341.479376 -275.485531) (xy 341.517497 -275.454406) (xy 341.560118 -275.429799)
			(xy 341.606134 -275.412347) (xy 341.654353 -275.402503) (xy 341.703528 -275.400522) (xy 341.752383 -275.406454)
			(xy 341.799654 -275.420146) (xy 341.844116 -275.441244) (xy 341.884619 -275.4692) (xy 341.920112 -275.503292)
			(xy 341.949677 -275.542636) (xy 341.972548 -275.586213) (xy 341.988132 -275.632894) (xy 341.996027 -275.681471)
			(xy 341.996522 -275.706078) (xy 342.314779 -275.706078) (xy 342.318874 -275.65535) (xy 342.331053 -275.605936)
			(xy 342.351001 -275.559116) (xy 342.378202 -275.516102) (xy 342.41195 -275.478008) (xy 342.451372 -275.445821)
			(xy 342.495446 -275.420375) (xy 342.543032 -275.402328) (xy 342.592896 -275.392148) (xy 342.643748 -275.390099)
			(xy 342.694269 -275.396233) (xy 342.743153 -275.410393) (xy 342.789132 -275.43221) (xy 342.831016 -275.46112)
			(xy 342.86772 -275.496375) (xy 342.898293 -275.537061) (xy 342.921944 -275.582124) (xy 342.93806 -275.630398)
			(xy 342.946224 -275.680632) (xy 342.946736 -275.706078) (xy 343.254833 -275.706078) (xy 343.258928 -275.65535)
			(xy 343.271107 -275.605936) (xy 343.291055 -275.559116) (xy 343.318256 -275.516102) (xy 343.352004 -275.478008)
			(xy 343.391426 -275.445821) (xy 343.4355 -275.420375) (xy 343.483086 -275.402328) (xy 343.53295 -275.392148)
			(xy 343.583802 -275.390099) (xy 343.634323 -275.396233) (xy 343.683207 -275.410393) (xy 343.729186 -275.43221)
			(xy 343.77107 -275.46112) (xy 343.807774 -275.496375) (xy 343.838347 -275.537061) (xy 343.861998 -275.582124)
			(xy 343.878114 -275.630398) (xy 343.886278 -275.680632) (xy 343.88679 -275.706078) (xy 343.886278 -275.731524)
			(xy 343.878114 -275.781758) (xy 343.861998 -275.830032) (xy 343.838347 -275.875095) (xy 343.807774 -275.915781)
			(xy 343.77107 -275.951036) (xy 343.729186 -275.979946) (xy 343.683207 -276.001763) (xy 343.634323 -276.015923)
			(xy 343.583802 -276.022057) (xy 343.53295 -276.020008) (xy 343.483086 -276.009828) (xy 343.4355 -275.991781)
			(xy 343.391426 -275.966335) (xy 343.352004 -275.934148) (xy 343.318256 -275.896054) (xy 343.291055 -275.85304)
			(xy 343.271107 -275.80622) (xy 343.258928 -275.756806) (xy 343.254833 -275.706078) (xy 342.946736 -275.706078)
			(xy 342.946224 -275.731524) (xy 342.93806 -275.781758) (xy 342.921944 -275.830032) (xy 342.898293 -275.875095)
			(xy 342.86772 -275.915781) (xy 342.831016 -275.951036) (xy 342.789132 -275.979946) (xy 342.743153 -276.001763)
			(xy 342.694269 -276.015923) (xy 342.643748 -276.022057) (xy 342.592896 -276.020008) (xy 342.543032 -276.009828)
			(xy 342.495446 -275.991781) (xy 342.451372 -275.966335) (xy 342.41195 -275.934148) (xy 342.378202 -275.896054)
			(xy 342.351001 -275.85304) (xy 342.331053 -275.80622) (xy 342.318874 -275.756806) (xy 342.314779 -275.706078)
			(xy 341.996522 -275.706078) (xy 341.996027 -275.730685) (xy 341.988132 -275.779262) (xy 341.972548 -275.825943)
			(xy 341.949677 -275.86952) (xy 341.920112 -275.908864) (xy 341.884619 -275.942956) (xy 341.844116 -275.970912)
			(xy 341.799654 -275.99201) (xy 341.752383 -276.005702) (xy 341.703528 -276.011634) (xy 341.654353 -276.009653)
			(xy 341.606134 -275.999809) (xy 341.560118 -275.982357) (xy 341.517497 -275.95775) (xy 341.479376 -275.926625)
			(xy 341.446741 -275.889788) (xy 341.420438 -275.848192) (xy 341.401147 -275.802916) (xy 341.38937 -275.755132)
			(xy 341.38541 -275.706078) (xy 341.066882 -275.706078) (xy 341.06637 -275.731524) (xy 341.058206 -275.781758)
			(xy 341.04209 -275.830032) (xy 341.018439 -275.875095) (xy 340.987866 -275.915781) (xy 340.951162 -275.951036)
			(xy 340.909278 -275.979946) (xy 340.863299 -276.001763) (xy 340.814415 -276.015923) (xy 340.763894 -276.022057)
			(xy 340.713042 -276.020008) (xy 340.663178 -276.009828) (xy 340.615592 -275.991781) (xy 340.571518 -275.966335)
			(xy 340.532096 -275.934148) (xy 340.498348 -275.896054) (xy 340.471147 -275.85304) (xy 340.451199 -275.80622)
			(xy 340.43902 -275.756806) (xy 340.434925 -275.706078) (xy 340.116414 -275.706078) (xy 340.115919 -275.730685)
			(xy 340.108024 -275.779262) (xy 340.09244 -275.825943) (xy 340.069569 -275.86952) (xy 340.040004 -275.908864)
			(xy 340.004511 -275.942956) (xy 339.964008 -275.970912) (xy 339.919546 -275.99201) (xy 339.872275 -276.005702)
			(xy 339.82342 -276.011634) (xy 339.774245 -276.009653) (xy 339.726026 -275.999809) (xy 339.68001 -275.982357)
			(xy 339.637389 -275.95775) (xy 339.599268 -275.926625) (xy 339.566633 -275.889788) (xy 339.54033 -275.848192)
			(xy 339.521039 -275.802916) (xy 339.509262 -275.755132) (xy 339.505302 -275.706078) (xy 339.186774 -275.706078)
			(xy 339.186262 -275.731524) (xy 339.178098 -275.781758) (xy 339.161982 -275.830032) (xy 339.138331 -275.875095)
			(xy 339.107758 -275.915781) (xy 339.071054 -275.951036) (xy 339.02917 -275.979946) (xy 338.983191 -276.001763)
			(xy 338.934307 -276.015923) (xy 338.883786 -276.022057) (xy 338.832934 -276.020008) (xy 338.78307 -276.009828)
			(xy 338.735484 -275.991781) (xy 338.69141 -275.966335) (xy 338.651988 -275.934148) (xy 338.61824 -275.896054)
			(xy 338.591039 -275.85304) (xy 338.571091 -275.80622) (xy 338.558912 -275.756806) (xy 338.554817 -275.706078)
			(xy 338.235725 -275.706078) (xy 338.235231 -275.735948) (xy 338.226401 -275.784784) (xy 338.209792 -275.831549)
			(xy 338.185843 -275.875015) (xy 338.155181 -275.914038) (xy 338.118615 -275.947591) (xy 338.09813 -275.961602)
			(xy 338.078299 -275.974083) (xy 338.035644 -275.993473) (xy 337.990528 -276.006125) (xy 337.96732 -276.009354)
			(xy 337.967066 -276.009354) (xy 337.958089 -276.010716) (xy 337.941868 -276.018849) (xy 337.929475 -276.032103)
			(xy 337.925664 -276.040342) (xy 337.886294 -276.135084) (xy 337.890104 -276.162008) (xy 337.898486 -276.17293)
			(xy 337.922855 -276.20517) (xy 337.963016 -276.275299) (xy 337.978496 -276.31263) (xy 337.983576 -276.325584)
			(xy 338.00542 -276.342602) (xy 338.075524 -276.351492) (xy 338.081874 -276.352) (xy 338.11718 -276.352)
			(xy 338.129004 -276.351453) (xy 338.150207 -276.340996) (xy 338.15782 -276.331934) (xy 338.172329 -276.313457)
			(xy 338.206067 -276.280766) (xy 338.244417 -276.253632) (xy 338.286473 -276.232699) (xy 338.331241 -276.218459)
			(xy 338.377663 -276.211251) (xy 338.401152 -276.210776) (xy 338.426414 -276.211265) (xy 338.476249 -276.219574)
			(xy 338.524037 -276.235973) (xy 338.568473 -276.260014) (xy 338.608346 -276.291043) (xy 338.642567 -276.328211)
			(xy 338.670203 -276.370506) (xy 338.6905 -276.416773) (xy 338.702903 -276.465749) (xy 338.707075 -276.516084)
			(xy 339.024971 -276.516084) (xy 339.029066 -276.465356) (xy 339.041245 -276.415942) (xy 339.061193 -276.369122)
			(xy 339.088394 -276.326108) (xy 339.122142 -276.288014) (xy 339.161564 -276.255827) (xy 339.205638 -276.230381)
			(xy 339.253224 -276.212334) (xy 339.303088 -276.202154) (xy 339.35394 -276.200105) (xy 339.404461 -276.206239)
			(xy 339.453345 -276.220399) (xy 339.499324 -276.242216) (xy 339.541208 -276.271126) (xy 339.577912 -276.306381)
			(xy 339.608485 -276.347067) (xy 339.632136 -276.39213) (xy 339.648252 -276.440404) (xy 339.656416 -276.490638)
			(xy 339.656928 -276.516084) (xy 339.964771 -276.516084) (xy 339.968866 -276.465356) (xy 339.981045 -276.415942)
			(xy 340.000993 -276.369122) (xy 340.028194 -276.326108) (xy 340.061942 -276.288014) (xy 340.101364 -276.255827)
			(xy 340.145438 -276.230381) (xy 340.193024 -276.212334) (xy 340.242888 -276.202154) (xy 340.29374 -276.200105)
			(xy 340.344261 -276.206239) (xy 340.393145 -276.220399) (xy 340.439124 -276.242216) (xy 340.481008 -276.271126)
			(xy 340.517712 -276.306381) (xy 340.548285 -276.347067) (xy 340.571936 -276.39213) (xy 340.588052 -276.440404)
			(xy 340.596216 -276.490638) (xy 340.596728 -276.516084) (xy 340.915256 -276.516084) (xy 340.919216 -276.46703)
			(xy 340.930993 -276.419246) (xy 340.950284 -276.37397) (xy 340.976587 -276.332374) (xy 341.009222 -276.295537)
			(xy 341.047343 -276.264412) (xy 341.089964 -276.239805) (xy 341.13598 -276.222353) (xy 341.184199 -276.212509)
			(xy 341.233374 -276.210528) (xy 341.282229 -276.21646) (xy 341.3295 -276.230152) (xy 341.373962 -276.25125)
			(xy 341.414465 -276.279206) (xy 341.449958 -276.313298) (xy 341.479523 -276.352642) (xy 341.502394 -276.396219)
			(xy 341.517978 -276.4429) (xy 341.525873 -276.491477) (xy 341.526368 -276.516084) (xy 341.844879 -276.516084)
			(xy 341.848974 -276.465356) (xy 341.861153 -276.415942) (xy 341.881101 -276.369122) (xy 341.908302 -276.326108)
			(xy 341.94205 -276.288014) (xy 341.981472 -276.255827) (xy 342.025546 -276.230381) (xy 342.073132 -276.212334)
			(xy 342.122996 -276.202154) (xy 342.173848 -276.200105) (xy 342.224369 -276.206239) (xy 342.273253 -276.220399)
			(xy 342.319232 -276.242216) (xy 342.361116 -276.271126) (xy 342.39782 -276.306381) (xy 342.428393 -276.347067)
			(xy 342.452044 -276.39213) (xy 342.46816 -276.440404) (xy 342.476324 -276.490638) (xy 342.476836 -276.516084)
			(xy 342.795364 -276.516084) (xy 342.799324 -276.46703) (xy 342.811101 -276.419246) (xy 342.830392 -276.37397)
			(xy 342.856695 -276.332374) (xy 342.88933 -276.295537) (xy 342.927451 -276.264412) (xy 342.970072 -276.239805)
			(xy 343.016088 -276.222353) (xy 343.064307 -276.212509) (xy 343.113482 -276.210528) (xy 343.162337 -276.21646)
			(xy 343.209608 -276.230152) (xy 343.25407 -276.25125) (xy 343.294573 -276.279206) (xy 343.330066 -276.313298)
			(xy 343.359631 -276.352642) (xy 343.382502 -276.396219) (xy 343.398086 -276.4429) (xy 343.405981 -276.491477)
			(xy 343.406476 -276.516084) (xy 343.724987 -276.516084) (xy 343.729082 -276.465356) (xy 343.741261 -276.415942)
			(xy 343.761209 -276.369122) (xy 343.78841 -276.326108) (xy 343.822158 -276.288014) (xy 343.86158 -276.255827)
			(xy 343.905654 -276.230381) (xy 343.95324 -276.212334) (xy 344.003104 -276.202154) (xy 344.053956 -276.200105)
			(xy 344.104477 -276.206239) (xy 344.153361 -276.220399) (xy 344.19934 -276.242216) (xy 344.241224 -276.271126)
			(xy 344.277928 -276.306381) (xy 344.308501 -276.347067) (xy 344.332152 -276.39213) (xy 344.348268 -276.440404)
			(xy 344.356432 -276.490638) (xy 344.356944 -276.516084) (xy 344.356432 -276.54153) (xy 344.348268 -276.591764)
			(xy 344.332152 -276.640038) (xy 344.308501 -276.685101) (xy 344.277928 -276.725787) (xy 344.241224 -276.761042)
			(xy 344.19934 -276.789952) (xy 344.153361 -276.811769) (xy 344.104477 -276.825929) (xy 344.053956 -276.832063)
			(xy 344.003104 -276.830014) (xy 343.95324 -276.819834) (xy 343.905654 -276.801787) (xy 343.86158 -276.776341)
			(xy 343.822158 -276.744154) (xy 343.78841 -276.70606) (xy 343.761209 -276.663046) (xy 343.741261 -276.616226)
			(xy 343.729082 -276.566812) (xy 343.724987 -276.516084) (xy 343.406476 -276.516084) (xy 343.405981 -276.540691)
			(xy 343.398086 -276.589268) (xy 343.382502 -276.635949) (xy 343.359631 -276.679526) (xy 343.330066 -276.71887)
			(xy 343.294573 -276.752962) (xy 343.25407 -276.780918) (xy 343.209608 -276.802016) (xy 343.162337 -276.815708)
			(xy 343.113482 -276.82164) (xy 343.064307 -276.819659) (xy 343.016088 -276.809815) (xy 342.970072 -276.792363)
			(xy 342.927451 -276.767756) (xy 342.88933 -276.736631) (xy 342.856695 -276.699794) (xy 342.830392 -276.658198)
			(xy 342.811101 -276.612922) (xy 342.799324 -276.565138) (xy 342.795364 -276.516084) (xy 342.476836 -276.516084)
			(xy 342.476324 -276.54153) (xy 342.46816 -276.591764) (xy 342.452044 -276.640038) (xy 342.428393 -276.685101)
			(xy 342.39782 -276.725787) (xy 342.361116 -276.761042) (xy 342.319232 -276.789952) (xy 342.273253 -276.811769)
			(xy 342.224369 -276.825929) (xy 342.173848 -276.832063) (xy 342.122996 -276.830014) (xy 342.073132 -276.819834)
			(xy 342.025546 -276.801787) (xy 341.981472 -276.776341) (xy 341.94205 -276.744154) (xy 341.908302 -276.70606)
			(xy 341.881101 -276.663046) (xy 341.861153 -276.616226) (xy 341.848974 -276.566812) (xy 341.844879 -276.516084)
			(xy 341.526368 -276.516084) (xy 341.525873 -276.540691) (xy 341.517978 -276.589268) (xy 341.502394 -276.635949)
			(xy 341.479523 -276.679526) (xy 341.449958 -276.71887) (xy 341.414465 -276.752962) (xy 341.373962 -276.780918)
			(xy 341.3295 -276.802016) (xy 341.282229 -276.815708) (xy 341.233374 -276.82164) (xy 341.184199 -276.819659)
			(xy 341.13598 -276.809815) (xy 341.089964 -276.792363) (xy 341.047343 -276.767756) (xy 341.009222 -276.736631)
			(xy 340.976587 -276.699794) (xy 340.950284 -276.658198) (xy 340.930993 -276.612922) (xy 340.919216 -276.565138)
			(xy 340.915256 -276.516084) (xy 340.596728 -276.516084) (xy 340.596216 -276.54153) (xy 340.588052 -276.591764)
			(xy 340.571936 -276.640038) (xy 340.548285 -276.685101) (xy 340.517712 -276.725787) (xy 340.481008 -276.761042)
			(xy 340.439124 -276.789952) (xy 340.393145 -276.811769) (xy 340.344261 -276.825929) (xy 340.29374 -276.832063)
			(xy 340.242888 -276.830014) (xy 340.193024 -276.819834) (xy 340.145438 -276.801787) (xy 340.101364 -276.776341)
			(xy 340.061942 -276.744154) (xy 340.028194 -276.70606) (xy 340.000993 -276.663046) (xy 339.981045 -276.616226)
			(xy 339.968866 -276.566812) (xy 339.964771 -276.516084) (xy 339.656928 -276.516084) (xy 339.656416 -276.54153)
			(xy 339.648252 -276.591764) (xy 339.632136 -276.640038) (xy 339.608485 -276.685101) (xy 339.577912 -276.725787)
			(xy 339.541208 -276.761042) (xy 339.499324 -276.789952) (xy 339.453345 -276.811769) (xy 339.404461 -276.825929)
			(xy 339.35394 -276.832063) (xy 339.303088 -276.830014) (xy 339.253224 -276.819834) (xy 339.205638 -276.801787)
			(xy 339.161564 -276.776341) (xy 339.122142 -276.744154) (xy 339.088394 -276.70606) (xy 339.061193 -276.663046)
			(xy 339.041245 -276.616226) (xy 339.029066 -276.566812) (xy 339.024971 -276.516084) (xy 338.707075 -276.516084)
			(xy 338.707076 -276.5161) (xy 338.702903 -276.566451) (xy 338.6905 -276.615427) (xy 338.670203 -276.661694)
			(xy 338.642567 -276.703989) (xy 338.608346 -276.741157) (xy 338.568473 -276.772186) (xy 338.524037 -276.796227)
			(xy 338.476249 -276.812626) (xy 338.426414 -276.820935) (xy 338.401152 -276.821392) (xy 338.377665 -276.820935)
			(xy 338.331253 -276.813694) (xy 338.286495 -276.799436) (xy 338.244446 -276.778497) (xy 338.206096 -276.751369)
			(xy 338.172349 -276.718693) (xy 338.15782 -276.700234) (xy 338.150172 -276.691217) (xy 338.128989 -276.680777)
			(xy 338.11718 -276.680168) (xy 338.081874 -276.680168) (xy 338.075524 -276.680676) (xy 338.00542 -276.689566)
			(xy 337.983576 -276.706584) (xy 337.978496 -276.719538) (xy 337.965288 -276.750526) (xy 337.959954 -276.761864)
			(xy 337.948392 -276.784097) (xy 337.942174 -276.794976) (xy 337.912964 -276.845268) (xy 337.897724 -276.871684)
			(xy 337.891953 -276.882832) (xy 337.891026 -276.907886) (xy 337.895946 -276.919436) (xy 337.938618 -277.007066)
			(xy 337.958938 -277.021798) (xy 337.971892 -277.023576) (xy 337.995987 -277.027313) (xy 338.042652 -277.041436)
			(xy 338.086481 -277.062794) (xy 338.126359 -277.090845) (xy 338.161273 -277.124876) (xy 338.190337 -277.164023)
			(xy 338.212811 -277.20729) (xy 338.228125 -277.253579) (xy 338.235889 -277.301712) (xy 338.236306 -277.32609)
			(xy 338.554817 -277.32609) (xy 338.558912 -277.275362) (xy 338.571091 -277.225948) (xy 338.591039 -277.179128)
			(xy 338.61824 -277.136114) (xy 338.651988 -277.09802) (xy 338.69141 -277.065833) (xy 338.735484 -277.040387)
			(xy 338.78307 -277.02234) (xy 338.832934 -277.01216) (xy 338.883786 -277.010111) (xy 338.934307 -277.016245)
			(xy 338.983191 -277.030405) (xy 339.02917 -277.052222) (xy 339.071054 -277.081132) (xy 339.107758 -277.116387)
			(xy 339.138331 -277.157073) (xy 339.161982 -277.202136) (xy 339.178098 -277.25041) (xy 339.186262 -277.300644)
			(xy 339.186774 -277.32609) (xy 339.505302 -277.32609) (xy 339.509262 -277.277036) (xy 339.521039 -277.229252)
			(xy 339.54033 -277.183976) (xy 339.566633 -277.14238) (xy 339.599268 -277.105543) (xy 339.637389 -277.074418)
			(xy 339.68001 -277.049811) (xy 339.726026 -277.032359) (xy 339.774245 -277.022515) (xy 339.82342 -277.020534)
			(xy 339.872275 -277.026466) (xy 339.919546 -277.040158) (xy 339.964008 -277.061256) (xy 340.004511 -277.089212)
			(xy 340.040004 -277.123304) (xy 340.069569 -277.162648) (xy 340.09244 -277.206225) (xy 340.108024 -277.252906)
			(xy 340.115919 -277.301483) (xy 340.116414 -277.32609) (xy 340.434925 -277.32609) (xy 340.43902 -277.275362)
			(xy 340.451199 -277.225948) (xy 340.471147 -277.179128) (xy 340.498348 -277.136114) (xy 340.532096 -277.09802)
			(xy 340.571518 -277.065833) (xy 340.615592 -277.040387) (xy 340.663178 -277.02234) (xy 340.713042 -277.01216)
			(xy 340.763894 -277.010111) (xy 340.814415 -277.016245) (xy 340.863299 -277.030405) (xy 340.909278 -277.052222)
			(xy 340.951162 -277.081132) (xy 340.987866 -277.116387) (xy 341.018439 -277.157073) (xy 341.04209 -277.202136)
			(xy 341.058206 -277.25041) (xy 341.06637 -277.300644) (xy 341.066882 -277.32609) (xy 341.38541 -277.32609)
			(xy 341.38937 -277.277036) (xy 341.401147 -277.229252) (xy 341.420438 -277.183976) (xy 341.446741 -277.14238)
			(xy 341.479376 -277.105543) (xy 341.517497 -277.074418) (xy 341.560118 -277.049811) (xy 341.606134 -277.032359)
			(xy 341.654353 -277.022515) (xy 341.703528 -277.020534) (xy 341.752383 -277.026466) (xy 341.799654 -277.040158)
			(xy 341.844116 -277.061256) (xy 341.884619 -277.089212) (xy 341.920112 -277.123304) (xy 341.949677 -277.162648)
			(xy 341.972548 -277.206225) (xy 341.988132 -277.252906) (xy 341.996027 -277.301483) (xy 341.996522 -277.32609)
			(xy 342.314779 -277.32609) (xy 342.318874 -277.275362) (xy 342.331053 -277.225948) (xy 342.351001 -277.179128)
			(xy 342.378202 -277.136114) (xy 342.41195 -277.09802) (xy 342.451372 -277.065833) (xy 342.495446 -277.040387)
			(xy 342.543032 -277.02234) (xy 342.592896 -277.01216) (xy 342.643748 -277.010111) (xy 342.694269 -277.016245)
			(xy 342.743153 -277.030405) (xy 342.789132 -277.052222) (xy 342.831016 -277.081132) (xy 342.86772 -277.116387)
			(xy 342.898293 -277.157073) (xy 342.921944 -277.202136) (xy 342.93806 -277.25041) (xy 342.946224 -277.300644)
			(xy 342.946736 -277.32609) (xy 343.254833 -277.32609) (xy 343.258928 -277.275362) (xy 343.271107 -277.225948)
			(xy 343.291055 -277.179128) (xy 343.318256 -277.136114) (xy 343.352004 -277.09802) (xy 343.391426 -277.065833)
			(xy 343.4355 -277.040387) (xy 343.483086 -277.02234) (xy 343.53295 -277.01216) (xy 343.583802 -277.010111)
			(xy 343.634323 -277.016245) (xy 343.683207 -277.030405) (xy 343.729186 -277.052222) (xy 343.77107 -277.081132)
			(xy 343.807774 -277.116387) (xy 343.838347 -277.157073) (xy 343.861998 -277.202136) (xy 343.878114 -277.25041)
			(xy 343.886278 -277.300644) (xy 343.88679 -277.32609) (xy 343.886278 -277.351536) (xy 343.878114 -277.40177)
			(xy 343.861998 -277.450044) (xy 343.838347 -277.495107) (xy 343.807774 -277.535793) (xy 343.77107 -277.571048)
			(xy 343.729186 -277.599958) (xy 343.683207 -277.621775) (xy 343.634323 -277.635935) (xy 343.583802 -277.642069)
			(xy 343.53295 -277.64002) (xy 343.483086 -277.62984) (xy 343.4355 -277.611793) (xy 343.391426 -277.586347)
			(xy 343.352004 -277.55416) (xy 343.318256 -277.516066) (xy 343.291055 -277.473052) (xy 343.271107 -277.426232)
			(xy 343.258928 -277.376818) (xy 343.254833 -277.32609) (xy 342.946736 -277.32609) (xy 342.946224 -277.351536)
			(xy 342.93806 -277.40177) (xy 342.921944 -277.450044) (xy 342.898293 -277.495107) (xy 342.86772 -277.535793)
			(xy 342.831016 -277.571048) (xy 342.789132 -277.599958) (xy 342.743153 -277.621775) (xy 342.694269 -277.635935)
			(xy 342.643748 -277.642069) (xy 342.592896 -277.64002) (xy 342.543032 -277.62984) (xy 342.495446 -277.611793)
			(xy 342.451372 -277.586347) (xy 342.41195 -277.55416) (xy 342.378202 -277.516066) (xy 342.351001 -277.473052)
			(xy 342.331053 -277.426232) (xy 342.318874 -277.376818) (xy 342.314779 -277.32609) (xy 341.996522 -277.32609)
			(xy 341.996027 -277.350697) (xy 341.988132 -277.399274) (xy 341.972548 -277.445955) (xy 341.949677 -277.489532)
			(xy 341.920112 -277.528876) (xy 341.884619 -277.562968) (xy 341.844116 -277.590924) (xy 341.799654 -277.612022)
			(xy 341.752383 -277.625714) (xy 341.703528 -277.631646) (xy 341.654353 -277.629665) (xy 341.606134 -277.619821)
			(xy 341.560118 -277.602369) (xy 341.517497 -277.577762) (xy 341.479376 -277.546637) (xy 341.446741 -277.5098)
			(xy 341.420438 -277.468204) (xy 341.401147 -277.422928) (xy 341.38937 -277.375144) (xy 341.38541 -277.32609)
			(xy 341.066882 -277.32609) (xy 341.06637 -277.351536) (xy 341.058206 -277.40177) (xy 341.04209 -277.450044)
			(xy 341.018439 -277.495107) (xy 340.987866 -277.535793) (xy 340.951162 -277.571048) (xy 340.909278 -277.599958)
			(xy 340.863299 -277.621775) (xy 340.814415 -277.635935) (xy 340.763894 -277.642069) (xy 340.713042 -277.64002)
			(xy 340.663178 -277.62984) (xy 340.615592 -277.611793) (xy 340.571518 -277.586347) (xy 340.532096 -277.55416)
			(xy 340.498348 -277.516066) (xy 340.471147 -277.473052) (xy 340.451199 -277.426232) (xy 340.43902 -277.376818)
			(xy 340.434925 -277.32609) (xy 340.116414 -277.32609) (xy 340.115919 -277.350697) (xy 340.108024 -277.399274)
			(xy 340.09244 -277.445955) (xy 340.069569 -277.489532) (xy 340.040004 -277.528876) (xy 340.004511 -277.562968)
			(xy 339.964008 -277.590924) (xy 339.919546 -277.612022) (xy 339.872275 -277.625714) (xy 339.82342 -277.631646)
			(xy 339.774245 -277.629665) (xy 339.726026 -277.619821) (xy 339.68001 -277.602369) (xy 339.637389 -277.577762)
			(xy 339.599268 -277.546637) (xy 339.566633 -277.5098) (xy 339.54033 -277.468204) (xy 339.521039 -277.422928)
			(xy 339.509262 -277.375144) (xy 339.505302 -277.32609) (xy 339.186774 -277.32609) (xy 339.186262 -277.351536)
			(xy 339.178098 -277.40177) (xy 339.161982 -277.450044) (xy 339.138331 -277.495107) (xy 339.107758 -277.535793)
			(xy 339.071054 -277.571048) (xy 339.02917 -277.599958) (xy 338.983191 -277.621775) (xy 338.934307 -277.635935)
			(xy 338.883786 -277.642069) (xy 338.832934 -277.64002) (xy 338.78307 -277.62984) (xy 338.735484 -277.611793)
			(xy 338.69141 -277.586347) (xy 338.651988 -277.55416) (xy 338.61824 -277.516066) (xy 338.591039 -277.473052)
			(xy 338.571091 -277.426232) (xy 338.558912 -277.376818) (xy 338.554817 -277.32609) (xy 338.236306 -277.32609)
			(xy 338.235821 -277.350911) (xy 338.227791 -277.399899) (xy 338.211942 -277.446942) (xy 338.188691 -277.490802)
			(xy 338.15865 -277.530322) (xy 338.122612 -277.564462) (xy 338.081525 -277.592321) (xy 338.036472 -277.613166)
			(xy 337.98864 -277.626448) (xy 337.964018 -277.62962) (xy 337.950048 -277.631144) (xy 337.92795 -277.647654)
			(xy 337.888072 -277.742396) (xy 337.884921 -277.750924) (xy 337.884204 -277.769078) (xy 337.889838 -277.78635)
			(xy 337.895184 -277.793704) (xy 337.897724 -277.797006) (xy 337.92166 -277.828918) (xy 337.961064 -277.898278)
			(xy 337.97621 -277.935182) (xy 337.98129 -277.94839) (xy 338.00288 -277.965408) (xy 338.119466 -277.980394)
			(xy 338.144866 -277.969218) (xy 338.153248 -277.957788) (xy 338.167713 -277.938487) (xy 338.2017 -277.904267)
			(xy 338.240639 -277.875808) (xy 338.283564 -277.853816) (xy 338.329409 -277.838836) (xy 338.377037 -277.83124)
			(xy 338.401152 -277.830788) (xy 338.426413 -277.831277) (xy 338.476246 -277.839585) (xy 338.524032 -277.855984)
			(xy 338.568466 -277.880024) (xy 338.608337 -277.911051) (xy 338.642557 -277.948218) (xy 338.670192 -277.990511)
			(xy 338.690488 -278.036777) (xy 338.702892 -278.085751) (xy 338.707064 -278.136096) (xy 339.024971 -278.136096)
			(xy 339.029066 -278.085368) (xy 339.041245 -278.035954) (xy 339.061193 -277.989134) (xy 339.088394 -277.94612)
			(xy 339.122142 -277.908026) (xy 339.161564 -277.875839) (xy 339.205638 -277.850393) (xy 339.253224 -277.832346)
			(xy 339.303088 -277.822166) (xy 339.35394 -277.820117) (xy 339.404461 -277.826251) (xy 339.453345 -277.840411)
			(xy 339.499324 -277.862228) (xy 339.541208 -277.891138) (xy 339.577912 -277.926393) (xy 339.608485 -277.967079)
			(xy 339.632136 -278.012142) (xy 339.648252 -278.060416) (xy 339.656416 -278.11065) (xy 339.656928 -278.136096)
			(xy 339.964771 -278.136096) (xy 339.968866 -278.085368) (xy 339.981045 -278.035954) (xy 340.000993 -277.989134)
			(xy 340.028194 -277.94612) (xy 340.061942 -277.908026) (xy 340.101364 -277.875839) (xy 340.145438 -277.850393)
			(xy 340.193024 -277.832346) (xy 340.242888 -277.822166) (xy 340.29374 -277.820117) (xy 340.344261 -277.826251)
			(xy 340.393145 -277.840411) (xy 340.439124 -277.862228) (xy 340.481008 -277.891138) (xy 340.517712 -277.926393)
			(xy 340.548285 -277.967079) (xy 340.571936 -278.012142) (xy 340.588052 -278.060416) (xy 340.596216 -278.11065)
			(xy 340.596728 -278.136096) (xy 340.915256 -278.136096) (xy 340.919216 -278.087042) (xy 340.930993 -278.039258)
			(xy 340.950284 -277.993982) (xy 340.976587 -277.952386) (xy 341.009222 -277.915549) (xy 341.047343 -277.884424)
			(xy 341.089964 -277.859817) (xy 341.13598 -277.842365) (xy 341.184199 -277.832521) (xy 341.233374 -277.83054)
			(xy 341.282229 -277.836472) (xy 341.3295 -277.850164) (xy 341.373962 -277.871262) (xy 341.414465 -277.899218)
			(xy 341.449958 -277.93331) (xy 341.479523 -277.972654) (xy 341.502394 -278.016231) (xy 341.517978 -278.062912)
			(xy 341.525873 -278.111489) (xy 341.526368 -278.136096) (xy 341.844879 -278.136096) (xy 341.848974 -278.085368)
			(xy 341.861153 -278.035954) (xy 341.881101 -277.989134) (xy 341.908302 -277.94612) (xy 341.94205 -277.908026)
			(xy 341.981472 -277.875839) (xy 342.025546 -277.850393) (xy 342.073132 -277.832346) (xy 342.122996 -277.822166)
			(xy 342.173848 -277.820117) (xy 342.224369 -277.826251) (xy 342.273253 -277.840411) (xy 342.319232 -277.862228)
			(xy 342.361116 -277.891138) (xy 342.39782 -277.926393) (xy 342.428393 -277.967079) (xy 342.452044 -278.012142)
			(xy 342.46816 -278.060416) (xy 342.476324 -278.11065) (xy 342.476836 -278.136096) (xy 342.795364 -278.136096)
			(xy 342.799324 -278.087042) (xy 342.811101 -278.039258) (xy 342.830392 -277.993982) (xy 342.856695 -277.952386)
			(xy 342.88933 -277.915549) (xy 342.927451 -277.884424) (xy 342.970072 -277.859817) (xy 343.016088 -277.842365)
			(xy 343.064307 -277.832521) (xy 343.113482 -277.83054) (xy 343.162337 -277.836472) (xy 343.209608 -277.850164)
			(xy 343.25407 -277.871262) (xy 343.294573 -277.899218) (xy 343.330066 -277.93331) (xy 343.359631 -277.972654)
			(xy 343.382502 -278.016231) (xy 343.398086 -278.062912) (xy 343.405981 -278.111489) (xy 343.406476 -278.136096)
			(xy 343.724987 -278.136096) (xy 343.729082 -278.085368) (xy 343.741261 -278.035954) (xy 343.761209 -277.989134)
			(xy 343.78841 -277.94612) (xy 343.822158 -277.908026) (xy 343.86158 -277.875839) (xy 343.905654 -277.850393)
			(xy 343.95324 -277.832346) (xy 344.003104 -277.822166) (xy 344.053956 -277.820117) (xy 344.104477 -277.826251)
			(xy 344.153361 -277.840411) (xy 344.19934 -277.862228) (xy 344.241224 -277.891138) (xy 344.277928 -277.926393)
			(xy 344.308501 -277.967079) (xy 344.332152 -278.012142) (xy 344.348268 -278.060416) (xy 344.356432 -278.11065)
			(xy 344.356944 -278.136096) (xy 344.356432 -278.161542) (xy 344.348268 -278.211776) (xy 344.332152 -278.26005)
			(xy 344.308501 -278.305113) (xy 344.277928 -278.345799) (xy 344.241224 -278.381054) (xy 344.19934 -278.409964)
			(xy 344.153361 -278.431781) (xy 344.104477 -278.445941) (xy 344.053956 -278.452075) (xy 344.003104 -278.450026)
			(xy 343.95324 -278.439846) (xy 343.905654 -278.421799) (xy 343.86158 -278.396353) (xy 343.822158 -278.364166)
			(xy 343.78841 -278.326072) (xy 343.761209 -278.283058) (xy 343.741261 -278.236238) (xy 343.729082 -278.186824)
			(xy 343.724987 -278.136096) (xy 343.406476 -278.136096) (xy 343.405981 -278.160703) (xy 343.398086 -278.20928)
			(xy 343.382502 -278.255961) (xy 343.359631 -278.299538) (xy 343.330066 -278.338882) (xy 343.294573 -278.372974)
			(xy 343.25407 -278.40093) (xy 343.209608 -278.422028) (xy 343.162337 -278.43572) (xy 343.113482 -278.441652)
			(xy 343.064307 -278.439671) (xy 343.016088 -278.429827) (xy 342.970072 -278.412375) (xy 342.927451 -278.387768)
			(xy 342.88933 -278.356643) (xy 342.856695 -278.319806) (xy 342.830392 -278.27821) (xy 342.811101 -278.232934)
			(xy 342.799324 -278.18515) (xy 342.795364 -278.136096) (xy 342.476836 -278.136096) (xy 342.476324 -278.161542)
			(xy 342.46816 -278.211776) (xy 342.452044 -278.26005) (xy 342.428393 -278.305113) (xy 342.39782 -278.345799)
			(xy 342.361116 -278.381054) (xy 342.319232 -278.409964) (xy 342.273253 -278.431781) (xy 342.224369 -278.445941)
			(xy 342.173848 -278.452075) (xy 342.122996 -278.450026) (xy 342.073132 -278.439846) (xy 342.025546 -278.421799)
			(xy 341.981472 -278.396353) (xy 341.94205 -278.364166) (xy 341.908302 -278.326072) (xy 341.881101 -278.283058)
			(xy 341.861153 -278.236238) (xy 341.848974 -278.186824) (xy 341.844879 -278.136096) (xy 341.526368 -278.136096)
			(xy 341.525873 -278.160703) (xy 341.517978 -278.20928) (xy 341.502394 -278.255961) (xy 341.479523 -278.299538)
			(xy 341.449958 -278.338882) (xy 341.414465 -278.372974) (xy 341.373962 -278.40093) (xy 341.3295 -278.422028)
			(xy 341.282229 -278.43572) (xy 341.233374 -278.441652) (xy 341.184199 -278.439671) (xy 341.13598 -278.429827)
			(xy 341.089964 -278.412375) (xy 341.047343 -278.387768) (xy 341.009222 -278.356643) (xy 340.976587 -278.319806)
			(xy 340.950284 -278.27821) (xy 340.930993 -278.232934) (xy 340.919216 -278.18515) (xy 340.915256 -278.136096)
			(xy 340.596728 -278.136096) (xy 340.596216 -278.161542) (xy 340.588052 -278.211776) (xy 340.571936 -278.26005)
			(xy 340.548285 -278.305113) (xy 340.517712 -278.345799) (xy 340.481008 -278.381054) (xy 340.439124 -278.409964)
			(xy 340.393145 -278.431781) (xy 340.344261 -278.445941) (xy 340.29374 -278.452075) (xy 340.242888 -278.450026)
			(xy 340.193024 -278.439846) (xy 340.145438 -278.421799) (xy 340.101364 -278.396353) (xy 340.061942 -278.364166)
			(xy 340.028194 -278.326072) (xy 340.000993 -278.283058) (xy 339.981045 -278.236238) (xy 339.968866 -278.186824)
			(xy 339.964771 -278.136096) (xy 339.656928 -278.136096) (xy 339.656416 -278.161542) (xy 339.648252 -278.211776)
			(xy 339.632136 -278.26005) (xy 339.608485 -278.305113) (xy 339.577912 -278.345799) (xy 339.541208 -278.381054)
			(xy 339.499324 -278.409964) (xy 339.453345 -278.431781) (xy 339.404461 -278.445941) (xy 339.35394 -278.452075)
			(xy 339.303088 -278.450026) (xy 339.253224 -278.439846) (xy 339.205638 -278.421799) (xy 339.161564 -278.396353)
			(xy 339.122142 -278.364166) (xy 339.088394 -278.326072) (xy 339.061193 -278.283058) (xy 339.041245 -278.236238)
			(xy 339.029066 -278.186824) (xy 339.024971 -278.136096) (xy 338.707064 -278.136096) (xy 338.707064 -278.1361)
			(xy 338.702892 -278.186449) (xy 338.690488 -278.235423) (xy 338.670192 -278.281689) (xy 338.642557 -278.323982)
			(xy 338.608337 -278.361149) (xy 338.568466 -278.392176) (xy 338.524032 -278.416216) (xy 338.476246 -278.432615)
			(xy 338.426413 -278.440923) (xy 338.401152 -278.441404) (xy 338.388389 -278.441265) (xy 338.362955 -278.439102)
			(xy 338.350352 -278.437086) (xy 338.350352 -278.43734) (xy 338.326897 -278.432916) (xy 338.281639 -278.417759)
			(xy 338.239282 -278.395759) (xy 338.200855 -278.36745) (xy 338.167289 -278.333518) (xy 338.152994 -278.314404)
			(xy 338.144866 -278.302974) (xy 338.119212 -278.291798) (xy 338.017104 -278.305006) (xy 338.003134 -278.306784)
			(xy 337.98129 -278.323802) (xy 337.97621 -278.33701) (xy 337.969352 -278.35352) (xy 337.962656 -278.368892)
			(xy 337.947661 -278.398885) (xy 337.93938 -278.413464) (xy 337.894168 -278.491442) (xy 337.892644 -278.494236)
			(xy 337.892644 -278.49449) (xy 337.887938 -278.505312) (xy 337.887937 -278.528881) (xy 337.892644 -278.539702)
			(xy 337.929474 -278.614124) (xy 337.935082 -278.624742) (xy 337.953911 -278.639588) (xy 337.965542 -278.642572)
			(xy 337.969098 -278.64308) (xy 337.993387 -278.646622) (xy 338.040483 -278.660449) (xy 338.084758 -278.681634)
			(xy 338.125072 -278.709633) (xy 338.160385 -278.743723) (xy 338.189787 -278.783025) (xy 338.21252 -278.826526)
			(xy 338.227997 -278.873105) (xy 338.235821 -278.92156) (xy 338.236306 -278.946102) (xy 338.554817 -278.946102)
			(xy 338.558912 -278.895374) (xy 338.571091 -278.84596) (xy 338.591039 -278.79914) (xy 338.61824 -278.756126)
			(xy 338.651988 -278.718032) (xy 338.69141 -278.685845) (xy 338.735484 -278.660399) (xy 338.78307 -278.642352)
			(xy 338.832934 -278.632172) (xy 338.883786 -278.630123) (xy 338.934307 -278.636257) (xy 338.983191 -278.650417)
			(xy 339.02917 -278.672234) (xy 339.071054 -278.701144) (xy 339.107758 -278.736399) (xy 339.138331 -278.777085)
			(xy 339.161982 -278.822148) (xy 339.178098 -278.870422) (xy 339.186262 -278.920656) (xy 339.186774 -278.946102)
			(xy 339.505302 -278.946102) (xy 339.509262 -278.897048) (xy 339.521039 -278.849264) (xy 339.54033 -278.803988)
			(xy 339.566633 -278.762392) (xy 339.599268 -278.725555) (xy 339.637389 -278.69443) (xy 339.68001 -278.669823)
			(xy 339.726026 -278.652371) (xy 339.774245 -278.642527) (xy 339.82342 -278.640546) (xy 339.872275 -278.646478)
			(xy 339.919546 -278.66017) (xy 339.964008 -278.681268) (xy 340.004511 -278.709224) (xy 340.040004 -278.743316)
			(xy 340.069569 -278.78266) (xy 340.09244 -278.826237) (xy 340.108024 -278.872918) (xy 340.115919 -278.921495)
			(xy 340.116414 -278.946102) (xy 340.434925 -278.946102) (xy 340.43902 -278.895374) (xy 340.451199 -278.84596)
			(xy 340.471147 -278.79914) (xy 340.498348 -278.756126) (xy 340.532096 -278.718032) (xy 340.571518 -278.685845)
			(xy 340.615592 -278.660399) (xy 340.663178 -278.642352) (xy 340.713042 -278.632172) (xy 340.763894 -278.630123)
			(xy 340.814415 -278.636257) (xy 340.863299 -278.650417) (xy 340.909278 -278.672234) (xy 340.951162 -278.701144)
			(xy 340.987866 -278.736399) (xy 341.018439 -278.777085) (xy 341.04209 -278.822148) (xy 341.058206 -278.870422)
			(xy 341.06637 -278.920656) (xy 341.066882 -278.946102) (xy 341.38541 -278.946102) (xy 341.38937 -278.897048)
			(xy 341.401147 -278.849264) (xy 341.420438 -278.803988) (xy 341.446741 -278.762392) (xy 341.479376 -278.725555)
			(xy 341.517497 -278.69443) (xy 341.560118 -278.669823) (xy 341.606134 -278.652371) (xy 341.654353 -278.642527)
			(xy 341.703528 -278.640546) (xy 341.752383 -278.646478) (xy 341.799654 -278.66017) (xy 341.844116 -278.681268)
			(xy 341.884619 -278.709224) (xy 341.920112 -278.743316) (xy 341.949677 -278.78266) (xy 341.972548 -278.826237)
			(xy 341.988132 -278.872918) (xy 341.996027 -278.921495) (xy 341.996522 -278.946102) (xy 342.314779 -278.946102)
			(xy 342.318874 -278.895374) (xy 342.331053 -278.84596) (xy 342.351001 -278.79914) (xy 342.378202 -278.756126)
			(xy 342.41195 -278.718032) (xy 342.451372 -278.685845) (xy 342.495446 -278.660399) (xy 342.543032 -278.642352)
			(xy 342.592896 -278.632172) (xy 342.643748 -278.630123) (xy 342.694269 -278.636257) (xy 342.743153 -278.650417)
			(xy 342.789132 -278.672234) (xy 342.831016 -278.701144) (xy 342.86772 -278.736399) (xy 342.898293 -278.777085)
			(xy 342.921944 -278.822148) (xy 342.93806 -278.870422) (xy 342.946224 -278.920656) (xy 342.946736 -278.946102)
			(xy 343.254833 -278.946102) (xy 343.258928 -278.895374) (xy 343.271107 -278.84596) (xy 343.291055 -278.79914)
			(xy 343.318256 -278.756126) (xy 343.352004 -278.718032) (xy 343.391426 -278.685845) (xy 343.4355 -278.660399)
			(xy 343.483086 -278.642352) (xy 343.53295 -278.632172) (xy 343.583802 -278.630123) (xy 343.634323 -278.636257)
			(xy 343.683207 -278.650417) (xy 343.729186 -278.672234) (xy 343.77107 -278.701144) (xy 343.807774 -278.736399)
			(xy 343.838347 -278.777085) (xy 343.861998 -278.822148) (xy 343.878114 -278.870422) (xy 343.886278 -278.920656)
			(xy 343.88679 -278.946102) (xy 343.886278 -278.971548) (xy 343.878114 -279.021782) (xy 343.861998 -279.070056)
			(xy 343.838347 -279.115119) (xy 343.807774 -279.155805) (xy 343.77107 -279.19106) (xy 343.729186 -279.21997)
			(xy 343.683207 -279.241787) (xy 343.634323 -279.255947) (xy 343.583802 -279.262081) (xy 343.53295 -279.260032)
			(xy 343.483086 -279.249852) (xy 343.4355 -279.231805) (xy 343.391426 -279.206359) (xy 343.352004 -279.174172)
			(xy 343.318256 -279.136078) (xy 343.291055 -279.093064) (xy 343.271107 -279.046244) (xy 343.258928 -278.99683)
			(xy 343.254833 -278.946102) (xy 342.946736 -278.946102) (xy 342.946224 -278.971548) (xy 342.93806 -279.021782)
			(xy 342.921944 -279.070056) (xy 342.898293 -279.115119) (xy 342.86772 -279.155805) (xy 342.831016 -279.19106)
			(xy 342.789132 -279.21997) (xy 342.743153 -279.241787) (xy 342.694269 -279.255947) (xy 342.643748 -279.262081)
			(xy 342.592896 -279.260032) (xy 342.543032 -279.249852) (xy 342.495446 -279.231805) (xy 342.451372 -279.206359)
			(xy 342.41195 -279.174172) (xy 342.378202 -279.136078) (xy 342.351001 -279.093064) (xy 342.331053 -279.046244)
			(xy 342.318874 -278.99683) (xy 342.314779 -278.946102) (xy 341.996522 -278.946102) (xy 341.996027 -278.970709)
			(xy 341.988132 -279.019286) (xy 341.972548 -279.065967) (xy 341.949677 -279.109544) (xy 341.920112 -279.148888)
			(xy 341.884619 -279.18298) (xy 341.844116 -279.210936) (xy 341.799654 -279.232034) (xy 341.752383 -279.245726)
			(xy 341.703528 -279.251658) (xy 341.654353 -279.249677) (xy 341.606134 -279.239833) (xy 341.560118 -279.222381)
			(xy 341.517497 -279.197774) (xy 341.479376 -279.166649) (xy 341.446741 -279.129812) (xy 341.420438 -279.088216)
			(xy 341.401147 -279.04294) (xy 341.38937 -278.995156) (xy 341.38541 -278.946102) (xy 341.066882 -278.946102)
			(xy 341.06637 -278.971548) (xy 341.058206 -279.021782) (xy 341.04209 -279.070056) (xy 341.018439 -279.115119)
			(xy 340.987866 -279.155805) (xy 340.951162 -279.19106) (xy 340.909278 -279.21997) (xy 340.863299 -279.241787)
			(xy 340.814415 -279.255947) (xy 340.763894 -279.262081) (xy 340.713042 -279.260032) (xy 340.663178 -279.249852)
			(xy 340.615592 -279.231805) (xy 340.571518 -279.206359) (xy 340.532096 -279.174172) (xy 340.498348 -279.136078)
			(xy 340.471147 -279.093064) (xy 340.451199 -279.046244) (xy 340.43902 -278.99683) (xy 340.434925 -278.946102)
			(xy 340.116414 -278.946102) (xy 340.115919 -278.970709) (xy 340.108024 -279.019286) (xy 340.09244 -279.065967)
			(xy 340.069569 -279.109544) (xy 340.040004 -279.148888) (xy 340.004511 -279.18298) (xy 339.964008 -279.210936)
			(xy 339.919546 -279.232034) (xy 339.872275 -279.245726) (xy 339.82342 -279.251658) (xy 339.774245 -279.249677)
			(xy 339.726026 -279.239833) (xy 339.68001 -279.222381) (xy 339.637389 -279.197774) (xy 339.599268 -279.166649)
			(xy 339.566633 -279.129812) (xy 339.54033 -279.088216) (xy 339.521039 -279.04294) (xy 339.509262 -278.995156)
			(xy 339.505302 -278.946102) (xy 339.186774 -278.946102) (xy 339.186262 -278.971548) (xy 339.178098 -279.021782)
			(xy 339.161982 -279.070056) (xy 339.138331 -279.115119) (xy 339.107758 -279.155805) (xy 339.071054 -279.19106)
			(xy 339.02917 -279.21997) (xy 338.983191 -279.241787) (xy 338.934307 -279.255947) (xy 338.883786 -279.262081)
			(xy 338.832934 -279.260032) (xy 338.78307 -279.249852) (xy 338.735484 -279.231805) (xy 338.69141 -279.206359)
			(xy 338.651988 -279.174172) (xy 338.61824 -279.136078) (xy 338.591039 -279.093064) (xy 338.571091 -279.046244)
			(xy 338.558912 -278.99683) (xy 338.554817 -278.946102) (xy 338.236306 -278.946102) (xy 338.23582 -278.970922)
			(xy 338.227789 -279.019909) (xy 338.211939 -279.066951) (xy 338.188687 -279.110808) (xy 338.158646 -279.150327)
			(xy 338.122608 -279.184465) (xy 338.081521 -279.212323) (xy 338.036469 -279.233167) (xy 337.988638 -279.246448)
			(xy 337.964018 -279.249632) (xy 337.950048 -279.251156) (xy 337.92795 -279.267666) (xy 337.888072 -279.362408)
			(xy 337.884923 -279.370935) (xy 337.88421 -279.389087) (xy 337.889846 -279.406357) (xy 337.895184 -279.413716)
			(xy 337.897724 -279.417018) (xy 337.921659 -279.448931) (xy 337.961062 -279.518291) (xy 337.97621 -279.555194)
			(xy 337.98129 -279.568402) (xy 338.00288 -279.58542) (xy 338.119466 -279.600406) (xy 338.144866 -279.58923)
			(xy 338.153248 -279.5778) (xy 338.167712 -279.558498) (xy 338.201699 -279.524277) (xy 338.240638 -279.495817)
			(xy 338.283562 -279.473824) (xy 338.329408 -279.458843) (xy 338.377037 -279.451247) (xy 338.401152 -279.4508)
			(xy 338.426412 -279.451289) (xy 338.476243 -279.459597) (xy 338.524027 -279.475995) (xy 338.56846 -279.500034)
			(xy 338.608329 -279.53106) (xy 338.642548 -279.568226) (xy 338.670182 -279.610517) (xy 338.690477 -279.65678)
			(xy 338.70288 -279.705753) (xy 338.707052 -279.7561) (xy 338.707051 -279.756108) (xy 339.024971 -279.756108)
			(xy 339.029066 -279.70538) (xy 339.041245 -279.655966) (xy 339.061193 -279.609146) (xy 339.088394 -279.566132)
			(xy 339.122142 -279.528038) (xy 339.161564 -279.495851) (xy 339.205638 -279.470405) (xy 339.253224 -279.452358)
			(xy 339.303088 -279.442178) (xy 339.35394 -279.440129) (xy 339.404461 -279.446263) (xy 339.453345 -279.460423)
			(xy 339.499324 -279.48224) (xy 339.541208 -279.51115) (xy 339.577912 -279.546405) (xy 339.608485 -279.587091)
			(xy 339.632136 -279.632154) (xy 339.648252 -279.680428) (xy 339.656416 -279.730662) (xy 339.656928 -279.756108)
			(xy 339.964771 -279.756108) (xy 339.968866 -279.70538) (xy 339.981045 -279.655966) (xy 340.000993 -279.609146)
			(xy 340.028194 -279.566132) (xy 340.061942 -279.528038) (xy 340.101364 -279.495851) (xy 340.145438 -279.470405)
			(xy 340.193024 -279.452358) (xy 340.242888 -279.442178) (xy 340.29374 -279.440129) (xy 340.344261 -279.446263)
			(xy 340.393145 -279.460423) (xy 340.439124 -279.48224) (xy 340.481008 -279.51115) (xy 340.517712 -279.546405)
			(xy 340.548285 -279.587091) (xy 340.571936 -279.632154) (xy 340.588052 -279.680428) (xy 340.596216 -279.730662)
			(xy 340.596728 -279.756108) (xy 340.915256 -279.756108) (xy 340.919216 -279.707054) (xy 340.930993 -279.65927)
			(xy 340.950284 -279.613994) (xy 340.976587 -279.572398) (xy 341.009222 -279.535561) (xy 341.047343 -279.504436)
			(xy 341.089964 -279.479829) (xy 341.13598 -279.462377) (xy 341.184199 -279.452533) (xy 341.233374 -279.450552)
			(xy 341.282229 -279.456484) (xy 341.3295 -279.470176) (xy 341.373962 -279.491274) (xy 341.414465 -279.51923)
			(xy 341.449958 -279.553322) (xy 341.479523 -279.592666) (xy 341.502394 -279.636243) (xy 341.517978 -279.682924)
			(xy 341.525873 -279.731501) (xy 341.526368 -279.756108) (xy 341.844879 -279.756108) (xy 341.848974 -279.70538)
			(xy 341.861153 -279.655966) (xy 341.881101 -279.609146) (xy 341.908302 -279.566132) (xy 341.94205 -279.528038)
			(xy 341.981472 -279.495851) (xy 342.025546 -279.470405) (xy 342.073132 -279.452358) (xy 342.122996 -279.442178)
			(xy 342.173848 -279.440129) (xy 342.224369 -279.446263) (xy 342.273253 -279.460423) (xy 342.319232 -279.48224)
			(xy 342.361116 -279.51115) (xy 342.39782 -279.546405) (xy 342.428393 -279.587091) (xy 342.452044 -279.632154)
			(xy 342.46816 -279.680428) (xy 342.476324 -279.730662) (xy 342.476836 -279.756108) (xy 342.795364 -279.756108)
			(xy 342.799324 -279.707054) (xy 342.811101 -279.65927) (xy 342.830392 -279.613994) (xy 342.856695 -279.572398)
			(xy 342.88933 -279.535561) (xy 342.927451 -279.504436) (xy 342.970072 -279.479829) (xy 343.016088 -279.462377)
			(xy 343.064307 -279.452533) (xy 343.113482 -279.450552) (xy 343.162337 -279.456484) (xy 343.209608 -279.470176)
			(xy 343.25407 -279.491274) (xy 343.294573 -279.51923) (xy 343.330066 -279.553322) (xy 343.359631 -279.592666)
			(xy 343.382502 -279.636243) (xy 343.398086 -279.682924) (xy 343.405981 -279.731501) (xy 343.406476 -279.756108)
			(xy 343.405981 -279.780715) (xy 343.398086 -279.829292) (xy 343.382502 -279.875973) (xy 343.359631 -279.91955)
			(xy 343.330066 -279.958894) (xy 343.294573 -279.992986) (xy 343.25407 -280.020942) (xy 343.209608 -280.04204)
			(xy 343.162337 -280.055732) (xy 343.113482 -280.061664) (xy 343.064307 -280.059683) (xy 343.016088 -280.049839)
			(xy 342.970072 -280.032387) (xy 342.927451 -280.00778) (xy 342.88933 -279.976655) (xy 342.856695 -279.939818)
			(xy 342.830392 -279.898222) (xy 342.811101 -279.852946) (xy 342.799324 -279.805162) (xy 342.795364 -279.756108)
			(xy 342.476836 -279.756108) (xy 342.476324 -279.781554) (xy 342.46816 -279.831788) (xy 342.452044 -279.880062)
			(xy 342.428393 -279.925125) (xy 342.39782 -279.965811) (xy 342.361116 -280.001066) (xy 342.319232 -280.029976)
			(xy 342.273253 -280.051793) (xy 342.224369 -280.065953) (xy 342.173848 -280.072087) (xy 342.122996 -280.070038)
			(xy 342.073132 -280.059858) (xy 342.025546 -280.041811) (xy 341.981472 -280.016365) (xy 341.94205 -279.984178)
			(xy 341.908302 -279.946084) (xy 341.881101 -279.90307) (xy 341.861153 -279.85625) (xy 341.848974 -279.806836)
			(xy 341.844879 -279.756108) (xy 341.526368 -279.756108) (xy 341.525873 -279.780715) (xy 341.517978 -279.829292)
			(xy 341.502394 -279.875973) (xy 341.479523 -279.91955) (xy 341.449958 -279.958894) (xy 341.414465 -279.992986)
			(xy 341.373962 -280.020942) (xy 341.3295 -280.04204) (xy 341.282229 -280.055732) (xy 341.233374 -280.061664)
			(xy 341.184199 -280.059683) (xy 341.13598 -280.049839) (xy 341.089964 -280.032387) (xy 341.047343 -280.00778)
			(xy 341.009222 -279.976655) (xy 340.976587 -279.939818) (xy 340.950284 -279.898222) (xy 340.930993 -279.852946)
			(xy 340.919216 -279.805162) (xy 340.915256 -279.756108) (xy 340.596728 -279.756108) (xy 340.596216 -279.781554)
			(xy 340.588052 -279.831788) (xy 340.571936 -279.880062) (xy 340.548285 -279.925125) (xy 340.517712 -279.965811)
			(xy 340.481008 -280.001066) (xy 340.439124 -280.029976) (xy 340.393145 -280.051793) (xy 340.344261 -280.065953)
			(xy 340.29374 -280.072087) (xy 340.242888 -280.070038) (xy 340.193024 -280.059858) (xy 340.145438 -280.041811)
			(xy 340.101364 -280.016365) (xy 340.061942 -279.984178) (xy 340.028194 -279.946084) (xy 340.000993 -279.90307)
			(xy 339.981045 -279.85625) (xy 339.968866 -279.806836) (xy 339.964771 -279.756108) (xy 339.656928 -279.756108)
			(xy 339.656416 -279.781554) (xy 339.648252 -279.831788) (xy 339.632136 -279.880062) (xy 339.608485 -279.925125)
			(xy 339.577912 -279.965811) (xy 339.541208 -280.001066) (xy 339.499324 -280.029976) (xy 339.453345 -280.051793)
			(xy 339.404461 -280.065953) (xy 339.35394 -280.072087) (xy 339.303088 -280.070038) (xy 339.253224 -280.059858)
			(xy 339.205638 -280.041811) (xy 339.161564 -280.016365) (xy 339.122142 -279.984178) (xy 339.088394 -279.946084)
			(xy 339.061193 -279.90307) (xy 339.041245 -279.85625) (xy 339.029066 -279.806836) (xy 339.024971 -279.756108)
			(xy 338.707051 -279.756108) (xy 338.70288 -279.806447) (xy 338.690477 -279.85542) (xy 338.670182 -279.901683)
			(xy 338.642548 -279.943974) (xy 338.608329 -279.98114) (xy 338.56846 -280.012166) (xy 338.524027 -280.036205)
			(xy 338.476243 -280.052603) (xy 338.426412 -280.060911) (xy 338.401152 -280.061416) (xy 338.388389 -280.061277)
			(xy 338.362955 -280.059114) (xy 338.350352 -280.057098) (xy 338.350352 -280.057352) (xy 338.326897 -280.052928)
			(xy 338.281638 -280.037771) (xy 338.239281 -280.015772) (xy 338.200853 -279.987464) (xy 338.167286 -279.953532)
			(xy 338.152994 -279.934416) (xy 338.144866 -279.922986) (xy 338.119212 -279.91181) (xy 338.017104 -279.925018)
			(xy 338.003134 -279.926796) (xy 337.98129 -279.943814) (xy 337.97621 -279.957022) (xy 337.969352 -279.973532)
			(xy 337.962655 -279.988903) (xy 337.947661 -280.018897) (xy 337.93938 -280.033476) (xy 337.894168 -280.111454)
			(xy 337.892644 -280.114248) (xy 337.892644 -280.114502) (xy 337.887941 -280.125323) (xy 337.887944 -280.148891)
			(xy 337.892644 -280.159714) (xy 337.929474 -280.234136) (xy 337.935084 -280.244752) (xy 337.953913 -280.259595)
			(xy 337.965542 -280.262584) (xy 337.969098 -280.263092) (xy 337.993652 -280.266692) (xy 338.041225 -280.280806)
			(xy 338.08589 -280.302425) (xy 338.126473 -280.330981) (xy 338.161907 -280.365721) (xy 338.191258 -280.405732)
			(xy 338.213755 -280.449962) (xy 338.228807 -280.497247) (xy 338.236016 -280.546343) (xy 338.235688 -280.566114)
			(xy 338.554817 -280.566114) (xy 338.558912 -280.515386) (xy 338.571091 -280.465972) (xy 338.591039 -280.419152)
			(xy 338.61824 -280.376138) (xy 338.651988 -280.338044) (xy 338.69141 -280.305857) (xy 338.735484 -280.280411)
			(xy 338.78307 -280.262364) (xy 338.832934 -280.252184) (xy 338.883786 -280.250135) (xy 338.934307 -280.256269)
			(xy 338.983191 -280.270429) (xy 339.02917 -280.292246) (xy 339.071054 -280.321156) (xy 339.107758 -280.356411)
			(xy 339.138331 -280.397097) (xy 339.161982 -280.44216) (xy 339.178098 -280.490434) (xy 339.186262 -280.540668)
			(xy 339.186774 -280.566114) (xy 339.505302 -280.566114) (xy 339.509262 -280.51706) (xy 339.521039 -280.469276)
			(xy 339.54033 -280.424) (xy 339.566633 -280.382404) (xy 339.599268 -280.345567) (xy 339.637389 -280.314442)
			(xy 339.68001 -280.289835) (xy 339.726026 -280.272383) (xy 339.774245 -280.262539) (xy 339.82342 -280.260558)
			(xy 339.872275 -280.26649) (xy 339.919546 -280.280182) (xy 339.964008 -280.30128) (xy 340.004511 -280.329236)
			(xy 340.040004 -280.363328) (xy 340.069569 -280.402672) (xy 340.09244 -280.446249) (xy 340.108024 -280.49293)
			(xy 340.115919 -280.541507) (xy 340.116414 -280.566114) (xy 340.434925 -280.566114) (xy 340.43902 -280.515386)
			(xy 340.451199 -280.465972) (xy 340.471147 -280.419152) (xy 340.498348 -280.376138) (xy 340.532096 -280.338044)
			(xy 340.571518 -280.305857) (xy 340.615592 -280.280411) (xy 340.663178 -280.262364) (xy 340.713042 -280.252184)
			(xy 340.763894 -280.250135) (xy 340.814415 -280.256269) (xy 340.863299 -280.270429) (xy 340.909278 -280.292246)
			(xy 340.951162 -280.321156) (xy 340.987866 -280.356411) (xy 341.018439 -280.397097) (xy 341.04209 -280.44216)
			(xy 341.058206 -280.490434) (xy 341.06637 -280.540668) (xy 341.066882 -280.566114) (xy 341.38541 -280.566114)
			(xy 341.38937 -280.51706) (xy 341.401147 -280.469276) (xy 341.420438 -280.424) (xy 341.446741 -280.382404)
			(xy 341.479376 -280.345567) (xy 341.517497 -280.314442) (xy 341.560118 -280.289835) (xy 341.606134 -280.272383)
			(xy 341.654353 -280.262539) (xy 341.703528 -280.260558) (xy 341.752383 -280.26649) (xy 341.799654 -280.280182)
			(xy 341.844116 -280.30128) (xy 341.884619 -280.329236) (xy 341.920112 -280.363328) (xy 341.949677 -280.402672)
			(xy 341.972548 -280.446249) (xy 341.988132 -280.49293) (xy 341.996027 -280.541507) (xy 341.996522 -280.566114)
			(xy 342.314779 -280.566114) (xy 342.318874 -280.515386) (xy 342.331053 -280.465972) (xy 342.351001 -280.419152)
			(xy 342.378202 -280.376138) (xy 342.41195 -280.338044) (xy 342.451372 -280.305857) (xy 342.495446 -280.280411)
			(xy 342.543032 -280.262364) (xy 342.592896 -280.252184) (xy 342.643748 -280.250135) (xy 342.694269 -280.256269)
			(xy 342.743153 -280.270429) (xy 342.789132 -280.292246) (xy 342.831016 -280.321156) (xy 342.86772 -280.356411)
			(xy 342.898293 -280.397097) (xy 342.921944 -280.44216) (xy 342.93806 -280.490434) (xy 342.946224 -280.540668)
			(xy 342.946736 -280.566114) (xy 343.254833 -280.566114) (xy 343.258928 -280.515386) (xy 343.271107 -280.465972)
			(xy 343.291055 -280.419152) (xy 343.318256 -280.376138) (xy 343.352004 -280.338044) (xy 343.391426 -280.305857)
			(xy 343.4355 -280.280411) (xy 343.483086 -280.262364) (xy 343.53295 -280.252184) (xy 343.583802 -280.250135)
			(xy 343.634323 -280.256269) (xy 343.683207 -280.270429) (xy 343.729186 -280.292246) (xy 343.77107 -280.321156)
			(xy 343.807774 -280.356411) (xy 343.838347 -280.397097) (xy 343.861998 -280.44216) (xy 343.878114 -280.490434)
			(xy 343.886278 -280.540668) (xy 343.88679 -280.566114) (xy 343.886278 -280.59156) (xy 343.878114 -280.641794)
			(xy 343.861998 -280.690068) (xy 343.838347 -280.735131) (xy 343.807774 -280.775817) (xy 343.77107 -280.811072)
			(xy 343.729186 -280.839982) (xy 343.683207 -280.861799) (xy 343.634323 -280.875959) (xy 343.583802 -280.882093)
			(xy 343.53295 -280.880044) (xy 343.483086 -280.869864) (xy 343.4355 -280.851817) (xy 343.391426 -280.826371)
			(xy 343.352004 -280.794184) (xy 343.318256 -280.75609) (xy 343.291055 -280.713076) (xy 343.271107 -280.666256)
			(xy 343.258928 -280.616842) (xy 343.254833 -280.566114) (xy 342.946736 -280.566114) (xy 342.946224 -280.59156)
			(xy 342.93806 -280.641794) (xy 342.921944 -280.690068) (xy 342.898293 -280.735131) (xy 342.86772 -280.775817)
			(xy 342.831016 -280.811072) (xy 342.789132 -280.839982) (xy 342.743153 -280.861799) (xy 342.694269 -280.875959)
			(xy 342.643748 -280.882093) (xy 342.592896 -280.880044) (xy 342.543032 -280.869864) (xy 342.495446 -280.851817)
			(xy 342.451372 -280.826371) (xy 342.41195 -280.794184) (xy 342.378202 -280.75609) (xy 342.351001 -280.713076)
			(xy 342.331053 -280.666256) (xy 342.318874 -280.616842) (xy 342.314779 -280.566114) (xy 341.996522 -280.566114)
			(xy 341.996027 -280.590721) (xy 341.988132 -280.639298) (xy 341.972548 -280.685979) (xy 341.949677 -280.729556)
			(xy 341.920112 -280.7689) (xy 341.884619 -280.802992) (xy 341.844116 -280.830948) (xy 341.799654 -280.852046)
			(xy 341.752383 -280.865738) (xy 341.703528 -280.87167) (xy 341.654353 -280.869689) (xy 341.606134 -280.859845)
			(xy 341.560118 -280.842393) (xy 341.517497 -280.817786) (xy 341.479376 -280.786661) (xy 341.446741 -280.749824)
			(xy 341.420438 -280.708228) (xy 341.401147 -280.662952) (xy 341.38937 -280.615168) (xy 341.38541 -280.566114)
			(xy 341.066882 -280.566114) (xy 341.06637 -280.59156) (xy 341.058206 -280.641794) (xy 341.04209 -280.690068)
			(xy 341.018439 -280.735131) (xy 340.987866 -280.775817) (xy 340.951162 -280.811072) (xy 340.909278 -280.839982)
			(xy 340.863299 -280.861799) (xy 340.814415 -280.875959) (xy 340.763894 -280.882093) (xy 340.713042 -280.880044)
			(xy 340.663178 -280.869864) (xy 340.615592 -280.851817) (xy 340.571518 -280.826371) (xy 340.532096 -280.794184)
			(xy 340.498348 -280.75609) (xy 340.471147 -280.713076) (xy 340.451199 -280.666256) (xy 340.43902 -280.616842)
			(xy 340.434925 -280.566114) (xy 340.116414 -280.566114) (xy 340.115919 -280.590721) (xy 340.108024 -280.639298)
			(xy 340.09244 -280.685979) (xy 340.069569 -280.729556) (xy 340.040004 -280.7689) (xy 340.004511 -280.802992)
			(xy 339.964008 -280.830948) (xy 339.919546 -280.852046) (xy 339.872275 -280.865738) (xy 339.82342 -280.87167)
			(xy 339.774245 -280.869689) (xy 339.726026 -280.859845) (xy 339.68001 -280.842393) (xy 339.637389 -280.817786)
			(xy 339.599268 -280.786661) (xy 339.566633 -280.749824) (xy 339.54033 -280.708228) (xy 339.521039 -280.662952)
			(xy 339.509262 -280.615168) (xy 339.505302 -280.566114) (xy 339.186774 -280.566114) (xy 339.186262 -280.59156)
			(xy 339.178098 -280.641794) (xy 339.161982 -280.690068) (xy 339.138331 -280.735131) (xy 339.107758 -280.775817)
			(xy 339.071054 -280.811072) (xy 339.02917 -280.839982) (xy 338.983191 -280.861799) (xy 338.934307 -280.875959)
			(xy 338.883786 -280.882093) (xy 338.832934 -280.880044) (xy 338.78307 -280.869864) (xy 338.735484 -280.851817)
			(xy 338.69141 -280.826371) (xy 338.651988 -280.794184) (xy 338.61824 -280.75609) (xy 338.591039 -280.713076)
			(xy 338.571091 -280.666256) (xy 338.558912 -280.616842) (xy 338.554817 -280.566114) (xy 338.235688 -280.566114)
			(xy 338.235194 -280.595959) (xy 338.226363 -280.644789) (xy 338.209753 -280.69155) (xy 338.185803 -280.73501)
			(xy 338.155143 -280.774027) (xy 338.118578 -280.807575) (xy 338.09813 -280.821638) (xy 338.078287 -280.834098)
			(xy 338.035635 -280.853484) (xy 337.990523 -280.866133) (xy 337.96732 -280.86939) (xy 337.967066 -280.86939)
			(xy 337.958091 -280.870753) (xy 337.941875 -280.878889) (xy 337.92949 -280.892146) (xy 337.925664 -280.900378)
			(xy 337.886294 -280.99512) (xy 337.890104 -281.022044) (xy 337.898486 -281.032966) (xy 337.922858 -281.065204)
			(xy 337.963027 -281.13533) (xy 337.978496 -281.172666) (xy 337.983576 -281.18562) (xy 338.00542 -281.202638)
			(xy 338.075524 -281.211528) (xy 338.081874 -281.212036) (xy 338.11718 -281.212036) (xy 338.129002 -281.211487)
			(xy 338.150196 -281.201022) (xy 338.15782 -281.19197) (xy 338.172328 -281.173491) (xy 338.206064 -281.140796)
			(xy 338.244414 -281.11366) (xy 338.28647 -281.092723) (xy 338.331239 -281.078482) (xy 338.377662 -281.071272)
			(xy 338.401152 -281.070812) (xy 338.426411 -281.071301) (xy 338.47624 -281.079609) (xy 338.524022 -281.096006)
			(xy 338.568453 -281.120044) (xy 338.608321 -281.151069) (xy 338.642538 -281.188233) (xy 338.670171 -281.230523)
			(xy 338.690465 -281.276784) (xy 338.702868 -281.325755) (xy 338.70704 -281.3761) (xy 338.707038 -281.37612)
			(xy 339.024971 -281.37612) (xy 339.029066 -281.325392) (xy 339.041245 -281.275978) (xy 339.061193 -281.229158)
			(xy 339.088394 -281.186144) (xy 339.122142 -281.14805) (xy 339.161564 -281.115863) (xy 339.205638 -281.090417)
			(xy 339.253224 -281.07237) (xy 339.303088 -281.06219) (xy 339.35394 -281.060141) (xy 339.404461 -281.066275)
			(xy 339.453345 -281.080435) (xy 339.499324 -281.102252) (xy 339.541208 -281.131162) (xy 339.577912 -281.166417)
			(xy 339.608485 -281.207103) (xy 339.632136 -281.252166) (xy 339.648252 -281.30044) (xy 339.656416 -281.350674)
			(xy 339.656928 -281.37612) (xy 339.964771 -281.37612) (xy 339.968866 -281.325392) (xy 339.981045 -281.275978)
			(xy 340.000993 -281.229158) (xy 340.028194 -281.186144) (xy 340.061942 -281.14805) (xy 340.101364 -281.115863)
			(xy 340.145438 -281.090417) (xy 340.193024 -281.07237) (xy 340.242888 -281.06219) (xy 340.29374 -281.060141)
			(xy 340.344261 -281.066275) (xy 340.393145 -281.080435) (xy 340.439124 -281.102252) (xy 340.481008 -281.131162)
			(xy 340.517712 -281.166417) (xy 340.548285 -281.207103) (xy 340.571936 -281.252166) (xy 340.588052 -281.30044)
			(xy 340.596216 -281.350674) (xy 340.596728 -281.37612) (xy 340.915256 -281.37612) (xy 340.919216 -281.327066)
			(xy 340.930993 -281.279282) (xy 340.950284 -281.234006) (xy 340.976587 -281.19241) (xy 341.009222 -281.155573)
			(xy 341.047343 -281.124448) (xy 341.089964 -281.099841) (xy 341.13598 -281.082389) (xy 341.184199 -281.072545)
			(xy 341.233374 -281.070564) (xy 341.282229 -281.076496) (xy 341.3295 -281.090188) (xy 341.373962 -281.111286)
			(xy 341.414465 -281.139242) (xy 341.449958 -281.173334) (xy 341.479523 -281.212678) (xy 341.502394 -281.256255)
			(xy 341.517978 -281.302936) (xy 341.525873 -281.351513) (xy 341.526368 -281.37612) (xy 341.844879 -281.37612)
			(xy 341.848974 -281.325392) (xy 341.861153 -281.275978) (xy 341.881101 -281.229158) (xy 341.908302 -281.186144)
			(xy 341.94205 -281.14805) (xy 341.981472 -281.115863) (xy 342.025546 -281.090417) (xy 342.073132 -281.07237)
			(xy 342.122996 -281.06219) (xy 342.173848 -281.060141) (xy 342.224369 -281.066275) (xy 342.273253 -281.080435)
			(xy 342.319232 -281.102252) (xy 342.361116 -281.131162) (xy 342.39782 -281.166417) (xy 342.428393 -281.207103)
			(xy 342.452044 -281.252166) (xy 342.46816 -281.30044) (xy 342.476324 -281.350674) (xy 342.476836 -281.37612)
			(xy 342.795364 -281.37612) (xy 342.799324 -281.327066) (xy 342.811101 -281.279282) (xy 342.830392 -281.234006)
			(xy 342.856695 -281.19241) (xy 342.88933 -281.155573) (xy 342.927451 -281.124448) (xy 342.970072 -281.099841)
			(xy 343.016088 -281.082389) (xy 343.064307 -281.072545) (xy 343.113482 -281.070564) (xy 343.162337 -281.076496)
			(xy 343.209608 -281.090188) (xy 343.25407 -281.111286) (xy 343.294573 -281.139242) (xy 343.330066 -281.173334)
			(xy 343.359631 -281.212678) (xy 343.382502 -281.256255) (xy 343.398086 -281.302936) (xy 343.405981 -281.351513)
			(xy 343.406476 -281.37612) (xy 343.724987 -281.37612) (xy 343.729082 -281.325392) (xy 343.741261 -281.275978)
			(xy 343.761209 -281.229158) (xy 343.78841 -281.186144) (xy 343.822158 -281.14805) (xy 343.86158 -281.115863)
			(xy 343.905654 -281.090417) (xy 343.95324 -281.07237) (xy 344.003104 -281.06219) (xy 344.053956 -281.060141)
			(xy 344.104477 -281.066275) (xy 344.153361 -281.080435) (xy 344.19934 -281.102252) (xy 344.241224 -281.131162)
			(xy 344.277928 -281.166417) (xy 344.308501 -281.207103) (xy 344.332152 -281.252166) (xy 344.348268 -281.30044)
			(xy 344.356432 -281.350674) (xy 344.356944 -281.37612) (xy 344.356432 -281.401566) (xy 344.348268 -281.4518)
			(xy 344.332152 -281.500074) (xy 344.308501 -281.545137) (xy 344.277928 -281.585823) (xy 344.241224 -281.621078)
			(xy 344.19934 -281.649988) (xy 344.153361 -281.671805) (xy 344.104477 -281.685965) (xy 344.053956 -281.692099)
			(xy 344.003104 -281.69005) (xy 343.95324 -281.67987) (xy 343.905654 -281.661823) (xy 343.86158 -281.636377)
			(xy 343.822158 -281.60419) (xy 343.78841 -281.566096) (xy 343.761209 -281.523082) (xy 343.741261 -281.476262)
			(xy 343.729082 -281.426848) (xy 343.724987 -281.37612) (xy 343.406476 -281.37612) (xy 343.405981 -281.400727)
			(xy 343.398086 -281.449304) (xy 343.382502 -281.495985) (xy 343.359631 -281.539562) (xy 343.330066 -281.578906)
			(xy 343.294573 -281.612998) (xy 343.25407 -281.640954) (xy 343.209608 -281.662052) (xy 343.162337 -281.675744)
			(xy 343.113482 -281.681676) (xy 343.064307 -281.679695) (xy 343.016088 -281.669851) (xy 342.970072 -281.652399)
			(xy 342.927451 -281.627792) (xy 342.88933 -281.596667) (xy 342.856695 -281.55983) (xy 342.830392 -281.518234)
			(xy 342.811101 -281.472958) (xy 342.799324 -281.425174) (xy 342.795364 -281.37612) (xy 342.476836 -281.37612)
			(xy 342.476324 -281.401566) (xy 342.46816 -281.4518) (xy 342.452044 -281.500074) (xy 342.428393 -281.545137)
			(xy 342.39782 -281.585823) (xy 342.361116 -281.621078) (xy 342.319232 -281.649988) (xy 342.273253 -281.671805)
			(xy 342.224369 -281.685965) (xy 342.173848 -281.692099) (xy 342.122996 -281.69005) (xy 342.073132 -281.67987)
			(xy 342.025546 -281.661823) (xy 341.981472 -281.636377) (xy 341.94205 -281.60419) (xy 341.908302 -281.566096)
			(xy 341.881101 -281.523082) (xy 341.861153 -281.476262) (xy 341.848974 -281.426848) (xy 341.844879 -281.37612)
			(xy 341.526368 -281.37612) (xy 341.525873 -281.400727) (xy 341.517978 -281.449304) (xy 341.502394 -281.495985)
			(xy 341.479523 -281.539562) (xy 341.449958 -281.578906) (xy 341.414465 -281.612998) (xy 341.373962 -281.640954)
			(xy 341.3295 -281.662052) (xy 341.282229 -281.675744) (xy 341.233374 -281.681676) (xy 341.184199 -281.679695)
			(xy 341.13598 -281.669851) (xy 341.089964 -281.652399) (xy 341.047343 -281.627792) (xy 341.009222 -281.596667)
			(xy 340.976587 -281.55983) (xy 340.950284 -281.518234) (xy 340.930993 -281.472958) (xy 340.919216 -281.425174)
			(xy 340.915256 -281.37612) (xy 340.596728 -281.37612) (xy 340.596216 -281.401566) (xy 340.588052 -281.4518)
			(xy 340.571936 -281.500074) (xy 340.548285 -281.545137) (xy 340.517712 -281.585823) (xy 340.481008 -281.621078)
			(xy 340.439124 -281.649988) (xy 340.393145 -281.671805) (xy 340.344261 -281.685965) (xy 340.29374 -281.692099)
			(xy 340.242888 -281.69005) (xy 340.193024 -281.67987) (xy 340.145438 -281.661823) (xy 340.101364 -281.636377)
			(xy 340.061942 -281.60419) (xy 340.028194 -281.566096) (xy 340.000993 -281.523082) (xy 339.981045 -281.476262)
			(xy 339.968866 -281.426848) (xy 339.964771 -281.37612) (xy 339.656928 -281.37612) (xy 339.656416 -281.401566)
			(xy 339.648252 -281.4518) (xy 339.632136 -281.500074) (xy 339.608485 -281.545137) (xy 339.577912 -281.585823)
			(xy 339.541208 -281.621078) (xy 339.499324 -281.649988) (xy 339.453345 -281.671805) (xy 339.404461 -281.685965)
			(xy 339.35394 -281.692099) (xy 339.303088 -281.69005) (xy 339.253224 -281.67987) (xy 339.205638 -281.661823)
			(xy 339.161564 -281.636377) (xy 339.122142 -281.60419) (xy 339.088394 -281.566096) (xy 339.061193 -281.523082)
			(xy 339.041245 -281.476262) (xy 339.029066 -281.426848) (xy 339.024971 -281.37612) (xy 338.707038 -281.37612)
			(xy 338.702868 -281.426445) (xy 338.690465 -281.475416) (xy 338.670171 -281.521677) (xy 338.642538 -281.563967)
			(xy 338.608321 -281.601131) (xy 338.568453 -281.632156) (xy 338.524022 -281.656194) (xy 338.47624 -281.672591)
			(xy 338.426411 -281.680899) (xy 338.401152 -281.681428) (xy 338.377666 -281.680971) (xy 338.331255 -281.673729)
			(xy 338.286499 -281.659469) (xy 338.244453 -281.638526) (xy 338.206107 -281.611396) (xy 338.172366 -281.578716)
			(xy 338.15782 -281.56027) (xy 338.150175 -281.551248) (xy 338.128992 -281.540799) (xy 338.11718 -281.540204)
			(xy 338.081874 -281.540204) (xy 338.075524 -281.540712) (xy 338.00542 -281.549602) (xy 337.983576 -281.56662)
			(xy 337.978496 -281.579574) (xy 337.965288 -281.610562) (xy 337.959955 -281.621901) (xy 337.948395 -281.644135)
			(xy 337.942174 -281.655012) (xy 337.912964 -281.705304) (xy 337.897724 -281.73172) (xy 337.891962 -281.742868)
			(xy 337.89105 -281.767914) (xy 337.895946 -281.779472) (xy 337.938618 -281.867102) (xy 337.958938 -281.881834)
			(xy 337.971892 -281.883612) (xy 337.995985 -281.887349) (xy 338.042648 -281.901473) (xy 338.086474 -281.922832)
			(xy 338.126349 -281.950884) (xy 338.16126 -281.984915) (xy 338.190319 -282.024062) (xy 338.212789 -282.067329)
			(xy 338.228097 -282.113617) (xy 338.235856 -282.161749) (xy 338.236306 -282.186126) (xy 338.554817 -282.186126)
			(xy 338.558912 -282.135398) (xy 338.571091 -282.085984) (xy 338.591039 -282.039164) (xy 338.61824 -281.99615)
			(xy 338.651988 -281.958056) (xy 338.69141 -281.925869) (xy 338.735484 -281.900423) (xy 338.78307 -281.882376)
			(xy 338.832934 -281.872196) (xy 338.883786 -281.870147) (xy 338.934307 -281.876281) (xy 338.983191 -281.890441)
			(xy 339.02917 -281.912258) (xy 339.071054 -281.941168) (xy 339.107758 -281.976423) (xy 339.138331 -282.017109)
			(xy 339.161982 -282.062172) (xy 339.178098 -282.110446) (xy 339.186262 -282.16068) (xy 339.186774 -282.186126)
			(xy 339.505302 -282.186126) (xy 339.509262 -282.137072) (xy 339.521039 -282.089288) (xy 339.54033 -282.044012)
			(xy 339.566633 -282.002416) (xy 339.599268 -281.965579) (xy 339.637389 -281.934454) (xy 339.68001 -281.909847)
			(xy 339.726026 -281.892395) (xy 339.774245 -281.882551) (xy 339.82342 -281.88057) (xy 339.872275 -281.886502)
			(xy 339.919546 -281.900194) (xy 339.964008 -281.921292) (xy 340.004511 -281.949248) (xy 340.040004 -281.98334)
			(xy 340.069569 -282.022684) (xy 340.09244 -282.066261) (xy 340.108024 -282.112942) (xy 340.115919 -282.161519)
			(xy 340.116414 -282.186126) (xy 340.434925 -282.186126) (xy 340.43902 -282.135398) (xy 340.451199 -282.085984)
			(xy 340.471147 -282.039164) (xy 340.498348 -281.99615) (xy 340.532096 -281.958056) (xy 340.571518 -281.925869)
			(xy 340.615592 -281.900423) (xy 340.663178 -281.882376) (xy 340.713042 -281.872196) (xy 340.763894 -281.870147)
			(xy 340.814415 -281.876281) (xy 340.863299 -281.890441) (xy 340.909278 -281.912258) (xy 340.951162 -281.941168)
			(xy 340.987866 -281.976423) (xy 341.018439 -282.017109) (xy 341.04209 -282.062172) (xy 341.058206 -282.110446)
			(xy 341.06637 -282.16068) (xy 341.066882 -282.186126) (xy 341.38541 -282.186126) (xy 341.38937 -282.137072)
			(xy 341.401147 -282.089288) (xy 341.420438 -282.044012) (xy 341.446741 -282.002416) (xy 341.479376 -281.965579)
			(xy 341.517497 -281.934454) (xy 341.560118 -281.909847) (xy 341.606134 -281.892395) (xy 341.654353 -281.882551)
			(xy 341.703528 -281.88057) (xy 341.752383 -281.886502) (xy 341.799654 -281.900194) (xy 341.844116 -281.921292)
			(xy 341.884619 -281.949248) (xy 341.920112 -281.98334) (xy 341.949677 -282.022684) (xy 341.972548 -282.066261)
			(xy 341.988132 -282.112942) (xy 341.996027 -282.161519) (xy 341.996522 -282.186126) (xy 342.314779 -282.186126)
			(xy 342.318874 -282.135398) (xy 342.331053 -282.085984) (xy 342.351001 -282.039164) (xy 342.378202 -281.99615)
			(xy 342.41195 -281.958056) (xy 342.451372 -281.925869) (xy 342.495446 -281.900423) (xy 342.543032 -281.882376)
			(xy 342.592896 -281.872196) (xy 342.643748 -281.870147) (xy 342.694269 -281.876281) (xy 342.743153 -281.890441)
			(xy 342.789132 -281.912258) (xy 342.831016 -281.941168) (xy 342.86772 -281.976423) (xy 342.898293 -282.017109)
			(xy 342.921944 -282.062172) (xy 342.93806 -282.110446) (xy 342.946224 -282.16068) (xy 342.946736 -282.186126)
			(xy 343.254833 -282.186126) (xy 343.258928 -282.135398) (xy 343.271107 -282.085984) (xy 343.291055 -282.039164)
			(xy 343.318256 -281.99615) (xy 343.352004 -281.958056) (xy 343.391426 -281.925869) (xy 343.4355 -281.900423)
			(xy 343.483086 -281.882376) (xy 343.53295 -281.872196) (xy 343.583802 -281.870147) (xy 343.634323 -281.876281)
			(xy 343.683207 -281.890441) (xy 343.729186 -281.912258) (xy 343.77107 -281.941168) (xy 343.807774 -281.976423)
			(xy 343.838347 -282.017109) (xy 343.861998 -282.062172) (xy 343.878114 -282.110446) (xy 343.886278 -282.16068)
			(xy 343.88679 -282.186126) (xy 343.886278 -282.211572) (xy 343.878114 -282.261806) (xy 343.861998 -282.31008)
			(xy 343.838347 -282.355143) (xy 343.807774 -282.395829) (xy 343.77107 -282.431084) (xy 343.729186 -282.459994)
			(xy 343.683207 -282.481811) (xy 343.634323 -282.495971) (xy 343.583802 -282.502105) (xy 343.53295 -282.500056)
			(xy 343.483086 -282.489876) (xy 343.4355 -282.471829) (xy 343.391426 -282.446383) (xy 343.352004 -282.414196)
			(xy 343.318256 -282.376102) (xy 343.291055 -282.333088) (xy 343.271107 -282.286268) (xy 343.258928 -282.236854)
			(xy 343.254833 -282.186126) (xy 342.946736 -282.186126) (xy 342.946224 -282.211572) (xy 342.93806 -282.261806)
			(xy 342.921944 -282.31008) (xy 342.898293 -282.355143) (xy 342.86772 -282.395829) (xy 342.831016 -282.431084)
			(xy 342.789132 -282.459994) (xy 342.743153 -282.481811) (xy 342.694269 -282.495971) (xy 342.643748 -282.502105)
			(xy 342.592896 -282.500056) (xy 342.543032 -282.489876) (xy 342.495446 -282.471829) (xy 342.451372 -282.446383)
			(xy 342.41195 -282.414196) (xy 342.378202 -282.376102) (xy 342.351001 -282.333088) (xy 342.331053 -282.286268)
			(xy 342.318874 -282.236854) (xy 342.314779 -282.186126) (xy 341.996522 -282.186126) (xy 341.996027 -282.210733)
			(xy 341.988132 -282.25931) (xy 341.972548 -282.305991) (xy 341.949677 -282.349568) (xy 341.920112 -282.388912)
			(xy 341.884619 -282.423004) (xy 341.844116 -282.45096) (xy 341.799654 -282.472058) (xy 341.752383 -282.48575)
			(xy 341.703528 -282.491682) (xy 341.654353 -282.489701) (xy 341.606134 -282.479857) (xy 341.560118 -282.462405)
			(xy 341.517497 -282.437798) (xy 341.479376 -282.406673) (xy 341.446741 -282.369836) (xy 341.420438 -282.32824)
			(xy 341.401147 -282.282964) (xy 341.38937 -282.23518) (xy 341.38541 -282.186126) (xy 341.066882 -282.186126)
			(xy 341.06637 -282.211572) (xy 341.058206 -282.261806) (xy 341.04209 -282.31008) (xy 341.018439 -282.355143)
			(xy 340.987866 -282.395829) (xy 340.951162 -282.431084) (xy 340.909278 -282.459994) (xy 340.863299 -282.481811)
			(xy 340.814415 -282.495971) (xy 340.763894 -282.502105) (xy 340.713042 -282.500056) (xy 340.663178 -282.489876)
			(xy 340.615592 -282.471829) (xy 340.571518 -282.446383) (xy 340.532096 -282.414196) (xy 340.498348 -282.376102)
			(xy 340.471147 -282.333088) (xy 340.451199 -282.286268) (xy 340.43902 -282.236854) (xy 340.434925 -282.186126)
			(xy 340.116414 -282.186126) (xy 340.115919 -282.210733) (xy 340.108024 -282.25931) (xy 340.09244 -282.305991)
			(xy 340.069569 -282.349568) (xy 340.040004 -282.388912) (xy 340.004511 -282.423004) (xy 339.964008 -282.45096)
			(xy 339.919546 -282.472058) (xy 339.872275 -282.48575) (xy 339.82342 -282.491682) (xy 339.774245 -282.489701)
			(xy 339.726026 -282.479857) (xy 339.68001 -282.462405) (xy 339.637389 -282.437798) (xy 339.599268 -282.406673)
			(xy 339.566633 -282.369836) (xy 339.54033 -282.32824) (xy 339.521039 -282.282964) (xy 339.509262 -282.23518)
			(xy 339.505302 -282.186126) (xy 339.186774 -282.186126) (xy 339.186262 -282.211572) (xy 339.178098 -282.261806)
			(xy 339.161982 -282.31008) (xy 339.138331 -282.355143) (xy 339.107758 -282.395829) (xy 339.071054 -282.431084)
			(xy 339.02917 -282.459994) (xy 338.983191 -282.481811) (xy 338.934307 -282.495971) (xy 338.883786 -282.502105)
			(xy 338.832934 -282.500056) (xy 338.78307 -282.489876) (xy 338.735484 -282.471829) (xy 338.69141 -282.446383)
			(xy 338.651988 -282.414196) (xy 338.61824 -282.376102) (xy 338.591039 -282.333088) (xy 338.571091 -282.286268)
			(xy 338.558912 -282.236854) (xy 338.554817 -282.186126) (xy 338.236306 -282.186126) (xy 338.235818 -282.210945)
			(xy 338.227784 -282.259928) (xy 338.211932 -282.306967) (xy 338.188678 -282.350822) (xy 338.158637 -282.390337)
			(xy 338.122599 -282.424472) (xy 338.081514 -282.452327) (xy 338.036463 -282.473169) (xy 337.988635 -282.486449)
			(xy 337.964018 -282.489656) (xy 337.950048 -282.49118) (xy 337.92795 -282.50769) (xy 337.888072 -282.602432)
			(xy 337.884927 -282.610959) (xy 337.884222 -282.629107) (xy 337.889864 -282.64637) (xy 337.895184 -282.65374)
			(xy 337.897724 -282.657042) (xy 337.921658 -282.688955) (xy 337.961058 -282.758317) (xy 337.97621 -282.795218)
			(xy 337.98129 -282.808426) (xy 338.00288 -282.825444) (xy 338.119466 -282.84043) (xy 338.144866 -282.829254)
			(xy 338.153248 -282.817824) (xy 338.167711 -282.798521) (xy 338.201697 -282.764297) (xy 338.240636 -282.735835)
			(xy 338.28356 -282.71384) (xy 338.329406 -282.698858) (xy 338.377036 -282.691261) (xy 338.401152 -282.690824)
			(xy 338.42641 -282.691313) (xy 338.476237 -282.69962) (xy 338.524017 -282.716017) (xy 338.568447 -282.740054)
			(xy 338.608313 -282.771078) (xy 338.642529 -282.808241) (xy 338.67016 -282.850529) (xy 338.690454 -282.896788)
			(xy 338.702856 -282.945757) (xy 338.707028 -282.9961) (xy 338.707025 -282.996132) (xy 339.024971 -282.996132)
			(xy 339.029066 -282.945404) (xy 339.041245 -282.89599) (xy 339.061193 -282.84917) (xy 339.088394 -282.806156)
			(xy 339.122142 -282.768062) (xy 339.161564 -282.735875) (xy 339.205638 -282.710429) (xy 339.253224 -282.692382)
			(xy 339.303088 -282.682202) (xy 339.35394 -282.680153) (xy 339.404461 -282.686287) (xy 339.453345 -282.700447)
			(xy 339.499324 -282.722264) (xy 339.541208 -282.751174) (xy 339.577912 -282.786429) (xy 339.608485 -282.827115)
			(xy 339.632136 -282.872178) (xy 339.648252 -282.920452) (xy 339.656416 -282.970686) (xy 339.656928 -282.996132)
			(xy 339.964771 -282.996132) (xy 339.968866 -282.945404) (xy 339.981045 -282.89599) (xy 340.000993 -282.84917)
			(xy 340.028194 -282.806156) (xy 340.061942 -282.768062) (xy 340.101364 -282.735875) (xy 340.145438 -282.710429)
			(xy 340.193024 -282.692382) (xy 340.242888 -282.682202) (xy 340.29374 -282.680153) (xy 340.344261 -282.686287)
			(xy 340.393145 -282.700447) (xy 340.439124 -282.722264) (xy 340.481008 -282.751174) (xy 340.517712 -282.786429)
			(xy 340.548285 -282.827115) (xy 340.571936 -282.872178) (xy 340.588052 -282.920452) (xy 340.596216 -282.970686)
			(xy 340.596728 -282.996132) (xy 340.915256 -282.996132) (xy 340.919216 -282.947078) (xy 340.930993 -282.899294)
			(xy 340.950284 -282.854018) (xy 340.976587 -282.812422) (xy 341.009222 -282.775585) (xy 341.047343 -282.74446)
			(xy 341.089964 -282.719853) (xy 341.13598 -282.702401) (xy 341.184199 -282.692557) (xy 341.233374 -282.690576)
			(xy 341.282229 -282.696508) (xy 341.3295 -282.7102) (xy 341.373962 -282.731298) (xy 341.414465 -282.759254)
			(xy 341.449958 -282.793346) (xy 341.479523 -282.83269) (xy 341.502394 -282.876267) (xy 341.517978 -282.922948)
			(xy 341.525873 -282.971525) (xy 341.526368 -282.996132) (xy 341.844879 -282.996132) (xy 341.848974 -282.945404)
			(xy 341.861153 -282.89599) (xy 341.881101 -282.84917) (xy 341.908302 -282.806156) (xy 341.94205 -282.768062)
			(xy 341.981472 -282.735875) (xy 342.025546 -282.710429) (xy 342.073132 -282.692382) (xy 342.122996 -282.682202)
			(xy 342.173848 -282.680153) (xy 342.224369 -282.686287) (xy 342.273253 -282.700447) (xy 342.319232 -282.722264)
			(xy 342.361116 -282.751174) (xy 342.39782 -282.786429) (xy 342.428393 -282.827115) (xy 342.452044 -282.872178)
			(xy 342.46816 -282.920452) (xy 342.476324 -282.970686) (xy 342.476836 -282.996132) (xy 342.795364 -282.996132)
			(xy 342.799324 -282.947078) (xy 342.811101 -282.899294) (xy 342.830392 -282.854018) (xy 342.856695 -282.812422)
			(xy 342.88933 -282.775585) (xy 342.927451 -282.74446) (xy 342.970072 -282.719853) (xy 343.016088 -282.702401)
			(xy 343.064307 -282.692557) (xy 343.113482 -282.690576) (xy 343.162337 -282.696508) (xy 343.209608 -282.7102)
			(xy 343.25407 -282.731298) (xy 343.294573 -282.759254) (xy 343.330066 -282.793346) (xy 343.359631 -282.83269)
			(xy 343.382502 -282.876267) (xy 343.398086 -282.922948) (xy 343.405981 -282.971525) (xy 343.406476 -282.996132)
			(xy 343.724987 -282.996132) (xy 343.729082 -282.945404) (xy 343.741261 -282.89599) (xy 343.761209 -282.84917)
			(xy 343.78841 -282.806156) (xy 343.822158 -282.768062) (xy 343.86158 -282.735875) (xy 343.905654 -282.710429)
			(xy 343.95324 -282.692382) (xy 344.003104 -282.682202) (xy 344.053956 -282.680153) (xy 344.104477 -282.686287)
			(xy 344.153361 -282.700447) (xy 344.19934 -282.722264) (xy 344.241224 -282.751174) (xy 344.277928 -282.786429)
			(xy 344.308501 -282.827115) (xy 344.332152 -282.872178) (xy 344.348268 -282.920452) (xy 344.356432 -282.970686)
			(xy 344.356944 -282.996132) (xy 344.356432 -283.021578) (xy 344.348268 -283.071812) (xy 344.332152 -283.120086)
			(xy 344.308501 -283.165149) (xy 344.277928 -283.205835) (xy 344.241224 -283.24109) (xy 344.19934 -283.27)
			(xy 344.153361 -283.291817) (xy 344.104477 -283.305977) (xy 344.053956 -283.312111) (xy 344.003104 -283.310062)
			(xy 343.95324 -283.299882) (xy 343.905654 -283.281835) (xy 343.86158 -283.256389) (xy 343.822158 -283.224202)
			(xy 343.78841 -283.186108) (xy 343.761209 -283.143094) (xy 343.741261 -283.096274) (xy 343.729082 -283.04686)
			(xy 343.724987 -282.996132) (xy 343.406476 -282.996132) (xy 343.405981 -283.020739) (xy 343.398086 -283.069316)
			(xy 343.382502 -283.115997) (xy 343.359631 -283.159574) (xy 343.330066 -283.198918) (xy 343.294573 -283.23301)
			(xy 343.25407 -283.260966) (xy 343.209608 -283.282064) (xy 343.162337 -283.295756) (xy 343.113482 -283.301688)
			(xy 343.064307 -283.299707) (xy 343.016088 -283.289863) (xy 342.970072 -283.272411) (xy 342.927451 -283.247804)
			(xy 342.88933 -283.216679) (xy 342.856695 -283.179842) (xy 342.830392 -283.138246) (xy 342.811101 -283.09297)
			(xy 342.799324 -283.045186) (xy 342.795364 -282.996132) (xy 342.476836 -282.996132) (xy 342.476324 -283.021578)
			(xy 342.46816 -283.071812) (xy 342.452044 -283.120086) (xy 342.428393 -283.165149) (xy 342.39782 -283.205835)
			(xy 342.361116 -283.24109) (xy 342.319232 -283.27) (xy 342.273253 -283.291817) (xy 342.224369 -283.305977)
			(xy 342.173848 -283.312111) (xy 342.122996 -283.310062) (xy 342.073132 -283.299882) (xy 342.025546 -283.281835)
			(xy 341.981472 -283.256389) (xy 341.94205 -283.224202) (xy 341.908302 -283.186108) (xy 341.881101 -283.143094)
			(xy 341.861153 -283.096274) (xy 341.848974 -283.04686) (xy 341.844879 -282.996132) (xy 341.526368 -282.996132)
			(xy 341.525873 -283.020739) (xy 341.517978 -283.069316) (xy 341.502394 -283.115997) (xy 341.479523 -283.159574)
			(xy 341.449958 -283.198918) (xy 341.414465 -283.23301) (xy 341.373962 -283.260966) (xy 341.3295 -283.282064)
			(xy 341.282229 -283.295756) (xy 341.233374 -283.301688) (xy 341.184199 -283.299707) (xy 341.13598 -283.289863)
			(xy 341.089964 -283.272411) (xy 341.047343 -283.247804) (xy 341.009222 -283.216679) (xy 340.976587 -283.179842)
			(xy 340.950284 -283.138246) (xy 340.930993 -283.09297) (xy 340.919216 -283.045186) (xy 340.915256 -282.996132)
			(xy 340.596728 -282.996132) (xy 340.596216 -283.021578) (xy 340.588052 -283.071812) (xy 340.571936 -283.120086)
			(xy 340.548285 -283.165149) (xy 340.517712 -283.205835) (xy 340.481008 -283.24109) (xy 340.439124 -283.27)
			(xy 340.393145 -283.291817) (xy 340.344261 -283.305977) (xy 340.29374 -283.312111) (xy 340.242888 -283.310062)
			(xy 340.193024 -283.299882) (xy 340.145438 -283.281835) (xy 340.101364 -283.256389) (xy 340.061942 -283.224202)
			(xy 340.028194 -283.186108) (xy 340.000993 -283.143094) (xy 339.981045 -283.096274) (xy 339.968866 -283.04686)
			(xy 339.964771 -282.996132) (xy 339.656928 -282.996132) (xy 339.656416 -283.021578) (xy 339.648252 -283.071812)
			(xy 339.632136 -283.120086) (xy 339.608485 -283.165149) (xy 339.577912 -283.205835) (xy 339.541208 -283.24109)
			(xy 339.499324 -283.27) (xy 339.453345 -283.291817) (xy 339.404461 -283.305977) (xy 339.35394 -283.312111)
			(xy 339.303088 -283.310062) (xy 339.253224 -283.299882) (xy 339.205638 -283.281835) (xy 339.161564 -283.256389)
			(xy 339.122142 -283.224202) (xy 339.088394 -283.186108) (xy 339.061193 -283.143094) (xy 339.041245 -283.096274)
			(xy 339.029066 -283.04686) (xy 339.024971 -282.996132) (xy 338.707025 -282.996132) (xy 338.702856 -283.046443)
			(xy 338.690454 -283.095412) (xy 338.67016 -283.141671) (xy 338.642529 -283.183959) (xy 338.608313 -283.221122)
			(xy 338.568447 -283.252146) (xy 338.524017 -283.276183) (xy 338.476237 -283.29258) (xy 338.42641 -283.300887)
			(xy 338.401152 -283.30144) (xy 338.388389 -283.301301) (xy 338.362955 -283.299138) (xy 338.350352 -283.297122)
			(xy 338.350352 -283.297376) (xy 338.326896 -283.292952) (xy 338.281637 -283.277797) (xy 338.239278 -283.255798)
			(xy 338.200849 -283.227491) (xy 338.16728 -283.193561) (xy 338.152994 -283.17444) (xy 338.144866 -283.16301)
			(xy 338.119212 -283.151834) (xy 338.017104 -283.165042) (xy 338.003134 -283.16682) (xy 337.98129 -283.183838)
			(xy 337.97621 -283.197046) (xy 337.969352 -283.213556) (xy 337.962655 -283.228927) (xy 337.947659 -283.25892)
			(xy 337.93938 -283.2735) (xy 337.894168 -283.351478) (xy 337.892644 -283.354272) (xy 337.892644 -283.354526)
			(xy 337.887947 -283.365347) (xy 337.88796 -283.388909) (xy 337.892644 -283.399738) (xy 337.929474 -283.47416)
			(xy 337.935087 -283.484772) (xy 337.953917 -283.499608) (xy 337.965542 -283.502608) (xy 337.969098 -283.503116)
			(xy 337.993386 -283.506658) (xy 338.040479 -283.520485) (xy 338.084751 -283.541672) (xy 338.125062 -283.569671)
			(xy 338.160371 -283.603762) (xy 338.189769 -283.643064) (xy 338.212497 -283.686565) (xy 338.22797 -283.733143)
			(xy 338.235788 -283.781597) (xy 338.236306 -283.806138) (xy 338.554817 -283.806138) (xy 338.558912 -283.75541)
			(xy 338.571091 -283.705996) (xy 338.591039 -283.659176) (xy 338.61824 -283.616162) (xy 338.651988 -283.578068)
			(xy 338.69141 -283.545881) (xy 338.735484 -283.520435) (xy 338.78307 -283.502388) (xy 338.832934 -283.492208)
			(xy 338.883786 -283.490159) (xy 338.934307 -283.496293) (xy 338.983191 -283.510453) (xy 339.02917 -283.53227)
			(xy 339.071054 -283.56118) (xy 339.107758 -283.596435) (xy 339.138331 -283.637121) (xy 339.161982 -283.682184)
			(xy 339.178098 -283.730458) (xy 339.186262 -283.780692) (xy 339.186774 -283.806138) (xy 339.505302 -283.806138)
			(xy 339.509262 -283.757084) (xy 339.521039 -283.7093) (xy 339.54033 -283.664024) (xy 339.566633 -283.622428)
			(xy 339.599268 -283.585591) (xy 339.637389 -283.554466) (xy 339.68001 -283.529859) (xy 339.726026 -283.512407)
			(xy 339.774245 -283.502563) (xy 339.82342 -283.500582) (xy 339.872275 -283.506514) (xy 339.919546 -283.520206)
			(xy 339.964008 -283.541304) (xy 340.004511 -283.56926) (xy 340.040004 -283.603352) (xy 340.069569 -283.642696)
			(xy 340.09244 -283.686273) (xy 340.108024 -283.732954) (xy 340.115919 -283.781531) (xy 340.116414 -283.806138)
			(xy 340.434925 -283.806138) (xy 340.43902 -283.75541) (xy 340.451199 -283.705996) (xy 340.471147 -283.659176)
			(xy 340.498348 -283.616162) (xy 340.532096 -283.578068) (xy 340.571518 -283.545881) (xy 340.615592 -283.520435)
			(xy 340.663178 -283.502388) (xy 340.713042 -283.492208) (xy 340.763894 -283.490159) (xy 340.814415 -283.496293)
			(xy 340.863299 -283.510453) (xy 340.909278 -283.53227) (xy 340.951162 -283.56118) (xy 340.987866 -283.596435)
			(xy 341.018439 -283.637121) (xy 341.04209 -283.682184) (xy 341.058206 -283.730458) (xy 341.06637 -283.780692)
			(xy 341.066882 -283.806138) (xy 341.38541 -283.806138) (xy 341.38937 -283.757084) (xy 341.401147 -283.7093)
			(xy 341.420438 -283.664024) (xy 341.446741 -283.622428) (xy 341.479376 -283.585591) (xy 341.517497 -283.554466)
			(xy 341.560118 -283.529859) (xy 341.606134 -283.512407) (xy 341.654353 -283.502563) (xy 341.703528 -283.500582)
			(xy 341.752383 -283.506514) (xy 341.799654 -283.520206) (xy 341.844116 -283.541304) (xy 341.884619 -283.56926)
			(xy 341.920112 -283.603352) (xy 341.949677 -283.642696) (xy 341.972548 -283.686273) (xy 341.988132 -283.732954)
			(xy 341.996027 -283.781531) (xy 341.996522 -283.806138) (xy 342.314779 -283.806138) (xy 342.318874 -283.75541)
			(xy 342.331053 -283.705996) (xy 342.351001 -283.659176) (xy 342.378202 -283.616162) (xy 342.41195 -283.578068)
			(xy 342.451372 -283.545881) (xy 342.495446 -283.520435) (xy 342.543032 -283.502388) (xy 342.592896 -283.492208)
			(xy 342.643748 -283.490159) (xy 342.694269 -283.496293) (xy 342.743153 -283.510453) (xy 342.789132 -283.53227)
			(xy 342.831016 -283.56118) (xy 342.86772 -283.596435) (xy 342.898293 -283.637121) (xy 342.921944 -283.682184)
			(xy 342.93806 -283.730458) (xy 342.946224 -283.780692) (xy 342.946736 -283.806138) (xy 343.254833 -283.806138)
			(xy 343.258928 -283.75541) (xy 343.271107 -283.705996) (xy 343.291055 -283.659176) (xy 343.318256 -283.616162)
			(xy 343.352004 -283.578068) (xy 343.391426 -283.545881) (xy 343.4355 -283.520435) (xy 343.483086 -283.502388)
			(xy 343.53295 -283.492208) (xy 343.583802 -283.490159) (xy 343.634323 -283.496293) (xy 343.683207 -283.510453)
			(xy 343.729186 -283.53227) (xy 343.77107 -283.56118) (xy 343.807774 -283.596435) (xy 343.838347 -283.637121)
			(xy 343.861998 -283.682184) (xy 343.878114 -283.730458) (xy 343.886278 -283.780692) (xy 343.88679 -283.806138)
			(xy 343.886278 -283.831584) (xy 343.878114 -283.881818) (xy 343.861998 -283.930092) (xy 343.838347 -283.975155)
			(xy 343.807774 -284.015841) (xy 343.77107 -284.051096) (xy 343.729186 -284.080006) (xy 343.683207 -284.101823)
			(xy 343.634323 -284.115983) (xy 343.583802 -284.122117) (xy 343.53295 -284.120068) (xy 343.483086 -284.109888)
			(xy 343.4355 -284.091841) (xy 343.391426 -284.066395) (xy 343.352004 -284.034208) (xy 343.318256 -283.996114)
			(xy 343.291055 -283.9531) (xy 343.271107 -283.90628) (xy 343.258928 -283.856866) (xy 343.254833 -283.806138)
			(xy 342.946736 -283.806138) (xy 342.946224 -283.831584) (xy 342.93806 -283.881818) (xy 342.921944 -283.930092)
			(xy 342.898293 -283.975155) (xy 342.86772 -284.015841) (xy 342.831016 -284.051096) (xy 342.789132 -284.080006)
			(xy 342.743153 -284.101823) (xy 342.694269 -284.115983) (xy 342.643748 -284.122117) (xy 342.592896 -284.120068)
			(xy 342.543032 -284.109888) (xy 342.495446 -284.091841) (xy 342.451372 -284.066395) (xy 342.41195 -284.034208)
			(xy 342.378202 -283.996114) (xy 342.351001 -283.9531) (xy 342.331053 -283.90628) (xy 342.318874 -283.856866)
			(xy 342.314779 -283.806138) (xy 341.996522 -283.806138) (xy 341.996027 -283.830745) (xy 341.988132 -283.879322)
			(xy 341.972548 -283.926003) (xy 341.949677 -283.96958) (xy 341.920112 -284.008924) (xy 341.884619 -284.043016)
			(xy 341.844116 -284.070972) (xy 341.799654 -284.09207) (xy 341.752383 -284.105762) (xy 341.703528 -284.111694)
			(xy 341.654353 -284.109713) (xy 341.606134 -284.099869) (xy 341.560118 -284.082417) (xy 341.517497 -284.05781)
			(xy 341.479376 -284.026685) (xy 341.446741 -283.989848) (xy 341.420438 -283.948252) (xy 341.401147 -283.902976)
			(xy 341.38937 -283.855192) (xy 341.38541 -283.806138) (xy 341.066882 -283.806138) (xy 341.06637 -283.831584)
			(xy 341.058206 -283.881818) (xy 341.04209 -283.930092) (xy 341.018439 -283.975155) (xy 340.987866 -284.015841)
			(xy 340.951162 -284.051096) (xy 340.909278 -284.080006) (xy 340.863299 -284.101823) (xy 340.814415 -284.115983)
			(xy 340.763894 -284.122117) (xy 340.713042 -284.120068) (xy 340.663178 -284.109888) (xy 340.615592 -284.091841)
			(xy 340.571518 -284.066395) (xy 340.532096 -284.034208) (xy 340.498348 -283.996114) (xy 340.471147 -283.9531)
			(xy 340.451199 -283.90628) (xy 340.43902 -283.856866) (xy 340.434925 -283.806138) (xy 340.116414 -283.806138)
			(xy 340.115919 -283.830745) (xy 340.108024 -283.879322) (xy 340.09244 -283.926003) (xy 340.069569 -283.96958)
			(xy 340.040004 -284.008924) (xy 340.004511 -284.043016) (xy 339.964008 -284.070972) (xy 339.919546 -284.09207)
			(xy 339.872275 -284.105762) (xy 339.82342 -284.111694) (xy 339.774245 -284.109713) (xy 339.726026 -284.099869)
			(xy 339.68001 -284.082417) (xy 339.637389 -284.05781) (xy 339.599268 -284.026685) (xy 339.566633 -283.989848)
			(xy 339.54033 -283.948252) (xy 339.521039 -283.902976) (xy 339.509262 -283.855192) (xy 339.505302 -283.806138)
			(xy 339.186774 -283.806138) (xy 339.186262 -283.831584) (xy 339.178098 -283.881818) (xy 339.161982 -283.930092)
			(xy 339.138331 -283.975155) (xy 339.107758 -284.015841) (xy 339.071054 -284.051096) (xy 339.02917 -284.080006)
			(xy 338.983191 -284.101823) (xy 338.934307 -284.115983) (xy 338.883786 -284.122117) (xy 338.832934 -284.120068)
			(xy 338.78307 -284.109888) (xy 338.735484 -284.091841) (xy 338.69141 -284.066395) (xy 338.651988 -284.034208)
			(xy 338.61824 -283.996114) (xy 338.591039 -283.9531) (xy 338.571091 -283.90628) (xy 338.558912 -283.856866)
			(xy 338.554817 -283.806138) (xy 338.236306 -283.806138) (xy 338.235817 -283.830956) (xy 338.227782 -283.879938)
			(xy 338.211928 -283.926975) (xy 338.188674 -283.970828) (xy 338.158633 -284.010342) (xy 338.122595 -284.044475)
			(xy 338.08151 -284.072329) (xy 338.03646 -284.093171) (xy 337.988633 -284.10645) (xy 337.964018 -284.109668)
			(xy 337.950048 -284.111192) (xy 337.92795 -284.127702) (xy 337.888072 -284.222444) (xy 337.884911 -284.230973)
			(xy 337.884178 -284.249136) (xy 337.8898 -284.266422) (xy 337.895184 -284.273752) (xy 337.897724 -284.277054)
			(xy 337.921658 -284.308968) (xy 337.961056 -284.378329) (xy 337.97621 -284.41523) (xy 337.98129 -284.428438)
			(xy 338.00288 -284.445456) (xy 338.119466 -284.460442) (xy 338.144866 -284.449266) (xy 338.153248 -284.437836)
			(xy 338.167714 -284.418538) (xy 338.201704 -284.384323) (xy 338.240644 -284.355869) (xy 338.283568 -284.333881)
			(xy 338.329412 -284.318904) (xy 338.377038 -284.31131) (xy 338.401152 -284.310836) (xy 338.426409 -284.311325)
			(xy 338.476234 -284.319632) (xy 338.524012 -284.336028) (xy 338.56844 -284.360064) (xy 338.608305 -284.391087)
			(xy 338.642519 -284.428248) (xy 338.67015 -284.470534) (xy 338.690443 -284.516792) (xy 338.702844 -284.565759)
			(xy 338.707016 -284.6161) (xy 338.707012 -284.616144) (xy 339.024971 -284.616144) (xy 339.029066 -284.565416)
			(xy 339.041245 -284.516002) (xy 339.061193 -284.469182) (xy 339.088394 -284.426168) (xy 339.122142 -284.388074)
			(xy 339.161564 -284.355887) (xy 339.205638 -284.330441) (xy 339.253224 -284.312394) (xy 339.303088 -284.302214)
			(xy 339.35394 -284.300165) (xy 339.404461 -284.306299) (xy 339.453345 -284.320459) (xy 339.499324 -284.342276)
			(xy 339.541208 -284.371186) (xy 339.577912 -284.406441) (xy 339.608485 -284.447127) (xy 339.632136 -284.49219)
			(xy 339.648252 -284.540464) (xy 339.656416 -284.590698) (xy 339.656928 -284.616144) (xy 339.964771 -284.616144)
			(xy 339.968866 -284.565416) (xy 339.981045 -284.516002) (xy 340.000993 -284.469182) (xy 340.028194 -284.426168)
			(xy 340.061942 -284.388074) (xy 340.101364 -284.355887) (xy 340.145438 -284.330441) (xy 340.193024 -284.312394)
			(xy 340.242888 -284.302214) (xy 340.29374 -284.300165) (xy 340.344261 -284.306299) (xy 340.393145 -284.320459)
			(xy 340.439124 -284.342276) (xy 340.481008 -284.371186) (xy 340.517712 -284.406441) (xy 340.548285 -284.447127)
			(xy 340.571936 -284.49219) (xy 340.588052 -284.540464) (xy 340.596216 -284.590698) (xy 340.596728 -284.616144)
			(xy 340.915256 -284.616144) (xy 340.919216 -284.56709) (xy 340.930993 -284.519306) (xy 340.950284 -284.47403)
			(xy 340.976587 -284.432434) (xy 341.009222 -284.395597) (xy 341.047343 -284.364472) (xy 341.089964 -284.339865)
			(xy 341.13598 -284.322413) (xy 341.184199 -284.312569) (xy 341.233374 -284.310588) (xy 341.282229 -284.31652)
			(xy 341.3295 -284.330212) (xy 341.373962 -284.35131) (xy 341.414465 -284.379266) (xy 341.449958 -284.413358)
			(xy 341.479523 -284.452702) (xy 341.502394 -284.496279) (xy 341.517978 -284.54296) (xy 341.525873 -284.591537)
			(xy 341.526368 -284.616144) (xy 341.844879 -284.616144) (xy 341.848974 -284.565416) (xy 341.861153 -284.516002)
			(xy 341.881101 -284.469182) (xy 341.908302 -284.426168) (xy 341.94205 -284.388074) (xy 341.981472 -284.355887)
			(xy 342.025546 -284.330441) (xy 342.073132 -284.312394) (xy 342.122996 -284.302214) (xy 342.173848 -284.300165)
			(xy 342.224369 -284.306299) (xy 342.273253 -284.320459) (xy 342.319232 -284.342276) (xy 342.361116 -284.371186)
			(xy 342.39782 -284.406441) (xy 342.428393 -284.447127) (xy 342.452044 -284.49219) (xy 342.46816 -284.540464)
			(xy 342.476324 -284.590698) (xy 342.476836 -284.616144) (xy 342.795364 -284.616144) (xy 342.799324 -284.56709)
			(xy 342.811101 -284.519306) (xy 342.830392 -284.47403) (xy 342.856695 -284.432434) (xy 342.88933 -284.395597)
			(xy 342.927451 -284.364472) (xy 342.970072 -284.339865) (xy 343.016088 -284.322413) (xy 343.064307 -284.312569)
			(xy 343.113482 -284.310588) (xy 343.162337 -284.31652) (xy 343.209608 -284.330212) (xy 343.25407 -284.35131)
			(xy 343.294573 -284.379266) (xy 343.330066 -284.413358) (xy 343.359631 -284.452702) (xy 343.382502 -284.496279)
			(xy 343.398086 -284.54296) (xy 343.405981 -284.591537) (xy 343.406476 -284.616144) (xy 343.724987 -284.616144)
			(xy 343.729082 -284.565416) (xy 343.741261 -284.516002) (xy 343.761209 -284.469182) (xy 343.78841 -284.426168)
			(xy 343.822158 -284.388074) (xy 343.86158 -284.355887) (xy 343.905654 -284.330441) (xy 343.95324 -284.312394)
			(xy 344.003104 -284.302214) (xy 344.053956 -284.300165) (xy 344.104477 -284.306299) (xy 344.153361 -284.320459)
			(xy 344.19934 -284.342276) (xy 344.241224 -284.371186) (xy 344.277928 -284.406441) (xy 344.308501 -284.447127)
			(xy 344.332152 -284.49219) (xy 344.348268 -284.540464) (xy 344.356432 -284.590698) (xy 344.356944 -284.616144)
			(xy 344.356432 -284.64159) (xy 344.348268 -284.691824) (xy 344.332152 -284.740098) (xy 344.308501 -284.785161)
			(xy 344.277928 -284.825847) (xy 344.241224 -284.861102) (xy 344.19934 -284.890012) (xy 344.153361 -284.911829)
			(xy 344.104477 -284.925989) (xy 344.053956 -284.932123) (xy 344.003104 -284.930074) (xy 343.95324 -284.919894)
			(xy 343.905654 -284.901847) (xy 343.86158 -284.876401) (xy 343.822158 -284.844214) (xy 343.78841 -284.80612)
			(xy 343.761209 -284.763106) (xy 343.741261 -284.716286) (xy 343.729082 -284.666872) (xy 343.724987 -284.616144)
			(xy 343.406476 -284.616144) (xy 343.405981 -284.640751) (xy 343.398086 -284.689328) (xy 343.382502 -284.736009)
			(xy 343.359631 -284.779586) (xy 343.330066 -284.81893) (xy 343.294573 -284.853022) (xy 343.25407 -284.880978)
			(xy 343.209608 -284.902076) (xy 343.162337 -284.915768) (xy 343.113482 -284.9217) (xy 343.064307 -284.919719)
			(xy 343.016088 -284.909875) (xy 342.970072 -284.892423) (xy 342.927451 -284.867816) (xy 342.88933 -284.836691)
			(xy 342.856695 -284.799854) (xy 342.830392 -284.758258) (xy 342.811101 -284.712982) (xy 342.799324 -284.665198)
			(xy 342.795364 -284.616144) (xy 342.476836 -284.616144) (xy 342.476324 -284.64159) (xy 342.46816 -284.691824)
			(xy 342.452044 -284.740098) (xy 342.428393 -284.785161) (xy 342.39782 -284.825847) (xy 342.361116 -284.861102)
			(xy 342.319232 -284.890012) (xy 342.273253 -284.911829) (xy 342.224369 -284.925989) (xy 342.173848 -284.932123)
			(xy 342.122996 -284.930074) (xy 342.073132 -284.919894) (xy 342.025546 -284.901847) (xy 341.981472 -284.876401)
			(xy 341.94205 -284.844214) (xy 341.908302 -284.80612) (xy 341.881101 -284.763106) (xy 341.861153 -284.716286)
			(xy 341.848974 -284.666872) (xy 341.844879 -284.616144) (xy 341.526368 -284.616144) (xy 341.525873 -284.640751)
			(xy 341.517978 -284.689328) (xy 341.502394 -284.736009) (xy 341.479523 -284.779586) (xy 341.449958 -284.81893)
			(xy 341.414465 -284.853022) (xy 341.373962 -284.880978) (xy 341.3295 -284.902076) (xy 341.282229 -284.915768)
			(xy 341.233374 -284.9217) (xy 341.184199 -284.919719) (xy 341.13598 -284.909875) (xy 341.089964 -284.892423)
			(xy 341.047343 -284.867816) (xy 341.009222 -284.836691) (xy 340.976587 -284.799854) (xy 340.950284 -284.758258)
			(xy 340.930993 -284.712982) (xy 340.919216 -284.665198) (xy 340.915256 -284.616144) (xy 340.596728 -284.616144)
			(xy 340.596216 -284.64159) (xy 340.588052 -284.691824) (xy 340.571936 -284.740098) (xy 340.548285 -284.785161)
			(xy 340.517712 -284.825847) (xy 340.481008 -284.861102) (xy 340.439124 -284.890012) (xy 340.393145 -284.911829)
			(xy 340.344261 -284.925989) (xy 340.29374 -284.932123) (xy 340.242888 -284.930074) (xy 340.193024 -284.919894)
			(xy 340.145438 -284.901847) (xy 340.101364 -284.876401) (xy 340.061942 -284.844214) (xy 340.028194 -284.80612)
			(xy 340.000993 -284.763106) (xy 339.981045 -284.716286) (xy 339.968866 -284.666872) (xy 339.964771 -284.616144)
			(xy 339.656928 -284.616144) (xy 339.656416 -284.64159) (xy 339.648252 -284.691824) (xy 339.632136 -284.740098)
			(xy 339.608485 -284.785161) (xy 339.577912 -284.825847) (xy 339.541208 -284.861102) (xy 339.499324 -284.890012)
			(xy 339.453345 -284.911829) (xy 339.404461 -284.925989) (xy 339.35394 -284.932123) (xy 339.303088 -284.930074)
			(xy 339.253224 -284.919894) (xy 339.205638 -284.901847) (xy 339.161564 -284.876401) (xy 339.122142 -284.844214)
			(xy 339.088394 -284.80612) (xy 339.061193 -284.763106) (xy 339.041245 -284.716286) (xy 339.029066 -284.666872)
			(xy 339.024971 -284.616144) (xy 338.707012 -284.616144) (xy 338.702844 -284.666441) (xy 338.690443 -284.715408)
			(xy 338.67015 -284.761666) (xy 338.642519 -284.803952) (xy 338.608305 -284.841113) (xy 338.56844 -284.872136)
			(xy 338.524012 -284.896172) (xy 338.476234 -284.912568) (xy 338.426409 -284.920875) (xy 338.401152 -284.921452)
			(xy 338.388389 -284.921313) (xy 338.362955 -284.91915) (xy 338.350352 -284.917134) (xy 338.350352 -284.917388)
			(xy 338.326898 -284.912963) (xy 338.281641 -284.897804) (xy 338.239288 -284.875802) (xy 338.200864 -284.84749)
			(xy 338.167303 -284.813555) (xy 338.152994 -284.794452) (xy 338.144866 -284.783022) (xy 338.119212 -284.771846)
			(xy 338.017104 -284.785054) (xy 338.003134 -284.786832) (xy 337.98129 -284.80385) (xy 337.97621 -284.817058)
			(xy 337.969352 -284.833568) (xy 337.962655 -284.848939) (xy 337.947658 -284.878931) (xy 337.93938 -284.893512)
			(xy 337.894168 -284.97149) (xy 337.892644 -284.974284) (xy 337.892644 -284.974538) (xy 337.887949 -284.985359)
			(xy 337.887967 -285.008919) (xy 337.892644 -285.01975) (xy 337.929474 -285.094172) (xy 337.935088 -285.104782)
			(xy 337.953919 -285.119614) (xy 337.965542 -285.12262) (xy 337.969098 -285.123128) (xy 337.993656 -285.126728)
			(xy 338.041237 -285.140843) (xy 338.085911 -285.162464) (xy 338.126503 -285.191023) (xy 338.161944 -285.225767)
			(xy 338.191303 -285.265784) (xy 338.213806 -285.31002) (xy 338.228864 -285.357312) (xy 338.236078 -285.406416)
			(xy 338.235753 -285.42615) (xy 338.554817 -285.42615) (xy 338.558912 -285.375422) (xy 338.571091 -285.326008)
			(xy 338.591039 -285.279188) (xy 338.61824 -285.236174) (xy 338.651988 -285.19808) (xy 338.69141 -285.165893)
			(xy 338.735484 -285.140447) (xy 338.78307 -285.1224) (xy 338.832934 -285.11222) (xy 338.883786 -285.110171)
			(xy 338.934307 -285.116305) (xy 338.983191 -285.130465) (xy 339.02917 -285.152282) (xy 339.071054 -285.181192)
			(xy 339.107758 -285.216447) (xy 339.138331 -285.257133) (xy 339.161982 -285.302196) (xy 339.178098 -285.35047)
			(xy 339.186262 -285.400704) (xy 339.186774 -285.42615) (xy 339.505302 -285.42615) (xy 339.509262 -285.377096)
			(xy 339.521039 -285.329312) (xy 339.54033 -285.284036) (xy 339.566633 -285.24244) (xy 339.599268 -285.205603)
			(xy 339.637389 -285.174478) (xy 339.68001 -285.149871) (xy 339.726026 -285.132419) (xy 339.774245 -285.122575)
			(xy 339.82342 -285.120594) (xy 339.872275 -285.126526) (xy 339.919546 -285.140218) (xy 339.964008 -285.161316)
			(xy 340.004511 -285.189272) (xy 340.040004 -285.223364) (xy 340.069569 -285.262708) (xy 340.09244 -285.306285)
			(xy 340.108024 -285.352966) (xy 340.115919 -285.401543) (xy 340.116414 -285.42615) (xy 340.434925 -285.42615)
			(xy 340.43902 -285.375422) (xy 340.451199 -285.326008) (xy 340.471147 -285.279188) (xy 340.498348 -285.236174)
			(xy 340.532096 -285.19808) (xy 340.571518 -285.165893) (xy 340.615592 -285.140447) (xy 340.663178 -285.1224)
			(xy 340.713042 -285.11222) (xy 340.763894 -285.110171) (xy 340.814415 -285.116305) (xy 340.863299 -285.130465)
			(xy 340.909278 -285.152282) (xy 340.951162 -285.181192) (xy 340.987866 -285.216447) (xy 341.018439 -285.257133)
			(xy 341.04209 -285.302196) (xy 341.058206 -285.35047) (xy 341.06637 -285.400704) (xy 341.066882 -285.42615)
			(xy 341.38541 -285.42615) (xy 341.38937 -285.377096) (xy 341.401147 -285.329312) (xy 341.420438 -285.284036)
			(xy 341.446741 -285.24244) (xy 341.479376 -285.205603) (xy 341.517497 -285.174478) (xy 341.560118 -285.149871)
			(xy 341.606134 -285.132419) (xy 341.654353 -285.122575) (xy 341.703528 -285.120594) (xy 341.752383 -285.126526)
			(xy 341.799654 -285.140218) (xy 341.844116 -285.161316) (xy 341.884619 -285.189272) (xy 341.920112 -285.223364)
			(xy 341.949677 -285.262708) (xy 341.972548 -285.306285) (xy 341.988132 -285.352966) (xy 341.996027 -285.401543)
			(xy 341.996522 -285.42615) (xy 342.314779 -285.42615) (xy 342.318874 -285.375422) (xy 342.331053 -285.326008)
			(xy 342.351001 -285.279188) (xy 342.378202 -285.236174) (xy 342.41195 -285.19808) (xy 342.451372 -285.165893)
			(xy 342.495446 -285.140447) (xy 342.543032 -285.1224) (xy 342.592896 -285.11222) (xy 342.643748 -285.110171)
			(xy 342.694269 -285.116305) (xy 342.743153 -285.130465) (xy 342.789132 -285.152282) (xy 342.831016 -285.181192)
			(xy 342.86772 -285.216447) (xy 342.898293 -285.257133) (xy 342.921944 -285.302196) (xy 342.93806 -285.35047)
			(xy 342.946224 -285.400704) (xy 342.946736 -285.42615) (xy 343.254833 -285.42615) (xy 343.258928 -285.375422)
			(xy 343.271107 -285.326008) (xy 343.291055 -285.279188) (xy 343.318256 -285.236174) (xy 343.352004 -285.19808)
			(xy 343.391426 -285.165893) (xy 343.4355 -285.140447) (xy 343.483086 -285.1224) (xy 343.53295 -285.11222)
			(xy 343.583802 -285.110171) (xy 343.634323 -285.116305) (xy 343.683207 -285.130465) (xy 343.729186 -285.152282)
			(xy 343.77107 -285.181192) (xy 343.807774 -285.216447) (xy 343.838347 -285.257133) (xy 343.861998 -285.302196)
			(xy 343.878114 -285.35047) (xy 343.886278 -285.400704) (xy 343.88679 -285.42615) (xy 343.886278 -285.451596)
			(xy 343.878114 -285.50183) (xy 343.861998 -285.550104) (xy 343.838347 -285.595167) (xy 343.807774 -285.635853)
			(xy 343.77107 -285.671108) (xy 343.729186 -285.700018) (xy 343.683207 -285.721835) (xy 343.634323 -285.735995)
			(xy 343.583802 -285.742129) (xy 343.53295 -285.74008) (xy 343.483086 -285.7299) (xy 343.4355 -285.711853)
			(xy 343.391426 -285.686407) (xy 343.352004 -285.65422) (xy 343.318256 -285.616126) (xy 343.291055 -285.573112)
			(xy 343.271107 -285.526292) (xy 343.258928 -285.476878) (xy 343.254833 -285.42615) (xy 342.946736 -285.42615)
			(xy 342.946224 -285.451596) (xy 342.93806 -285.50183) (xy 342.921944 -285.550104) (xy 342.898293 -285.595167)
			(xy 342.86772 -285.635853) (xy 342.831016 -285.671108) (xy 342.789132 -285.700018) (xy 342.743153 -285.721835)
			(xy 342.694269 -285.735995) (xy 342.643748 -285.742129) (xy 342.592896 -285.74008) (xy 342.543032 -285.7299)
			(xy 342.495446 -285.711853) (xy 342.451372 -285.686407) (xy 342.41195 -285.65422) (xy 342.378202 -285.616126)
			(xy 342.351001 -285.573112) (xy 342.331053 -285.526292) (xy 342.318874 -285.476878) (xy 342.314779 -285.42615)
			(xy 341.996522 -285.42615) (xy 341.996027 -285.450757) (xy 341.988132 -285.499334) (xy 341.972548 -285.546015)
			(xy 341.949677 -285.589592) (xy 341.920112 -285.628936) (xy 341.884619 -285.663028) (xy 341.844116 -285.690984)
			(xy 341.799654 -285.712082) (xy 341.752383 -285.725774) (xy 341.703528 -285.731706) (xy 341.654353 -285.729725)
			(xy 341.606134 -285.719881) (xy 341.560118 -285.702429) (xy 341.517497 -285.677822) (xy 341.479376 -285.646697)
			(xy 341.446741 -285.60986) (xy 341.420438 -285.568264) (xy 341.401147 -285.522988) (xy 341.38937 -285.475204)
			(xy 341.38541 -285.42615) (xy 341.066882 -285.42615) (xy 341.06637 -285.451596) (xy 341.058206 -285.50183)
			(xy 341.04209 -285.550104) (xy 341.018439 -285.595167) (xy 340.987866 -285.635853) (xy 340.951162 -285.671108)
			(xy 340.909278 -285.700018) (xy 340.863299 -285.721835) (xy 340.814415 -285.735995) (xy 340.763894 -285.742129)
			(xy 340.713042 -285.74008) (xy 340.663178 -285.7299) (xy 340.615592 -285.711853) (xy 340.571518 -285.686407)
			(xy 340.532096 -285.65422) (xy 340.498348 -285.616126) (xy 340.471147 -285.573112) (xy 340.451199 -285.526292)
			(xy 340.43902 -285.476878) (xy 340.434925 -285.42615) (xy 340.116414 -285.42615) (xy 340.115919 -285.450757)
			(xy 340.108024 -285.499334) (xy 340.09244 -285.546015) (xy 340.069569 -285.589592) (xy 340.040004 -285.628936)
			(xy 340.004511 -285.663028) (xy 339.964008 -285.690984) (xy 339.919546 -285.712082) (xy 339.872275 -285.725774)
			(xy 339.82342 -285.731706) (xy 339.774245 -285.729725) (xy 339.726026 -285.719881) (xy 339.68001 -285.702429)
			(xy 339.637389 -285.677822) (xy 339.599268 -285.646697) (xy 339.566633 -285.60986) (xy 339.54033 -285.568264)
			(xy 339.521039 -285.522988) (xy 339.509262 -285.475204) (xy 339.505302 -285.42615) (xy 339.186774 -285.42615)
			(xy 339.186262 -285.451596) (xy 339.178098 -285.50183) (xy 339.161982 -285.550104) (xy 339.138331 -285.595167)
			(xy 339.107758 -285.635853) (xy 339.071054 -285.671108) (xy 339.02917 -285.700018) (xy 338.983191 -285.721835)
			(xy 338.934307 -285.735995) (xy 338.883786 -285.742129) (xy 338.832934 -285.74008) (xy 338.78307 -285.7299)
			(xy 338.735484 -285.711853) (xy 338.69141 -285.686407) (xy 338.651988 -285.65422) (xy 338.61824 -285.616126)
			(xy 338.591039 -285.573112) (xy 338.571091 -285.526292) (xy 338.558912 -285.476878) (xy 338.554817 -285.42615)
			(xy 338.235753 -285.42615) (xy 338.23526 -285.45604) (xy 338.226431 -285.504879) (xy 338.209823 -285.551649)
			(xy 338.185873 -285.59512) (xy 338.155212 -285.634147) (xy 338.118644 -285.667704) (xy 338.09813 -285.681674)
			(xy 338.0783 -285.694156) (xy 338.035644 -285.713548) (xy 337.990529 -285.726201) (xy 337.96732 -285.729426)
			(xy 337.967066 -285.729426) (xy 337.958092 -285.73079) (xy 337.941882 -285.738929) (xy 337.929505 -285.75219)
			(xy 337.925664 -285.760414) (xy 337.886294 -285.855156) (xy 337.890104 -285.88208) (xy 337.898486 -285.893002)
			(xy 337.922856 -285.925241) (xy 337.963021 -285.995369) (xy 337.978496 -286.032702) (xy 337.983576 -286.045656)
			(xy 338.00542 -286.062674) (xy 338.075524 -286.071564) (xy 338.081874 -286.072072) (xy 338.11718 -286.072072)
			(xy 338.129003 -286.071524) (xy 338.150202 -286.061064) (xy 338.15782 -286.052006) (xy 338.17233 -286.03353)
			(xy 338.206069 -286.000842) (xy 338.244419 -285.973711) (xy 338.286475 -285.95278) (xy 338.331243 -285.938542)
			(xy 338.377664 -285.931334) (xy 338.401152 -285.930848) (xy 338.426416 -285.931337) (xy 338.476256 -285.939647)
			(xy 338.524048 -285.956047) (xy 338.568488 -285.980091) (xy 338.608365 -286.011122) (xy 338.642589 -286.048294)
			(xy 338.670227 -286.090592) (xy 338.690526 -286.136864) (xy 338.702931 -286.185845) (xy 338.7071 -286.236156)
			(xy 339.024971 -286.236156) (xy 339.029066 -286.185428) (xy 339.041245 -286.136014) (xy 339.061193 -286.089194)
			(xy 339.088394 -286.04618) (xy 339.122142 -286.008086) (xy 339.161564 -285.975899) (xy 339.205638 -285.950453)
			(xy 339.253224 -285.932406) (xy 339.303088 -285.922226) (xy 339.35394 -285.920177) (xy 339.404461 -285.926311)
			(xy 339.453345 -285.940471) (xy 339.499324 -285.962288) (xy 339.541208 -285.991198) (xy 339.577912 -286.026453)
			(xy 339.608485 -286.067139) (xy 339.632136 -286.112202) (xy 339.648252 -286.160476) (xy 339.656416 -286.21071)
			(xy 339.656928 -286.236156) (xy 339.964771 -286.236156) (xy 339.968866 -286.185428) (xy 339.981045 -286.136014)
			(xy 340.000993 -286.089194) (xy 340.028194 -286.04618) (xy 340.061942 -286.008086) (xy 340.101364 -285.975899)
			(xy 340.145438 -285.950453) (xy 340.193024 -285.932406) (xy 340.242888 -285.922226) (xy 340.29374 -285.920177)
			(xy 340.344261 -285.926311) (xy 340.393145 -285.940471) (xy 340.439124 -285.962288) (xy 340.481008 -285.991198)
			(xy 340.517712 -286.026453) (xy 340.548285 -286.067139) (xy 340.571936 -286.112202) (xy 340.588052 -286.160476)
			(xy 340.596216 -286.21071) (xy 340.596728 -286.236156) (xy 340.915256 -286.236156) (xy 340.919216 -286.187102)
			(xy 340.930993 -286.139318) (xy 340.950284 -286.094042) (xy 340.976587 -286.052446) (xy 341.009222 -286.015609)
			(xy 341.047343 -285.984484) (xy 341.089964 -285.959877) (xy 341.13598 -285.942425) (xy 341.184199 -285.932581)
			(xy 341.233374 -285.9306) (xy 341.282229 -285.936532) (xy 341.3295 -285.950224) (xy 341.373962 -285.971322)
			(xy 341.414465 -285.999278) (xy 341.449958 -286.03337) (xy 341.479523 -286.072714) (xy 341.502394 -286.116291)
			(xy 341.517978 -286.162972) (xy 341.525873 -286.211549) (xy 341.526368 -286.236156) (xy 341.844879 -286.236156)
			(xy 341.848974 -286.185428) (xy 341.861153 -286.136014) (xy 341.881101 -286.089194) (xy 341.908302 -286.04618)
			(xy 341.94205 -286.008086) (xy 341.981472 -285.975899) (xy 342.025546 -285.950453) (xy 342.073132 -285.932406)
			(xy 342.122996 -285.922226) (xy 342.173848 -285.920177) (xy 342.224369 -285.926311) (xy 342.273253 -285.940471)
			(xy 342.319232 -285.962288) (xy 342.361116 -285.991198) (xy 342.39782 -286.026453) (xy 342.428393 -286.067139)
			(xy 342.452044 -286.112202) (xy 342.46816 -286.160476) (xy 342.476324 -286.21071) (xy 342.476836 -286.236156)
			(xy 342.795364 -286.236156) (xy 342.799324 -286.187102) (xy 342.811101 -286.139318) (xy 342.830392 -286.094042)
			(xy 342.856695 -286.052446) (xy 342.88933 -286.015609) (xy 342.927451 -285.984484) (xy 342.970072 -285.959877)
			(xy 343.016088 -285.942425) (xy 343.064307 -285.932581) (xy 343.113482 -285.9306) (xy 343.162337 -285.936532)
			(xy 343.209608 -285.950224) (xy 343.25407 -285.971322) (xy 343.294573 -285.999278) (xy 343.330066 -286.03337)
			(xy 343.359631 -286.072714) (xy 343.382502 -286.116291) (xy 343.398086 -286.162972) (xy 343.405981 -286.211549)
			(xy 343.406476 -286.236156) (xy 343.724987 -286.236156) (xy 343.729082 -286.185428) (xy 343.741261 -286.136014)
			(xy 343.761209 -286.089194) (xy 343.78841 -286.04618) (xy 343.822158 -286.008086) (xy 343.86158 -285.975899)
			(xy 343.905654 -285.950453) (xy 343.95324 -285.932406) (xy 344.003104 -285.922226) (xy 344.053956 -285.920177)
			(xy 344.104477 -285.926311) (xy 344.153361 -285.940471) (xy 344.19934 -285.962288) (xy 344.241224 -285.991198)
			(xy 344.277928 -286.026453) (xy 344.308501 -286.067139) (xy 344.332152 -286.112202) (xy 344.348268 -286.160476)
			(xy 344.356432 -286.21071) (xy 344.356944 -286.236156) (xy 344.356432 -286.261602) (xy 344.348268 -286.311836)
			(xy 344.332152 -286.36011) (xy 344.308501 -286.405173) (xy 344.277928 -286.445859) (xy 344.241224 -286.481114)
			(xy 344.19934 -286.510024) (xy 344.153361 -286.531841) (xy 344.104477 -286.546001) (xy 344.053956 -286.552135)
			(xy 344.003104 -286.550086) (xy 343.95324 -286.539906) (xy 343.905654 -286.521859) (xy 343.86158 -286.496413)
			(xy 343.822158 -286.464226) (xy 343.78841 -286.426132) (xy 343.761209 -286.383118) (xy 343.741261 -286.336298)
			(xy 343.729082 -286.286884) (xy 343.724987 -286.236156) (xy 343.406476 -286.236156) (xy 343.405981 -286.260763)
			(xy 343.398086 -286.30934) (xy 343.382502 -286.356021) (xy 343.359631 -286.399598) (xy 343.330066 -286.438942)
			(xy 343.294573 -286.473034) (xy 343.25407 -286.50099) (xy 343.209608 -286.522088) (xy 343.162337 -286.53578)
			(xy 343.113482 -286.541712) (xy 343.064307 -286.539731) (xy 343.016088 -286.529887) (xy 342.970072 -286.512435)
			(xy 342.927451 -286.487828) (xy 342.88933 -286.456703) (xy 342.856695 -286.419866) (xy 342.830392 -286.37827)
			(xy 342.811101 -286.332994) (xy 342.799324 -286.28521) (xy 342.795364 -286.236156) (xy 342.476836 -286.236156)
			(xy 342.476324 -286.261602) (xy 342.46816 -286.311836) (xy 342.452044 -286.36011) (xy 342.428393 -286.405173)
			(xy 342.39782 -286.445859) (xy 342.361116 -286.481114) (xy 342.319232 -286.510024) (xy 342.273253 -286.531841)
			(xy 342.224369 -286.546001) (xy 342.173848 -286.552135) (xy 342.122996 -286.550086) (xy 342.073132 -286.539906)
			(xy 342.025546 -286.521859) (xy 341.981472 -286.496413) (xy 341.94205 -286.464226) (xy 341.908302 -286.426132)
			(xy 341.881101 -286.383118) (xy 341.861153 -286.336298) (xy 341.848974 -286.286884) (xy 341.844879 -286.236156)
			(xy 341.526368 -286.236156) (xy 341.525873 -286.260763) (xy 341.517978 -286.30934) (xy 341.502394 -286.356021)
			(xy 341.479523 -286.399598) (xy 341.449958 -286.438942) (xy 341.414465 -286.473034) (xy 341.373962 -286.50099)
			(xy 341.3295 -286.522088) (xy 341.282229 -286.53578) (xy 341.233374 -286.541712) (xy 341.184199 -286.539731)
			(xy 341.13598 -286.529887) (xy 341.089964 -286.512435) (xy 341.047343 -286.487828) (xy 341.009222 -286.456703)
			(xy 340.976587 -286.419866) (xy 340.950284 -286.37827) (xy 340.930993 -286.332994) (xy 340.919216 -286.28521)
			(xy 340.915256 -286.236156) (xy 340.596728 -286.236156) (xy 340.596216 -286.261602) (xy 340.588052 -286.311836)
			(xy 340.571936 -286.36011) (xy 340.548285 -286.405173) (xy 340.517712 -286.445859) (xy 340.481008 -286.481114)
			(xy 340.439124 -286.510024) (xy 340.393145 -286.531841) (xy 340.344261 -286.546001) (xy 340.29374 -286.552135)
			(xy 340.242888 -286.550086) (xy 340.193024 -286.539906) (xy 340.145438 -286.521859) (xy 340.101364 -286.496413)
			(xy 340.061942 -286.464226) (xy 340.028194 -286.426132) (xy 340.000993 -286.383118) (xy 339.981045 -286.336298)
			(xy 339.968866 -286.286884) (xy 339.964771 -286.236156) (xy 339.656928 -286.236156) (xy 339.656416 -286.261602)
			(xy 339.648252 -286.311836) (xy 339.632136 -286.36011) (xy 339.608485 -286.405173) (xy 339.577912 -286.445859)
			(xy 339.541208 -286.481114) (xy 339.499324 -286.510024) (xy 339.453345 -286.531841) (xy 339.404461 -286.546001)
			(xy 339.35394 -286.552135) (xy 339.303088 -286.550086) (xy 339.253224 -286.539906) (xy 339.205638 -286.521859)
			(xy 339.161564 -286.496413) (xy 339.122142 -286.464226) (xy 339.088394 -286.426132) (xy 339.061193 -286.383118)
			(xy 339.041245 -286.336298) (xy 339.029066 -286.286884) (xy 339.024971 -286.236156) (xy 338.7071 -286.236156)
			(xy 338.707104 -286.2362) (xy 338.702931 -286.286555) (xy 338.690526 -286.335536) (xy 338.670227 -286.381808)
			(xy 338.642589 -286.424106) (xy 338.608365 -286.461278) (xy 338.568488 -286.492309) (xy 338.524048 -286.516353)
			(xy 338.476256 -286.532753) (xy 338.426416 -286.541063) (xy 338.401152 -286.541464) (xy 338.377666 -286.541007)
			(xy 338.331254 -286.533766) (xy 338.286497 -286.519507) (xy 338.244449 -286.498566) (xy 338.206101 -286.471437)
			(xy 338.172357 -286.438759) (xy 338.15782 -286.420306) (xy 338.150177 -286.411279) (xy 338.128993 -286.400823)
			(xy 338.11718 -286.40024) (xy 338.081874 -286.40024) (xy 338.075524 -286.400748) (xy 338.00542 -286.409638)
			(xy 337.983576 -286.426656) (xy 337.978496 -286.43961) (xy 337.965288 -286.470598) (xy 337.959955 -286.481936)
			(xy 337.948393 -286.50417) (xy 337.942174 -286.515048) (xy 337.897724 -286.59201) (xy 337.89196 -286.603158)
			(xy 337.891044 -286.628207) (xy 337.895946 -286.639762) (xy 337.938618 -286.726884) (xy 337.958938 -286.741616)
			(xy 337.971892 -286.743394) (xy 337.996012 -286.747102) (xy 338.042733 -286.76118) (xy 338.086622 -286.782508)
			(xy 338.126561 -286.810544) (xy 338.161533 -286.844573) (xy 338.19065 -286.883731) (xy 338.21317 -286.92702)
			(xy 338.22852 -286.973339) (xy 338.236309 -287.02151) (xy 338.236814 -287.045908) (xy 338.554817 -287.045908)
			(xy 338.558912 -286.99518) (xy 338.571091 -286.945766) (xy 338.591039 -286.898946) (xy 338.61824 -286.855932)
			(xy 338.651988 -286.817838) (xy 338.69141 -286.785651) (xy 338.735484 -286.760205) (xy 338.78307 -286.742158)
			(xy 338.832934 -286.731978) (xy 338.883786 -286.729929) (xy 338.934307 -286.736063) (xy 338.983191 -286.750223)
			(xy 339.02917 -286.77204) (xy 339.071054 -286.80095) (xy 339.107758 -286.836205) (xy 339.138331 -286.876891)
			(xy 339.161982 -286.921954) (xy 339.178098 -286.970228) (xy 339.186262 -287.020462) (xy 339.186774 -287.045908)
			(xy 339.505302 -287.045908) (xy 339.509262 -286.996854) (xy 339.521039 -286.94907) (xy 339.54033 -286.903794)
			(xy 339.566633 -286.862198) (xy 339.599268 -286.825361) (xy 339.637389 -286.794236) (xy 339.68001 -286.769629)
			(xy 339.726026 -286.752177) (xy 339.774245 -286.742333) (xy 339.82342 -286.740352) (xy 339.872275 -286.746284)
			(xy 339.919546 -286.759976) (xy 339.964008 -286.781074) (xy 340.004511 -286.80903) (xy 340.040004 -286.843122)
			(xy 340.069569 -286.882466) (xy 340.09244 -286.926043) (xy 340.108024 -286.972724) (xy 340.115919 -287.021301)
			(xy 340.116414 -287.045908) (xy 340.434925 -287.045908) (xy 340.43902 -286.99518) (xy 340.451199 -286.945766)
			(xy 340.471147 -286.898946) (xy 340.498348 -286.855932) (xy 340.532096 -286.817838) (xy 340.571518 -286.785651)
			(xy 340.615592 -286.760205) (xy 340.663178 -286.742158) (xy 340.713042 -286.731978) (xy 340.763894 -286.729929)
			(xy 340.814415 -286.736063) (xy 340.863299 -286.750223) (xy 340.909278 -286.77204) (xy 340.951162 -286.80095)
			(xy 340.987866 -286.836205) (xy 341.018439 -286.876891) (xy 341.04209 -286.921954) (xy 341.058206 -286.970228)
			(xy 341.06637 -287.020462) (xy 341.066882 -287.045908) (xy 341.38541 -287.045908) (xy 341.38937 -286.996854)
			(xy 341.401147 -286.94907) (xy 341.420438 -286.903794) (xy 341.446741 -286.862198) (xy 341.479376 -286.825361)
			(xy 341.517497 -286.794236) (xy 341.560118 -286.769629) (xy 341.606134 -286.752177) (xy 341.654353 -286.742333)
			(xy 341.703528 -286.740352) (xy 341.752383 -286.746284) (xy 341.799654 -286.759976) (xy 341.844116 -286.781074)
			(xy 341.884619 -286.80903) (xy 341.920112 -286.843122) (xy 341.949677 -286.882466) (xy 341.972548 -286.926043)
			(xy 341.988132 -286.972724) (xy 341.996027 -287.021301) (xy 341.996522 -287.045908) (xy 342.314779 -287.045908)
			(xy 342.318874 -286.99518) (xy 342.331053 -286.945766) (xy 342.351001 -286.898946) (xy 342.378202 -286.855932)
			(xy 342.41195 -286.817838) (xy 342.451372 -286.785651) (xy 342.495446 -286.760205) (xy 342.543032 -286.742158)
			(xy 342.592896 -286.731978) (xy 342.643748 -286.729929) (xy 342.694269 -286.736063) (xy 342.743153 -286.750223)
			(xy 342.789132 -286.77204) (xy 342.831016 -286.80095) (xy 342.86772 -286.836205) (xy 342.898293 -286.876891)
			(xy 342.921944 -286.921954) (xy 342.93806 -286.970228) (xy 342.946224 -287.020462) (xy 342.946736 -287.045908)
			(xy 343.254833 -287.045908) (xy 343.258928 -286.99518) (xy 343.271107 -286.945766) (xy 343.291055 -286.898946)
			(xy 343.318256 -286.855932) (xy 343.352004 -286.817838) (xy 343.391426 -286.785651) (xy 343.4355 -286.760205)
			(xy 343.483086 -286.742158) (xy 343.53295 -286.731978) (xy 343.583802 -286.729929) (xy 343.634323 -286.736063)
			(xy 343.683207 -286.750223) (xy 343.729186 -286.77204) (xy 343.77107 -286.80095) (xy 343.807774 -286.836205)
			(xy 343.838347 -286.876891) (xy 343.861998 -286.921954) (xy 343.878114 -286.970228) (xy 343.886278 -287.020462)
			(xy 343.88679 -287.045908) (xy 343.886278 -287.071354) (xy 343.878114 -287.121588) (xy 343.861998 -287.169862)
			(xy 343.838347 -287.214925) (xy 343.807774 -287.255611) (xy 343.77107 -287.290866) (xy 343.729186 -287.319776)
			(xy 343.683207 -287.341593) (xy 343.634323 -287.355753) (xy 343.583802 -287.361887) (xy 343.53295 -287.359838)
			(xy 343.483086 -287.349658) (xy 343.4355 -287.331611) (xy 343.391426 -287.306165) (xy 343.352004 -287.273978)
			(xy 343.318256 -287.235884) (xy 343.291055 -287.19287) (xy 343.271107 -287.14605) (xy 343.258928 -287.096636)
			(xy 343.254833 -287.045908) (xy 342.946736 -287.045908) (xy 342.946224 -287.071354) (xy 342.93806 -287.121588)
			(xy 342.921944 -287.169862) (xy 342.898293 -287.214925) (xy 342.86772 -287.255611) (xy 342.831016 -287.290866)
			(xy 342.789132 -287.319776) (xy 342.743153 -287.341593) (xy 342.694269 -287.355753) (xy 342.643748 -287.361887)
			(xy 342.592896 -287.359838) (xy 342.543032 -287.349658) (xy 342.495446 -287.331611) (xy 342.451372 -287.306165)
			(xy 342.41195 -287.273978) (xy 342.378202 -287.235884) (xy 342.351001 -287.19287) (xy 342.331053 -287.14605)
			(xy 342.318874 -287.096636) (xy 342.314779 -287.045908) (xy 341.996522 -287.045908) (xy 341.996027 -287.070515)
			(xy 341.988132 -287.119092) (xy 341.972548 -287.165773) (xy 341.949677 -287.20935) (xy 341.920112 -287.248694)
			(xy 341.884619 -287.282786) (xy 341.844116 -287.310742) (xy 341.799654 -287.33184) (xy 341.752383 -287.345532)
			(xy 341.703528 -287.351464) (xy 341.654353 -287.349483) (xy 341.606134 -287.339639) (xy 341.560118 -287.322187)
			(xy 341.517497 -287.29758) (xy 341.479376 -287.266455) (xy 341.446741 -287.229618) (xy 341.420438 -287.188022)
			(xy 341.401147 -287.142746) (xy 341.38937 -287.094962) (xy 341.38541 -287.045908) (xy 341.066882 -287.045908)
			(xy 341.06637 -287.071354) (xy 341.058206 -287.121588) (xy 341.04209 -287.169862) (xy 341.018439 -287.214925)
			(xy 340.987866 -287.255611) (xy 340.951162 -287.290866) (xy 340.909278 -287.319776) (xy 340.863299 -287.341593)
			(xy 340.814415 -287.355753) (xy 340.763894 -287.361887) (xy 340.713042 -287.359838) (xy 340.663178 -287.349658)
			(xy 340.615592 -287.331611) (xy 340.571518 -287.306165) (xy 340.532096 -287.273978) (xy 340.498348 -287.235884)
			(xy 340.471147 -287.19287) (xy 340.451199 -287.14605) (xy 340.43902 -287.096636) (xy 340.434925 -287.045908)
			(xy 340.116414 -287.045908) (xy 340.115919 -287.070515) (xy 340.108024 -287.119092) (xy 340.09244 -287.165773)
			(xy 340.069569 -287.20935) (xy 340.040004 -287.248694) (xy 340.004511 -287.282786) (xy 339.964008 -287.310742)
			(xy 339.919546 -287.33184) (xy 339.872275 -287.345532) (xy 339.82342 -287.351464) (xy 339.774245 -287.349483)
			(xy 339.726026 -287.339639) (xy 339.68001 -287.322187) (xy 339.637389 -287.29758) (xy 339.599268 -287.266455)
			(xy 339.566633 -287.229618) (xy 339.54033 -287.188022) (xy 339.521039 -287.142746) (xy 339.509262 -287.094962)
			(xy 339.505302 -287.045908) (xy 339.186774 -287.045908) (xy 339.186262 -287.071354) (xy 339.178098 -287.121588)
			(xy 339.161982 -287.169862) (xy 339.138331 -287.214925) (xy 339.107758 -287.255611) (xy 339.071054 -287.290866)
			(xy 339.02917 -287.319776) (xy 338.983191 -287.341593) (xy 338.934307 -287.355753) (xy 338.883786 -287.361887)
			(xy 338.832934 -287.359838) (xy 338.78307 -287.349658) (xy 338.735484 -287.331611) (xy 338.69141 -287.306165)
			(xy 338.651988 -287.273978) (xy 338.61824 -287.235884) (xy 338.591039 -287.19287) (xy 338.571091 -287.14605)
			(xy 338.558912 -287.096636) (xy 338.554817 -287.045908) (xy 338.236814 -287.045908) (xy 338.236332 -287.070773)
			(xy 338.228285 -287.119846) (xy 338.212389 -287.166966) (xy 338.189064 -287.210886) (xy 338.158928 -287.250443)
			(xy 338.122778 -287.284592) (xy 338.08157 -287.312428) (xy 338.036394 -287.333216) (xy 337.988446 -287.346406)
			(xy 337.963764 -287.349438) (xy 337.949794 -287.350962) (xy 337.927696 -287.367472) (xy 337.887818 -287.46196)
			(xy 337.885005 -287.469376) (xy 337.883695 -287.485176) (xy 337.885278 -287.492948) (xy 337.887818 -287.504632)
			(xy 337.89493 -287.513522) (xy 337.919787 -287.546156) (xy 337.960596 -287.617319) (xy 337.97621 -287.655254)
			(xy 337.98129 -287.668462) (xy 338.003134 -287.68548) (xy 338.017104 -287.687258) (xy 338.119466 -287.700466)
			(xy 338.144866 -287.68929) (xy 338.153248 -287.67786) (xy 338.167714 -287.658561) (xy 338.201702 -287.624344)
			(xy 338.240642 -287.595887) (xy 338.283566 -287.573897) (xy 338.32941 -287.558919) (xy 338.377038 -287.551324)
			(xy 338.401152 -287.55086) (xy 338.426415 -287.551349) (xy 338.476253 -287.559658) (xy 338.524043 -287.576058)
			(xy 338.568482 -287.600101) (xy 338.608356 -287.631131) (xy 338.642579 -287.668301) (xy 338.670217 -287.710598)
			(xy 338.690515 -287.756867) (xy 338.702919 -287.805847) (xy 338.707089 -287.856168) (xy 339.024971 -287.856168)
			(xy 339.029066 -287.80544) (xy 339.041245 -287.756026) (xy 339.061193 -287.709206) (xy 339.088394 -287.666192)
			(xy 339.122142 -287.628098) (xy 339.161564 -287.595911) (xy 339.205638 -287.570465) (xy 339.253224 -287.552418)
			(xy 339.303088 -287.542238) (xy 339.35394 -287.540189) (xy 339.404461 -287.546323) (xy 339.453345 -287.560483)
			(xy 339.499324 -287.5823) (xy 339.541208 -287.61121) (xy 339.577912 -287.646465) (xy 339.608485 -287.687151)
			(xy 339.632136 -287.732214) (xy 339.648252 -287.780488) (xy 339.656416 -287.830722) (xy 339.656928 -287.856168)
			(xy 339.964771 -287.856168) (xy 339.968866 -287.80544) (xy 339.981045 -287.756026) (xy 340.000993 -287.709206)
			(xy 340.028194 -287.666192) (xy 340.061942 -287.628098) (xy 340.101364 -287.595911) (xy 340.145438 -287.570465)
			(xy 340.193024 -287.552418) (xy 340.242888 -287.542238) (xy 340.29374 -287.540189) (xy 340.344261 -287.546323)
			(xy 340.393145 -287.560483) (xy 340.439124 -287.5823) (xy 340.481008 -287.61121) (xy 340.517712 -287.646465)
			(xy 340.548285 -287.687151) (xy 340.571936 -287.732214) (xy 340.588052 -287.780488) (xy 340.596216 -287.830722)
			(xy 340.596728 -287.856168) (xy 340.915256 -287.856168) (xy 340.919216 -287.807114) (xy 340.930993 -287.75933)
			(xy 340.950284 -287.714054) (xy 340.976587 -287.672458) (xy 341.009222 -287.635621) (xy 341.047343 -287.604496)
			(xy 341.089964 -287.579889) (xy 341.13598 -287.562437) (xy 341.184199 -287.552593) (xy 341.233374 -287.550612)
			(xy 341.282229 -287.556544) (xy 341.3295 -287.570236) (xy 341.373962 -287.591334) (xy 341.414465 -287.61929)
			(xy 341.449958 -287.653382) (xy 341.479523 -287.692726) (xy 341.502394 -287.736303) (xy 341.517978 -287.782984)
			(xy 341.525873 -287.831561) (xy 341.526368 -287.856168) (xy 341.844879 -287.856168) (xy 341.848974 -287.80544)
			(xy 341.861153 -287.756026) (xy 341.881101 -287.709206) (xy 341.908302 -287.666192) (xy 341.94205 -287.628098)
			(xy 341.981472 -287.595911) (xy 342.025546 -287.570465) (xy 342.073132 -287.552418) (xy 342.122996 -287.542238)
			(xy 342.173848 -287.540189) (xy 342.224369 -287.546323) (xy 342.273253 -287.560483) (xy 342.319232 -287.5823)
			(xy 342.361116 -287.61121) (xy 342.39782 -287.646465) (xy 342.428393 -287.687151) (xy 342.452044 -287.732214)
			(xy 342.46816 -287.780488) (xy 342.476324 -287.830722) (xy 342.476836 -287.856168) (xy 342.795364 -287.856168)
			(xy 342.799324 -287.807114) (xy 342.811101 -287.75933) (xy 342.830392 -287.714054) (xy 342.856695 -287.672458)
			(xy 342.88933 -287.635621) (xy 342.927451 -287.604496) (xy 342.970072 -287.579889) (xy 343.016088 -287.562437)
			(xy 343.064307 -287.552593) (xy 343.113482 -287.550612) (xy 343.162337 -287.556544) (xy 343.209608 -287.570236)
			(xy 343.25407 -287.591334) (xy 343.294573 -287.61929) (xy 343.330066 -287.653382) (xy 343.359631 -287.692726)
			(xy 343.382502 -287.736303) (xy 343.398086 -287.782984) (xy 343.405981 -287.831561) (xy 343.406476 -287.856168)
			(xy 343.724987 -287.856168) (xy 343.729082 -287.80544) (xy 343.741261 -287.756026) (xy 343.761209 -287.709206)
			(xy 343.78841 -287.666192) (xy 343.822158 -287.628098) (xy 343.86158 -287.595911) (xy 343.905654 -287.570465)
			(xy 343.95324 -287.552418) (xy 344.003104 -287.542238) (xy 344.053956 -287.540189) (xy 344.104477 -287.546323)
			(xy 344.153361 -287.560483) (xy 344.19934 -287.5823) (xy 344.241224 -287.61121) (xy 344.277928 -287.646465)
			(xy 344.308501 -287.687151) (xy 344.332152 -287.732214) (xy 344.348268 -287.780488) (xy 344.356432 -287.830722)
			(xy 344.356944 -287.856168) (xy 344.356432 -287.881614) (xy 344.348268 -287.931848) (xy 344.332152 -287.980122)
			(xy 344.308501 -288.025185) (xy 344.277928 -288.065871) (xy 344.241224 -288.101126) (xy 344.19934 -288.130036)
			(xy 344.153361 -288.151853) (xy 344.104477 -288.166013) (xy 344.053956 -288.172147) (xy 344.003104 -288.170098)
			(xy 343.95324 -288.159918) (xy 343.905654 -288.141871) (xy 343.86158 -288.116425) (xy 343.822158 -288.084238)
			(xy 343.78841 -288.046144) (xy 343.761209 -288.00313) (xy 343.741261 -287.95631) (xy 343.729082 -287.906896)
			(xy 343.724987 -287.856168) (xy 343.406476 -287.856168) (xy 343.405981 -287.880775) (xy 343.398086 -287.929352)
			(xy 343.382502 -287.976033) (xy 343.359631 -288.01961) (xy 343.330066 -288.058954) (xy 343.294573 -288.093046)
			(xy 343.25407 -288.121002) (xy 343.209608 -288.1421) (xy 343.162337 -288.155792) (xy 343.113482 -288.161724)
			(xy 343.064307 -288.159743) (xy 343.016088 -288.149899) (xy 342.970072 -288.132447) (xy 342.927451 -288.10784)
			(xy 342.88933 -288.076715) (xy 342.856695 -288.039878) (xy 342.830392 -287.998282) (xy 342.811101 -287.953006)
			(xy 342.799324 -287.905222) (xy 342.795364 -287.856168) (xy 342.476836 -287.856168) (xy 342.476324 -287.881614)
			(xy 342.46816 -287.931848) (xy 342.452044 -287.980122) (xy 342.428393 -288.025185) (xy 342.39782 -288.065871)
			(xy 342.361116 -288.101126) (xy 342.319232 -288.130036) (xy 342.273253 -288.151853) (xy 342.224369 -288.166013)
			(xy 342.173848 -288.172147) (xy 342.122996 -288.170098) (xy 342.073132 -288.159918) (xy 342.025546 -288.141871)
			(xy 341.981472 -288.116425) (xy 341.94205 -288.084238) (xy 341.908302 -288.046144) (xy 341.881101 -288.00313)
			(xy 341.861153 -287.95631) (xy 341.848974 -287.906896) (xy 341.844879 -287.856168) (xy 341.526368 -287.856168)
			(xy 341.525873 -287.880775) (xy 341.517978 -287.929352) (xy 341.502394 -287.976033) (xy 341.479523 -288.01961)
			(xy 341.449958 -288.058954) (xy 341.414465 -288.093046) (xy 341.373962 -288.121002) (xy 341.3295 -288.1421)
			(xy 341.282229 -288.155792) (xy 341.233374 -288.161724) (xy 341.184199 -288.159743) (xy 341.13598 -288.149899)
			(xy 341.089964 -288.132447) (xy 341.047343 -288.10784) (xy 341.009222 -288.076715) (xy 340.976587 -288.039878)
			(xy 340.950284 -287.998282) (xy 340.930993 -287.953006) (xy 340.919216 -287.905222) (xy 340.915256 -287.856168)
			(xy 340.596728 -287.856168) (xy 340.596216 -287.881614) (xy 340.588052 -287.931848) (xy 340.571936 -287.980122)
			(xy 340.548285 -288.025185) (xy 340.517712 -288.065871) (xy 340.481008 -288.101126) (xy 340.439124 -288.130036)
			(xy 340.393145 -288.151853) (xy 340.344261 -288.166013) (xy 340.29374 -288.172147) (xy 340.242888 -288.170098)
			(xy 340.193024 -288.159918) (xy 340.145438 -288.141871) (xy 340.101364 -288.116425) (xy 340.061942 -288.084238)
			(xy 340.028194 -288.046144) (xy 340.000993 -288.00313) (xy 339.981045 -287.95631) (xy 339.968866 -287.906896)
			(xy 339.964771 -287.856168) (xy 339.656928 -287.856168) (xy 339.656416 -287.881614) (xy 339.648252 -287.931848)
			(xy 339.632136 -287.980122) (xy 339.608485 -288.025185) (xy 339.577912 -288.065871) (xy 339.541208 -288.101126)
			(xy 339.499324 -288.130036) (xy 339.453345 -288.151853) (xy 339.404461 -288.166013) (xy 339.35394 -288.172147)
			(xy 339.303088 -288.170098) (xy 339.253224 -288.159918) (xy 339.205638 -288.141871) (xy 339.161564 -288.116425)
			(xy 339.122142 -288.084238) (xy 339.088394 -288.046144) (xy 339.061193 -288.00313) (xy 339.041245 -287.95631)
			(xy 339.029066 -287.906896) (xy 339.024971 -287.856168) (xy 338.707089 -287.856168) (xy 338.707092 -287.8562)
			(xy 338.702919 -287.906553) (xy 338.690515 -287.955533) (xy 338.670217 -288.001802) (xy 338.642579 -288.044099)
			(xy 338.608356 -288.081269) (xy 338.568482 -288.112299) (xy 338.524043 -288.136342) (xy 338.476253 -288.152742)
			(xy 338.426415 -288.161051) (xy 338.401152 -288.161476) (xy 338.388389 -288.161337) (xy 338.362955 -288.159174)
			(xy 338.350352 -288.157158) (xy 338.350352 -288.157412) (xy 338.326897 -288.152987) (xy 338.28164 -288.137829)
			(xy 338.239285 -288.115828) (xy 338.20086 -288.087518) (xy 338.167297 -288.053584) (xy 338.152994 -288.034476)
			(xy 338.144866 -288.023046) (xy 338.119212 -288.01187) (xy 338.017104 -288.025078) (xy 338.003134 -288.026856)
			(xy 337.98129 -288.043874) (xy 337.97621 -288.057082) (xy 337.969352 -288.073592) (xy 337.962654 -288.088963)
			(xy 337.947656 -288.118954) (xy 337.93938 -288.133536) (xy 337.917536 -288.171128) (xy 337.894168 -288.21126)
			(xy 337.888436 -288.222501) (xy 337.88763 -288.247688) (xy 337.892644 -288.259266) (xy 337.935824 -288.346642)
			(xy 337.956652 -288.361374) (xy 337.969352 -288.363152) (xy 337.993621 -288.36669) (xy 338.040678 -288.380504)
			(xy 338.084916 -288.401671) (xy 338.125196 -288.429646) (xy 338.16048 -288.463708) (xy 338.189857 -288.502978)
			(xy 338.212569 -288.546443) (xy 338.228032 -288.592983) (xy 338.235847 -288.641399) (xy 338.236306 -288.66592)
			(xy 338.554817 -288.66592) (xy 338.558912 -288.615192) (xy 338.571091 -288.565778) (xy 338.591039 -288.518958)
			(xy 338.61824 -288.475944) (xy 338.651988 -288.43785) (xy 338.69141 -288.405663) (xy 338.735484 -288.380217)
			(xy 338.78307 -288.36217) (xy 338.832934 -288.35199) (xy 338.883786 -288.349941) (xy 338.934307 -288.356075)
			(xy 338.983191 -288.370235) (xy 339.02917 -288.392052) (xy 339.071054 -288.420962) (xy 339.107758 -288.456217)
			(xy 339.138331 -288.496903) (xy 339.161982 -288.541966) (xy 339.178098 -288.59024) (xy 339.186262 -288.640474)
			(xy 339.186774 -288.66592) (xy 339.505302 -288.66592) (xy 339.509262 -288.616866) (xy 339.521039 -288.569082)
			(xy 339.54033 -288.523806) (xy 339.566633 -288.48221) (xy 339.599268 -288.445373) (xy 339.637389 -288.414248)
			(xy 339.68001 -288.389641) (xy 339.726026 -288.372189) (xy 339.774245 -288.362345) (xy 339.82342 -288.360364)
			(xy 339.872275 -288.366296) (xy 339.919546 -288.379988) (xy 339.964008 -288.401086) (xy 340.004511 -288.429042)
			(xy 340.040004 -288.463134) (xy 340.069569 -288.502478) (xy 340.09244 -288.546055) (xy 340.108024 -288.592736)
			(xy 340.115919 -288.641313) (xy 340.116414 -288.66592) (xy 340.434925 -288.66592) (xy 340.43902 -288.615192)
			(xy 340.451199 -288.565778) (xy 340.471147 -288.518958) (xy 340.498348 -288.475944) (xy 340.532096 -288.43785)
			(xy 340.571518 -288.405663) (xy 340.615592 -288.380217) (xy 340.663178 -288.36217) (xy 340.713042 -288.35199)
			(xy 340.763894 -288.349941) (xy 340.814415 -288.356075) (xy 340.863299 -288.370235) (xy 340.909278 -288.392052)
			(xy 340.951162 -288.420962) (xy 340.987866 -288.456217) (xy 341.018439 -288.496903) (xy 341.04209 -288.541966)
			(xy 341.058206 -288.59024) (xy 341.06637 -288.640474) (xy 341.066882 -288.66592) (xy 341.38541 -288.66592)
			(xy 341.38937 -288.616866) (xy 341.401147 -288.569082) (xy 341.420438 -288.523806) (xy 341.446741 -288.48221)
			(xy 341.479376 -288.445373) (xy 341.517497 -288.414248) (xy 341.560118 -288.389641) (xy 341.606134 -288.372189)
			(xy 341.654353 -288.362345) (xy 341.703528 -288.360364) (xy 341.752383 -288.366296) (xy 341.799654 -288.379988)
			(xy 341.844116 -288.401086) (xy 341.884619 -288.429042) (xy 341.920112 -288.463134) (xy 341.949677 -288.502478)
			(xy 341.972548 -288.546055) (xy 341.988132 -288.592736) (xy 341.996027 -288.641313) (xy 341.996522 -288.66592)
			(xy 342.314779 -288.66592) (xy 342.318874 -288.615192) (xy 342.331053 -288.565778) (xy 342.351001 -288.518958)
			(xy 342.378202 -288.475944) (xy 342.41195 -288.43785) (xy 342.451372 -288.405663) (xy 342.495446 -288.380217)
			(xy 342.543032 -288.36217) (xy 342.592896 -288.35199) (xy 342.643748 -288.349941) (xy 342.694269 -288.356075)
			(xy 342.743153 -288.370235) (xy 342.789132 -288.392052) (xy 342.831016 -288.420962) (xy 342.86772 -288.456217)
			(xy 342.898293 -288.496903) (xy 342.921944 -288.541966) (xy 342.93806 -288.59024) (xy 342.946224 -288.640474)
			(xy 342.946736 -288.66592) (xy 343.254833 -288.66592) (xy 343.258928 -288.615192) (xy 343.271107 -288.565778)
			(xy 343.291055 -288.518958) (xy 343.318256 -288.475944) (xy 343.352004 -288.43785) (xy 343.391426 -288.405663)
			(xy 343.4355 -288.380217) (xy 343.483086 -288.36217) (xy 343.53295 -288.35199) (xy 343.583802 -288.349941)
			(xy 343.634323 -288.356075) (xy 343.683207 -288.370235) (xy 343.729186 -288.392052) (xy 343.77107 -288.420962)
			(xy 343.807774 -288.456217) (xy 343.838347 -288.496903) (xy 343.861998 -288.541966) (xy 343.878114 -288.59024)
			(xy 343.886278 -288.640474) (xy 343.88679 -288.66592) (xy 343.886278 -288.691366) (xy 343.878114 -288.7416)
			(xy 343.861998 -288.789874) (xy 343.838347 -288.834937) (xy 343.807774 -288.875623) (xy 343.77107 -288.910878)
			(xy 343.729186 -288.939788) (xy 343.683207 -288.961605) (xy 343.634323 -288.975765) (xy 343.583802 -288.981899)
			(xy 343.53295 -288.97985) (xy 343.483086 -288.96967) (xy 343.4355 -288.951623) (xy 343.391426 -288.926177)
			(xy 343.352004 -288.89399) (xy 343.318256 -288.855896) (xy 343.291055 -288.812882) (xy 343.271107 -288.766062)
			(xy 343.258928 -288.716648) (xy 343.254833 -288.66592) (xy 342.946736 -288.66592) (xy 342.946224 -288.691366)
			(xy 342.93806 -288.7416) (xy 342.921944 -288.789874) (xy 342.898293 -288.834937) (xy 342.86772 -288.875623)
			(xy 342.831016 -288.910878) (xy 342.789132 -288.939788) (xy 342.743153 -288.961605) (xy 342.694269 -288.975765)
			(xy 342.643748 -288.981899) (xy 342.592896 -288.97985) (xy 342.543032 -288.96967) (xy 342.495446 -288.951623)
			(xy 342.451372 -288.926177) (xy 342.41195 -288.89399) (xy 342.378202 -288.855896) (xy 342.351001 -288.812882)
			(xy 342.331053 -288.766062) (xy 342.318874 -288.716648) (xy 342.314779 -288.66592) (xy 341.996522 -288.66592)
			(xy 341.996027 -288.690527) (xy 341.988132 -288.739104) (xy 341.972548 -288.785785) (xy 341.949677 -288.829362)
			(xy 341.920112 -288.868706) (xy 341.884619 -288.902798) (xy 341.844116 -288.930754) (xy 341.799654 -288.951852)
			(xy 341.752383 -288.965544) (xy 341.703528 -288.971476) (xy 341.654353 -288.969495) (xy 341.606134 -288.959651)
			(xy 341.560118 -288.942199) (xy 341.517497 -288.917592) (xy 341.479376 -288.886467) (xy 341.446741 -288.84963)
			(xy 341.420438 -288.808034) (xy 341.401147 -288.762758) (xy 341.38937 -288.714974) (xy 341.38541 -288.66592)
			(xy 341.066882 -288.66592) (xy 341.06637 -288.691366) (xy 341.058206 -288.7416) (xy 341.04209 -288.789874)
			(xy 341.018439 -288.834937) (xy 340.987866 -288.875623) (xy 340.951162 -288.910878) (xy 340.909278 -288.939788)
			(xy 340.863299 -288.961605) (xy 340.814415 -288.975765) (xy 340.763894 -288.981899) (xy 340.713042 -288.97985)
			(xy 340.663178 -288.96967) (xy 340.615592 -288.951623) (xy 340.571518 -288.926177) (xy 340.532096 -288.89399)
			(xy 340.498348 -288.855896) (xy 340.471147 -288.812882) (xy 340.451199 -288.766062) (xy 340.43902 -288.716648)
			(xy 340.434925 -288.66592) (xy 340.116414 -288.66592) (xy 340.115919 -288.690527) (xy 340.108024 -288.739104)
			(xy 340.09244 -288.785785) (xy 340.069569 -288.829362) (xy 340.040004 -288.868706) (xy 340.004511 -288.902798)
			(xy 339.964008 -288.930754) (xy 339.919546 -288.951852) (xy 339.872275 -288.965544) (xy 339.82342 -288.971476)
			(xy 339.774245 -288.969495) (xy 339.726026 -288.959651) (xy 339.68001 -288.942199) (xy 339.637389 -288.917592)
			(xy 339.599268 -288.886467) (xy 339.566633 -288.84963) (xy 339.54033 -288.808034) (xy 339.521039 -288.762758)
			(xy 339.509262 -288.714974) (xy 339.505302 -288.66592) (xy 339.186774 -288.66592) (xy 339.186262 -288.691366)
			(xy 339.178098 -288.7416) (xy 339.161982 -288.789874) (xy 339.138331 -288.834937) (xy 339.107758 -288.875623)
			(xy 339.071054 -288.910878) (xy 339.02917 -288.939788) (xy 338.983191 -288.961605) (xy 338.934307 -288.975765)
			(xy 338.883786 -288.981899) (xy 338.832934 -288.97985) (xy 338.78307 -288.96967) (xy 338.735484 -288.951623)
			(xy 338.69141 -288.926177) (xy 338.651988 -288.89399) (xy 338.61824 -288.855896) (xy 338.591039 -288.812882)
			(xy 338.571091 -288.766062) (xy 338.558912 -288.716648) (xy 338.554817 -288.66592) (xy 338.236306 -288.66592)
			(xy 338.235819 -288.690739) (xy 338.227785 -288.739724) (xy 338.211933 -288.786763) (xy 338.18868 -288.830618)
			(xy 338.158639 -288.870134) (xy 338.122601 -288.90427) (xy 338.081516 -288.932126) (xy 338.036465 -288.952969)
			(xy 337.988636 -288.966249) (xy 337.964018 -288.96945) (xy 337.950048 -288.970974) (xy 337.92795 -288.987484)
			(xy 337.888072 -289.082226) (xy 337.884926 -289.090753) (xy 337.884219 -289.108902) (xy 337.889859 -289.126166)
			(xy 337.895184 -289.133534) (xy 337.897724 -289.136836) (xy 337.921659 -289.168749) (xy 337.961059 -289.23811)
			(xy 337.97621 -289.275012) (xy 337.98129 -289.28822) (xy 338.00288 -289.305238) (xy 338.119466 -289.320224)
			(xy 338.144866 -289.309048) (xy 338.153248 -289.297618) (xy 338.167711 -289.278315) (xy 338.201698 -289.244092)
			(xy 338.240636 -289.21563) (xy 338.283561 -289.193636) (xy 338.329407 -289.178654) (xy 338.377036 -289.171058)
			(xy 338.401152 -289.170618) (xy 338.42641 -289.171107) (xy 338.476239 -289.179414) (xy 338.52402 -289.195811)
			(xy 338.56845 -289.219849) (xy 338.608317 -289.250873) (xy 338.642534 -289.288037) (xy 338.670166 -289.330326)
			(xy 338.69046 -289.376586) (xy 338.702862 -289.425556) (xy 338.707034 -289.4759) (xy 338.707032 -289.475926)
			(xy 339.024971 -289.475926) (xy 339.029066 -289.425198) (xy 339.041245 -289.375784) (xy 339.061193 -289.328964)
			(xy 339.088394 -289.28595) (xy 339.122142 -289.247856) (xy 339.161564 -289.215669) (xy 339.205638 -289.190223)
			(xy 339.253224 -289.172176) (xy 339.303088 -289.161996) (xy 339.35394 -289.159947) (xy 339.404461 -289.166081)
			(xy 339.453345 -289.180241) (xy 339.499324 -289.202058) (xy 339.541208 -289.230968) (xy 339.577912 -289.266223)
			(xy 339.608485 -289.306909) (xy 339.632136 -289.351972) (xy 339.648252 -289.400246) (xy 339.656416 -289.45048)
			(xy 339.656928 -289.475926) (xy 339.964771 -289.475926) (xy 339.968866 -289.425198) (xy 339.981045 -289.375784)
			(xy 340.000993 -289.328964) (xy 340.028194 -289.28595) (xy 340.061942 -289.247856) (xy 340.101364 -289.215669)
			(xy 340.145438 -289.190223) (xy 340.193024 -289.172176) (xy 340.242888 -289.161996) (xy 340.29374 -289.159947)
			(xy 340.344261 -289.166081) (xy 340.393145 -289.180241) (xy 340.439124 -289.202058) (xy 340.481008 -289.230968)
			(xy 340.517712 -289.266223) (xy 340.548285 -289.306909) (xy 340.571936 -289.351972) (xy 340.588052 -289.400246)
			(xy 340.596216 -289.45048) (xy 340.596728 -289.475926) (xy 340.915256 -289.475926) (xy 340.919216 -289.426872)
			(xy 340.930993 -289.379088) (xy 340.950284 -289.333812) (xy 340.976587 -289.292216) (xy 341.009222 -289.255379)
			(xy 341.047343 -289.224254) (xy 341.089964 -289.199647) (xy 341.13598 -289.182195) (xy 341.184199 -289.172351)
			(xy 341.233374 -289.17037) (xy 341.282229 -289.176302) (xy 341.3295 -289.189994) (xy 341.373962 -289.211092)
			(xy 341.414465 -289.239048) (xy 341.449958 -289.27314) (xy 341.479523 -289.312484) (xy 341.502394 -289.356061)
			(xy 341.517978 -289.402742) (xy 341.525873 -289.451319) (xy 341.526368 -289.475926) (xy 341.844879 -289.475926)
			(xy 341.848974 -289.425198) (xy 341.861153 -289.375784) (xy 341.881101 -289.328964) (xy 341.908302 -289.28595)
			(xy 341.94205 -289.247856) (xy 341.981472 -289.215669) (xy 342.025546 -289.190223) (xy 342.073132 -289.172176)
			(xy 342.122996 -289.161996) (xy 342.173848 -289.159947) (xy 342.224369 -289.166081) (xy 342.273253 -289.180241)
			(xy 342.319232 -289.202058) (xy 342.361116 -289.230968) (xy 342.39782 -289.266223) (xy 342.428393 -289.306909)
			(xy 342.452044 -289.351972) (xy 342.46816 -289.400246) (xy 342.476324 -289.45048) (xy 342.476836 -289.475926)
			(xy 342.795364 -289.475926) (xy 342.799324 -289.426872) (xy 342.811101 -289.379088) (xy 342.830392 -289.333812)
			(xy 342.856695 -289.292216) (xy 342.88933 -289.255379) (xy 342.927451 -289.224254) (xy 342.970072 -289.199647)
			(xy 343.016088 -289.182195) (xy 343.064307 -289.172351) (xy 343.113482 -289.17037) (xy 343.162337 -289.176302)
			(xy 343.209608 -289.189994) (xy 343.25407 -289.211092) (xy 343.294573 -289.239048) (xy 343.330066 -289.27314)
			(xy 343.359631 -289.312484) (xy 343.382502 -289.356061) (xy 343.398086 -289.402742) (xy 343.405981 -289.451319)
			(xy 343.406476 -289.475926) (xy 343.724987 -289.475926) (xy 343.729082 -289.425198) (xy 343.741261 -289.375784)
			(xy 343.761209 -289.328964) (xy 343.78841 -289.28595) (xy 343.822158 -289.247856) (xy 343.86158 -289.215669)
			(xy 343.905654 -289.190223) (xy 343.95324 -289.172176) (xy 344.003104 -289.161996) (xy 344.053956 -289.159947)
			(xy 344.104477 -289.166081) (xy 344.153361 -289.180241) (xy 344.19934 -289.202058) (xy 344.241224 -289.230968)
			(xy 344.277928 -289.266223) (xy 344.308501 -289.306909) (xy 344.332152 -289.351972) (xy 344.348268 -289.400246)
			(xy 344.356432 -289.45048) (xy 344.356944 -289.475926) (xy 344.356432 -289.501372) (xy 344.348268 -289.551606)
			(xy 344.332152 -289.59988) (xy 344.308501 -289.644943) (xy 344.277928 -289.685629) (xy 344.241224 -289.720884)
			(xy 344.19934 -289.749794) (xy 344.153361 -289.771611) (xy 344.104477 -289.785771) (xy 344.053956 -289.791905)
			(xy 344.003104 -289.789856) (xy 343.95324 -289.779676) (xy 343.905654 -289.761629) (xy 343.86158 -289.736183)
			(xy 343.822158 -289.703996) (xy 343.78841 -289.665902) (xy 343.761209 -289.622888) (xy 343.741261 -289.576068)
			(xy 343.729082 -289.526654) (xy 343.724987 -289.475926) (xy 343.406476 -289.475926) (xy 343.405981 -289.500533)
			(xy 343.398086 -289.54911) (xy 343.382502 -289.595791) (xy 343.359631 -289.639368) (xy 343.330066 -289.678712)
			(xy 343.294573 -289.712804) (xy 343.25407 -289.74076) (xy 343.209608 -289.761858) (xy 343.162337 -289.77555)
			(xy 343.113482 -289.781482) (xy 343.064307 -289.779501) (xy 343.016088 -289.769657) (xy 342.970072 -289.752205)
			(xy 342.927451 -289.727598) (xy 342.88933 -289.696473) (xy 342.856695 -289.659636) (xy 342.830392 -289.61804)
			(xy 342.811101 -289.572764) (xy 342.799324 -289.52498) (xy 342.795364 -289.475926) (xy 342.476836 -289.475926)
			(xy 342.476324 -289.501372) (xy 342.46816 -289.551606) (xy 342.452044 -289.59988) (xy 342.428393 -289.644943)
			(xy 342.39782 -289.685629) (xy 342.361116 -289.720884) (xy 342.319232 -289.749794) (xy 342.273253 -289.771611)
			(xy 342.224369 -289.785771) (xy 342.173848 -289.791905) (xy 342.122996 -289.789856) (xy 342.073132 -289.779676)
			(xy 342.025546 -289.761629) (xy 341.981472 -289.736183) (xy 341.94205 -289.703996) (xy 341.908302 -289.665902)
			(xy 341.881101 -289.622888) (xy 341.861153 -289.576068) (xy 341.848974 -289.526654) (xy 341.844879 -289.475926)
			(xy 341.526368 -289.475926) (xy 341.525873 -289.500533) (xy 341.517978 -289.54911) (xy 341.502394 -289.595791)
			(xy 341.479523 -289.639368) (xy 341.449958 -289.678712) (xy 341.414465 -289.712804) (xy 341.373962 -289.74076)
			(xy 341.3295 -289.761858) (xy 341.282229 -289.77555) (xy 341.233374 -289.781482) (xy 341.184199 -289.779501)
			(xy 341.13598 -289.769657) (xy 341.089964 -289.752205) (xy 341.047343 -289.727598) (xy 341.009222 -289.696473)
			(xy 340.976587 -289.659636) (xy 340.950284 -289.61804) (xy 340.930993 -289.572764) (xy 340.919216 -289.52498)
			(xy 340.915256 -289.475926) (xy 340.596728 -289.475926) (xy 340.596216 -289.501372) (xy 340.588052 -289.551606)
			(xy 340.571936 -289.59988) (xy 340.548285 -289.644943) (xy 340.517712 -289.685629) (xy 340.481008 -289.720884)
			(xy 340.439124 -289.749794) (xy 340.393145 -289.771611) (xy 340.344261 -289.785771) (xy 340.29374 -289.791905)
			(xy 340.242888 -289.789856) (xy 340.193024 -289.779676) (xy 340.145438 -289.761629) (xy 340.101364 -289.736183)
			(xy 340.061942 -289.703996) (xy 340.028194 -289.665902) (xy 340.000993 -289.622888) (xy 339.981045 -289.576068)
			(xy 339.968866 -289.526654) (xy 339.964771 -289.475926) (xy 339.656928 -289.475926) (xy 339.656416 -289.501372)
			(xy 339.648252 -289.551606) (xy 339.632136 -289.59988) (xy 339.608485 -289.644943) (xy 339.577912 -289.685629)
			(xy 339.541208 -289.720884) (xy 339.499324 -289.749794) (xy 339.453345 -289.771611) (xy 339.404461 -289.785771)
			(xy 339.35394 -289.791905) (xy 339.303088 -289.789856) (xy 339.253224 -289.779676) (xy 339.205638 -289.761629)
			(xy 339.161564 -289.736183) (xy 339.122142 -289.703996) (xy 339.088394 -289.665902) (xy 339.061193 -289.622888)
			(xy 339.041245 -289.576068) (xy 339.029066 -289.526654) (xy 339.024971 -289.475926) (xy 338.707032 -289.475926)
			(xy 338.702862 -289.526244) (xy 338.69046 -289.575214) (xy 338.670166 -289.621474) (xy 338.642534 -289.663763)
			(xy 338.608317 -289.700927) (xy 338.56845 -289.731951) (xy 338.52402 -289.755989) (xy 338.476239 -289.772386)
			(xy 338.42641 -289.780693) (xy 338.401152 -289.781234) (xy 338.388389 -289.781095) (xy 338.362955 -289.778932)
			(xy 338.350352 -289.776916) (xy 338.350352 -289.77717) (xy 338.326896 -289.772746) (xy 338.281637 -289.75759)
			(xy 338.239279 -289.735592) (xy 338.20085 -289.707284) (xy 338.167281 -289.673354) (xy 338.152994 -289.654234)
			(xy 338.144866 -289.642804) (xy 338.119212 -289.631628) (xy 338.017104 -289.644836) (xy 338.003134 -289.646614)
			(xy 337.98129 -289.663632) (xy 337.97621 -289.67684) (xy 337.969352 -289.69335) (xy 337.962655 -289.708721)
			(xy 337.947659 -289.738714) (xy 337.93938 -289.753294) (xy 337.894168 -289.831272) (xy 337.892644 -289.834066)
			(xy 337.892644 -289.83432) (xy 337.887945 -289.845141) (xy 337.887956 -289.868705) (xy 337.892644 -289.879532)
			(xy 337.929474 -289.953954) (xy 337.935086 -289.964567) (xy 337.953916 -289.979405) (xy 337.965542 -289.982402)
			(xy 337.969098 -289.98291) (xy 337.993657 -289.98651) (xy 338.041241 -290.000625) (xy 338.085917 -290.022247)
			(xy 338.126511 -290.050806) (xy 338.161955 -290.085552) (xy 338.191315 -290.12557) (xy 338.213821 -290.169808)
			(xy 338.22888 -290.217102) (xy 338.236095 -290.266208) (xy 338.23577 -290.285932) (xy 338.554817 -290.285932)
			(xy 338.558912 -290.235204) (xy 338.571091 -290.18579) (xy 338.591039 -290.13897) (xy 338.61824 -290.095956)
			(xy 338.651988 -290.057862) (xy 338.69141 -290.025675) (xy 338.735484 -290.000229) (xy 338.78307 -289.982182)
			(xy 338.832934 -289.972002) (xy 338.883786 -289.969953) (xy 338.934307 -289.976087) (xy 338.983191 -289.990247)
			(xy 339.02917 -290.012064) (xy 339.071054 -290.040974) (xy 339.107758 -290.076229) (xy 339.138331 -290.116915)
			(xy 339.161982 -290.161978) (xy 339.178098 -290.210252) (xy 339.186262 -290.260486) (xy 339.186774 -290.285932)
			(xy 339.505302 -290.285932) (xy 339.509262 -290.236878) (xy 339.521039 -290.189094) (xy 339.54033 -290.143818)
			(xy 339.566633 -290.102222) (xy 339.599268 -290.065385) (xy 339.637389 -290.03426) (xy 339.68001 -290.009653)
			(xy 339.726026 -289.992201) (xy 339.774245 -289.982357) (xy 339.82342 -289.980376) (xy 339.872275 -289.986308)
			(xy 339.919546 -290) (xy 339.964008 -290.021098) (xy 340.004511 -290.049054) (xy 340.040004 -290.083146)
			(xy 340.069569 -290.12249) (xy 340.09244 -290.166067) (xy 340.108024 -290.212748) (xy 340.115919 -290.261325)
			(xy 340.116414 -290.285932) (xy 340.434925 -290.285932) (xy 340.43902 -290.235204) (xy 340.451199 -290.18579)
			(xy 340.471147 -290.13897) (xy 340.498348 -290.095956) (xy 340.532096 -290.057862) (xy 340.571518 -290.025675)
			(xy 340.615592 -290.000229) (xy 340.663178 -289.982182) (xy 340.713042 -289.972002) (xy 340.763894 -289.969953)
			(xy 340.814415 -289.976087) (xy 340.863299 -289.990247) (xy 340.909278 -290.012064) (xy 340.951162 -290.040974)
			(xy 340.987866 -290.076229) (xy 341.018439 -290.116915) (xy 341.04209 -290.161978) (xy 341.058206 -290.210252)
			(xy 341.06637 -290.260486) (xy 341.066882 -290.285932) (xy 341.38541 -290.285932) (xy 341.38937 -290.236878)
			(xy 341.401147 -290.189094) (xy 341.420438 -290.143818) (xy 341.446741 -290.102222) (xy 341.479376 -290.065385)
			(xy 341.517497 -290.03426) (xy 341.560118 -290.009653) (xy 341.606134 -289.992201) (xy 341.654353 -289.982357)
			(xy 341.703528 -289.980376) (xy 341.752383 -289.986308) (xy 341.799654 -290) (xy 341.844116 -290.021098)
			(xy 341.884619 -290.049054) (xy 341.920112 -290.083146) (xy 341.949677 -290.12249) (xy 341.972548 -290.166067)
			(xy 341.988132 -290.212748) (xy 341.996027 -290.261325) (xy 341.996522 -290.285932) (xy 342.314779 -290.285932)
			(xy 342.318874 -290.235204) (xy 342.331053 -290.18579) (xy 342.351001 -290.13897) (xy 342.378202 -290.095956)
			(xy 342.41195 -290.057862) (xy 342.451372 -290.025675) (xy 342.495446 -290.000229) (xy 342.543032 -289.982182)
			(xy 342.592896 -289.972002) (xy 342.643748 -289.969953) (xy 342.694269 -289.976087) (xy 342.743153 -289.990247)
			(xy 342.789132 -290.012064) (xy 342.831016 -290.040974) (xy 342.86772 -290.076229) (xy 342.898293 -290.116915)
			(xy 342.921944 -290.161978) (xy 342.93806 -290.210252) (xy 342.946224 -290.260486) (xy 342.946736 -290.285932)
			(xy 343.254833 -290.285932) (xy 343.258928 -290.235204) (xy 343.271107 -290.18579) (xy 343.291055 -290.13897)
			(xy 343.318256 -290.095956) (xy 343.352004 -290.057862) (xy 343.391426 -290.025675) (xy 343.4355 -290.000229)
			(xy 343.483086 -289.982182) (xy 343.53295 -289.972002) (xy 343.583802 -289.969953) (xy 343.634323 -289.976087)
			(xy 343.683207 -289.990247) (xy 343.729186 -290.012064) (xy 343.77107 -290.040974) (xy 343.807774 -290.076229)
			(xy 343.838347 -290.116915) (xy 343.861998 -290.161978) (xy 343.878114 -290.210252) (xy 343.886278 -290.260486)
			(xy 343.88679 -290.285932) (xy 343.886278 -290.311378) (xy 343.878114 -290.361612) (xy 343.861998 -290.409886)
			(xy 343.838347 -290.454949) (xy 343.807774 -290.495635) (xy 343.77107 -290.53089) (xy 343.729186 -290.5598)
			(xy 343.683207 -290.581617) (xy 343.634323 -290.595777) (xy 343.583802 -290.601911) (xy 343.53295 -290.599862)
			(xy 343.483086 -290.589682) (xy 343.4355 -290.571635) (xy 343.391426 -290.546189) (xy 343.352004 -290.514002)
			(xy 343.318256 -290.475908) (xy 343.291055 -290.432894) (xy 343.271107 -290.386074) (xy 343.258928 -290.33666)
			(xy 343.254833 -290.285932) (xy 342.946736 -290.285932) (xy 342.946224 -290.311378) (xy 342.93806 -290.361612)
			(xy 342.921944 -290.409886) (xy 342.898293 -290.454949) (xy 342.86772 -290.495635) (xy 342.831016 -290.53089)
			(xy 342.789132 -290.5598) (xy 342.743153 -290.581617) (xy 342.694269 -290.595777) (xy 342.643748 -290.601911)
			(xy 342.592896 -290.599862) (xy 342.543032 -290.589682) (xy 342.495446 -290.571635) (xy 342.451372 -290.546189)
			(xy 342.41195 -290.514002) (xy 342.378202 -290.475908) (xy 342.351001 -290.432894) (xy 342.331053 -290.386074)
			(xy 342.318874 -290.33666) (xy 342.314779 -290.285932) (xy 341.996522 -290.285932) (xy 341.996027 -290.310539)
			(xy 341.988132 -290.359116) (xy 341.972548 -290.405797) (xy 341.949677 -290.449374) (xy 341.920112 -290.488718)
			(xy 341.884619 -290.52281) (xy 341.844116 -290.550766) (xy 341.799654 -290.571864) (xy 341.752383 -290.585556)
			(xy 341.703528 -290.591488) (xy 341.654353 -290.589507) (xy 341.606134 -290.579663) (xy 341.560118 -290.562211)
			(xy 341.517497 -290.537604) (xy 341.479376 -290.506479) (xy 341.446741 -290.469642) (xy 341.420438 -290.428046)
			(xy 341.401147 -290.38277) (xy 341.38937 -290.334986) (xy 341.38541 -290.285932) (xy 341.066882 -290.285932)
			(xy 341.06637 -290.311378) (xy 341.058206 -290.361612) (xy 341.04209 -290.409886) (xy 341.018439 -290.454949)
			(xy 340.987866 -290.495635) (xy 340.951162 -290.53089) (xy 340.909278 -290.5598) (xy 340.863299 -290.581617)
			(xy 340.814415 -290.595777) (xy 340.763894 -290.601911) (xy 340.713042 -290.599862) (xy 340.663178 -290.589682)
			(xy 340.615592 -290.571635) (xy 340.571518 -290.546189) (xy 340.532096 -290.514002) (xy 340.498348 -290.475908)
			(xy 340.471147 -290.432894) (xy 340.451199 -290.386074) (xy 340.43902 -290.33666) (xy 340.434925 -290.285932)
			(xy 340.116414 -290.285932) (xy 340.115919 -290.310539) (xy 340.108024 -290.359116) (xy 340.09244 -290.405797)
			(xy 340.069569 -290.449374) (xy 340.040004 -290.488718) (xy 340.004511 -290.52281) (xy 339.964008 -290.550766)
			(xy 339.919546 -290.571864) (xy 339.872275 -290.585556) (xy 339.82342 -290.591488) (xy 339.774245 -290.589507)
			(xy 339.726026 -290.579663) (xy 339.68001 -290.562211) (xy 339.637389 -290.537604) (xy 339.599268 -290.506479)
			(xy 339.566633 -290.469642) (xy 339.54033 -290.428046) (xy 339.521039 -290.38277) (xy 339.509262 -290.334986)
			(xy 339.505302 -290.285932) (xy 339.186774 -290.285932) (xy 339.186262 -290.311378) (xy 339.178098 -290.361612)
			(xy 339.161982 -290.409886) (xy 339.138331 -290.454949) (xy 339.107758 -290.495635) (xy 339.071054 -290.53089)
			(xy 339.02917 -290.5598) (xy 338.983191 -290.581617) (xy 338.934307 -290.595777) (xy 338.883786 -290.601911)
			(xy 338.832934 -290.599862) (xy 338.78307 -290.589682) (xy 338.735484 -290.571635) (xy 338.69141 -290.546189)
			(xy 338.651988 -290.514002) (xy 338.61824 -290.475908) (xy 338.591039 -290.432894) (xy 338.571091 -290.386074)
			(xy 338.558912 -290.33666) (xy 338.554817 -290.285932) (xy 338.23577 -290.285932) (xy 338.235278 -290.315835)
			(xy 338.22645 -290.364677) (xy 338.209843 -290.411449) (xy 338.185893 -290.454922) (xy 338.155231 -290.493952)
			(xy 338.118663 -290.527512) (xy 338.09813 -290.541456) (xy 338.0783 -290.553939) (xy 338.035645 -290.573332)
			(xy 337.990529 -290.585985) (xy 337.96732 -290.589208) (xy 337.967066 -290.589208) (xy 337.958091 -290.590572)
			(xy 337.941878 -290.598709) (xy 337.929498 -290.611968) (xy 337.925664 -290.620196) (xy 337.886294 -290.714938)
			(xy 337.890104 -290.741862) (xy 337.898486 -290.752784) (xy 337.922857 -290.785023) (xy 337.963024 -290.855149)
			(xy 337.978496 -290.892484) (xy 337.983576 -290.905438) (xy 338.00542 -290.922456) (xy 338.075524 -290.931346)
			(xy 338.081874 -290.931854) (xy 338.11718 -290.931854) (xy 338.129003 -290.931306) (xy 338.150199 -290.920843)
			(xy 338.15782 -290.911788) (xy 338.172327 -290.893308) (xy 338.206063 -290.860611) (xy 338.244412 -290.833473)
			(xy 338.286469 -290.812536) (xy 338.331238 -290.798293) (xy 338.377662 -290.791083) (xy 338.401152 -290.79063)
			(xy 338.426409 -290.791119) (xy 338.476236 -290.799426) (xy 338.524015 -290.815822) (xy 338.568443 -290.839859)
			(xy 338.608309 -290.870882) (xy 338.642524 -290.908044) (xy 338.670155 -290.950331) (xy 338.690448 -290.99659)
			(xy 338.70285 -291.045558) (xy 338.707022 -291.0959) (xy 338.707019 -291.095938) (xy 339.024971 -291.095938)
			(xy 339.029066 -291.04521) (xy 339.041245 -290.995796) (xy 339.061193 -290.948976) (xy 339.088394 -290.905962)
			(xy 339.122142 -290.867868) (xy 339.161564 -290.835681) (xy 339.205638 -290.810235) (xy 339.253224 -290.792188)
			(xy 339.303088 -290.782008) (xy 339.35394 -290.779959) (xy 339.404461 -290.786093) (xy 339.453345 -290.800253)
			(xy 339.499324 -290.82207) (xy 339.541208 -290.85098) (xy 339.577912 -290.886235) (xy 339.608485 -290.926921)
			(xy 339.632136 -290.971984) (xy 339.648252 -291.020258) (xy 339.656416 -291.070492) (xy 339.656928 -291.095938)
			(xy 339.964771 -291.095938) (xy 339.968866 -291.04521) (xy 339.981045 -290.995796) (xy 340.000993 -290.948976)
			(xy 340.028194 -290.905962) (xy 340.061942 -290.867868) (xy 340.101364 -290.835681) (xy 340.145438 -290.810235)
			(xy 340.193024 -290.792188) (xy 340.242888 -290.782008) (xy 340.29374 -290.779959) (xy 340.344261 -290.786093)
			(xy 340.393145 -290.800253) (xy 340.439124 -290.82207) (xy 340.481008 -290.85098) (xy 340.517712 -290.886235)
			(xy 340.548285 -290.926921) (xy 340.571936 -290.971984) (xy 340.588052 -291.020258) (xy 340.596216 -291.070492)
			(xy 340.596728 -291.095938) (xy 340.915256 -291.095938) (xy 340.919216 -291.046884) (xy 340.930993 -290.9991)
			(xy 340.950284 -290.953824) (xy 340.976587 -290.912228) (xy 341.009222 -290.875391) (xy 341.047343 -290.844266)
			(xy 341.089964 -290.819659) (xy 341.13598 -290.802207) (xy 341.184199 -290.792363) (xy 341.233374 -290.790382)
			(xy 341.282229 -290.796314) (xy 341.3295 -290.810006) (xy 341.373962 -290.831104) (xy 341.414465 -290.85906)
			(xy 341.449958 -290.893152) (xy 341.479523 -290.932496) (xy 341.502394 -290.976073) (xy 341.517978 -291.022754)
			(xy 341.525873 -291.071331) (xy 341.526368 -291.095938) (xy 341.844879 -291.095938) (xy 341.848974 -291.04521)
			(xy 341.861153 -290.995796) (xy 341.881101 -290.948976) (xy 341.908302 -290.905962) (xy 341.94205 -290.867868)
			(xy 341.981472 -290.835681) (xy 342.025546 -290.810235) (xy 342.073132 -290.792188) (xy 342.122996 -290.782008)
			(xy 342.173848 -290.779959) (xy 342.224369 -290.786093) (xy 342.273253 -290.800253) (xy 342.319232 -290.82207)
			(xy 342.361116 -290.85098) (xy 342.39782 -290.886235) (xy 342.428393 -290.926921) (xy 342.452044 -290.971984)
			(xy 342.46816 -291.020258) (xy 342.476324 -291.070492) (xy 342.476836 -291.095938) (xy 342.795364 -291.095938)
			(xy 342.799324 -291.046884) (xy 342.811101 -290.9991) (xy 342.830392 -290.953824) (xy 342.856695 -290.912228)
			(xy 342.88933 -290.875391) (xy 342.927451 -290.844266) (xy 342.970072 -290.819659) (xy 343.016088 -290.802207)
			(xy 343.064307 -290.792363) (xy 343.113482 -290.790382) (xy 343.162337 -290.796314) (xy 343.209608 -290.810006)
			(xy 343.25407 -290.831104) (xy 343.294573 -290.85906) (xy 343.330066 -290.893152) (xy 343.359631 -290.932496)
			(xy 343.382502 -290.976073) (xy 343.398086 -291.022754) (xy 343.405981 -291.071331) (xy 343.406476 -291.095938)
			(xy 343.724987 -291.095938) (xy 343.729082 -291.04521) (xy 343.741261 -290.995796) (xy 343.761209 -290.948976)
			(xy 343.78841 -290.905962) (xy 343.822158 -290.867868) (xy 343.86158 -290.835681) (xy 343.905654 -290.810235)
			(xy 343.95324 -290.792188) (xy 344.003104 -290.782008) (xy 344.053956 -290.779959) (xy 344.104477 -290.786093)
			(xy 344.153361 -290.800253) (xy 344.19934 -290.82207) (xy 344.241224 -290.85098) (xy 344.277928 -290.886235)
			(xy 344.308501 -290.926921) (xy 344.332152 -290.971984) (xy 344.348268 -291.020258) (xy 344.356432 -291.070492)
			(xy 344.356944 -291.095938) (xy 344.356432 -291.121384) (xy 344.348268 -291.171618) (xy 344.332152 -291.219892)
			(xy 344.308501 -291.264955) (xy 344.277928 -291.305641) (xy 344.241224 -291.340896) (xy 344.19934 -291.369806)
			(xy 344.153361 -291.391623) (xy 344.104477 -291.405783) (xy 344.053956 -291.411917) (xy 344.003104 -291.409868)
			(xy 343.95324 -291.399688) (xy 343.905654 -291.381641) (xy 343.86158 -291.356195) (xy 343.822158 -291.324008)
			(xy 343.78841 -291.285914) (xy 343.761209 -291.2429) (xy 343.741261 -291.19608) (xy 343.729082 -291.146666)
			(xy 343.724987 -291.095938) (xy 343.406476 -291.095938) (xy 343.405981 -291.120545) (xy 343.398086 -291.169122)
			(xy 343.382502 -291.215803) (xy 343.359631 -291.25938) (xy 343.330066 -291.298724) (xy 343.294573 -291.332816)
			(xy 343.25407 -291.360772) (xy 343.209608 -291.38187) (xy 343.162337 -291.395562) (xy 343.113482 -291.401494)
			(xy 343.064307 -291.399513) (xy 343.016088 -291.389669) (xy 342.970072 -291.372217) (xy 342.927451 -291.34761)
			(xy 342.88933 -291.316485) (xy 342.856695 -291.279648) (xy 342.830392 -291.238052) (xy 342.811101 -291.192776)
			(xy 342.799324 -291.144992) (xy 342.795364 -291.095938) (xy 342.476836 -291.095938) (xy 342.476324 -291.121384)
			(xy 342.46816 -291.171618) (xy 342.452044 -291.219892) (xy 342.428393 -291.264955) (xy 342.39782 -291.305641)
			(xy 342.361116 -291.340896) (xy 342.319232 -291.369806) (xy 342.273253 -291.391623) (xy 342.224369 -291.405783)
			(xy 342.173848 -291.411917) (xy 342.122996 -291.409868) (xy 342.073132 -291.399688) (xy 342.025546 -291.381641)
			(xy 341.981472 -291.356195) (xy 341.94205 -291.324008) (xy 341.908302 -291.285914) (xy 341.881101 -291.2429)
			(xy 341.861153 -291.19608) (xy 341.848974 -291.146666) (xy 341.844879 -291.095938) (xy 341.526368 -291.095938)
			(xy 341.525873 -291.120545) (xy 341.517978 -291.169122) (xy 341.502394 -291.215803) (xy 341.479523 -291.25938)
			(xy 341.449958 -291.298724) (xy 341.414465 -291.332816) (xy 341.373962 -291.360772) (xy 341.3295 -291.38187)
			(xy 341.282229 -291.395562) (xy 341.233374 -291.401494) (xy 341.184199 -291.399513) (xy 341.13598 -291.389669)
			(xy 341.089964 -291.372217) (xy 341.047343 -291.34761) (xy 341.009222 -291.316485) (xy 340.976587 -291.279648)
			(xy 340.950284 -291.238052) (xy 340.930993 -291.192776) (xy 340.919216 -291.144992) (xy 340.915256 -291.095938)
			(xy 340.596728 -291.095938) (xy 340.596216 -291.121384) (xy 340.588052 -291.171618) (xy 340.571936 -291.219892)
			(xy 340.548285 -291.264955) (xy 340.517712 -291.305641) (xy 340.481008 -291.340896) (xy 340.439124 -291.369806)
			(xy 340.393145 -291.391623) (xy 340.344261 -291.405783) (xy 340.29374 -291.411917) (xy 340.242888 -291.409868)
			(xy 340.193024 -291.399688) (xy 340.145438 -291.381641) (xy 340.101364 -291.356195) (xy 340.061942 -291.324008)
			(xy 340.028194 -291.285914) (xy 340.000993 -291.2429) (xy 339.981045 -291.19608) (xy 339.968866 -291.146666)
			(xy 339.964771 -291.095938) (xy 339.656928 -291.095938) (xy 339.656416 -291.121384) (xy 339.648252 -291.171618)
			(xy 339.632136 -291.219892) (xy 339.608485 -291.264955) (xy 339.577912 -291.305641) (xy 339.541208 -291.340896)
			(xy 339.499324 -291.369806) (xy 339.453345 -291.391623) (xy 339.404461 -291.405783) (xy 339.35394 -291.411917)
			(xy 339.303088 -291.409868) (xy 339.253224 -291.399688) (xy 339.205638 -291.381641) (xy 339.161564 -291.356195)
			(xy 339.122142 -291.324008) (xy 339.088394 -291.285914) (xy 339.061193 -291.2429) (xy 339.041245 -291.19608)
			(xy 339.029066 -291.146666) (xy 339.024971 -291.095938) (xy 338.707019 -291.095938) (xy 338.70285 -291.146242)
			(xy 338.690448 -291.19521) (xy 338.670155 -291.241469) (xy 338.642524 -291.283756) (xy 338.608309 -291.320918)
			(xy 338.568443 -291.351941) (xy 338.524015 -291.375978) (xy 338.476236 -291.392374) (xy 338.426409 -291.400681)
			(xy 338.401152 -291.401246) (xy 338.377666 -291.400789) (xy 338.331254 -291.393547) (xy 338.286498 -291.379288)
			(xy 338.244451 -291.358346) (xy 338.206104 -291.331216) (xy 338.172362 -291.298537) (xy 338.15782 -291.280088)
			(xy 338.150176 -291.271064) (xy 338.128992 -291.260611) (xy 338.11718 -291.260022) (xy 338.081874 -291.260022)
			(xy 338.075524 -291.26053) (xy 338.00542 -291.26942) (xy 337.983576 -291.286438) (xy 337.978496 -291.299392)
			(xy 337.965288 -291.33038) (xy 337.959955 -291.341719) (xy 337.948394 -291.363953) (xy 337.942174 -291.37483)
			(xy 337.912964 -291.425122) (xy 337.897724 -291.451538) (xy 337.891942 -291.462687) (xy 337.890994 -291.487751)
			(xy 337.895946 -291.49929) (xy 337.938618 -291.58692) (xy 337.958938 -291.601652) (xy 337.971892 -291.60343)
			(xy 337.995985 -291.607167) (xy 338.042647 -291.621291) (xy 338.086471 -291.64265) (xy 338.126344 -291.670703)
			(xy 338.161253 -291.704735) (xy 338.19031 -291.743882) (xy 338.212778 -291.787149) (xy 338.228084 -291.833436)
			(xy 338.23584 -291.881568) (xy 338.236306 -291.905944) (xy 338.554817 -291.905944) (xy 338.558912 -291.855216)
			(xy 338.571091 -291.805802) (xy 338.591039 -291.758982) (xy 338.61824 -291.715968) (xy 338.651988 -291.677874)
			(xy 338.69141 -291.645687) (xy 338.735484 -291.620241) (xy 338.78307 -291.602194) (xy 338.832934 -291.592014)
			(xy 338.883786 -291.589965) (xy 338.934307 -291.596099) (xy 338.983191 -291.610259) (xy 339.02917 -291.632076)
			(xy 339.071054 -291.660986) (xy 339.107758 -291.696241) (xy 339.138331 -291.736927) (xy 339.161982 -291.78199)
			(xy 339.178098 -291.830264) (xy 339.186262 -291.880498) (xy 339.186774 -291.905944) (xy 339.505302 -291.905944)
			(xy 339.509262 -291.85689) (xy 339.521039 -291.809106) (xy 339.54033 -291.76383) (xy 339.566633 -291.722234)
			(xy 339.599268 -291.685397) (xy 339.637389 -291.654272) (xy 339.68001 -291.629665) (xy 339.726026 -291.612213)
			(xy 339.774245 -291.602369) (xy 339.82342 -291.600388) (xy 339.872275 -291.60632) (xy 339.919546 -291.620012)
			(xy 339.964008 -291.64111) (xy 340.004511 -291.669066) (xy 340.040004 -291.703158) (xy 340.069569 -291.742502)
			(xy 340.09244 -291.786079) (xy 340.108024 -291.83276) (xy 340.115919 -291.881337) (xy 340.116414 -291.905944)
			(xy 340.434925 -291.905944) (xy 340.43902 -291.855216) (xy 340.451199 -291.805802) (xy 340.471147 -291.758982)
			(xy 340.498348 -291.715968) (xy 340.532096 -291.677874) (xy 340.571518 -291.645687) (xy 340.615592 -291.620241)
			(xy 340.663178 -291.602194) (xy 340.713042 -291.592014) (xy 340.763894 -291.589965) (xy 340.814415 -291.596099)
			(xy 340.863299 -291.610259) (xy 340.909278 -291.632076) (xy 340.951162 -291.660986) (xy 340.987866 -291.696241)
			(xy 341.018439 -291.736927) (xy 341.04209 -291.78199) (xy 341.058206 -291.830264) (xy 341.06637 -291.880498)
			(xy 341.066882 -291.905944) (xy 341.38541 -291.905944) (xy 341.38937 -291.85689) (xy 341.401147 -291.809106)
			(xy 341.420438 -291.76383) (xy 341.446741 -291.722234) (xy 341.479376 -291.685397) (xy 341.517497 -291.654272)
			(xy 341.560118 -291.629665) (xy 341.606134 -291.612213) (xy 341.654353 -291.602369) (xy 341.703528 -291.600388)
			(xy 341.752383 -291.60632) (xy 341.799654 -291.620012) (xy 341.844116 -291.64111) (xy 341.884619 -291.669066)
			(xy 341.920112 -291.703158) (xy 341.949677 -291.742502) (xy 341.972548 -291.786079) (xy 341.988132 -291.83276)
			(xy 341.996027 -291.881337) (xy 341.996522 -291.905944) (xy 342.314779 -291.905944) (xy 342.318874 -291.855216)
			(xy 342.331053 -291.805802) (xy 342.351001 -291.758982) (xy 342.378202 -291.715968) (xy 342.41195 -291.677874)
			(xy 342.451372 -291.645687) (xy 342.495446 -291.620241) (xy 342.543032 -291.602194) (xy 342.592896 -291.592014)
			(xy 342.643748 -291.589965) (xy 342.694269 -291.596099) (xy 342.743153 -291.610259) (xy 342.789132 -291.632076)
			(xy 342.831016 -291.660986) (xy 342.86772 -291.696241) (xy 342.898293 -291.736927) (xy 342.921944 -291.78199)
			(xy 342.93806 -291.830264) (xy 342.946224 -291.880498) (xy 342.946736 -291.905944) (xy 343.254833 -291.905944)
			(xy 343.258928 -291.855216) (xy 343.271107 -291.805802) (xy 343.291055 -291.758982) (xy 343.318256 -291.715968)
			(xy 343.352004 -291.677874) (xy 343.391426 -291.645687) (xy 343.4355 -291.620241) (xy 343.483086 -291.602194)
			(xy 343.53295 -291.592014) (xy 343.583802 -291.589965) (xy 343.634323 -291.596099) (xy 343.683207 -291.610259)
			(xy 343.729186 -291.632076) (xy 343.77107 -291.660986) (xy 343.807774 -291.696241) (xy 343.838347 -291.736927)
			(xy 343.861998 -291.78199) (xy 343.878114 -291.830264) (xy 343.886278 -291.880498) (xy 343.88679 -291.905944)
			(xy 343.886278 -291.93139) (xy 343.878114 -291.981624) (xy 343.861998 -292.029898) (xy 343.838347 -292.074961)
			(xy 343.807774 -292.115647) (xy 343.77107 -292.150902) (xy 343.729186 -292.179812) (xy 343.683207 -292.201629)
			(xy 343.634323 -292.215789) (xy 343.583802 -292.221923) (xy 343.53295 -292.219874) (xy 343.483086 -292.209694)
			(xy 343.4355 -292.191647) (xy 343.391426 -292.166201) (xy 343.352004 -292.134014) (xy 343.318256 -292.09592)
			(xy 343.291055 -292.052906) (xy 343.271107 -292.006086) (xy 343.258928 -291.956672) (xy 343.254833 -291.905944)
			(xy 342.946736 -291.905944) (xy 342.946224 -291.93139) (xy 342.93806 -291.981624) (xy 342.921944 -292.029898)
			(xy 342.898293 -292.074961) (xy 342.86772 -292.115647) (xy 342.831016 -292.150902) (xy 342.789132 -292.179812)
			(xy 342.743153 -292.201629) (xy 342.694269 -292.215789) (xy 342.643748 -292.221923) (xy 342.592896 -292.219874)
			(xy 342.543032 -292.209694) (xy 342.495446 -292.191647) (xy 342.451372 -292.166201) (xy 342.41195 -292.134014)
			(xy 342.378202 -292.09592) (xy 342.351001 -292.052906) (xy 342.331053 -292.006086) (xy 342.318874 -291.956672)
			(xy 342.314779 -291.905944) (xy 341.996522 -291.905944) (xy 341.996027 -291.930551) (xy 341.988132 -291.979128)
			(xy 341.972548 -292.025809) (xy 341.949677 -292.069386) (xy 341.920112 -292.10873) (xy 341.884619 -292.142822)
			(xy 341.844116 -292.170778) (xy 341.799654 -292.191876) (xy 341.752383 -292.205568) (xy 341.703528 -292.2115)
			(xy 341.654353 -292.209519) (xy 341.606134 -292.199675) (xy 341.560118 -292.182223) (xy 341.517497 -292.157616)
			(xy 341.479376 -292.126491) (xy 341.446741 -292.089654) (xy 341.420438 -292.048058) (xy 341.401147 -292.002782)
			(xy 341.38937 -291.954998) (xy 341.38541 -291.905944) (xy 341.066882 -291.905944) (xy 341.06637 -291.93139)
			(xy 341.058206 -291.981624) (xy 341.04209 -292.029898) (xy 341.018439 -292.074961) (xy 340.987866 -292.115647)
			(xy 340.951162 -292.150902) (xy 340.909278 -292.179812) (xy 340.863299 -292.201629) (xy 340.814415 -292.215789)
			(xy 340.763894 -292.221923) (xy 340.713042 -292.219874) (xy 340.663178 -292.209694) (xy 340.615592 -292.191647)
			(xy 340.571518 -292.166201) (xy 340.532096 -292.134014) (xy 340.498348 -292.09592) (xy 340.471147 -292.052906)
			(xy 340.451199 -292.006086) (xy 340.43902 -291.956672) (xy 340.434925 -291.905944) (xy 340.116414 -291.905944)
			(xy 340.115919 -291.930551) (xy 340.108024 -291.979128) (xy 340.09244 -292.025809) (xy 340.069569 -292.069386)
			(xy 340.040004 -292.10873) (xy 340.004511 -292.142822) (xy 339.964008 -292.170778) (xy 339.919546 -292.191876)
			(xy 339.872275 -292.205568) (xy 339.82342 -292.2115) (xy 339.774245 -292.209519) (xy 339.726026 -292.199675)
			(xy 339.68001 -292.182223) (xy 339.637389 -292.157616) (xy 339.599268 -292.126491) (xy 339.566633 -292.089654)
			(xy 339.54033 -292.048058) (xy 339.521039 -292.002782) (xy 339.509262 -291.954998) (xy 339.505302 -291.905944)
			(xy 339.186774 -291.905944) (xy 339.186262 -291.93139) (xy 339.178098 -291.981624) (xy 339.161982 -292.029898)
			(xy 339.138331 -292.074961) (xy 339.107758 -292.115647) (xy 339.071054 -292.150902) (xy 339.02917 -292.179812)
			(xy 338.983191 -292.201629) (xy 338.934307 -292.215789) (xy 338.883786 -292.221923) (xy 338.832934 -292.219874)
			(xy 338.78307 -292.209694) (xy 338.735484 -292.191647) (xy 338.69141 -292.166201) (xy 338.651988 -292.134014)
			(xy 338.61824 -292.09592) (xy 338.591039 -292.052906) (xy 338.571091 -292.006086) (xy 338.558912 -291.956672)
			(xy 338.554817 -291.905944) (xy 338.236306 -291.905944) (xy 338.235817 -291.930762) (xy 338.22778 -291.979743)
			(xy 338.211926 -292.02678) (xy 338.188672 -292.070632) (xy 338.15863 -292.110144) (xy 338.122593 -292.144277)
			(xy 338.081508 -292.172131) (xy 338.036459 -292.192971) (xy 337.988632 -292.20625) (xy 337.964018 -292.209474)
			(xy 337.950048 -292.210998) (xy 337.92795 -292.227508) (xy 337.888072 -292.32225) (xy 337.884913 -292.330779)
			(xy 337.884181 -292.348941) (xy 337.889804 -292.366226) (xy 337.895184 -292.373558) (xy 337.897724 -292.37686)
			(xy 337.921657 -292.408774) (xy 337.961055 -292.478136) (xy 337.97621 -292.515036) (xy 337.98129 -292.528244)
			(xy 338.00288 -292.545262) (xy 338.119466 -292.560248) (xy 338.144866 -292.549072) (xy 338.153248 -292.537642)
			(xy 338.167714 -292.518344) (xy 338.201704 -292.484128) (xy 338.240644 -292.455674) (xy 338.283568 -292.433685)
			(xy 338.329411 -292.418708) (xy 338.377038 -292.411113) (xy 338.401152 -292.410642) (xy 338.426408 -292.411131)
			(xy 338.476233 -292.419438) (xy 338.52401 -292.435833) (xy 338.568437 -292.45987) (xy 338.608301 -292.490891)
			(xy 338.642515 -292.528052) (xy 338.670145 -292.570337) (xy 338.690437 -292.616594) (xy 338.702838 -292.66556)
			(xy 338.70701 -292.7159) (xy 338.707006 -292.71595) (xy 339.024971 -292.71595) (xy 339.029066 -292.665222)
			(xy 339.041245 -292.615808) (xy 339.061193 -292.568988) (xy 339.088394 -292.525974) (xy 339.122142 -292.48788)
			(xy 339.161564 -292.455693) (xy 339.205638 -292.430247) (xy 339.253224 -292.4122) (xy 339.303088 -292.40202)
			(xy 339.35394 -292.399971) (xy 339.404461 -292.406105) (xy 339.453345 -292.420265) (xy 339.499324 -292.442082)
			(xy 339.541208 -292.470992) (xy 339.577912 -292.506247) (xy 339.608485 -292.546933) (xy 339.632136 -292.591996)
			(xy 339.648252 -292.64027) (xy 339.656416 -292.690504) (xy 339.656928 -292.71595) (xy 339.964771 -292.71595)
			(xy 339.968866 -292.665222) (xy 339.981045 -292.615808) (xy 340.000993 -292.568988) (xy 340.028194 -292.525974)
			(xy 340.061942 -292.48788) (xy 340.101364 -292.455693) (xy 340.145438 -292.430247) (xy 340.193024 -292.4122)
			(xy 340.242888 -292.40202) (xy 340.29374 -292.399971) (xy 340.344261 -292.406105) (xy 340.393145 -292.420265)
			(xy 340.439124 -292.442082) (xy 340.481008 -292.470992) (xy 340.517712 -292.506247) (xy 340.548285 -292.546933)
			(xy 340.571936 -292.591996) (xy 340.588052 -292.64027) (xy 340.596216 -292.690504) (xy 340.596728 -292.71595)
			(xy 340.915256 -292.71595) (xy 340.919216 -292.666896) (xy 340.930993 -292.619112) (xy 340.950284 -292.573836)
			(xy 340.976587 -292.53224) (xy 341.009222 -292.495403) (xy 341.047343 -292.464278) (xy 341.089964 -292.439671)
			(xy 341.13598 -292.422219) (xy 341.184199 -292.412375) (xy 341.233374 -292.410394) (xy 341.282229 -292.416326)
			(xy 341.3295 -292.430018) (xy 341.373962 -292.451116) (xy 341.414465 -292.479072) (xy 341.449958 -292.513164)
			(xy 341.479523 -292.552508) (xy 341.502394 -292.596085) (xy 341.517978 -292.642766) (xy 341.525873 -292.691343)
			(xy 341.526368 -292.71595) (xy 341.844879 -292.71595) (xy 341.848974 -292.665222) (xy 341.861153 -292.615808)
			(xy 341.881101 -292.568988) (xy 341.908302 -292.525974) (xy 341.94205 -292.48788) (xy 341.981472 -292.455693)
			(xy 342.025546 -292.430247) (xy 342.073132 -292.4122) (xy 342.122996 -292.40202) (xy 342.173848 -292.399971)
			(xy 342.224369 -292.406105) (xy 342.273253 -292.420265) (xy 342.319232 -292.442082) (xy 342.361116 -292.470992)
			(xy 342.39782 -292.506247) (xy 342.428393 -292.546933) (xy 342.452044 -292.591996) (xy 342.46816 -292.64027)
			(xy 342.476324 -292.690504) (xy 342.476836 -292.71595) (xy 342.795364 -292.71595) (xy 342.799324 -292.666896)
			(xy 342.811101 -292.619112) (xy 342.830392 -292.573836) (xy 342.856695 -292.53224) (xy 342.88933 -292.495403)
			(xy 342.927451 -292.464278) (xy 342.970072 -292.439671) (xy 343.016088 -292.422219) (xy 343.064307 -292.412375)
			(xy 343.113482 -292.410394) (xy 343.162337 -292.416326) (xy 343.209608 -292.430018) (xy 343.25407 -292.451116)
			(xy 343.294573 -292.479072) (xy 343.330066 -292.513164) (xy 343.359631 -292.552508) (xy 343.382502 -292.596085)
			(xy 343.398086 -292.642766) (xy 343.405981 -292.691343) (xy 343.406476 -292.71595) (xy 343.724987 -292.71595)
			(xy 343.729082 -292.665222) (xy 343.741261 -292.615808) (xy 343.761209 -292.568988) (xy 343.78841 -292.525974)
			(xy 343.822158 -292.48788) (xy 343.86158 -292.455693) (xy 343.905654 -292.430247) (xy 343.95324 -292.4122)
			(xy 344.003104 -292.40202) (xy 344.053956 -292.399971) (xy 344.104477 -292.406105) (xy 344.153361 -292.420265)
			(xy 344.19934 -292.442082) (xy 344.241224 -292.470992) (xy 344.277928 -292.506247) (xy 344.308501 -292.546933)
			(xy 344.332152 -292.591996) (xy 344.348268 -292.64027) (xy 344.356432 -292.690504) (xy 344.356944 -292.71595)
			(xy 344.356432 -292.741396) (xy 344.348268 -292.79163) (xy 344.332152 -292.839904) (xy 344.308501 -292.884967)
			(xy 344.277928 -292.925653) (xy 344.241224 -292.960908) (xy 344.19934 -292.989818) (xy 344.153361 -293.011635)
			(xy 344.104477 -293.025795) (xy 344.053956 -293.031929) (xy 344.003104 -293.02988) (xy 343.95324 -293.0197)
			(xy 343.905654 -293.001653) (xy 343.86158 -292.976207) (xy 343.822158 -292.94402) (xy 343.78841 -292.905926)
			(xy 343.761209 -292.862912) (xy 343.741261 -292.816092) (xy 343.729082 -292.766678) (xy 343.724987 -292.71595)
			(xy 343.406476 -292.71595) (xy 343.405981 -292.740557) (xy 343.398086 -292.789134) (xy 343.382502 -292.835815)
			(xy 343.359631 -292.879392) (xy 343.330066 -292.918736) (xy 343.294573 -292.952828) (xy 343.25407 -292.980784)
			(xy 343.209608 -293.001882) (xy 343.162337 -293.015574) (xy 343.113482 -293.021506) (xy 343.064307 -293.019525)
			(xy 343.016088 -293.009681) (xy 342.970072 -292.992229) (xy 342.927451 -292.967622) (xy 342.88933 -292.936497)
			(xy 342.856695 -292.89966) (xy 342.830392 -292.858064) (xy 342.811101 -292.812788) (xy 342.799324 -292.765004)
			(xy 342.795364 -292.71595) (xy 342.476836 -292.71595) (xy 342.476324 -292.741396) (xy 342.46816 -292.79163)
			(xy 342.452044 -292.839904) (xy 342.428393 -292.884967) (xy 342.39782 -292.925653) (xy 342.361116 -292.960908)
			(xy 342.319232 -292.989818) (xy 342.273253 -293.011635) (xy 342.224369 -293.025795) (xy 342.173848 -293.031929)
			(xy 342.122996 -293.02988) (xy 342.073132 -293.0197) (xy 342.025546 -293.001653) (xy 341.981472 -292.976207)
			(xy 341.94205 -292.94402) (xy 341.908302 -292.905926) (xy 341.881101 -292.862912) (xy 341.861153 -292.816092)
			(xy 341.848974 -292.766678) (xy 341.844879 -292.71595) (xy 341.526368 -292.71595) (xy 341.525873 -292.740557)
			(xy 341.517978 -292.789134) (xy 341.502394 -292.835815) (xy 341.479523 -292.879392) (xy 341.449958 -292.918736)
			(xy 341.414465 -292.952828) (xy 341.373962 -292.980784) (xy 341.3295 -293.001882) (xy 341.282229 -293.015574)
			(xy 341.233374 -293.021506) (xy 341.184199 -293.019525) (xy 341.13598 -293.009681) (xy 341.089964 -292.992229)
			(xy 341.047343 -292.967622) (xy 341.009222 -292.936497) (xy 340.976587 -292.89966) (xy 340.950284 -292.858064)
			(xy 340.930993 -292.812788) (xy 340.919216 -292.765004) (xy 340.915256 -292.71595) (xy 340.596728 -292.71595)
			(xy 340.596216 -292.741396) (xy 340.588052 -292.79163) (xy 340.571936 -292.839904) (xy 340.548285 -292.884967)
			(xy 340.517712 -292.925653) (xy 340.481008 -292.960908) (xy 340.439124 -292.989818) (xy 340.393145 -293.011635)
			(xy 340.344261 -293.025795) (xy 340.29374 -293.031929) (xy 340.242888 -293.02988) (xy 340.193024 -293.0197)
			(xy 340.145438 -293.001653) (xy 340.101364 -292.976207) (xy 340.061942 -292.94402) (xy 340.028194 -292.905926)
			(xy 340.000993 -292.862912) (xy 339.981045 -292.816092) (xy 339.968866 -292.766678) (xy 339.964771 -292.71595)
			(xy 339.656928 -292.71595) (xy 339.656416 -292.741396) (xy 339.648252 -292.79163) (xy 339.632136 -292.839904)
			(xy 339.608485 -292.884967) (xy 339.577912 -292.925653) (xy 339.541208 -292.960908) (xy 339.499324 -292.989818)
			(xy 339.453345 -293.011635) (xy 339.404461 -293.025795) (xy 339.35394 -293.031929) (xy 339.303088 -293.02988)
			(xy 339.253224 -293.0197) (xy 339.205638 -293.001653) (xy 339.161564 -292.976207) (xy 339.122142 -292.94402)
			(xy 339.088394 -292.905926) (xy 339.061193 -292.862912) (xy 339.041245 -292.816092) (xy 339.029066 -292.766678)
			(xy 339.024971 -292.71595) (xy 338.707006 -292.71595) (xy 338.702838 -292.76624) (xy 338.690437 -292.815206)
			(xy 338.670145 -292.861463) (xy 338.642515 -292.903748) (xy 338.608301 -292.940909) (xy 338.568437 -292.97193)
			(xy 338.52401 -292.995967) (xy 338.476233 -293.012362) (xy 338.426408 -293.020669) (xy 338.401152 -293.021258)
			(xy 338.388389 -293.021119) (xy 338.362955 -293.018956) (xy 338.350352 -293.01694) (xy 338.350352 -293.017194)
			(xy 338.326898 -293.012769) (xy 338.281641 -292.997611) (xy 338.239287 -292.975609) (xy 338.200863 -292.947297)
			(xy 338.167302 -292.913362) (xy 338.152994 -292.894258) (xy 338.144866 -292.882828) (xy 338.119212 -292.871652)
			(xy 338.017104 -292.88486) (xy 338.003134 -292.886638) (xy 337.98129 -292.903656) (xy 337.97621 -292.916864)
			(xy 337.969352 -292.933374) (xy 337.962654 -292.948745) (xy 337.947658 -292.978737) (xy 337.93938 -292.993318)
			(xy 337.894168 -293.071296) (xy 337.892644 -293.07409) (xy 337.892644 -293.074344) (xy 337.887951 -293.085165)
			(xy 337.887971 -293.108724) (xy 337.892644 -293.119556) (xy 337.929474 -293.193978) (xy 337.935089 -293.204587)
			(xy 337.953919 -293.219418) (xy 337.965542 -293.222426) (xy 337.969098 -293.222934) (xy 337.993389 -293.226476)
			(xy 338.040487 -293.240301) (xy 338.084766 -293.261486) (xy 338.125084 -293.289484) (xy 338.160402 -293.323573)
			(xy 338.189809 -293.362875) (xy 338.212548 -293.406376) (xy 338.228032 -293.452956) (xy 338.235863 -293.501413)
			(xy 338.236306 -293.525956) (xy 338.554817 -293.525956) (xy 338.558912 -293.475228) (xy 338.571091 -293.425814)
			(xy 338.591039 -293.378994) (xy 338.61824 -293.33598) (xy 338.651988 -293.297886) (xy 338.69141 -293.265699)
			(xy 338.735484 -293.240253) (xy 338.78307 -293.222206) (xy 338.832934 -293.212026) (xy 338.883786 -293.209977)
			(xy 338.934307 -293.216111) (xy 338.983191 -293.230271) (xy 339.02917 -293.252088) (xy 339.071054 -293.280998)
			(xy 339.107758 -293.316253) (xy 339.138331 -293.356939) (xy 339.161982 -293.402002) (xy 339.178098 -293.450276)
			(xy 339.186262 -293.50051) (xy 339.186774 -293.525956) (xy 339.505302 -293.525956) (xy 339.509262 -293.476902)
			(xy 339.521039 -293.429118) (xy 339.54033 -293.383842) (xy 339.566633 -293.342246) (xy 339.599268 -293.305409)
			(xy 339.637389 -293.274284) (xy 339.68001 -293.249677) (xy 339.726026 -293.232225) (xy 339.774245 -293.222381)
			(xy 339.82342 -293.2204) (xy 339.872275 -293.226332) (xy 339.919546 -293.240024) (xy 339.964008 -293.261122)
			(xy 340.004511 -293.289078) (xy 340.040004 -293.32317) (xy 340.069569 -293.362514) (xy 340.09244 -293.406091)
			(xy 340.108024 -293.452772) (xy 340.115919 -293.501349) (xy 340.116414 -293.525956) (xy 340.445356 -293.525956)
			(xy 340.449316 -293.476902) (xy 340.461093 -293.429118) (xy 340.480384 -293.383842) (xy 340.506687 -293.342246)
			(xy 340.539322 -293.305409) (xy 340.577443 -293.274284) (xy 340.620064 -293.249677) (xy 340.66608 -293.232225)
			(xy 340.714299 -293.222381) (xy 340.763474 -293.2204) (xy 340.812329 -293.226332) (xy 340.8596 -293.240024)
			(xy 340.904062 -293.261122) (xy 340.944565 -293.289078) (xy 340.980058 -293.32317) (xy 341.009623 -293.362514)
			(xy 341.032494 -293.406091) (xy 341.048078 -293.452772) (xy 341.055973 -293.501349) (xy 341.056468 -293.525956)
			(xy 341.38541 -293.525956) (xy 341.38937 -293.476902) (xy 341.401147 -293.429118) (xy 341.420438 -293.383842)
			(xy 341.446741 -293.342246) (xy 341.479376 -293.305409) (xy 341.517497 -293.274284) (xy 341.560118 -293.249677)
			(xy 341.606134 -293.232225) (xy 341.654353 -293.222381) (xy 341.703528 -293.2204) (xy 341.752383 -293.226332)
			(xy 341.799654 -293.240024) (xy 341.844116 -293.261122) (xy 341.884619 -293.289078) (xy 341.920112 -293.32317)
			(xy 341.949677 -293.362514) (xy 341.972548 -293.406091) (xy 341.988132 -293.452772) (xy 341.996027 -293.501349)
			(xy 341.996522 -293.525956) (xy 342.32521 -293.525956) (xy 342.32917 -293.476902) (xy 342.340947 -293.429118)
			(xy 342.360238 -293.383842) (xy 342.386541 -293.342246) (xy 342.419176 -293.305409) (xy 342.457297 -293.274284)
			(xy 342.499918 -293.249677) (xy 342.545934 -293.232225) (xy 342.594153 -293.222381) (xy 342.643328 -293.2204)
			(xy 342.692183 -293.226332) (xy 342.739454 -293.240024) (xy 342.783916 -293.261122) (xy 342.824419 -293.289078)
			(xy 342.859912 -293.32317) (xy 342.889477 -293.362514) (xy 342.912348 -293.406091) (xy 342.927932 -293.452772)
			(xy 342.935827 -293.501349) (xy 342.936322 -293.525956) (xy 343.254833 -293.525956) (xy 343.258928 -293.475228)
			(xy 343.271107 -293.425814) (xy 343.291055 -293.378994) (xy 343.318256 -293.33598) (xy 343.352004 -293.297886)
			(xy 343.391426 -293.265699) (xy 343.4355 -293.240253) (xy 343.483086 -293.222206) (xy 343.53295 -293.212026)
			(xy 343.583802 -293.209977) (xy 343.634323 -293.216111) (xy 343.683207 -293.230271) (xy 343.729186 -293.252088)
			(xy 343.77107 -293.280998) (xy 343.807774 -293.316253) (xy 343.838347 -293.356939) (xy 343.861998 -293.402002)
			(xy 343.878114 -293.450276) (xy 343.886278 -293.50051) (xy 343.88679 -293.525956) (xy 343.886278 -293.551402)
			(xy 343.878114 -293.601636) (xy 343.861998 -293.64991) (xy 343.838347 -293.694973) (xy 343.807774 -293.735659)
			(xy 343.77107 -293.770914) (xy 343.729186 -293.799824) (xy 343.683207 -293.821641) (xy 343.634323 -293.835801)
			(xy 343.583802 -293.841935) (xy 343.53295 -293.839886) (xy 343.483086 -293.829706) (xy 343.4355 -293.811659)
			(xy 343.391426 -293.786213) (xy 343.352004 -293.754026) (xy 343.318256 -293.715932) (xy 343.291055 -293.672918)
			(xy 343.271107 -293.626098) (xy 343.258928 -293.576684) (xy 343.254833 -293.525956) (xy 342.936322 -293.525956)
			(xy 342.935827 -293.550563) (xy 342.927932 -293.59914) (xy 342.912348 -293.645821) (xy 342.889477 -293.689398)
			(xy 342.859912 -293.728742) (xy 342.824419 -293.762834) (xy 342.783916 -293.79079) (xy 342.739454 -293.811888)
			(xy 342.692183 -293.82558) (xy 342.643328 -293.831512) (xy 342.594153 -293.829531) (xy 342.545934 -293.819687)
			(xy 342.499918 -293.802235) (xy 342.457297 -293.777628) (xy 342.419176 -293.746503) (xy 342.386541 -293.709666)
			(xy 342.360238 -293.66807) (xy 342.340947 -293.622794) (xy 342.32917 -293.57501) (xy 342.32521 -293.525956)
			(xy 341.996522 -293.525956) (xy 341.996027 -293.550563) (xy 341.988132 -293.59914) (xy 341.972548 -293.645821)
			(xy 341.949677 -293.689398) (xy 341.920112 -293.728742) (xy 341.884619 -293.762834) (xy 341.844116 -293.79079)
			(xy 341.799654 -293.811888) (xy 341.752383 -293.82558) (xy 341.703528 -293.831512) (xy 341.654353 -293.829531)
			(xy 341.606134 -293.819687) (xy 341.560118 -293.802235) (xy 341.517497 -293.777628) (xy 341.479376 -293.746503)
			(xy 341.446741 -293.709666) (xy 341.420438 -293.66807) (xy 341.401147 -293.622794) (xy 341.38937 -293.57501)
			(xy 341.38541 -293.525956) (xy 341.056468 -293.525956) (xy 341.055973 -293.550563) (xy 341.048078 -293.59914)
			(xy 341.032494 -293.645821) (xy 341.009623 -293.689398) (xy 340.980058 -293.728742) (xy 340.944565 -293.762834)
			(xy 340.904062 -293.79079) (xy 340.8596 -293.811888) (xy 340.812329 -293.82558) (xy 340.763474 -293.831512)
			(xy 340.714299 -293.829531) (xy 340.66608 -293.819687) (xy 340.620064 -293.802235) (xy 340.577443 -293.777628)
			(xy 340.539322 -293.746503) (xy 340.506687 -293.709666) (xy 340.480384 -293.66807) (xy 340.461093 -293.622794)
			(xy 340.449316 -293.57501) (xy 340.445356 -293.525956) (xy 340.116414 -293.525956) (xy 340.115919 -293.550563)
			(xy 340.108024 -293.59914) (xy 340.09244 -293.645821) (xy 340.069569 -293.689398) (xy 340.040004 -293.728742)
			(xy 340.004511 -293.762834) (xy 339.964008 -293.79079) (xy 339.919546 -293.811888) (xy 339.872275 -293.82558)
			(xy 339.82342 -293.831512) (xy 339.774245 -293.829531) (xy 339.726026 -293.819687) (xy 339.68001 -293.802235)
			(xy 339.637389 -293.777628) (xy 339.599268 -293.746503) (xy 339.566633 -293.709666) (xy 339.54033 -293.66807)
			(xy 339.521039 -293.622794) (xy 339.509262 -293.57501) (xy 339.505302 -293.525956) (xy 339.186774 -293.525956)
			(xy 339.186262 -293.551402) (xy 339.178098 -293.601636) (xy 339.161982 -293.64991) (xy 339.138331 -293.694973)
			(xy 339.107758 -293.735659) (xy 339.071054 -293.770914) (xy 339.02917 -293.799824) (xy 338.983191 -293.821641)
			(xy 338.934307 -293.835801) (xy 338.883786 -293.841935) (xy 338.832934 -293.839886) (xy 338.78307 -293.829706)
			(xy 338.735484 -293.811659) (xy 338.69141 -293.786213) (xy 338.651988 -293.754026) (xy 338.61824 -293.715932)
			(xy 338.591039 -293.672918) (xy 338.571091 -293.626098) (xy 338.558912 -293.576684) (xy 338.554817 -293.525956)
			(xy 338.236306 -293.525956) (xy 338.235841 -293.549924) (xy 338.228356 -293.597272) (xy 338.213563 -293.642869)
			(xy 338.191826 -293.685593) (xy 338.163679 -293.724395) (xy 338.129814 -293.758321) (xy 338.091063 -293.786538)
			(xy 338.048377 -293.808352) (xy 338.002808 -293.823227) (xy 337.955473 -293.830797) (xy 337.931506 -293.831264)
			(xy 337.930744 -293.831264) (xy 337.907559 -293.830819) (xy 337.861728 -293.823776) (xy 337.817491 -293.809876)
			(xy 337.775868 -293.789439) (xy 337.737819 -293.762936) (xy 337.70422 -293.730978) (xy 337.689698 -293.7129)
			(xy 337.685888 -293.708074) (xy 337.676236 -293.700454) (xy 337.668707 -293.694831) (xy 337.650832 -293.689077)
			(xy 337.641438 -293.689278) (xy 337.558888 -293.694358) (xy 337.546356 -293.695763) (xy 337.524899 -293.708952)
			(xy 337.517994 -293.719504) (xy 337.500468 -293.749476) (xy 337.500468 -293.74973) (xy 337.46948 -293.803324)
			(xy 337.459464 -293.820259) (xy 337.437343 -293.852802) (xy 337.425284 -293.868348) (xy 337.42503 -293.868602)
			(xy 337.419758 -293.875942) (xy 337.414252 -293.893142) (xy 337.415023 -293.911185) (xy 337.418172 -293.919656)
			(xy 337.452716 -294.001698) (xy 337.456591 -294.009868) (xy 337.468995 -294.02301) (xy 337.485179 -294.031049)
			(xy 337.494118 -294.032432) (xy 337.518739 -294.0356) (xy 337.566568 -294.048883) (xy 337.611618 -294.069729)
			(xy 337.652701 -294.09759) (xy 337.688735 -294.131731) (xy 337.71877 -294.171252) (xy 337.742014 -294.215112)
			(xy 337.757856 -294.262156) (xy 337.765878 -294.311142) (xy 337.766406 -294.335962) (xy 338.095348 -294.335962)
			(xy 338.099308 -294.286908) (xy 338.111085 -294.239124) (xy 338.130376 -294.193848) (xy 338.156679 -294.152252)
			(xy 338.189314 -294.115415) (xy 338.227435 -294.08429) (xy 338.270056 -294.059683) (xy 338.316072 -294.042231)
			(xy 338.364291 -294.032387) (xy 338.413466 -294.030406) (xy 338.462321 -294.036338) (xy 338.509592 -294.05003)
			(xy 338.554054 -294.071128) (xy 338.594557 -294.099084) (xy 338.63005 -294.133176) (xy 338.659615 -294.17252)
			(xy 338.682486 -294.216097) (xy 338.69807 -294.262778) (xy 338.705965 -294.311355) (xy 338.70646 -294.335962)
			(xy 339.035402 -294.335962) (xy 339.039362 -294.286908) (xy 339.051139 -294.239124) (xy 339.07043 -294.193848)
			(xy 339.096733 -294.152252) (xy 339.129368 -294.115415) (xy 339.167489 -294.08429) (xy 339.21011 -294.059683)
			(xy 339.256126 -294.042231) (xy 339.304345 -294.032387) (xy 339.35352 -294.030406) (xy 339.402375 -294.036338)
			(xy 339.449646 -294.05003) (xy 339.494108 -294.071128) (xy 339.534611 -294.099084) (xy 339.570104 -294.133176)
			(xy 339.599669 -294.17252) (xy 339.62254 -294.216097) (xy 339.638124 -294.262778) (xy 339.646019 -294.311355)
			(xy 339.646514 -294.335962) (xy 339.975202 -294.335962) (xy 339.979162 -294.286908) (xy 339.990939 -294.239124)
			(xy 340.01023 -294.193848) (xy 340.036533 -294.152252) (xy 340.069168 -294.115415) (xy 340.107289 -294.08429)
			(xy 340.14991 -294.059683) (xy 340.195926 -294.042231) (xy 340.244145 -294.032387) (xy 340.29332 -294.030406)
			(xy 340.342175 -294.036338) (xy 340.389446 -294.05003) (xy 340.433908 -294.071128) (xy 340.474411 -294.099084)
			(xy 340.509904 -294.133176) (xy 340.539469 -294.17252) (xy 340.56234 -294.216097) (xy 340.577924 -294.262778)
			(xy 340.585819 -294.311355) (xy 340.586314 -294.335962) (xy 340.915256 -294.335962) (xy 340.919216 -294.286908)
			(xy 340.930993 -294.239124) (xy 340.950284 -294.193848) (xy 340.976587 -294.152252) (xy 341.009222 -294.115415)
			(xy 341.047343 -294.08429) (xy 341.089964 -294.059683) (xy 341.13598 -294.042231) (xy 341.184199 -294.032387)
			(xy 341.233374 -294.030406) (xy 341.282229 -294.036338) (xy 341.3295 -294.05003) (xy 341.373962 -294.071128)
			(xy 341.414465 -294.099084) (xy 341.449958 -294.133176) (xy 341.479523 -294.17252) (xy 341.502394 -294.216097)
			(xy 341.517978 -294.262778) (xy 341.525873 -294.311355) (xy 341.526368 -294.335962) (xy 341.85531 -294.335962)
			(xy 341.85927 -294.286908) (xy 341.871047 -294.239124) (xy 341.890338 -294.193848) (xy 341.916641 -294.152252)
			(xy 341.949276 -294.115415) (xy 341.987397 -294.08429) (xy 342.030018 -294.059683) (xy 342.076034 -294.042231)
			(xy 342.124253 -294.032387) (xy 342.173428 -294.030406) (xy 342.222283 -294.036338) (xy 342.269554 -294.05003)
			(xy 342.314016 -294.071128) (xy 342.354519 -294.099084) (xy 342.390012 -294.133176) (xy 342.419577 -294.17252)
			(xy 342.442448 -294.216097) (xy 342.458032 -294.262778) (xy 342.465927 -294.311355) (xy 342.466422 -294.335962)
			(xy 342.795364 -294.335962) (xy 342.799324 -294.286908) (xy 342.811101 -294.239124) (xy 342.830392 -294.193848)
			(xy 342.856695 -294.152252) (xy 342.88933 -294.115415) (xy 342.927451 -294.08429) (xy 342.970072 -294.059683)
			(xy 343.016088 -294.042231) (xy 343.064307 -294.032387) (xy 343.113482 -294.030406) (xy 343.162337 -294.036338)
			(xy 343.209608 -294.05003) (xy 343.25407 -294.071128) (xy 343.294573 -294.099084) (xy 343.330066 -294.133176)
			(xy 343.359631 -294.17252) (xy 343.382502 -294.216097) (xy 343.398086 -294.262778) (xy 343.405981 -294.311355)
			(xy 343.406476 -294.335962) (xy 343.735418 -294.335962) (xy 343.739378 -294.286908) (xy 343.751155 -294.239124)
			(xy 343.770446 -294.193848) (xy 343.796749 -294.152252) (xy 343.829384 -294.115415) (xy 343.867505 -294.08429)
			(xy 343.910126 -294.059683) (xy 343.956142 -294.042231) (xy 344.004361 -294.032387) (xy 344.053536 -294.030406)
			(xy 344.102391 -294.036338) (xy 344.149662 -294.05003) (xy 344.194124 -294.071128) (xy 344.234627 -294.099084)
			(xy 344.27012 -294.133176) (xy 344.299685 -294.17252) (xy 344.322556 -294.216097) (xy 344.33814 -294.262778)
			(xy 344.346035 -294.311355) (xy 344.34653 -294.335962) (xy 344.346035 -294.360569) (xy 344.33814 -294.409146)
			(xy 344.322556 -294.455827) (xy 344.299685 -294.499404) (xy 344.27012 -294.538748) (xy 344.234627 -294.57284)
			(xy 344.194124 -294.600796) (xy 344.149662 -294.621894) (xy 344.102391 -294.635586) (xy 344.053536 -294.641518)
			(xy 344.004361 -294.639537) (xy 343.956142 -294.629693) (xy 343.910126 -294.612241) (xy 343.867505 -294.587634)
			(xy 343.829384 -294.556509) (xy 343.796749 -294.519672) (xy 343.770446 -294.478076) (xy 343.751155 -294.4328)
			(xy 343.739378 -294.385016) (xy 343.735418 -294.335962) (xy 343.406476 -294.335962) (xy 343.405981 -294.360569)
			(xy 343.398086 -294.409146) (xy 343.382502 -294.455827) (xy 343.359631 -294.499404) (xy 343.330066 -294.538748)
			(xy 343.294573 -294.57284) (xy 343.25407 -294.600796) (xy 343.209608 -294.621894) (xy 343.162337 -294.635586)
			(xy 343.113482 -294.641518) (xy 343.064307 -294.639537) (xy 343.016088 -294.629693) (xy 342.970072 -294.612241)
			(xy 342.927451 -294.587634) (xy 342.88933 -294.556509) (xy 342.856695 -294.519672) (xy 342.830392 -294.478076)
			(xy 342.811101 -294.4328) (xy 342.799324 -294.385016) (xy 342.795364 -294.335962) (xy 342.466422 -294.335962)
			(xy 342.465927 -294.360569) (xy 342.458032 -294.409146) (xy 342.442448 -294.455827) (xy 342.419577 -294.499404)
			(xy 342.390012 -294.538748) (xy 342.354519 -294.57284) (xy 342.314016 -294.600796) (xy 342.269554 -294.621894)
			(xy 342.222283 -294.635586) (xy 342.173428 -294.641518) (xy 342.124253 -294.639537) (xy 342.076034 -294.629693)
			(xy 342.030018 -294.612241) (xy 341.987397 -294.587634) (xy 341.949276 -294.556509) (xy 341.916641 -294.519672)
			(xy 341.890338 -294.478076) (xy 341.871047 -294.4328) (xy 341.85927 -294.385016) (xy 341.85531 -294.335962)
			(xy 341.526368 -294.335962) (xy 341.525873 -294.360569) (xy 341.517978 -294.409146) (xy 341.502394 -294.455827)
			(xy 341.479523 -294.499404) (xy 341.449958 -294.538748) (xy 341.414465 -294.57284) (xy 341.373962 -294.600796)
			(xy 341.3295 -294.621894) (xy 341.282229 -294.635586) (xy 341.233374 -294.641518) (xy 341.184199 -294.639537)
			(xy 341.13598 -294.629693) (xy 341.089964 -294.612241) (xy 341.047343 -294.587634) (xy 341.009222 -294.556509)
			(xy 340.976587 -294.519672) (xy 340.950284 -294.478076) (xy 340.930993 -294.4328) (xy 340.919216 -294.385016)
			(xy 340.915256 -294.335962) (xy 340.586314 -294.335962) (xy 340.585819 -294.360569) (xy 340.577924 -294.409146)
			(xy 340.56234 -294.455827) (xy 340.539469 -294.499404) (xy 340.509904 -294.538748) (xy 340.474411 -294.57284)
			(xy 340.433908 -294.600796) (xy 340.389446 -294.621894) (xy 340.342175 -294.635586) (xy 340.29332 -294.641518)
			(xy 340.244145 -294.639537) (xy 340.195926 -294.629693) (xy 340.14991 -294.612241) (xy 340.107289 -294.587634)
			(xy 340.069168 -294.556509) (xy 340.036533 -294.519672) (xy 340.01023 -294.478076) (xy 339.990939 -294.4328)
			(xy 339.979162 -294.385016) (xy 339.975202 -294.335962) (xy 339.646514 -294.335962) (xy 339.646019 -294.360569)
			(xy 339.638124 -294.409146) (xy 339.62254 -294.455827) (xy 339.599669 -294.499404) (xy 339.570104 -294.538748)
			(xy 339.534611 -294.57284) (xy 339.494108 -294.600796) (xy 339.449646 -294.621894) (xy 339.402375 -294.635586)
			(xy 339.35352 -294.641518) (xy 339.304345 -294.639537) (xy 339.256126 -294.629693) (xy 339.21011 -294.612241)
			(xy 339.167489 -294.587634) (xy 339.129368 -294.556509) (xy 339.096733 -294.519672) (xy 339.07043 -294.478076)
			(xy 339.051139 -294.4328) (xy 339.039362 -294.385016) (xy 339.035402 -294.335962) (xy 338.70646 -294.335962)
			(xy 338.705965 -294.360569) (xy 338.69807 -294.409146) (xy 338.682486 -294.455827) (xy 338.659615 -294.499404)
			(xy 338.63005 -294.538748) (xy 338.594557 -294.57284) (xy 338.554054 -294.600796) (xy 338.509592 -294.621894)
			(xy 338.462321 -294.635586) (xy 338.413466 -294.641518) (xy 338.364291 -294.639537) (xy 338.316072 -294.629693)
			(xy 338.270056 -294.612241) (xy 338.227435 -294.587634) (xy 338.189314 -294.556509) (xy 338.156679 -294.519672)
			(xy 338.130376 -294.478076) (xy 338.111085 -294.4328) (xy 338.099308 -294.385016) (xy 338.095348 -294.335962)
			(xy 337.766406 -294.335962) (xy 337.765963 -294.359957) (xy 337.758461 -294.407357) (xy 337.743635 -294.453)
			(xy 337.721852 -294.495761) (xy 337.693647 -294.534588) (xy 337.659715 -294.568524) (xy 337.620892 -294.596733)
			(xy 337.578133 -294.618522) (xy 337.532492 -294.633352) (xy 337.485093 -294.64086) (xy 337.461098 -294.64127)
			(xy 337.437321 -294.640816) (xy 337.390341 -294.633444) (xy 337.345072 -294.618879) (xy 337.302608 -294.597472)
			(xy 337.263976 -294.569741) (xy 337.23011 -294.536356) (xy 337.201828 -294.498126) (xy 337.179814 -294.455973)
			(xy 337.164601 -294.410918) (xy 337.156556 -294.364049) (xy 337.15579 -294.34028) (xy 337.15579 -294.335708)
			(xy 337.15615 -294.314839) (xy 337.161876 -294.273495) (xy 337.17318 -294.233316) (xy 337.18119 -294.214042)
			(xy 337.18119 -294.213788) (xy 337.184459 -294.205383) (xy 337.18549 -294.187389) (xy 337.180228 -294.170151)
			(xy 337.175094 -294.162734) (xy 337.11261 -294.080946) (xy 337.086956 -294.070532) (xy 337.07324 -294.072564)
			(xy 337.05285 -294.075423) (xy 337.011786 -294.078476) (xy 336.991198 -294.07866) (xy 336.970609 -294.078479)
			(xy 336.929546 -294.075426) (xy 336.909156 -294.072564) (xy 336.89544 -294.070532) (xy 336.869786 -294.080946)
			(xy 336.807048 -294.16248) (xy 336.801864 -294.169917) (xy 336.7966 -294.187251) (xy 336.797671 -294.205336)
			(xy 336.800952 -294.213788) (xy 336.800952 -294.214042) (xy 336.808903 -294.233157) (xy 336.820158 -294.272998)
			(xy 336.825927 -294.313994) (xy 336.826352 -294.334692) (xy 336.826352 -294.34028) (xy 336.825565 -294.36405)
			(xy 336.817532 -294.410923) (xy 336.802328 -294.455984) (xy 336.780321 -294.498142) (xy 336.752043 -294.536377)
			(xy 336.718177 -294.569765) (xy 336.679544 -294.597498) (xy 336.637077 -294.618904) (xy 336.591805 -294.633466)
			(xy 336.544822 -294.640832) (xy 336.521044 -294.64127) (xy 336.49705 -294.640827) (xy 336.449651 -294.633326)
			(xy 336.40401 -294.6185) (xy 336.361251 -294.596717) (xy 336.322426 -294.568511) (xy 336.288493 -294.534579)
			(xy 336.260286 -294.495755) (xy 336.238502 -294.452996) (xy 336.223676 -294.407355) (xy 336.216173 -294.359956)
			(xy 336.215736 -294.335962) (xy 336.216226 -294.311131) (xy 336.224271 -294.262124) (xy 336.240143 -294.215066)
			(xy 336.263423 -294.171198) (xy 336.293497 -294.131676) (xy 336.329572 -294.097545) (xy 336.370696 -294.069702)
			(xy 336.415785 -294.048884) (xy 336.463649 -294.035639) (xy 336.488278 -294.032432) (xy 336.502248 -294.030908)
			(xy 336.524346 -294.014398) (xy 336.564224 -293.919402) (xy 336.566697 -293.912975) (xy 336.568494 -293.899327)
			(xy 336.56778 -293.892478) (xy 336.565748 -293.879016) (xy 336.55254 -293.862252) (xy 336.549238 -293.857934)
			(xy 336.540856 -293.850822) (xy 336.505296 -293.83228) (xy 336.493612 -293.832026) (xy 336.466688 -293.83101)
			(xy 336.445232 -293.82989) (xy 336.402421 -293.826206) (xy 336.38109 -293.823644) (xy 336.369406 -293.82212)
			(xy 336.347308 -293.82974) (xy 335.900522 -294.276526) (xy 335.896859 -294.280399) (xy 335.8911 -294.289367)
			(xy 335.889092 -294.294306) (xy 335.885028 -294.30472) (xy 335.885282 -294.31107) (xy 335.886298 -294.335962)
			(xy 335.886298 -294.336216) (xy 335.885811 -294.360196) (xy 335.878278 -294.407561) (xy 335.863432 -294.453165)
			(xy 335.841637 -294.495887) (xy 335.813429 -294.534676) (xy 335.779504 -294.568576) (xy 335.740694 -294.596755)
			(xy 335.697956 -294.618518) (xy 335.652341 -294.633331) (xy 335.60497 -294.640829) (xy 335.58099 -294.64127)
			(xy 335.557114 -294.640254) (xy 335.549748 -294.64) (xy 335.539334 -294.644064) (xy 335.534404 -294.646087)
			(xy 335.525443 -294.651851) (xy 335.521554 -294.655494) (xy 335.322926 -294.854122) (xy 335.316075 -294.861486)
			(xy 335.308313 -294.880025) (xy 335.308303 -294.900123) (xy 335.316045 -294.91867) (xy 335.322926 -294.926004)
			(xy 335.323942 -294.92702) (xy 335.324196 -294.927274) (xy 335.341321 -294.944646) (xy 335.370383 -294.98382)
			(xy 335.392856 -295.027113) (xy 335.408169 -295.073424) (xy 335.415935 -295.121579) (xy 335.416398 -295.145968)
			(xy 335.74534 -295.145968) (xy 335.7493 -295.096914) (xy 335.761077 -295.04913) (xy 335.780368 -295.003854)
			(xy 335.806671 -294.962258) (xy 335.839306 -294.925421) (xy 335.877427 -294.894296) (xy 335.920048 -294.869689)
			(xy 335.966064 -294.852237) (xy 336.014283 -294.842393) (xy 336.063458 -294.840412) (xy 336.112313 -294.846344)
			(xy 336.159584 -294.860036) (xy 336.204046 -294.881134) (xy 336.244549 -294.90909) (xy 336.280042 -294.943182)
			(xy 336.309607 -294.982526) (xy 336.332478 -295.026103) (xy 336.348062 -295.072784) (xy 336.355957 -295.121361)
			(xy 336.356452 -295.145968) (xy 337.625194 -295.145968) (xy 337.629154 -295.096914) (xy 337.640931 -295.04913)
			(xy 337.660222 -295.003854) (xy 337.686525 -294.962258) (xy 337.71916 -294.925421) (xy 337.757281 -294.894296)
			(xy 337.799902 -294.869689) (xy 337.845918 -294.852237) (xy 337.894137 -294.842393) (xy 337.943312 -294.840412)
			(xy 337.992167 -294.846344) (xy 338.039438 -294.860036) (xy 338.0839 -294.881134) (xy 338.124403 -294.90909)
			(xy 338.159896 -294.943182) (xy 338.189461 -294.982526) (xy 338.212332 -295.026103) (xy 338.227916 -295.072784)
			(xy 338.235811 -295.121361) (xy 338.236306 -295.145968) (xy 338.565248 -295.145968) (xy 338.569208 -295.096914)
			(xy 338.580985 -295.04913) (xy 338.600276 -295.003854) (xy 338.626579 -294.962258) (xy 338.659214 -294.925421)
			(xy 338.697335 -294.894296) (xy 338.739956 -294.869689) (xy 338.785972 -294.852237) (xy 338.834191 -294.842393)
			(xy 338.883366 -294.840412) (xy 338.932221 -294.846344) (xy 338.979492 -294.860036) (xy 339.023954 -294.881134)
			(xy 339.064457 -294.90909) (xy 339.09995 -294.943182) (xy 339.129515 -294.982526) (xy 339.152386 -295.026103)
			(xy 339.16797 -295.072784) (xy 339.175865 -295.121361) (xy 339.17636 -295.145968) (xy 339.505302 -295.145968)
			(xy 339.509262 -295.096914) (xy 339.521039 -295.04913) (xy 339.54033 -295.003854) (xy 339.566633 -294.962258)
			(xy 339.599268 -294.925421) (xy 339.637389 -294.894296) (xy 339.68001 -294.869689) (xy 339.726026 -294.852237)
			(xy 339.774245 -294.842393) (xy 339.82342 -294.840412) (xy 339.872275 -294.846344) (xy 339.919546 -294.860036)
			(xy 339.964008 -294.881134) (xy 340.004511 -294.90909) (xy 340.040004 -294.943182) (xy 340.069569 -294.982526)
			(xy 340.09244 -295.026103) (xy 340.108024 -295.072784) (xy 340.115919 -295.121361) (xy 340.116414 -295.145968)
			(xy 340.445356 -295.145968) (xy 340.449316 -295.096914) (xy 340.461093 -295.04913) (xy 340.480384 -295.003854)
			(xy 340.506687 -294.962258) (xy 340.539322 -294.925421) (xy 340.577443 -294.894296) (xy 340.620064 -294.869689)
			(xy 340.66608 -294.852237) (xy 340.714299 -294.842393) (xy 340.763474 -294.840412) (xy 340.812329 -294.846344)
			(xy 340.8596 -294.860036) (xy 340.904062 -294.881134) (xy 340.944565 -294.90909) (xy 340.980058 -294.943182)
			(xy 341.009623 -294.982526) (xy 341.032494 -295.026103) (xy 341.048078 -295.072784) (xy 341.055973 -295.121361)
			(xy 341.056468 -295.145968) (xy 341.38541 -295.145968) (xy 341.38937 -295.096914) (xy 341.401147 -295.04913)
			(xy 341.420438 -295.003854) (xy 341.446741 -294.962258) (xy 341.479376 -294.925421) (xy 341.517497 -294.894296)
			(xy 341.560118 -294.869689) (xy 341.606134 -294.852237) (xy 341.654353 -294.842393) (xy 341.703528 -294.840412)
			(xy 341.752383 -294.846344) (xy 341.799654 -294.860036) (xy 341.844116 -294.881134) (xy 341.884619 -294.90909)
			(xy 341.920112 -294.943182) (xy 341.949677 -294.982526) (xy 341.972548 -295.026103) (xy 341.988132 -295.072784)
			(xy 341.996027 -295.121361) (xy 341.996522 -295.145968) (xy 342.32521 -295.145968) (xy 342.32917 -295.096914)
			(xy 342.340947 -295.04913) (xy 342.360238 -295.003854) (xy 342.386541 -294.962258) (xy 342.419176 -294.925421)
			(xy 342.457297 -294.894296) (xy 342.499918 -294.869689) (xy 342.545934 -294.852237) (xy 342.594153 -294.842393)
			(xy 342.643328 -294.840412) (xy 342.692183 -294.846344) (xy 342.739454 -294.860036) (xy 342.783916 -294.881134)
			(xy 342.824419 -294.90909) (xy 342.859912 -294.943182) (xy 342.889477 -294.982526) (xy 342.912348 -295.026103)
			(xy 342.927932 -295.072784) (xy 342.935827 -295.121361) (xy 342.936322 -295.145968) (xy 343.265264 -295.145968)
			(xy 343.269224 -295.096914) (xy 343.281001 -295.04913) (xy 343.300292 -295.003854) (xy 343.326595 -294.962258)
			(xy 343.35923 -294.925421) (xy 343.397351 -294.894296) (xy 343.439972 -294.869689) (xy 343.485988 -294.852237)
			(xy 343.534207 -294.842393) (xy 343.583382 -294.840412) (xy 343.632237 -294.846344) (xy 343.679508 -294.860036)
			(xy 343.72397 -294.881134) (xy 343.764473 -294.90909) (xy 343.799966 -294.943182) (xy 343.829531 -294.982526)
			(xy 343.852402 -295.026103) (xy 343.867986 -295.072784) (xy 343.875881 -295.121361) (xy 343.876376 -295.145968)
			(xy 343.875881 -295.170575) (xy 343.867986 -295.219152) (xy 343.852402 -295.265833) (xy 343.829531 -295.30941)
			(xy 343.799966 -295.348754) (xy 343.764473 -295.382846) (xy 343.72397 -295.410802) (xy 343.679508 -295.4319)
			(xy 343.632237 -295.445592) (xy 343.583382 -295.451524) (xy 343.534207 -295.449543) (xy 343.485988 -295.439699)
			(xy 343.439972 -295.422247) (xy 343.397351 -295.39764) (xy 343.35923 -295.366515) (xy 343.326595 -295.329678)
			(xy 343.300292 -295.288082) (xy 343.281001 -295.242806) (xy 343.269224 -295.195022) (xy 343.265264 -295.145968)
			(xy 342.936322 -295.145968) (xy 342.935827 -295.170575) (xy 342.927932 -295.219152) (xy 342.912348 -295.265833)
			(xy 342.889477 -295.30941) (xy 342.859912 -295.348754) (xy 342.824419 -295.382846) (xy 342.783916 -295.410802)
			(xy 342.739454 -295.4319) (xy 342.692183 -295.445592) (xy 342.643328 -295.451524) (xy 342.594153 -295.449543)
			(xy 342.545934 -295.439699) (xy 342.499918 -295.422247) (xy 342.457297 -295.39764) (xy 342.419176 -295.366515)
			(xy 342.386541 -295.329678) (xy 342.360238 -295.288082) (xy 342.340947 -295.242806) (xy 342.32917 -295.195022)
			(xy 342.32521 -295.145968) (xy 341.996522 -295.145968) (xy 341.996027 -295.170575) (xy 341.988132 -295.219152)
			(xy 341.972548 -295.265833) (xy 341.949677 -295.30941) (xy 341.920112 -295.348754) (xy 341.884619 -295.382846)
			(xy 341.844116 -295.410802) (xy 341.799654 -295.4319) (xy 341.752383 -295.445592) (xy 341.703528 -295.451524)
			(xy 341.654353 -295.449543) (xy 341.606134 -295.439699) (xy 341.560118 -295.422247) (xy 341.517497 -295.39764)
			(xy 341.479376 -295.366515) (xy 341.446741 -295.329678) (xy 341.420438 -295.288082) (xy 341.401147 -295.242806)
			(xy 341.38937 -295.195022) (xy 341.38541 -295.145968) (xy 341.056468 -295.145968) (xy 341.055973 -295.170575)
			(xy 341.048078 -295.219152) (xy 341.032494 -295.265833) (xy 341.009623 -295.30941) (xy 340.980058 -295.348754)
			(xy 340.944565 -295.382846) (xy 340.904062 -295.410802) (xy 340.8596 -295.4319) (xy 340.812329 -295.445592)
			(xy 340.763474 -295.451524) (xy 340.714299 -295.449543) (xy 340.66608 -295.439699) (xy 340.620064 -295.422247)
			(xy 340.577443 -295.39764) (xy 340.539322 -295.366515) (xy 340.506687 -295.329678) (xy 340.480384 -295.288082)
			(xy 340.461093 -295.242806) (xy 340.449316 -295.195022) (xy 340.445356 -295.145968) (xy 340.116414 -295.145968)
			(xy 340.115919 -295.170575) (xy 340.108024 -295.219152) (xy 340.09244 -295.265833) (xy 340.069569 -295.30941)
			(xy 340.040004 -295.348754) (xy 340.004511 -295.382846) (xy 339.964008 -295.410802) (xy 339.919546 -295.4319)
			(xy 339.872275 -295.445592) (xy 339.82342 -295.451524) (xy 339.774245 -295.449543) (xy 339.726026 -295.439699)
			(xy 339.68001 -295.422247) (xy 339.637389 -295.39764) (xy 339.599268 -295.366515) (xy 339.566633 -295.329678)
			(xy 339.54033 -295.288082) (xy 339.521039 -295.242806) (xy 339.509262 -295.195022) (xy 339.505302 -295.145968)
			(xy 339.17636 -295.145968) (xy 339.175865 -295.170575) (xy 339.16797 -295.219152) (xy 339.152386 -295.265833)
			(xy 339.129515 -295.30941) (xy 339.09995 -295.348754) (xy 339.064457 -295.382846) (xy 339.023954 -295.410802)
			(xy 338.979492 -295.4319) (xy 338.932221 -295.445592) (xy 338.883366 -295.451524) (xy 338.834191 -295.449543)
			(xy 338.785972 -295.439699) (xy 338.739956 -295.422247) (xy 338.697335 -295.39764) (xy 338.659214 -295.366515)
			(xy 338.626579 -295.329678) (xy 338.600276 -295.288082) (xy 338.580985 -295.242806) (xy 338.569208 -295.195022)
			(xy 338.565248 -295.145968) (xy 338.236306 -295.145968) (xy 338.235811 -295.170575) (xy 338.227916 -295.219152)
			(xy 338.212332 -295.265833) (xy 338.189461 -295.30941) (xy 338.159896 -295.348754) (xy 338.124403 -295.382846)
			(xy 338.0839 -295.410802) (xy 338.039438 -295.4319) (xy 337.992167 -295.445592) (xy 337.943312 -295.451524)
			(xy 337.894137 -295.449543) (xy 337.845918 -295.439699) (xy 337.799902 -295.422247) (xy 337.757281 -295.39764)
			(xy 337.71916 -295.366515) (xy 337.686525 -295.329678) (xy 337.660222 -295.288082) (xy 337.640931 -295.242806)
			(xy 337.629154 -295.195022) (xy 337.625194 -295.145968) (xy 336.356452 -295.145968) (xy 336.355957 -295.170575)
			(xy 336.348062 -295.219152) (xy 336.332478 -295.265833) (xy 336.309607 -295.30941) (xy 336.280042 -295.348754)
			(xy 336.244549 -295.382846) (xy 336.204046 -295.410802) (xy 336.159584 -295.4319) (xy 336.112313 -295.445592)
			(xy 336.063458 -295.451524) (xy 336.014283 -295.449543) (xy 335.966064 -295.439699) (xy 335.920048 -295.422247)
			(xy 335.877427 -295.39764) (xy 335.839306 -295.366515) (xy 335.806671 -295.329678) (xy 335.780368 -295.288082)
			(xy 335.761077 -295.242806) (xy 335.7493 -295.195022) (xy 335.74534 -295.145968) (xy 335.416398 -295.145968)
			(xy 335.415954 -295.169963) (xy 335.408451 -295.217361) (xy 335.393626 -295.263003) (xy 335.371842 -295.305762)
			(xy 335.343636 -295.344588) (xy 335.309704 -295.378522) (xy 335.270881 -295.40673) (xy 335.228123 -295.428517)
			(xy 335.182483 -295.443346) (xy 335.135084 -295.450852) (xy 335.11109 -295.451276) (xy 335.098327 -295.451139)
			(xy 335.072893 -295.448979) (xy 335.06029 -295.446958) (xy 335.06029 -295.447212) (xy 335.036474 -295.442717)
			(xy 334.990559 -295.427206) (xy 334.947663 -295.404652) (xy 334.908858 -295.375618) (xy 334.891634 -295.358566)
			(xy 334.89138 -295.358058) (xy 334.891126 -295.357804) (xy 334.883679 -295.351116) (xy 334.865183 -295.34352)
			(xy 334.845187 -295.34352) (xy 334.826691 -295.351116) (xy 334.819244 -295.357804) (xy 334.685132 -295.491916)
			(xy 334.677766 -295.499028) (xy 334.670146 -295.517824) (xy 334.670146 -295.535858) (xy 334.67167 -295.548558)
			(xy 334.695292 -295.639998) (xy 334.713834 -295.659048) (xy 334.726788 -295.662858) (xy 334.750238 -295.670212)
			(xy 334.7946 -295.691354) (xy 334.835001 -295.719331) (xy 334.870399 -295.753418) (xy 334.899879 -295.792737)
			(xy 334.922678 -295.83627) (xy 334.938209 -295.882893) (xy 334.946071 -295.931403) (xy 334.946498 -295.955974)
			(xy 336.21524 -295.955974) (xy 336.2192 -295.90692) (xy 336.230977 -295.859136) (xy 336.250268 -295.81386)
			(xy 336.276571 -295.772264) (xy 336.309206 -295.735427) (xy 336.347327 -295.704302) (xy 336.389948 -295.679695)
			(xy 336.435964 -295.662243) (xy 336.484183 -295.652399) (xy 336.533358 -295.650418) (xy 336.582213 -295.65635)
			(xy 336.629484 -295.670042) (xy 336.673946 -295.69114) (xy 336.714449 -295.719096) (xy 336.749942 -295.753188)
			(xy 336.779507 -295.792532) (xy 336.802378 -295.836109) (xy 336.817962 -295.88279) (xy 336.825857 -295.931367)
			(xy 336.826352 -295.955974) (xy 338.095348 -295.955974) (xy 338.099308 -295.90692) (xy 338.111085 -295.859136)
			(xy 338.130376 -295.81386) (xy 338.156679 -295.772264) (xy 338.189314 -295.735427) (xy 338.227435 -295.704302)
			(xy 338.270056 -295.679695) (xy 338.316072 -295.662243) (xy 338.364291 -295.652399) (xy 338.413466 -295.650418)
			(xy 338.462321 -295.65635) (xy 338.509592 -295.670042) (xy 338.554054 -295.69114) (xy 338.594557 -295.719096)
			(xy 338.63005 -295.753188) (xy 338.659615 -295.792532) (xy 338.682486 -295.836109) (xy 338.69807 -295.88279)
			(xy 338.705965 -295.931367) (xy 338.70646 -295.955974) (xy 339.035402 -295.955974) (xy 339.039362 -295.90692)
			(xy 339.051139 -295.859136) (xy 339.07043 -295.81386) (xy 339.096733 -295.772264) (xy 339.129368 -295.735427)
			(xy 339.167489 -295.704302) (xy 339.21011 -295.679695) (xy 339.256126 -295.662243) (xy 339.304345 -295.652399)
			(xy 339.35352 -295.650418) (xy 339.402375 -295.65635) (xy 339.449646 -295.670042) (xy 339.494108 -295.69114)
			(xy 339.534611 -295.719096) (xy 339.570104 -295.753188) (xy 339.599669 -295.792532) (xy 339.62254 -295.836109)
			(xy 339.638124 -295.88279) (xy 339.646019 -295.931367) (xy 339.646514 -295.955974) (xy 339.975202 -295.955974)
			(xy 339.979162 -295.90692) (xy 339.990939 -295.859136) (xy 340.01023 -295.81386) (xy 340.036533 -295.772264)
			(xy 340.069168 -295.735427) (xy 340.107289 -295.704302) (xy 340.14991 -295.679695) (xy 340.195926 -295.662243)
			(xy 340.244145 -295.652399) (xy 340.29332 -295.650418) (xy 340.342175 -295.65635) (xy 340.389446 -295.670042)
			(xy 340.433908 -295.69114) (xy 340.474411 -295.719096) (xy 340.509904 -295.753188) (xy 340.539469 -295.792532)
			(xy 340.56234 -295.836109) (xy 340.577924 -295.88279) (xy 340.585819 -295.931367) (xy 340.586314 -295.955974)
			(xy 340.585819 -295.980581) (xy 340.577924 -296.029158) (xy 340.56234 -296.075839) (xy 340.539469 -296.119416)
			(xy 340.509904 -296.15876) (xy 340.474411 -296.192852) (xy 340.433908 -296.220808) (xy 340.389446 -296.241906)
			(xy 340.342175 -296.255598) (xy 340.29332 -296.26153) (xy 340.244145 -296.259549) (xy 340.195926 -296.249705)
			(xy 340.14991 -296.232253) (xy 340.107289 -296.207646) (xy 340.069168 -296.176521) (xy 340.036533 -296.139684)
			(xy 340.01023 -296.098088) (xy 339.990939 -296.052812) (xy 339.979162 -296.005028) (xy 339.975202 -295.955974)
			(xy 339.646514 -295.955974) (xy 339.646019 -295.980581) (xy 339.638124 -296.029158) (xy 339.62254 -296.075839)
			(xy 339.599669 -296.119416) (xy 339.570104 -296.15876) (xy 339.534611 -296.192852) (xy 339.494108 -296.220808)
			(xy 339.449646 -296.241906) (xy 339.402375 -296.255598) (xy 339.35352 -296.26153) (xy 339.304345 -296.259549)
			(xy 339.256126 -296.249705) (xy 339.21011 -296.232253) (xy 339.167489 -296.207646) (xy 339.129368 -296.176521)
			(xy 339.096733 -296.139684) (xy 339.07043 -296.098088) (xy 339.051139 -296.052812) (xy 339.039362 -296.005028)
			(xy 339.035402 -295.955974) (xy 338.70646 -295.955974) (xy 338.705965 -295.980581) (xy 338.69807 -296.029158)
			(xy 338.682486 -296.075839) (xy 338.659615 -296.119416) (xy 338.63005 -296.15876) (xy 338.594557 -296.192852)
			(xy 338.554054 -296.220808) (xy 338.509592 -296.241906) (xy 338.462321 -296.255598) (xy 338.413466 -296.26153)
			(xy 338.364291 -296.259549) (xy 338.316072 -296.249705) (xy 338.270056 -296.232253) (xy 338.227435 -296.207646)
			(xy 338.189314 -296.176521) (xy 338.156679 -296.139684) (xy 338.130376 -296.098088) (xy 338.111085 -296.052812)
			(xy 338.099308 -296.005028) (xy 338.095348 -295.955974) (xy 336.826352 -295.955974) (xy 336.825857 -295.980581)
			(xy 336.817962 -296.029158) (xy 336.802378 -296.075839) (xy 336.779507 -296.119416) (xy 336.749942 -296.15876)
			(xy 336.714449 -296.192852) (xy 336.673946 -296.220808) (xy 336.629484 -296.241906) (xy 336.582213 -296.255598)
			(xy 336.533358 -296.26153) (xy 336.484183 -296.259549) (xy 336.435964 -296.249705) (xy 336.389948 -296.232253)
			(xy 336.347327 -296.207646) (xy 336.309206 -296.176521) (xy 336.276571 -296.139684) (xy 336.250268 -296.098088)
			(xy 336.230977 -296.052812) (xy 336.2192 -296.005028) (xy 336.21524 -295.955974) (xy 334.946498 -295.955974)
			(xy 334.946054 -295.979968) (xy 334.93855 -296.027366) (xy 334.923724 -296.073007) (xy 334.90194 -296.115766)
			(xy 334.873734 -296.15459) (xy 334.839802 -296.188524) (xy 334.800979 -296.216731) (xy 334.758222 -296.238518)
			(xy 334.712582 -296.253346) (xy 334.665184 -296.260852) (xy 334.64119 -296.261282) (xy 334.615929 -296.26076)
			(xy 334.566097 -296.252443) (xy 334.518314 -296.236038) (xy 334.473882 -296.211992) (xy 334.434014 -296.18096)
			(xy 334.399797 -296.14379) (xy 334.372164 -296.101496) (xy 334.35187 -296.05523) (xy 334.339467 -296.006254)
			(xy 334.336898 -295.98112) (xy 334.336136 -295.971722) (xy 334.332072 -295.96334) (xy 334.33009 -295.959359)
			(xy 334.324978 -295.952083) (xy 334.321912 -295.948862) (xy 334.310482 -295.937686) (xy 334.303023 -295.931049)
			(xy 334.284532 -295.923573) (xy 334.264587 -295.923708) (xy 334.246199 -295.931433) (xy 334.238854 -295.938194)
			(xy 334.23606 -295.940988) (xy 334.22866 -295.947829) (xy 334.210062 -295.955551) (xy 334.199992 -295.955974)
			(xy 334.034638 -295.955974) (xy 334.00619 -295.980612) (xy 334.003396 -295.999408) (xy 333.999487 -296.023336)
			(xy 333.985095 -296.069632) (xy 333.963569 -296.113073) (xy 333.935449 -296.152566) (xy 333.901442 -296.187121)
			(xy 333.862402 -296.215867) (xy 333.81931 -296.238084) (xy 333.773249 -296.253213) (xy 333.725377 -296.260873)
			(xy 333.676895 -296.260873) (xy 333.629023 -296.253213) (xy 333.582962 -296.238084) (xy 333.53987 -296.215867)
			(xy 333.50083 -296.187121) (xy 333.466823 -296.152566) (xy 333.438703 -296.113073) (xy 333.417177 -296.069632)
			(xy 333.402785 -296.023336) (xy 333.398876 -295.999408) (xy 333.396082 -295.980612) (xy 333.367634 -295.955974)
			(xy 333.094584 -295.955974) (xy 333.066136 -295.980612) (xy 333.063342 -295.999408) (xy 333.059433 -296.023336)
			(xy 333.045041 -296.069632) (xy 333.023515 -296.113073) (xy 332.995395 -296.152566) (xy 332.961388 -296.187121)
			(xy 332.922348 -296.215867) (xy 332.879256 -296.238084) (xy 332.833195 -296.253213) (xy 332.785323 -296.260873)
			(xy 332.736841 -296.260873) (xy 332.688969 -296.253213) (xy 332.642908 -296.238084) (xy 332.599816 -296.215867)
			(xy 332.560776 -296.187121) (xy 332.526769 -296.152566) (xy 332.498649 -296.113073) (xy 332.477123 -296.069632)
			(xy 332.462731 -296.023336) (xy 332.458822 -295.999408) (xy 332.456028 -295.980612) (xy 332.42758 -295.955974)
			(xy 332.15453 -295.955974) (xy 332.126082 -295.980612) (xy 332.123288 -295.999408) (xy 332.119379 -296.023336)
			(xy 332.104987 -296.069632) (xy 332.083461 -296.113073) (xy 332.055341 -296.152566) (xy 332.021334 -296.187121)
			(xy 331.982294 -296.215867) (xy 331.939202 -296.238084) (xy 331.893141 -296.253213) (xy 331.845269 -296.260873)
			(xy 331.796787 -296.260873) (xy 331.748915 -296.253213) (xy 331.702854 -296.238084) (xy 331.659762 -296.215867)
			(xy 331.620722 -296.187121) (xy 331.586715 -296.152566) (xy 331.558595 -296.113073) (xy 331.537069 -296.069632)
			(xy 331.522677 -296.023336) (xy 331.518768 -295.999408) (xy 331.515974 -295.980612) (xy 331.487526 -295.955974)
			(xy 331.214476 -295.955974) (xy 331.186028 -295.980612) (xy 331.183488 -295.999408) (xy 331.17958 -296.023335)
			(xy 331.16519 -296.06963) (xy 331.143664 -296.113068) (xy 331.115543 -296.152559) (xy 331.081535 -296.187108)
			(xy 331.042494 -296.215849) (xy 330.999401 -296.238059) (xy 330.95334 -296.253179) (xy 330.905468 -296.26083)
			(xy 330.881228 -296.261282) (xy 330.856667 -296.260794) (xy 330.808176 -296.25294) (xy 330.761566 -296.237431)
			(xy 330.718038 -296.214664) (xy 330.698094 -296.200322) (xy 330.682854 -296.188892) (xy 330.645262 -296.191686)
			(xy 327.598002 -299.238946) (xy 339.464724 -299.238946) (xy 339.464724 -299.184454) (xy 339.472478 -299.130518)
			(xy 339.487829 -299.078233) (xy 339.510464 -299.028665) (xy 339.539922 -298.982823) (xy 339.575604 -298.941639)
			(xy 339.616783 -298.905952) (xy 339.662621 -298.876488) (xy 339.712186 -298.853847) (xy 339.764469 -298.838489)
			(xy 339.818404 -298.830728) (xy 339.84565 -298.830238) (xy 339.87107 -298.83063) (xy 339.921462 -298.837361)
			(xy 339.970511 -298.850735) (xy 340.017345 -298.870516) (xy 340.039452 -298.88307) (xy 340.048088 -298.88815)
			(xy 340.067138 -298.891198) (xy 340.154768 -298.870878) (xy 340.170516 -298.859702) (xy 340.176104 -298.851574)
			(xy 340.193776 -298.825571) (xy 340.234518 -298.777686) (xy 340.280856 -298.735193) (xy 340.332082 -298.698741)
			(xy 340.387414 -298.668888) (xy 340.446007 -298.64609) (xy 340.506965 -298.630694) (xy 340.569356 -298.622936)
			(xy 340.600792 -298.622466) (xy 340.631522 -298.622964) (xy 340.692533 -298.630371) (xy 340.752208 -298.645078)
			(xy 340.809674 -298.66687) (xy 340.864094 -298.69543) (xy 340.914676 -298.730342) (xy 340.96068 -298.771096)
			(xy 341.001437 -298.817098) (xy 341.036352 -298.867676) (xy 341.064916 -298.922095) (xy 341.086712 -298.97956)
			(xy 341.101423 -299.039233) (xy 341.108834 -299.100244) (xy 341.1093 -299.130974) (xy 341.108704 -299.165929)
			(xy 341.099146 -299.235181) (xy 341.080192 -299.302472) (xy 341.0522 -299.366533) (xy 341.015698 -299.426156)
			(xy 340.993984 -299.453554) (xy 340.988706 -299.460566) (xy 340.98272 -299.477047) (xy 340.9823 -299.485812)
			(xy 340.9823 -299.792136) (xy 340.982643 -299.800915) (xy 340.988641 -299.817418) (xy 340.993984 -299.824394)
			(xy 341.015692 -299.851797) (xy 341.052191 -299.911422) (xy 341.080185 -299.975481) (xy 341.099147 -300.042769)
			(xy 341.108719 -300.11202) (xy 341.1093 -300.146974) (xy 341.108838 -300.177706) (xy 341.101432 -300.238722)
			(xy 341.086725 -300.2984) (xy 341.064932 -300.35587) (xy 341.03637 -300.410295) (xy 341.001456 -300.460879)
			(xy 340.960699 -300.506886) (xy 340.914693 -300.547645) (xy 340.86411 -300.582561) (xy 340.809687 -300.611125)
			(xy 340.752217 -300.63292) (xy 340.692539 -300.647629) (xy 340.631524 -300.655037) (xy 340.600792 -300.655482)
			(xy 340.568296 -300.654941) (xy 340.503832 -300.646666) (xy 340.440951 -300.630239) (xy 340.380676 -300.605928)
			(xy 340.323994 -300.57413) (xy 340.271829 -300.535364) (xy 340.225032 -300.490263) (xy 340.204298 -300.465236)
			(xy 340.197967 -300.457981) (xy 340.181254 -300.44845) (xy 340.171786 -300.446694) (xy 340.140798 -300.442376)
			(xy 340.13137 -300.441495) (xy 340.112973 -300.445928) (xy 340.104984 -300.451012) (xy 340.080943 -300.466974)
			(xy 340.029068 -300.492251) (xy 339.973974 -300.509414) (xy 339.916921 -300.518069) (xy 339.888068 -300.518576)
			(xy 339.860816 -300.518152) (xy 339.806867 -300.510391) (xy 339.754572 -300.495032) (xy 339.704995 -300.472387)
			(xy 339.659144 -300.442917) (xy 339.617954 -300.407223) (xy 339.582263 -300.36603) (xy 339.552798 -300.320177)
			(xy 339.530157 -300.270598) (xy 339.514802 -300.218302) (xy 339.507046 -300.164352) (xy 339.507046 -300.109848)
			(xy 339.514802 -300.055898) (xy 339.530157 -300.003602) (xy 339.552798 -299.954023) (xy 339.582263 -299.90817)
			(xy 339.617954 -299.866977) (xy 339.659144 -299.831283) (xy 339.704995 -299.801813) (xy 339.754572 -299.779168)
			(xy 339.806867 -299.763809) (xy 339.860816 -299.756048) (xy 339.888068 -299.75556) (xy 339.918245 -299.756119)
			(xy 339.977849 -299.765595) (xy 340.035221 -299.784331) (xy 340.088929 -299.811862) (xy 340.11362 -299.82922)
			(xy 340.121498 -299.834459) (xy 340.139736 -299.839419) (xy 340.14918 -299.838872) (xy 340.200742 -299.83303)
			(xy 340.2076 -299.824394) (xy 340.212909 -299.817403) (xy 340.218875 -299.800905) (xy 340.219284 -299.792136)
			(xy 340.219284 -299.611034) (xy 340.218927 -299.601799) (xy 340.212359 -299.584534) (xy 340.200101 -299.570717)
			(xy 340.192106 -299.566076) (xy 340.100158 -299.517562) (xy 340.072218 -299.519086) (xy 340.06028 -299.52696)
			(xy 340.036419 -299.542582) (xy 339.985043 -299.567341) (xy 339.930554 -299.584174) (xy 339.874165 -299.592704)
			(xy 339.84565 -299.593254) (xy 339.818404 -299.592672) (xy 339.764469 -299.584911) (xy 339.712186 -299.569553)
			(xy 339.662621 -299.546912) (xy 339.616783 -299.517448) (xy 339.575604 -299.481761) (xy 339.539922 -299.440577)
			(xy 339.510464 -299.394735) (xy 339.487829 -299.345167) (xy 339.472478 -299.292882) (xy 339.464724 -299.238946)
			(xy 327.598002 -299.238946) (xy 326.332342 -300.504606) (xy 326.324976 -300.511718) (xy 326.317356 -300.530514)
			(xy 326.317356 -301.6504) (xy 326.316932 -301.660469) (xy 326.309212 -301.679069) (xy 326.30237 -301.686468)
			(xy 326.243485 -301.745353) (xy 340.488772 -301.745353) (xy 340.488772 -301.681431) (xy 340.496783 -301.618013)
			(xy 340.51268 -301.556099) (xy 340.536212 -301.496666) (xy 340.567006 -301.440651) (xy 340.604579 -301.388936)
			(xy 340.648336 -301.342339) (xy 340.697589 -301.301594) (xy 340.75156 -301.267343) (xy 340.809399 -301.240126)
			(xy 340.870192 -301.220373) (xy 340.932982 -301.208395) (xy 340.996778 -301.204382) (xy 341.060574 -301.208395)
			(xy 341.123364 -301.220373) (xy 341.184157 -301.240126) (xy 341.241996 -301.267343) (xy 341.295967 -301.301594)
			(xy 341.34522 -301.342339) (xy 341.388977 -301.388936) (xy 341.42655 -301.440651) (xy 341.457344 -301.496666)
			(xy 341.480876 -301.556099) (xy 341.496773 -301.618013) (xy 341.504784 -301.681431) (xy 341.505286 -301.713392)
			(xy 341.504784 -301.745353) (xy 341.496773 -301.808771) (xy 341.480876 -301.870685) (xy 341.457344 -301.930118)
			(xy 341.42655 -301.986133) (xy 341.388977 -302.037848) (xy 341.34522 -302.084445) (xy 341.295967 -302.12519)
			(xy 341.241996 -302.159441) (xy 341.184157 -302.186658) (xy 341.123364 -302.206411) (xy 341.060574 -302.218389)
			(xy 340.996778 -302.222403) (xy 340.932982 -302.218389) (xy 340.870192 -302.206411) (xy 340.809399 -302.186658)
			(xy 340.75156 -302.159441) (xy 340.697589 -302.12519) (xy 340.648336 -302.084445) (xy 340.604579 -302.037848)
			(xy 340.567006 -301.986133) (xy 340.536212 -301.930118) (xy 340.51268 -301.870685) (xy 340.496783 -301.808771)
			(xy 340.488772 -301.745353) (xy 326.243485 -301.745353) (xy 323.20865 -304.780188) (xy 326.752462 -304.780188)
			(xy 326.756491 -304.637867) (xy 326.768566 -304.496002) (xy 326.788647 -304.355048) (xy 326.81667 -304.215455)
			(xy 326.852546 -304.077671) (xy 326.89616 -303.942138) (xy 326.947372 -303.809289) (xy 327.006018 -303.67955)
			(xy 327.071909 -303.553337) (xy 327.144836 -303.431054) (xy 327.224564 -303.313092) (xy 327.310838 -303.19983)
			(xy 327.403382 -303.091631) (xy 327.501898 -302.98884) (xy 327.606073 -302.891788) (xy 327.715571 -302.800784)
			(xy 327.830042 -302.716122) (xy 327.94912 -302.638071) (xy 328.072423 -302.566882) (xy 328.199556 -302.502783)
			(xy 328.330112 -302.445979) (xy 328.463672 -302.396653) (xy 328.599809 -302.354961) (xy 328.738087 -302.321038)
			(xy 328.878062 -302.294993) (xy 329.019287 -302.276908) (xy 329.161308 -302.266843) (xy 329.303672 -302.264828)
			(xy 329.445922 -302.270871) (xy 329.587602 -302.284951) (xy 329.728258 -302.307025) (xy 329.86744 -302.337021)
			(xy 330.004702 -302.374843) (xy 330.139605 -302.420371) (xy 330.271716 -302.473457) (xy 330.400612 -302.533933)
			(xy 330.52588 -302.601604) (xy 330.647119 -302.676254) (xy 330.76394 -302.757643) (xy 330.87597 -302.845511)
			(xy 330.982849 -302.939577) (xy 331.084235 -303.039538) (xy 331.179804 -303.145076) (xy 331.269249 -303.255851)
			(xy 331.352283 -303.371509) (xy 331.428641 -303.491679) (xy 331.498078 -303.615977) (xy 331.560371 -303.744004)
			(xy 331.615322 -303.875351) (xy 331.662754 -304.009596) (xy 331.702515 -304.146309) (xy 331.734477 -304.285053)
			(xy 331.758539 -304.425383) (xy 331.774623 -304.566849) (xy 331.782679 -304.708999) (xy 331.783182 -304.780188)
			(xy 331.782679 -304.851377) (xy 331.774623 -304.993527) (xy 331.767594 -305.055351) (xy 333.14867 -305.055351)
			(xy 333.14867 -305.000849) (xy 333.156426 -304.946901) (xy 333.171781 -304.894606) (xy 333.194421 -304.845029)
			(xy 333.223887 -304.799178) (xy 333.259578 -304.757988) (xy 333.300767 -304.722295) (xy 333.346617 -304.692828)
			(xy 333.396193 -304.670186) (xy 333.448487 -304.654829) (xy 333.502435 -304.647071) (xy 333.529686 -304.646584)
			(xy 333.539931 -304.646673) (xy 333.560389 -304.647819) (xy 333.57058 -304.64887) (xy 333.579978 -304.649886)
			(xy 333.598012 -304.64506) (xy 333.66837 -304.594768) (xy 333.67853 -304.579274) (xy 333.680562 -304.569876)
			(xy 333.687473 -304.541019) (xy 333.707125 -304.485027) (xy 333.733149 -304.431698) (xy 333.765193 -304.381754)
			(xy 333.783686 -304.358548) (xy 333.788935 -304.351534) (xy 333.794795 -304.335043) (xy 333.795116 -304.32629)
			(xy 333.795116 -304.172366) (xy 333.794764 -304.163618) (xy 333.788919 -304.147127) (xy 333.783686 -304.140108)
			(xy 333.764796 -304.116355) (xy 333.732197 -304.065163) (xy 333.718662 -304.038) (xy 333.714459 -304.030064)
			(xy 333.70158 -304.017567) (xy 333.693516 -304.013616) (xy 333.666084 -304.001424) (xy 333.65788 -303.998021)
			(xy 333.640186 -303.996596) (xy 333.63154 -303.99863) (xy 333.606578 -304.005128) (xy 333.555476 -304.012138)
			(xy 333.529686 -304.0126) (xy 333.502435 -304.012129) (xy 333.448487 -304.004371) (xy 333.396193 -303.989014)
			(xy 333.346617 -303.966372) (xy 333.300767 -303.936905) (xy 333.259578 -303.901212) (xy 333.223887 -303.860022)
			(xy 333.194421 -303.814171) (xy 333.171781 -303.764594) (xy 333.156426 -303.712299) (xy 333.14867 -303.658351)
			(xy 333.14867 -303.603849) (xy 333.156426 -303.549901) (xy 333.171781 -303.497606) (xy 333.194421 -303.448029)
			(xy 333.223887 -303.402178) (xy 333.259578 -303.360988) (xy 333.300767 -303.325295) (xy 333.346617 -303.295828)
			(xy 333.396193 -303.273186) (xy 333.448487 -303.257829) (xy 333.502435 -303.250071) (xy 333.529686 -303.249584)
			(xy 333.556134 -303.250062) (xy 333.608525 -303.257356) (xy 333.659405 -303.27182) (xy 333.707797 -303.293177)
			(xy 333.752775 -303.321016) (xy 333.793473 -303.354804) (xy 333.811626 -303.374044) (xy 333.817809 -303.380336)
			(xy 333.833415 -303.388535) (xy 333.842106 -303.390046) (xy 333.872078 -303.394364) (xy 333.88096 -303.395259)
			(xy 333.898396 -303.391485) (xy 333.906114 -303.386998) (xy 333.936652 -303.368487) (xy 334.001832 -303.33931)
			(xy 334.070456 -303.319551) (xy 334.141172 -303.3096) (xy 334.176878 -303.30902) (xy 334.207611 -303.309458)
			(xy 334.268628 -303.316865) (xy 334.328308 -303.331573) (xy 334.38578 -303.353368) (xy 334.440205 -303.381931)
			(xy 334.49079 -303.416847) (xy 334.536798 -303.457607) (xy 334.577556 -303.503615) (xy 334.612472 -303.5542)
			(xy 334.641035 -303.608626) (xy 334.662829 -303.666098) (xy 334.677536 -303.725778) (xy 334.684942 -303.786795)
			(xy 334.685386 -303.817528) (xy 334.684824 -303.852484) (xy 334.675258 -303.921738) (xy 334.656296 -303.989029)
			(xy 334.628297 -304.053089) (xy 334.591787 -304.112711) (xy 334.57007 -304.140108) (xy 334.564793 -304.147103)
			(xy 334.558951 -304.163609) (xy 334.55864 -304.172366) (xy 334.55864 -304.32629) (xy 334.559001 -304.335037)
			(xy 334.564838 -304.351529) (xy 334.57007 -304.358548) (xy 334.591755 -304.385969) (xy 334.628258 -304.445588)
			(xy 334.656256 -304.509643) (xy 334.675223 -304.576927) (xy 334.684802 -304.646175) (xy 334.685386 -304.681128)
			(xy 334.68497 -304.71186) (xy 334.677558 -304.772877) (xy 334.662845 -304.832555) (xy 334.641047 -304.890024)
			(xy 334.61248 -304.944447) (xy 334.591765 -304.974455) (xy 343.718382 -304.974455) (xy 343.718382 -304.910533)
			(xy 343.726393 -304.847115) (xy 343.74229 -304.785201) (xy 343.765822 -304.725768) (xy 343.796616 -304.669753)
			(xy 343.834189 -304.618038) (xy 343.877946 -304.571441) (xy 343.927199 -304.530696) (xy 343.98117 -304.496445)
			(xy 344.039009 -304.469228) (xy 344.099802 -304.449475) (xy 344.162592 -304.437497) (xy 344.226388 -304.433484)
			(xy 344.290184 -304.437497) (xy 344.352974 -304.449475) (xy 344.413767 -304.469228) (xy 344.471606 -304.496445)
			(xy 344.525577 -304.530696) (xy 344.57483 -304.571441) (xy 344.618587 -304.618038) (xy 344.65616 -304.669753)
			(xy 344.686954 -304.725768) (xy 344.710486 -304.785201) (xy 344.726383 -304.847115) (xy 344.734394 -304.910533)
			(xy 344.734896 -304.942494) (xy 344.734394 -304.974455) (xy 344.726383 -305.037873) (xy 344.710486 -305.099787)
			(xy 344.686954 -305.15922) (xy 344.65616 -305.215235) (xy 344.618587 -305.26695) (xy 344.57483 -305.313547)
			(xy 344.525577 -305.354292) (xy 344.471606 -305.388543) (xy 344.413767 -305.41576) (xy 344.352974 -305.435513)
			(xy 344.290184 -305.447491) (xy 344.226388 -305.451505) (xy 344.162592 -305.447491) (xy 344.099802 -305.435513)
			(xy 344.039009 -305.41576) (xy 343.98117 -305.388543) (xy 343.927199 -305.354292) (xy 343.877946 -305.313547)
			(xy 343.834189 -305.26695) (xy 343.796616 -305.215235) (xy 343.765822 -305.15922) (xy 343.74229 -305.099787)
			(xy 343.726393 -305.037873) (xy 343.718382 -304.974455) (xy 334.591765 -304.974455) (xy 334.577561 -304.99503)
			(xy 334.5368 -305.041035) (xy 334.490791 -305.081792) (xy 334.440205 -305.116706) (xy 334.385779 -305.145267)
			(xy 334.328307 -305.16706) (xy 334.268628 -305.181767) (xy 334.20761 -305.189173) (xy 334.176878 -305.189636)
			(xy 334.145823 -305.189181) (xy 334.084176 -305.181607) (xy 334.023915 -305.166562) (xy 333.99476 -305.155854)
			(xy 333.98587 -305.152552) (xy 333.967328 -305.152552) (xy 333.886556 -305.183286) (xy 333.872586 -305.195478)
			(xy 333.868268 -305.20386) (xy 333.855857 -305.226764) (xy 333.825796 -305.269308) (xy 333.790225 -305.307365)
			(xy 333.749805 -305.340226) (xy 333.705288 -305.367279) (xy 333.657503 -305.388023) (xy 333.60734 -305.402069)
			(xy 333.555732 -305.409157) (xy 333.529686 -305.4096) (xy 333.502435 -305.409129) (xy 333.448487 -305.401371)
			(xy 333.396193 -305.386014) (xy 333.346617 -305.363372) (xy 333.300767 -305.333905) (xy 333.259578 -305.298212)
			(xy 333.223887 -305.257022) (xy 333.194421 -305.211171) (xy 333.171781 -305.161594) (xy 333.156426 -305.109299)
			(xy 333.14867 -305.055351) (xy 331.767594 -305.055351) (xy 331.758539 -305.134993) (xy 331.734477 -305.275323)
			(xy 331.703418 -305.410147) (xy 339.849008 -305.410147) (xy 339.849008 -305.355653) (xy 339.856763 -305.301714)
			(xy 339.872114 -305.249427) (xy 339.89475 -305.199857) (xy 339.924209 -305.154013) (xy 339.959893 -305.112827)
			(xy 340.001074 -305.077138) (xy 340.046915 -305.047673) (xy 340.096482 -305.025031) (xy 340.148767 -305.009673)
			(xy 340.202705 -305.001911) (xy 340.229952 -305.001422) (xy 340.256402 -305.001843) (xy 340.308796 -305.009147)
			(xy 340.359677 -305.023622) (xy 340.40807 -305.044989) (xy 340.453046 -305.072839) (xy 340.493741 -305.106637)
			(xy 340.511892 -305.125882) (xy 340.518081 -305.132167) (xy 340.533683 -305.140369) (xy 340.542372 -305.141884)
			(xy 340.572344 -305.146202) (xy 340.581227 -305.147075) (xy 340.598661 -305.143315) (xy 340.60638 -305.138836)
			(xy 340.636929 -305.120342) (xy 340.702104 -305.09116) (xy 340.770725 -305.071396) (xy 340.841438 -305.06144)
			(xy 340.877144 -305.060858) (xy 340.907875 -305.061314) (xy 340.968887 -305.068727) (xy 341.028562 -305.083439)
			(xy 341.086028 -305.105237) (xy 341.140448 -305.133802) (xy 341.191029 -305.168717) (xy 341.237033 -305.209474)
			(xy 341.277789 -305.255479) (xy 341.312704 -305.30606) (xy 341.341267 -305.360481) (xy 341.363063 -305.417948)
			(xy 341.377775 -305.477623) (xy 341.385186 -305.538635) (xy 341.385652 -305.569366) (xy 341.385096 -305.604322)
			(xy 341.375526 -305.673576) (xy 341.356563 -305.740867) (xy 341.328562 -305.804927) (xy 341.292053 -305.864548)
			(xy 341.270336 -305.891946) (xy 341.265056 -305.898956) (xy 341.259072 -305.915439) (xy 341.258652 -305.924204)
			(xy 341.258652 -306.062634) (xy 342.14054 -306.062634) (xy 342.141042 -306.030119) (xy 342.149316 -305.965619)
			(xy 342.165747 -305.9027) (xy 342.190065 -305.842389) (xy 342.221875 -305.785671) (xy 342.260657 -305.733472)
			(xy 342.305777 -305.686643) (xy 342.356501 -305.64595) (xy 342.411998 -305.612056) (xy 342.471364 -305.585514)
			(xy 342.53363 -305.566758) (xy 342.597779 -305.556095) (xy 342.630252 -305.55438) (xy 342.64092 -305.554126)
			(xy 342.660224 -305.544728) (xy 342.722708 -305.470814) (xy 342.72855 -305.450494) (xy 342.72728 -305.439826)
			(xy 342.725742 -305.427437) (xy 342.724087 -305.402525) (xy 342.723978 -305.390042) (xy 342.724464 -305.362791)
			(xy 342.73222 -305.308843) (xy 342.747575 -305.256548) (xy 342.770217 -305.206971) (xy 342.799683 -305.161121)
			(xy 342.835374 -305.11993) (xy 342.876565 -305.084239) (xy 342.922415 -305.054773) (xy 342.971992 -305.032131)
			(xy 343.024287 -305.016776) (xy 343.078235 -305.00902) (xy 343.132737 -305.00902) (xy 343.186685 -305.016776)
			(xy 343.23898 -305.032131) (xy 343.288557 -305.054773) (xy 343.334407 -305.084239) (xy 343.375598 -305.11993)
			(xy 343.411289 -305.161121) (xy 343.440755 -305.206971) (xy 343.463397 -305.256548) (xy 343.478752 -305.308843)
			(xy 343.486508 -305.362791) (xy 343.486994 -305.390042) (xy 343.486505 -305.418099) (xy 343.478267 -305.473605)
			(xy 343.46199 -305.527306) (xy 343.438024 -305.578044) (xy 343.406885 -305.624726) (xy 343.369247 -305.666344)
			(xy 343.325919 -305.702002) (xy 343.277837 -305.730931) (xy 343.226037 -305.752506) (xy 343.198958 -305.759866)
			(xy 343.188544 -305.76266) (xy 343.17178 -305.775614) (xy 343.126314 -305.860958) (xy 343.124536 -305.882294)
			(xy 343.128092 -305.892454) (xy 343.137391 -305.919854) (xy 343.150486 -305.976218) (xy 343.157114 -306.033702)
			(xy 343.157556 -306.062634) (xy 343.157054 -306.094595) (xy 343.149043 -306.158013) (xy 343.133146 -306.219927)
			(xy 343.109614 -306.27936) (xy 343.07882 -306.335375) (xy 343.041247 -306.38709) (xy 342.99749 -306.433687)
			(xy 342.948237 -306.474432) (xy 342.897863 -306.5064) (xy 345.257361 -306.5064) (xy 345.261375 -306.442601)
			(xy 345.273353 -306.379809) (xy 345.293107 -306.319013) (xy 345.320325 -306.261172) (xy 345.354577 -306.207198)
			(xy 345.395324 -306.157943) (xy 345.441922 -306.114183) (xy 345.493638 -306.076608) (xy 345.549655 -306.045811)
			(xy 345.609091 -306.022278) (xy 345.671007 -306.00638) (xy 345.734428 -305.998367) (xy 345.76639 -305.997864)
			(xy 345.79719 -305.998317) (xy 345.858336 -306.005779) (xy 345.918133 -306.020571) (xy 345.975706 -306.042477)
			(xy 346.030212 -306.071175) (xy 346.080853 -306.106246) (xy 346.126889 -306.147176) (xy 346.167644 -306.193366)
			(xy 346.202523 -306.24414) (xy 346.231014 -306.298754) (xy 346.252701 -306.35641) (xy 346.26042 -306.38623)
			(xy 346.26296 -306.396898) (xy 346.276168 -306.413662) (xy 346.361004 -306.460144) (xy 346.382086 -306.461922)
			(xy 346.392246 -306.458366) (xy 346.422434 -306.448629) (xy 346.484992 -306.438166) (xy 346.516706 -306.437538)
			(xy 346.543961 -306.43795) (xy 346.597916 -306.445709) (xy 346.650218 -306.461068) (xy 346.699801 -306.483715)
			(xy 346.745656 -306.513187) (xy 346.78685 -306.548887) (xy 346.822544 -306.590085) (xy 346.85201 -306.635945)
			(xy 346.87465 -306.685531) (xy 346.890002 -306.737835) (xy 346.897754 -306.791791) (xy 346.898214 -306.819046)
			(xy 346.897805 -306.845744) (xy 346.890346 -306.898617) (xy 346.875593 -306.949935) (xy 346.853836 -306.998698)
			(xy 346.825497 -307.043954) (xy 346.79113 -307.08482) (xy 346.751405 -307.120501) (xy 346.707096 -307.150299)
			(xy 346.659068 -307.173634) (xy 346.6338 -307.182266) (xy 346.62237 -307.185822) (xy 346.605352 -307.202332)
			(xy 346.570554 -307.300884) (xy 346.573348 -307.324252) (xy 346.579698 -307.334412) (xy 346.595416 -307.359238)
			(xy 346.621635 -307.411824) (xy 346.641608 -307.467086) (xy 346.655068 -307.524284) (xy 346.661836 -307.582654)
			(xy 346.662248 -307.612034) (xy 346.661746 -307.643995) (xy 346.653735 -307.707413) (xy 346.637838 -307.769327)
			(xy 346.614306 -307.82876) (xy 346.583512 -307.884775) (xy 346.545939 -307.93649) (xy 346.502182 -307.983087)
			(xy 346.452929 -308.023832) (xy 346.398958 -308.058083) (xy 346.341119 -308.0853) (xy 346.280326 -308.105053)
			(xy 346.217536 -308.117031) (xy 346.15374 -308.121045) (xy 346.089944 -308.117031) (xy 346.027154 -308.105053)
			(xy 345.966361 -308.0853) (xy 345.908522 -308.058083) (xy 345.854551 -308.023832) (xy 345.805298 -307.983087)
			(xy 345.761541 -307.93649) (xy 345.723968 -307.884775) (xy 345.693174 -307.82876) (xy 345.669642 -307.769327)
			(xy 345.653745 -307.707413) (xy 345.645734 -307.643995) (xy 345.645232 -307.612034) (xy 345.645682 -307.579923)
			(xy 345.653764 -307.516213) (xy 345.669804 -307.454027) (xy 345.693545 -307.394356) (xy 345.724612 -307.338149)
			(xy 345.762508 -307.286301) (xy 345.806631 -307.239637) (xy 345.856278 -307.1989) (xy 345.910659 -307.164739)
			(xy 345.968909 -307.137697) (xy 346.0301 -307.118204) (xy 346.093259 -307.106571) (xy 346.125292 -307.104288)
			(xy 346.133884 -307.103517) (xy 346.149802 -307.096893) (xy 346.16257 -307.085307) (xy 346.166948 -307.077872)
			(xy 346.181934 -307.050694) (xy 346.185718 -307.043075) (xy 346.188536 -307.026309) (xy 346.185724 -307.009542)
			(xy 346.181934 -307.001926) (xy 346.173044 -306.984654) (xy 346.168472 -306.975002) (xy 346.151962 -306.961032)
			(xy 346.059506 -306.9336) (xy 346.03817 -306.93614) (xy 346.029026 -306.941728) (xy 345.99918 -306.959074)
			(xy 345.935804 -306.986441) (xy 345.869303 -307.004966) (xy 345.800906 -307.014307) (xy 345.76639 -307.01488)
			(xy 345.734428 -307.014433) (xy 345.671007 -307.00642) (xy 345.609091 -306.990522) (xy 345.549655 -306.966989)
			(xy 345.493638 -306.936192) (xy 345.441922 -306.898617) (xy 345.395324 -306.854857) (xy 345.354577 -306.805602)
			(xy 345.320325 -306.751628) (xy 345.293107 -306.693787) (xy 345.273353 -306.632991) (xy 345.261375 -306.570199)
			(xy 345.257361 -306.5064) (xy 342.897863 -306.5064) (xy 342.894266 -306.508683) (xy 342.836427 -306.5359)
			(xy 342.775634 -306.555653) (xy 342.712844 -306.567631) (xy 342.649048 -306.571645) (xy 342.585252 -306.567631)
			(xy 342.522462 -306.555653) (xy 342.461669 -306.5359) (xy 342.40383 -306.508683) (xy 342.349859 -306.474432)
			(xy 342.300606 -306.433687) (xy 342.256849 -306.38709) (xy 342.219276 -306.335375) (xy 342.188482 -306.27936)
			(xy 342.16495 -306.219927) (xy 342.149053 -306.158013) (xy 342.141042 -306.094595) (xy 342.14054 -306.062634)
			(xy 341.258652 -306.062634) (xy 341.258652 -306.078128) (xy 341.25901 -306.086905) (xy 341.264999 -306.103407)
			(xy 341.270336 -306.110386) (xy 341.292048 -306.137786) (xy 341.328544 -306.197412) (xy 341.356537 -306.261472)
			(xy 341.375498 -306.328761) (xy 341.385071 -306.398011) (xy 341.385652 -306.432966) (xy 341.385137 -306.466018)
			(xy 341.376563 -306.531564) (xy 341.359569 -306.595447) (xy 341.334441 -306.65659) (xy 341.301603 -306.713961)
			(xy 341.261608 -306.766594) (xy 341.215131 -306.813601) (xy 341.162955 -306.85419) (xy 341.10596 -306.887676)
			(xy 341.045106 -306.913496) (xy 340.98142 -306.931213) (xy 340.948772 -306.936394) (xy 340.938866 -306.937918)
			(xy 340.922102 -306.94757) (xy 340.866476 -307.018944) (xy 340.861142 -307.037486) (xy 340.862158 -307.047646)
			(xy 340.863117 -307.057588) (xy 340.864136 -307.077536) (xy 340.86419 -307.087524) (xy 340.863704 -307.114775)
			(xy 340.855948 -307.168723) (xy 340.840593 -307.221018) (xy 340.817951 -307.270595) (xy 340.788485 -307.316445)
			(xy 340.752794 -307.357636) (xy 340.711603 -307.393327) (xy 340.665753 -307.422793) (xy 340.616176 -307.445435)
			(xy 340.563881 -307.46079) (xy 340.509933 -307.468546) (xy 340.455431 -307.468546) (xy 340.401483 -307.46079)
			(xy 340.349188 -307.445435) (xy 340.299611 -307.422793) (xy 340.253761 -307.393327) (xy 340.21257 -307.357636)
			(xy 340.176879 -307.316445) (xy 340.147413 -307.270595) (xy 340.124771 -307.221018) (xy 340.109416 -307.168723)
			(xy 340.10166 -307.114775) (xy 340.101174 -307.087524) (xy 340.101665 -307.05915) (xy 340.110081 -307.003028)
			(xy 340.126717 -306.948772) (xy 340.151204 -306.897579) (xy 340.183005 -306.850577) (xy 340.221416 -306.808803)
			(xy 340.26559 -306.773179) (xy 340.314553 -306.744491) (xy 340.340696 -306.733448) (xy 340.350094 -306.729638)
			(xy 340.364064 -306.716176) (xy 340.401148 -306.633626) (xy 340.40191 -306.614322) (xy 340.398608 -306.60467)
			(xy 340.389101 -306.577055) (xy 340.375772 -306.520189) (xy 340.369054 -306.462169) (xy 340.368636 -306.432966)
			(xy 340.369213 -306.398011) (xy 340.378778 -306.328758) (xy 340.397737 -306.261467) (xy 340.425733 -306.197407)
			(xy 340.462237 -306.137785) (xy 340.483952 -306.110386) (xy 340.489259 -306.103394) (xy 340.495227 -306.086897)
			(xy 340.495636 -306.078128) (xy 340.495636 -305.924204) (xy 340.495266 -305.915428) (xy 340.489286 -305.898925)
			(xy 340.483952 -305.891946) (xy 340.465064 -305.868191) (xy 340.432464 -305.817) (xy 340.418928 -305.789838)
			(xy 340.41472 -305.781905) (xy 340.401843 -305.769408) (xy 340.393782 -305.765454) (xy 340.36635 -305.753262)
			(xy 340.358135 -305.749892) (xy 340.340451 -305.748445) (xy 340.331806 -305.750468) (xy 340.306845 -305.756971)
			(xy 340.255742 -305.763978) (xy 340.229952 -305.764438) (xy 340.202705 -305.763889) (xy 340.148767 -305.756127)
			(xy 340.096482 -305.740769) (xy 340.046915 -305.718127) (xy 340.001074 -305.688662) (xy 339.959893 -305.652973)
			(xy 339.924209 -305.611787) (xy 339.89475 -305.565943) (xy 339.872114 -305.516373) (xy 339.856763 -305.464086)
			(xy 339.849008 -305.410147) (xy 331.703418 -305.410147) (xy 331.702515 -305.414067) (xy 331.662754 -305.55078)
			(xy 331.615322 -305.685025) (xy 331.560371 -305.816372) (xy 331.498078 -305.944399) (xy 331.428641 -306.068697)
			(xy 331.352283 -306.188867) (xy 331.269249 -306.304525) (xy 331.179804 -306.4153) (xy 331.084235 -306.520838)
			(xy 330.982849 -306.620799) (xy 330.87597 -306.714865) (xy 330.76394 -306.802733) (xy 330.647119 -306.884122)
			(xy 330.52588 -306.958772) (xy 330.400612 -307.026443) (xy 330.271716 -307.086919) (xy 330.139605 -307.140005)
			(xy 330.004702 -307.185533) (xy 329.86744 -307.223355) (xy 329.728258 -307.253351) (xy 329.587602 -307.275425)
			(xy 329.445922 -307.289505) (xy 329.303672 -307.295548) (xy 329.161308 -307.293533) (xy 329.019287 -307.283468)
			(xy 328.878062 -307.265383) (xy 328.738087 -307.239338) (xy 328.599809 -307.205415) (xy 328.463672 -307.163723)
			(xy 328.330112 -307.114397) (xy 328.199556 -307.057593) (xy 328.072423 -306.993494) (xy 327.94912 -306.922305)
			(xy 327.830042 -306.844254) (xy 327.715571 -306.759592) (xy 327.606073 -306.668588) (xy 327.501898 -306.571536)
			(xy 327.403382 -306.468745) (xy 327.310838 -306.360546) (xy 327.224564 -306.247284) (xy 327.144836 -306.129322)
			(xy 327.071909 -306.007039) (xy 327.006018 -305.880826) (xy 326.947372 -305.751087) (xy 326.89616 -305.618238)
			(xy 326.852546 -305.482705) (xy 326.81667 -305.344921) (xy 326.788647 -305.205328) (xy 326.768566 -305.064374)
			(xy 326.756491 -304.922509) (xy 326.752462 -304.780188) (xy 323.20865 -304.780188) (xy 317.812209 -310.176629)
			(xy 332.667604 -310.176629) (xy 332.667604 -310.112707) (xy 332.675615 -310.049289) (xy 332.691512 -309.987375)
			(xy 332.715044 -309.927942) (xy 332.745838 -309.871927) (xy 332.783411 -309.820212) (xy 332.827168 -309.773615)
			(xy 332.876421 -309.73287) (xy 332.930392 -309.698619) (xy 332.988231 -309.671402) (xy 333.049024 -309.651649)
			(xy 333.111814 -309.639671) (xy 333.17561 -309.635658) (xy 333.239406 -309.639671) (xy 333.302196 -309.651649)
			(xy 333.362989 -309.671402) (xy 333.420828 -309.698619) (xy 333.474799 -309.73287) (xy 333.506735 -309.759289)
			(xy 334.460162 -309.759289) (xy 334.465371 -309.696417) (xy 334.478316 -309.634671) (xy 334.4988 -309.575002)
			(xy 334.526507 -309.518324) (xy 334.561012 -309.465509) (xy 334.601786 -309.417368) (xy 334.6482 -309.374639)
			(xy 334.699544 -309.337981) (xy 334.755028 -309.307954) (xy 334.8138 -309.285021) (xy 334.874957 -309.269535)
			(xy 334.93756 -309.261732) (xy 334.969104 -309.261256) (xy 335.004096 -309.261834) (xy 335.073421 -309.271427)
			(xy 335.140775 -309.290432) (xy 335.173066 -309.303928) (xy 335.185004 -309.309008) (xy 335.21015 -309.306976)
			(xy 335.303114 -309.24627) (xy 335.315306 -309.223918) (xy 335.315306 -309.21071) (xy 335.315747 -309.179978)
			(xy 335.323155 -309.118961) (xy 335.337864 -309.059282) (xy 335.359659 -309.001811) (xy 335.388223 -308.947386)
			(xy 335.423139 -308.896802) (xy 335.463897 -308.850795) (xy 335.509905 -308.810036) (xy 335.56049 -308.775121)
			(xy 335.614915 -308.746557) (xy 335.672386 -308.724762) (xy 335.732065 -308.710054) (xy 335.793082 -308.702647)
			(xy 335.823814 -308.702202) (xy 335.854235 -308.70268) (xy 335.914638 -308.709987) (xy 335.97374 -308.724436)
			(xy 336.002376 -308.734714) (xy 336.010738 -308.737373) (xy 336.028269 -308.73751) (xy 336.036666 -308.734968)
			(xy 336.06486 -308.725316) (xy 336.073109 -308.722239) (xy 336.086893 -308.711302) (xy 336.091784 -308.70398)
			(xy 336.10951 -308.676098) (xy 336.151114 -308.624769) (xy 336.199019 -308.579265) (xy 336.252418 -308.540353)
			(xy 336.310409 -308.50869) (xy 336.372014 -308.484809) (xy 336.436195 -308.469114) (xy 336.468974 -308.464966)
			(xy 336.477527 -308.463631) (xy 336.493109 -308.45612) (xy 336.499454 -308.450234) (xy 336.520282 -308.429152)
			(xy 336.526099 -308.422856) (xy 336.533495 -308.407404) (xy 336.53476 -308.398926) (xy 336.53864 -308.369149)
			(xy 336.554497 -308.311235) (xy 336.579231 -308.256519) (xy 336.612231 -308.206354) (xy 336.632042 -308.183788)
			(xy 336.642202 -308.172612) (xy 336.647282 -308.14391) (xy 336.600546 -308.031388) (xy 336.57667 -308.014624)
			(xy 336.561684 -308.013862) (xy 336.529231 -308.011815) (xy 336.465183 -308.00058) (xy 336.40309 -307.981274)
			(xy 336.343963 -307.954212) (xy 336.288767 -307.919836) (xy 336.238403 -307.878705) (xy 336.193691 -307.831491)
			(xy 336.155361 -307.778963) (xy 336.124038 -307.721979) (xy 336.100233 -307.661468) (xy 336.091784 -307.630068)
			(xy 336.088668 -307.619885) (xy 336.075625 -307.60309) (xy 336.056882 -307.593044) (xy 336.046318 -307.591714)
			(xy 336.014763 -307.588842) (xy 335.952666 -307.576231) (xy 335.892618 -307.556) (xy 335.835549 -307.528464)
			(xy 335.782345 -307.494049) (xy 335.73383 -307.453288) (xy 335.690757 -307.406815) (xy 335.653794 -307.355349)
			(xy 335.623512 -307.299689) (xy 335.600383 -307.240696) (xy 335.584764 -307.179287) (xy 335.576898 -307.116412)
			(xy 335.576418 -307.08473) (xy 335.576866 -307.053998) (xy 335.584272 -306.99298) (xy 335.598979 -306.933301)
			(xy 335.620772 -306.87583) (xy 335.649335 -306.821404) (xy 335.68425 -306.770819) (xy 335.725009 -306.724812)
			(xy 335.771016 -306.684053) (xy 335.821601 -306.649137) (xy 335.876026 -306.620574) (xy 335.933497 -306.59878)
			(xy 335.993176 -306.584072) (xy 336.054194 -306.576666) (xy 336.084926 -306.576222) (xy 336.115533 -306.57669)
			(xy 336.176303 -306.584063) (xy 336.235748 -306.598677) (xy 336.29301 -306.620319) (xy 336.34726 -306.648677)
			(xy 336.397715 -306.683341) (xy 336.443645 -306.723809) (xy 336.484387 -306.769497) (xy 336.519351 -306.819745)
			(xy 336.548031 -306.873825) (xy 336.570014 -306.930957) (xy 336.57794 -306.960524) (xy 336.581042 -306.970713)
			(xy 336.59409 -306.98751) (xy 336.61284 -306.997552) (xy 336.623406 -306.998878) (xy 336.644318 -307.000687)
			(xy 336.685773 -307.007296) (xy 336.70621 -307.012086) (xy 336.715912 -307.014046) (xy 336.735481 -307.01118)
			(xy 336.752512 -307.001124) (xy 336.764474 -306.985373) (xy 336.769589 -306.966268) (xy 336.767098 -306.946647)
			(xy 336.75737 -306.929427) (xy 336.749898 -306.922932) (xy 336.724514 -306.902221) (xy 336.678772 -306.855319)
			(xy 336.639434 -306.802929) (xy 336.607153 -306.74592) (xy 336.582464 -306.685235) (xy 336.565776 -306.621882)
			(xy 336.557365 -306.556909) (xy 336.556858 -306.524152) (xy 336.55731 -306.493421) (xy 336.564724 -306.432408)
			(xy 336.579437 -306.372734) (xy 336.601234 -306.315268) (xy 336.6298 -306.260847) (xy 336.664715 -306.210267)
			(xy 336.705473 -306.164263) (xy 336.751478 -306.123507) (xy 336.802059 -306.088592) (xy 336.85648 -306.060029)
			(xy 336.913947 -306.038232) (xy 336.973622 -306.023521) (xy 337.034635 -306.01611) (xy 337.065366 -306.015644)
			(xy 337.096619 -306.016114) (xy 337.158653 -306.023783) (xy 337.219279 -306.038996) (xy 337.277584 -306.061525)
			(xy 337.332688 -306.09103) (xy 337.383761 -306.127066) (xy 337.430032 -306.16909) (xy 337.470804 -306.216468)
			(xy 337.48853 -306.242212) (xy 337.496404 -306.253896) (xy 337.520788 -306.265834) (xy 337.636866 -306.257198)
			(xy 337.659218 -306.241704) (xy 337.66506 -306.229258) (xy 337.679112 -306.200524) (xy 337.713341 -306.146488)
			(xy 337.754078 -306.097172) (xy 337.800679 -306.053356) (xy 337.852408 -306.015732) (xy 337.908448 -305.984893)
			(xy 337.967914 -305.961328) (xy 338.029866 -305.945409) (xy 338.093326 -305.937386) (xy 338.125308 -305.936904)
			(xy 338.156041 -305.93733) (xy 338.217058 -305.94474) (xy 338.276737 -305.959451) (xy 338.334208 -305.981248)
			(xy 338.388632 -306.009813) (xy 338.439217 -306.04473) (xy 338.485224 -306.08549) (xy 338.525982 -306.131499)
			(xy 338.560897 -306.182085) (xy 338.589461 -306.23651) (xy 338.611255 -306.293982) (xy 338.625964 -306.353662)
			(xy 338.633371 -306.414679) (xy 338.633816 -306.445412) (xy 338.63329 -306.47859) (xy 338.624658 -306.544382)
			(xy 338.607541 -306.608492) (xy 338.582231 -306.669831) (xy 338.549158 -306.727357) (xy 338.508884 -306.780093)
			(xy 338.462092 -306.827142) (xy 338.409578 -306.867705) (xy 338.352234 -306.901093) (xy 338.291035 -306.926739)
			(xy 338.22702 -306.944207) (xy 338.161276 -306.9532) (xy 338.128102 -306.95392) (xy 338.115402 -306.95392)
			(xy 338.093304 -306.965858) (xy 338.032344 -307.057044) (xy 338.029804 -307.08219) (xy 338.03463 -307.093874)
			(xy 338.045381 -307.121376) (xy 338.061219 -307.178263) (xy 338.070372 -307.236601) (xy 338.071968 -307.266086)
			(xy 338.072743 -307.275619) (xy 338.080451 -307.293108) (xy 338.086954 -307.300122) (xy 338.109052 -307.32222)
			(xy 338.116 -307.328559) (xy 338.133211 -307.336109) (xy 338.14258 -307.336952) (xy 338.168995 -307.338604)
			(xy 338.221032 -307.348264) (xy 338.271232 -307.365027) (xy 338.318632 -307.388572) (xy 338.362321 -307.418445)
			(xy 338.401458 -307.454074) (xy 338.435292 -307.494772) (xy 338.463172 -307.539758) (xy 338.464674 -307.543157)
			(xy 343.824808 -307.543157) (xy 343.824808 -307.479235) (xy 343.832819 -307.415817) (xy 343.848716 -307.353903)
			(xy 343.872248 -307.29447) (xy 343.903042 -307.238455) (xy 343.940615 -307.18674) (xy 343.984372 -307.140143)
			(xy 344.033625 -307.099398) (xy 344.087596 -307.065147) (xy 344.145435 -307.03793) (xy 344.206228 -307.018177)
			(xy 344.269018 -307.006199) (xy 344.332814 -307.002186) (xy 344.39661 -307.006199) (xy 344.4594 -307.018177)
			(xy 344.520193 -307.03793) (xy 344.578032 -307.065147) (xy 344.632003 -307.099398) (xy 344.681256 -307.140143)
			(xy 344.725013 -307.18674) (xy 344.762586 -307.238455) (xy 344.79338 -307.29447) (xy 344.816912 -307.353903)
			(xy 344.832809 -307.415817) (xy 344.84082 -307.479235) (xy 344.841322 -307.511196) (xy 344.84082 -307.543157)
			(xy 344.832809 -307.606575) (xy 344.816912 -307.668489) (xy 344.79338 -307.727922) (xy 344.762586 -307.783937)
			(xy 344.725013 -307.835652) (xy 344.681256 -307.882249) (xy 344.632003 -307.922994) (xy 344.578032 -307.957245)
			(xy 344.520193 -307.984462) (xy 344.4594 -308.004215) (xy 344.39661 -308.016193) (xy 344.332814 -308.020207)
			(xy 344.269018 -308.016193) (xy 344.206228 -308.004215) (xy 344.145435 -307.984462) (xy 344.087596 -307.957245)
			(xy 344.033625 -307.922994) (xy 343.984372 -307.882249) (xy 343.940615 -307.835652) (xy 343.903042 -307.783937)
			(xy 343.872248 -307.727922) (xy 343.848716 -307.668489) (xy 343.832819 -307.606575) (xy 343.824808 -307.543157)
			(xy 338.464674 -307.543157) (xy 338.484564 -307.588168) (xy 338.499055 -307.639071) (xy 338.506367 -307.691489)
			(xy 338.506816 -307.717952) (xy 338.5063 -307.745203) (xy 338.49855 -307.799152) (xy 338.4832 -307.851448)
			(xy 338.460564 -307.901028) (xy 338.431102 -307.946881) (xy 338.395413 -307.988074) (xy 338.354226 -308.023768)
			(xy 338.308377 -308.053237) (xy 338.258801 -308.075881) (xy 338.206507 -308.091238) (xy 338.152559 -308.098996)
			(xy 338.125308 -308.09946) (xy 338.098461 -308.098997) (xy 338.045295 -308.091494) (xy 337.993707 -308.076608)
			(xy 337.944717 -308.054632) (xy 337.899294 -308.026002) (xy 337.858336 -307.991283) (xy 337.822653 -307.951162)
			(xy 337.792951 -307.906432) (xy 337.769817 -307.857978) (xy 337.761326 -307.832506) (xy 337.758185 -307.82361)
			(xy 337.746425 -307.808871) (xy 337.738466 -307.803804) (xy 337.711796 -307.788056) (xy 337.703327 -307.783565)
			(xy 337.684388 -307.780698) (xy 337.674966 -307.782468) (xy 337.647574 -307.788186) (xy 337.591948 -307.794292)
			(xy 337.563968 -307.79466) (xy 337.532396 -307.794194) (xy 337.469736 -307.786382) (xy 337.408527 -307.77087)
			(xy 337.34971 -307.747897) (xy 337.294191 -307.717816) (xy 337.242825 -307.681091) (xy 337.21929 -307.66004)
			(xy 337.209892 -307.651404) (xy 337.186016 -307.645054) (xy 337.079844 -307.66893) (xy 337.061048 -307.684932)
			(xy 337.056222 -307.696616) (xy 337.044755 -307.723791) (xy 337.016464 -307.775549) (xy 336.982372 -307.823684)
			(xy 336.942937 -307.867549) (xy 336.921094 -307.88737) (xy 336.909918 -307.897276) (xy 336.90179 -307.925216)
			(xy 336.935826 -308.04231) (xy 336.957924 -308.061614) (xy 336.972656 -308.0639) (xy 336.999301 -308.068469)
			(xy 337.051011 -308.084241) (xy 337.099977 -308.107155) (xy 337.145217 -308.136752) (xy 337.185826 -308.17244)
			(xy 337.22099 -308.213504) (xy 337.250004 -308.25912) (xy 337.272288 -308.308376) (xy 337.287395 -308.360284)
			(xy 337.295022 -308.413805) (xy 337.29549 -308.440836) (xy 337.295021 -308.468432) (xy 337.28705 -308.523047)
			(xy 337.271295 -308.575943) (xy 337.248085 -308.626018) (xy 337.217902 -308.672227) (xy 337.181378 -308.713606)
			(xy 337.139274 -308.749292) (xy 337.092468 -308.77854) (xy 337.067398 -308.790086) (xy 337.059656 -308.793824)
			(xy 337.047054 -308.805499) (xy 337.04276 -308.812946) (xy 337.02879 -308.839362) (xy 337.025092 -308.847197)
			(xy 337.02262 -308.864332) (xy 337.023964 -308.87289) (xy 337.028378 -308.897031) (xy 337.033082 -308.945886)
			(xy 337.033362 -308.970426) (xy 337.032987 -309.00116) (xy 337.025574 -309.062181) (xy 337.01086 -309.121863)
			(xy 336.98906 -309.179336) (xy 336.96049 -309.233762) (xy 336.925568 -309.284348) (xy 336.908895 -309.303166)
			(xy 341.391494 -309.303166) (xy 341.392058 -309.26821) (xy 341.401624 -309.198956) (xy 341.420585 -309.131665)
			(xy 341.448584 -309.067605) (xy 341.485093 -309.007984) (xy 341.50681 -308.980586) (xy 341.512087 -308.973591)
			(xy 341.51793 -308.957085) (xy 341.51824 -308.948328) (xy 341.51824 -308.794404) (xy 341.517885 -308.785656)
			(xy 341.512044 -308.769164) (xy 341.50681 -308.762146) (xy 341.48512 -308.73473) (xy 341.448618 -308.675109)
			(xy 341.420621 -308.611053) (xy 341.401655 -308.543768) (xy 341.392077 -308.47452) (xy 341.391494 -308.439566)
			(xy 341.391924 -308.408834) (xy 341.399336 -308.347819) (xy 341.414049 -308.288142) (xy 341.435847 -308.230674)
			(xy 341.464413 -308.176252) (xy 341.499331 -308.12567) (xy 341.54009 -308.079665) (xy 341.586098 -308.038909)
			(xy 341.636683 -308.003995) (xy 341.691107 -307.975432) (xy 341.748577 -307.953638) (xy 341.808255 -307.93893)
			(xy 341.86927 -307.931521) (xy 341.900002 -307.931058) (xy 341.931057 -307.931519) (xy 341.992704 -307.939091)
			(xy 342.052965 -307.954134) (xy 342.08212 -307.96484) (xy 342.09101 -307.968142) (xy 342.109552 -307.968142)
			(xy 342.190324 -307.937408) (xy 342.204294 -307.925216) (xy 342.208612 -307.916834) (xy 342.221035 -307.893937)
			(xy 342.251095 -307.851394) (xy 342.286665 -307.813337) (xy 342.327083 -307.780476) (xy 342.371598 -307.753421)
			(xy 342.41938 -307.732677) (xy 342.469542 -307.718629) (xy 342.521148 -307.711538) (xy 342.547194 -307.711094)
			(xy 342.574447 -307.711553) (xy 342.628399 -307.719309) (xy 342.680698 -307.734665) (xy 342.730279 -307.757307)
			(xy 342.776133 -307.786775) (xy 342.817327 -307.822469) (xy 342.853021 -307.863662) (xy 342.88249 -307.909516)
			(xy 342.905133 -307.959096) (xy 342.920489 -308.011395) (xy 342.928247 -308.065347) (xy 342.928247 -308.119853)
			(xy 342.920489 -308.173805) (xy 342.905133 -308.226104) (xy 342.88249 -308.275684) (xy 342.853021 -308.321538)
			(xy 342.817327 -308.362731) (xy 342.776133 -308.398425) (xy 342.730279 -308.427893) (xy 342.680698 -308.450535)
			(xy 342.628399 -308.465891) (xy 342.574447 -308.473647) (xy 342.547194 -308.47411) (xy 342.536949 -308.474015)
			(xy 342.516491 -308.472873) (xy 342.5063 -308.471824) (xy 342.496902 -308.470808) (xy 342.478868 -308.475634)
			(xy 342.40851 -308.525926) (xy 342.39835 -308.54142) (xy 342.396318 -308.550818) (xy 342.389409 -308.579675)
			(xy 342.369756 -308.635667) (xy 342.343732 -308.688996) (xy 342.311687 -308.738941) (xy 342.293194 -308.762146)
			(xy 342.287945 -308.76916) (xy 342.282086 -308.785651) (xy 342.281764 -308.794404) (xy 342.281764 -308.948328)
			(xy 342.282123 -308.957075) (xy 342.287963 -308.973566) (xy 342.293194 -308.980586) (xy 342.312082 -309.004341)
			(xy 342.344682 -309.055532) (xy 342.358218 -309.082694) (xy 342.362401 -309.090642) (xy 342.375295 -309.103131)
			(xy 342.383364 -309.107078) (xy 342.410796 -309.11927) (xy 342.419003 -309.122663) (xy 342.436694 -309.124094)
			(xy 342.44534 -309.122064) (xy 342.470303 -309.11557) (xy 342.521404 -309.108557) (xy 342.547194 -309.108094)
			(xy 342.574447 -309.108553) (xy 342.628399 -309.116309) (xy 342.680698 -309.131665) (xy 342.730279 -309.154307)
			(xy 342.776133 -309.183775) (xy 342.817327 -309.219469) (xy 342.853021 -309.260662) (xy 342.88249 -309.306516)
			(xy 342.905133 -309.356096) (xy 342.920489 -309.408395) (xy 342.928247 -309.462347) (xy 342.928247 -309.516853)
			(xy 342.920489 -309.570805) (xy 342.905133 -309.623104) (xy 342.88249 -309.672684) (xy 342.853021 -309.718538)
			(xy 342.817327 -309.759731) (xy 342.776133 -309.795425) (xy 342.730279 -309.824893) (xy 342.680698 -309.847535)
			(xy 342.628399 -309.862891) (xy 342.574447 -309.870647) (xy 342.547194 -309.87111) (xy 342.520745 -309.870648)
			(xy 342.468354 -309.863351) (xy 342.417474 -309.848884) (xy 342.369081 -309.827524) (xy 342.324104 -309.799682)
			(xy 342.283406 -309.765891) (xy 342.265254 -309.74665) (xy 342.259078 -309.74035) (xy 342.243467 -309.732155)
			(xy 342.234774 -309.730648) (xy 342.204802 -309.72633) (xy 342.19592 -309.725425) (xy 342.178483 -309.729206)
			(xy 342.170766 -309.733696) (xy 342.140208 -309.752174) (xy 342.075036 -309.781359) (xy 342.006418 -309.801127)
			(xy 341.935707 -309.811088) (xy 341.900002 -309.811674) (xy 341.869269 -309.81126) (xy 341.80825 -309.803851)
			(xy 341.74857 -309.789141) (xy 341.691097 -309.767344) (xy 341.636672 -309.738778) (xy 341.586086 -309.70386)
			(xy 341.540079 -309.663098) (xy 341.499321 -309.617088) (xy 341.464406 -309.566501) (xy 341.435843 -309.512073)
			(xy 341.41405 -309.4546) (xy 341.399343 -309.394918) (xy 341.391938 -309.333899) (xy 341.391494 -309.303166)
			(xy 336.908895 -309.303166) (xy 336.884804 -309.330355) (xy 336.838791 -309.371113) (xy 336.7882 -309.406027)
			(xy 336.73377 -309.434589) (xy 336.676294 -309.456382) (xy 336.61661 -309.471087) (xy 336.555588 -309.478491)
			(xy 336.524854 -309.478934) (xy 336.494433 -309.478463) (xy 336.43403 -309.471153) (xy 336.374928 -309.456701)
			(xy 336.346292 -309.446422) (xy 336.337935 -309.443747) (xy 336.320399 -309.44362) (xy 336.312002 -309.446168)
			(xy 336.283808 -309.45582) (xy 336.275565 -309.458909) (xy 336.261776 -309.469837) (xy 336.256884 -309.477156)
			(xy 336.239492 -309.504503) (xy 336.198801 -309.554947) (xy 336.152028 -309.599811) (xy 336.099932 -309.638364)
			(xy 336.043358 -309.669983) (xy 335.983224 -309.694155) (xy 335.920505 -309.710487) (xy 335.856219 -309.718714)
			(xy 335.823814 -309.719218) (xy 335.788822 -309.718636) (xy 335.719498 -309.709045) (xy 335.652143 -309.690041)
			(xy 335.619852 -309.676546) (xy 335.607914 -309.671466) (xy 335.582768 -309.673498) (xy 335.489804 -309.734204)
			(xy 335.477612 -309.756556) (xy 335.477612 -309.769764) (xy 335.47717 -309.801308) (xy 335.469371 -309.863911)
			(xy 335.453888 -309.92507) (xy 335.430959 -309.983843) (xy 335.400936 -310.039329) (xy 335.364281 -310.090675)
			(xy 335.321555 -310.137092) (xy 335.273417 -310.177868) (xy 335.220604 -310.212377) (xy 335.163928 -310.240088)
			(xy 335.104259 -310.260575) (xy 335.042515 -310.273525) (xy 334.979643 -310.278737) (xy 334.916609 -310.276133)
			(xy 334.854382 -310.265752) (xy 334.793916 -310.247753) (xy 334.736141 -310.222413) (xy 334.681945 -310.190121)
			(xy 334.632158 -310.151374) (xy 334.587547 -310.106766) (xy 334.548797 -310.056982) (xy 334.516502 -310.002787)
			(xy 334.491158 -309.945014) (xy 334.473156 -309.884549) (xy 334.46277 -309.822322) (xy 334.460162 -309.759289)
			(xy 333.506735 -309.759289) (xy 333.524052 -309.773615) (xy 333.567809 -309.820212) (xy 333.605382 -309.871927)
			(xy 333.636176 -309.927942) (xy 333.659708 -309.987375) (xy 333.675605 -310.049289) (xy 333.683616 -310.112707)
			(xy 333.684118 -310.144668) (xy 333.683616 -310.176629) (xy 333.675605 -310.240047) (xy 333.659708 -310.301961)
			(xy 333.636176 -310.361394) (xy 333.605382 -310.417409) (xy 333.597591 -310.428132) (xy 337.30514 -310.428132)
			(xy 337.309211 -310.37251) (xy 337.321337 -310.318073) (xy 337.34126 -310.265982) (xy 337.368556 -310.217347)
			(xy 337.402642 -310.173204) (xy 337.442791 -310.134495) (xy 337.488149 -310.102044) (xy 337.537749 -310.076543)
			(xy 337.590533 -310.058536) (xy 337.645376 -310.048406) (xy 337.70111 -310.046369) (xy 337.756547 -310.052469)
			(xy 337.810504 -310.066575) (xy 337.861833 -310.088387) (xy 337.909439 -310.117441) (xy 337.952307 -310.153116)
			(xy 337.989524 -310.194653) (xy 338.020297 -310.241166) (xy 338.043969 -310.291663) (xy 338.060037 -310.34507)
			(xy 338.068157 -310.400246) (xy 338.068665 -310.4281) (xy 338.321221 -310.4281) (xy 338.325235 -310.364311)
			(xy 338.33721 -310.301529) (xy 338.35696 -310.240742) (xy 338.384172 -310.18291) (xy 338.418418 -310.128944)
			(xy 338.459157 -310.079695) (xy 338.505747 -310.03594) (xy 338.557453 -309.99837) (xy 338.61346 -309.967575)
			(xy 338.672885 -309.944043) (xy 338.734791 -309.928144) (xy 338.798201 -309.920128) (xy 338.830158 -309.919624)
			(xy 338.860799 -309.920055) (xy 338.921636 -309.92743) (xy 338.981144 -309.942067) (xy 339.038462 -309.963751)
			(xy 339.092756 -309.99217) (xy 339.143239 -310.026911) (xy 339.18918 -310.067469) (xy 339.209888 -310.090058)
			(xy 339.216238 -310.096916) (xy 339.232494 -310.105552) (xy 339.318346 -310.115458) (xy 339.33638 -310.11114)
			(xy 339.344 -310.105552) (xy 339.368184 -310.089318) (xy 339.420443 -310.063598) (xy 339.476002 -310.046113)
			(xy 339.533571 -310.037267) (xy 339.562694 -310.036718) (xy 339.589949 -310.037128) (xy 339.643904 -310.044885)
			(xy 339.696207 -310.060242) (xy 339.745791 -310.082886) (xy 339.791648 -310.112355) (xy 339.832844 -310.148052)
			(xy 339.868541 -310.189247) (xy 339.898012 -310.235104) (xy 339.920656 -310.284688) (xy 339.936013 -310.33699)
			(xy 339.943771 -310.390945) (xy 339.943771 -310.445455) (xy 339.936013 -310.49941) (xy 339.920656 -310.551712)
			(xy 339.898012 -310.601296) (xy 339.868541 -310.647153) (xy 339.832844 -310.688348) (xy 339.791648 -310.724045)
			(xy 339.745791 -310.753514) (xy 339.696207 -310.776158) (xy 339.643904 -310.791515) (xy 339.589949 -310.799272)
			(xy 339.562694 -310.799734) (xy 339.534878 -310.799218) (xy 339.479835 -310.791143) (xy 339.426546 -310.775167)
			(xy 339.376141 -310.751626) (xy 339.352636 -310.736742) (xy 339.344762 -310.731408) (xy 339.326728 -310.727344)
			(xy 339.24113 -310.73979) (xy 339.224874 -310.74868) (xy 339.219032 -310.756046) (xy 339.198244 -310.779884)
			(xy 339.151785 -310.822803) (xy 339.10036 -310.859626) (xy 339.044765 -310.889785) (xy 338.985857 -310.912814)
			(xy 338.924547 -310.928357) (xy 338.861783 -310.936174) (xy 338.830158 -310.93664) (xy 338.798201 -310.936072)
			(xy 338.734791 -310.928056) (xy 338.672885 -310.912157) (xy 338.61346 -310.888625) (xy 338.557453 -310.85783)
			(xy 338.505747 -310.82026) (xy 338.459157 -310.776505) (xy 338.418418 -310.727256) (xy 338.384172 -310.67329)
			(xy 338.35696 -310.615458) (xy 338.33721 -310.554671) (xy 338.325235 -310.491889) (xy 338.321221 -310.4281)
			(xy 338.068665 -310.4281) (xy 338.068666 -310.428132) (xy 338.068157 -310.456018) (xy 338.060037 -310.511194)
			(xy 338.043969 -310.564601) (xy 338.020297 -310.615098) (xy 337.989524 -310.661611) (xy 337.952307 -310.703148)
			(xy 337.909439 -310.738823) (xy 337.861833 -310.767877) (xy 337.810504 -310.789689) (xy 337.756547 -310.803795)
			(xy 337.70111 -310.809895) (xy 337.645376 -310.807858) (xy 337.590533 -310.797728) (xy 337.537749 -310.779721)
			(xy 337.488149 -310.75422) (xy 337.442791 -310.721769) (xy 337.402642 -310.68306) (xy 337.368556 -310.638917)
			(xy 337.34126 -310.590282) (xy 337.321337 -310.538191) (xy 337.309211 -310.483754) (xy 337.30514 -310.428132)
			(xy 333.597591 -310.428132) (xy 333.567809 -310.469124) (xy 333.524052 -310.515721) (xy 333.474799 -310.556466)
			(xy 333.420828 -310.590717) (xy 333.362989 -310.617934) (xy 333.302196 -310.637687) (xy 333.239406 -310.649665)
			(xy 333.17561 -310.653679) (xy 333.111814 -310.649665) (xy 333.049024 -310.637687) (xy 332.988231 -310.617934)
			(xy 332.930392 -310.590717) (xy 332.876421 -310.556466) (xy 332.827168 -310.515721) (xy 332.783411 -310.469124)
			(xy 332.745838 -310.417409) (xy 332.715044 -310.361394) (xy 332.691512 -310.301961) (xy 332.675615 -310.240047)
			(xy 332.667604 -310.176629) (xy 317.812209 -310.176629) (xy 308.129432 -319.859406) (xy 308.12203 -319.866241)
			(xy 308.103431 -319.87395) (xy 308.093364 -319.874392) (xy 262.663686 -319.874392) (xy 262.653681 -319.873901)
			(xy 262.635195 -319.866239) (xy 262.621049 -319.852086) (xy 262.613394 -319.833597) (xy 262.612886 -319.823592)
			(xy 262.612886 -298.330112) (xy 262.605266 -298.311316) (xy 262.5979 -298.304204) (xy 259.562346 -295.26865)
			(xy 259.554947 -295.261807) (xy 259.536348 -295.254084) (xy 259.526278 -295.253664) (xy 214.595456 -295.253664)
			(xy 214.57666 -295.261284) (xy 214.569548 -295.26865) (xy 212.370162 -297.468036) (xy 212.363315 -297.475433)
			(xy 212.355583 -297.494032) (xy 212.355176 -297.504104) (xy 212.355176 -319.296034) (xy 212.354746 -319.306101)
			(xy 212.34702 -319.324694) (xy 212.34019 -319.332102) (xy 211.812886 -319.859406) (xy 211.805486 -319.86625)
			(xy 211.786889 -319.873978) (xy 211.776818 -319.874392) (xy 211.644738 -319.874392) (xy 211.630585 -319.874851)
			(xy 211.603367 -319.882617) (xy 211.57933 -319.897562) (xy 211.560323 -319.918536) (xy 211.54781 -319.943924)
			(xy 211.542753 -319.971774) (xy 211.545543 -319.999941) (xy 211.555963 -320.026257) (xy 211.573212 -320.048699)
			(xy 211.584286 -320.057526) (xy 211.634829 -320.09556) (xy 211.731609 -320.177029) (xy 211.823136 -320.264358)
			(xy 211.909056 -320.35721) (xy 211.989035 -320.455226) (xy 212.062763 -320.558025) (xy 212.129957 -320.665211)
			(xy 212.190355 -320.776367) (xy 212.243724 -320.891064) (xy 212.289857 -321.008858) (xy 212.328576 -321.129293)
			(xy 212.35973 -321.251902) (xy 212.383199 -321.376212) (xy 212.398893 -321.50174) (xy 212.40675 -321.628001)
			(xy 212.407246 -321.691254) (xy 212.40672 -321.756943) (xy 212.404662 -321.788747) (xy 213.931494 -321.788747)
			(xy 213.931494 -321.724825) (xy 213.939505 -321.661407) (xy 213.955402 -321.599493) (xy 213.978934 -321.54006)
			(xy 214.009728 -321.484045) (xy 214.047301 -321.43233) (xy 214.091058 -321.385733) (xy 214.140311 -321.344988)
			(xy 214.194282 -321.310737) (xy 214.252121 -321.28352) (xy 214.312914 -321.263767) (xy 214.375704 -321.251789)
			(xy 214.4395 -321.247776) (xy 214.503296 -321.251789) (xy 214.566086 -321.263767) (xy 214.626879 -321.28352)
			(xy 214.684718 -321.310737) (xy 214.738689 -321.344988) (xy 214.787942 -321.385733) (xy 214.831699 -321.43233)
			(xy 214.869272 -321.484045) (xy 214.900066 -321.54006) (xy 214.923598 -321.599493) (xy 214.939495 -321.661407)
			(xy 214.947506 -321.724825) (xy 214.948008 -321.756786) (xy 214.947506 -321.788747) (xy 214.939495 -321.852165)
			(xy 214.923598 -321.914079) (xy 214.900066 -321.973512) (xy 214.869272 -322.029527) (xy 214.831699 -322.081242)
			(xy 214.787942 -322.127839) (xy 214.738689 -322.168584) (xy 214.684718 -322.202835) (xy 214.626879 -322.230052)
			(xy 214.566086 -322.249805) (xy 214.503296 -322.261783) (xy 214.4395 -322.265797) (xy 214.375704 -322.261783)
			(xy 214.312914 -322.249805) (xy 214.252121 -322.230052) (xy 214.194282 -322.202835) (xy 214.140311 -322.168584)
			(xy 214.091058 -322.127839) (xy 214.047301 -322.081242) (xy 214.009728 -322.029527) (xy 213.978934 -321.973512)
			(xy 213.955402 -321.914079) (xy 213.939505 -321.852165) (xy 213.931494 -321.788747) (xy 212.404662 -321.788747)
			(xy 212.398238 -321.888048) (xy 212.381307 -322.018331) (xy 212.355998 -322.147249) (xy 212.322417 -322.274263)
			(xy 212.280702 -322.398844) (xy 212.23103 -322.52047) (xy 212.228639 -322.52539) (xy 214.686132 -322.52539)
			(xy 214.690203 -322.469768) (xy 214.702329 -322.415331) (xy 214.722252 -322.36324) (xy 214.749548 -322.314605)
			(xy 214.783634 -322.270462) (xy 214.823783 -322.231753) (xy 214.869141 -322.199302) (xy 214.918741 -322.173801)
			(xy 214.971525 -322.155794) (xy 215.026368 -322.145664) (xy 215.082102 -322.143627) (xy 215.137539 -322.149727)
			(xy 215.191496 -322.163833) (xy 215.242825 -322.185645) (xy 215.290431 -322.214699) (xy 215.333299 -322.250374)
			(xy 215.370516 -322.291911) (xy 215.401289 -322.338424) (xy 215.424961 -322.388921) (xy 215.441029 -322.442328)
			(xy 215.449149 -322.497504) (xy 215.449658 -322.52539) (xy 215.449149 -322.553276) (xy 215.441029 -322.608452)
			(xy 215.424961 -322.661859) (xy 215.401289 -322.712356) (xy 215.370516 -322.758869) (xy 215.333299 -322.800406)
			(xy 215.290431 -322.836081) (xy 215.242825 -322.865135) (xy 215.191496 -322.886947) (xy 215.137539 -322.901053)
			(xy 215.082102 -322.907153) (xy 215.026368 -322.905116) (xy 214.971525 -322.894986) (xy 214.918741 -322.876979)
			(xy 214.869141 -322.851478) (xy 214.823783 -322.819027) (xy 214.783634 -322.780318) (xy 214.749548 -322.736175)
			(xy 214.722252 -322.68754) (xy 214.702329 -322.635449) (xy 214.690203 -322.581012) (xy 214.686132 -322.52539)
			(xy 212.228639 -322.52539) (xy 212.173606 -322.638635) (xy 212.108671 -322.752845) (xy 212.036496 -322.862622)
			(xy 211.957382 -322.96751) (xy 211.871659 -323.067069) (xy 211.779686 -323.160884) (xy 211.731098 -323.205094)
			(xy 211.720519 -323.21526) (xy 211.705185 -323.240259) (xy 211.697589 -323.268585) (xy 211.698356 -323.297902)
			(xy 211.707423 -323.325792) (xy 211.724043 -323.349955) (xy 211.735162 -323.359526) (xy 211.759971 -323.380282)
			(xy 211.804656 -323.427052) (xy 211.843055 -323.479106) (xy 211.874549 -323.535607) (xy 211.898629 -323.595643)
			(xy 211.914908 -323.658246) (xy 211.923123 -323.722408) (xy 211.92363 -323.75475) (xy 211.92363 -323.755258)
			(xy 211.923086 -323.788945) (xy 211.914197 -323.85573) (xy 211.896568 -323.920757) (xy 211.870508 -323.982887)
			(xy 211.836474 -324.041033) (xy 211.816188 -324.067932) (xy 211.811108 -324.074536) (xy 211.802726 -324.097142)
			(xy 211.802472 -324.113906) (xy 211.805266 -324.122288) (xy 211.809584 -324.135496) (xy 211.813902 -324.141846)
			(xy 211.814156 -324.1421) (xy 211.831642 -324.167852) (xy 211.860895 -324.222797) (xy 211.883226 -324.2809)
			(xy 211.898302 -324.341294) (xy 211.905896 -324.403076) (xy 211.906358 -324.4342) (xy 211.906358 -324.434454)
			(xy 211.905856 -324.466431) (xy 211.897841 -324.529881) (xy 211.881936 -324.591826) (xy 211.858393 -324.651288)
			(xy 211.827583 -324.707332) (xy 211.789991 -324.759072) (xy 211.746212 -324.805692) (xy 211.696934 -324.846458)
			(xy 211.642936 -324.880726) (xy 211.585069 -324.907957) (xy 211.524245 -324.92772) (xy 211.461424 -324.939703)
			(xy 211.397596 -324.943719) (xy 211.333768 -324.939703) (xy 211.270947 -324.92772) (xy 211.210123 -324.907957)
			(xy 211.152256 -324.880726) (xy 211.098258 -324.846458) (xy 211.04898 -324.805692) (xy 211.005201 -324.759072)
			(xy 210.967609 -324.707332) (xy 210.936799 -324.651288) (xy 210.913256 -324.591826) (xy 210.897351 -324.529881)
			(xy 210.889336 -324.466431) (xy 210.888834 -324.434454) (xy 210.888834 -324.4342) (xy 210.889381 -324.400514)
			(xy 210.898276 -324.333732) (xy 210.915911 -324.26871) (xy 210.941977 -324.206585) (xy 210.976018 -324.148446)
			(xy 210.996276 -324.121526) (xy 211.001356 -324.114922) (xy 211.009738 -324.092316) (xy 211.009992 -324.075552)
			(xy 211.007198 -324.06717) (xy 211.00288 -324.053962) (xy 210.998562 -324.047612) (xy 210.998308 -324.047358)
			(xy 210.982043 -324.023455) (xy 210.954431 -323.972654) (xy 210.932763 -323.919049) (xy 210.917316 -323.863331)
			(xy 210.908292 -323.80622) (xy 210.906614 -323.777356) (xy 210.905513 -323.762699) (xy 210.895983 -323.734906)
			(xy 210.878939 -323.710975) (xy 210.855788 -323.692883) (xy 210.828447 -323.682126) (xy 210.799175 -323.679595)
			(xy 210.784694 -323.682106) (xy 210.717149 -323.695457) (xy 210.580715 -323.714086) (xy 210.443334 -323.723431)
			(xy 210.374484 -323.724016) (xy 210.310618 -323.723524) (xy 210.183139 -323.715503) (xy 210.056414 -323.699493)
			(xy 209.930945 -323.675557) (xy 209.807227 -323.64379) (xy 209.685747 -323.604317) (xy 209.566986 -323.557295)
			(xy 209.451412 -323.502908) (xy 209.33948 -323.441371) (xy 209.231634 -323.372928) (xy 209.128298 -323.297848)
			(xy 209.02988 -323.216427) (xy 208.936769 -323.128987) (xy 208.849332 -323.035874) (xy 208.767914 -322.937453)
			(xy 208.692837 -322.834115) (xy 208.624397 -322.726266) (xy 208.562864 -322.614333) (xy 208.50848 -322.498757)
			(xy 208.461462 -322.379994) (xy 208.421993 -322.258514) (xy 208.39023 -322.134794) (xy 208.366298 -322.009324)
			(xy 208.350291 -321.8826) (xy 208.342274 -321.75512) (xy 208.341722 -321.691254) (xy 208.342205 -321.628002)
			(xy 208.350073 -321.501743) (xy 208.365777 -321.376217) (xy 208.389254 -321.25191) (xy 208.420414 -321.129304)
			(xy 208.459137 -321.008872) (xy 208.505273 -320.891081) (xy 208.558644 -320.776386) (xy 208.619042 -320.665231)
			(xy 208.686234 -320.558047) (xy 208.759961 -320.455248) (xy 208.839936 -320.357231) (xy 208.925851 -320.264376)
			(xy 209.017373 -320.177043) (xy 209.114147 -320.095569) (xy 209.164682 -320.057526) (xy 209.175757 -320.048721)
			(xy 209.192958 -320.026271) (xy 209.203341 -319.999964) (xy 209.206107 -319.971817) (xy 209.201046 -319.943992)
			(xy 209.188544 -319.918623) (xy 209.169563 -319.897657) (xy 209.145557 -319.882703) (xy 209.11837 -319.874909)
			(xy 209.10423 -319.874392) (xy 199.89546 -319.874392) (xy 199.876664 -319.882012) (xy 199.869552 -319.889378)
			(xy 198.833232 -320.925698) (xy 198.826382 -320.933095) (xy 198.818642 -320.951693) (xy 198.818246 -320.961766)
			(xy 198.818246 -323.270372) (xy 198.818006 -323.277323) (xy 198.814267 -323.290713) (xy 198.81088 -323.296788)
			(xy 198.810626 -323.297042) (xy 198.80707 -323.303138) (xy 198.805292 -323.309488) (xy 198.80326 -323.323458)
			(xy 198.80326 -324.5353) (xy 202.330084 -324.5353) (xy 202.334076 -324.446414) (xy 202.346019 -324.358244)
			(xy 202.365818 -324.271499) (xy 202.393312 -324.186879) (xy 202.428281 -324.105063) (xy 202.470443 -324.026711)
			(xy 202.519458 -323.952454) (xy 202.574932 -323.882889) (xy 202.636419 -323.818577) (xy 202.703423 -323.760036)
			(xy 202.775404 -323.707736) (xy 202.851784 -323.662099) (xy 202.931947 -323.623492) (xy 203.015248 -323.592226)
			(xy 203.101016 -323.568553) (xy 203.188561 -323.552663) (xy 203.277178 -323.544684) (xy 203.321666 -323.544184)
			(xy 205.074266 -323.544184) (xy 205.118756 -323.544683) (xy 205.207377 -323.552656) (xy 205.294926 -323.568541)
			(xy 205.3807 -323.592211) (xy 205.464006 -323.623473) (xy 205.544174 -323.662078) (xy 205.620559 -323.707714)
			(xy 205.692546 -323.760013) (xy 205.759555 -323.818554) (xy 205.821046 -323.882867) (xy 205.876525 -323.952433)
			(xy 205.925544 -324.026692) (xy 205.967709 -324.105046) (xy 206.002681 -324.186865) (xy 206.030178 -324.271489)
			(xy 206.049978 -324.358237) (xy 206.061922 -324.44641) (xy 206.065914 -324.5353) (xy 206.061922 -324.62419)
			(xy 206.049978 -324.712363) (xy 206.030178 -324.799111) (xy 206.002681 -324.883735) (xy 205.967709 -324.965554)
			(xy 205.925544 -325.043908) (xy 205.876525 -325.118167) (xy 205.821046 -325.187733) (xy 205.759555 -325.252046)
			(xy 205.692546 -325.310587) (xy 205.620559 -325.362886) (xy 205.544174 -325.408522) (xy 205.464006 -325.447127)
			(xy 205.439573 -325.456296) (xy 211.848698 -325.456296) (xy 211.852769 -325.400674) (xy 211.864895 -325.346237)
			(xy 211.884818 -325.294146) (xy 211.912114 -325.245511) (xy 211.9462 -325.201368) (xy 211.986349 -325.162659)
			(xy 212.031707 -325.130208) (xy 212.081307 -325.104707) (xy 212.134091 -325.0867) (xy 212.188934 -325.07657)
			(xy 212.244668 -325.074533) (xy 212.300105 -325.080633) (xy 212.354062 -325.094739) (xy 212.405391 -325.116551)
			(xy 212.452997 -325.145605) (xy 212.495865 -325.18128) (xy 212.533082 -325.222817) (xy 212.563855 -325.26933)
			(xy 212.587527 -325.319827) (xy 212.603595 -325.373234) (xy 212.611715 -325.42841) (xy 212.612224 -325.456296)
			(xy 212.611715 -325.484182) (xy 212.603595 -325.539358) (xy 212.587527 -325.592765) (xy 212.563855 -325.643262)
			(xy 212.533082 -325.689775) (xy 212.495865 -325.731312) (xy 212.452997 -325.766987) (xy 212.405391 -325.796041)
			(xy 212.354062 -325.817853) (xy 212.300105 -325.831959) (xy 212.244668 -325.838059) (xy 212.188934 -325.836022)
			(xy 212.134091 -325.825892) (xy 212.081307 -325.807885) (xy 212.031707 -325.782384) (xy 211.986349 -325.749933)
			(xy 211.9462 -325.711224) (xy 211.912114 -325.667081) (xy 211.884818 -325.618446) (xy 211.864895 -325.566355)
			(xy 211.852769 -325.511918) (xy 211.848698 -325.456296) (xy 205.439573 -325.456296) (xy 205.3807 -325.478389)
			(xy 205.294926 -325.502059) (xy 205.207377 -325.517944) (xy 205.118756 -325.525917) (xy 205.074266 -325.5264)
			(xy 203.321666 -325.5264) (xy 203.277178 -325.525916) (xy 203.188561 -325.517937) (xy 203.101016 -325.502047)
			(xy 203.015248 -325.478374) (xy 202.931947 -325.447108) (xy 202.851784 -325.408501) (xy 202.775404 -325.362864)
			(xy 202.703423 -325.310564) (xy 202.636419 -325.252023) (xy 202.574932 -325.187711) (xy 202.519458 -325.118146)
			(xy 202.470443 -325.043889) (xy 202.428281 -324.965537) (xy 202.393312 -324.883721) (xy 202.365818 -324.799101)
			(xy 202.346019 -324.712356) (xy 202.334076 -324.624186) (xy 202.330084 -324.5353) (xy 198.80326 -324.5353)
			(xy 198.80326 -325.454518) (xy 198.802832 -325.464586) (xy 198.795109 -325.483182) (xy 198.788274 -325.490586)
			(xy 197.768972 -326.509888) (xy 211.88121 -326.509888) (xy 211.885281 -326.454266) (xy 211.897407 -326.399829)
			(xy 211.91733 -326.347738) (xy 211.944626 -326.299103) (xy 211.978712 -326.25496) (xy 212.018861 -326.216251)
			(xy 212.064219 -326.1838) (xy 212.113819 -326.158299) (xy 212.166603 -326.140292) (xy 212.221446 -326.130162)
			(xy 212.27718 -326.128125) (xy 212.332617 -326.134225) (xy 212.386574 -326.148331) (xy 212.437903 -326.170143)
			(xy 212.485509 -326.199197) (xy 212.497471 -326.209152) (xy 217.917266 -326.209152) (xy 217.921337 -326.15353)
			(xy 217.933463 -326.099093) (xy 217.953386 -326.047002) (xy 217.980682 -325.998367) (xy 218.014768 -325.954224)
			(xy 218.054917 -325.915515) (xy 218.100275 -325.883064) (xy 218.149875 -325.857563) (xy 218.202659 -325.839556)
			(xy 218.257502 -325.829426) (xy 218.313236 -325.827389) (xy 218.368673 -325.833489) (xy 218.42263 -325.847595)
			(xy 218.473959 -325.869407) (xy 218.521565 -325.898461) (xy 218.564433 -325.934136) (xy 218.60165 -325.975673)
			(xy 218.632423 -326.022186) (xy 218.656095 -326.072683) (xy 218.672163 -326.12609) (xy 218.680283 -326.181266)
			(xy 218.680792 -326.209152) (xy 218.680283 -326.237038) (xy 218.672163 -326.292214) (xy 218.656095 -326.345621)
			(xy 218.632423 -326.396118) (xy 218.60165 -326.442631) (xy 218.564433 -326.484168) (xy 218.521565 -326.519843)
			(xy 218.473959 -326.548897) (xy 218.42263 -326.570709) (xy 218.368673 -326.584815) (xy 218.313236 -326.590915)
			(xy 218.257502 -326.588878) (xy 218.202659 -326.578748) (xy 218.149875 -326.560741) (xy 218.100275 -326.53524)
			(xy 218.054917 -326.502789) (xy 218.014768 -326.46408) (xy 217.980682 -326.419937) (xy 217.953386 -326.371302)
			(xy 217.933463 -326.319211) (xy 217.921337 -326.264774) (xy 217.917266 -326.209152) (xy 212.497471 -326.209152)
			(xy 212.528377 -326.234872) (xy 212.565594 -326.276409) (xy 212.596367 -326.322922) (xy 212.620039 -326.373419)
			(xy 212.636107 -326.426826) (xy 212.644227 -326.482002) (xy 212.644736 -326.509888) (xy 212.644227 -326.537774)
			(xy 212.636107 -326.59295) (xy 212.620039 -326.646357) (xy 212.596367 -326.696854) (xy 212.565594 -326.743367)
			(xy 212.528377 -326.784904) (xy 212.485509 -326.820579) (xy 212.437903 -326.849633) (xy 212.386574 -326.871445)
			(xy 212.332617 -326.885551) (xy 212.27718 -326.891651) (xy 212.221446 -326.889614) (xy 212.166603 -326.879484)
			(xy 212.113819 -326.861477) (xy 212.064219 -326.835976) (xy 212.018861 -326.803525) (xy 211.978712 -326.764816)
			(xy 211.944626 -326.720673) (xy 211.91733 -326.672038) (xy 211.897407 -326.619947) (xy 211.885281 -326.56551)
			(xy 211.88121 -326.509888) (xy 197.768972 -326.509888) (xy 197.238112 -327.040748) (xy 197.230717 -327.047602)
			(xy 197.212118 -327.055349) (xy 197.202044 -327.055734) (xy 197.096888 -327.055734) (xy 197.078092 -327.063354)
			(xy 197.07098 -327.07072) (xy 197.046596 -327.095104) (xy 214.324946 -327.095104) (xy 214.325448 -327.063143)
			(xy 214.333459 -326.999725) (xy 214.349356 -326.937811) (xy 214.372888 -326.878378) (xy 214.403682 -326.822363)
			(xy 214.441255 -326.770648) (xy 214.485012 -326.724051) (xy 214.534265 -326.683306) (xy 214.588236 -326.649055)
			(xy 214.646075 -326.621838) (xy 214.706868 -326.602085) (xy 214.769658 -326.590107) (xy 214.833454 -326.586094)
			(xy 214.89725 -326.590107) (xy 214.96004 -326.602085) (xy 215.020833 -326.621838) (xy 215.078672 -326.649055)
			(xy 215.132643 -326.683306) (xy 215.181896 -326.724051) (xy 215.225653 -326.770648) (xy 215.263226 -326.822363)
			(xy 215.29402 -326.878378) (xy 215.317552 -326.937811) (xy 215.333449 -326.999725) (xy 215.34146 -327.063143)
			(xy 215.341962 -327.095104) (xy 215.341444 -327.127483) (xy 215.333232 -327.191717) (xy 215.316929 -327.254389)
			(xy 215.292799 -327.314482) (xy 215.261232 -327.371024) (xy 215.242394 -327.397364) (xy 215.235282 -327.407016)
			(xy 215.231218 -327.430892) (xy 215.262206 -327.531984) (xy 215.278716 -327.54951) (xy 215.290146 -327.553574)
			(xy 215.319508 -327.564421) (xy 215.37551 -327.592386) (xy 215.427654 -327.627015) (xy 215.475153 -327.667785)
			(xy 215.517286 -327.714078) (xy 215.553417 -327.765194) (xy 215.582999 -327.820359) (xy 215.605583 -327.878739)
			(xy 215.620829 -327.93945) (xy 215.628506 -328.001574) (xy 215.628982 -328.032872) (xy 215.62848 -328.064833)
			(xy 215.620469 -328.128251) (xy 215.604572 -328.190165) (xy 215.58104 -328.249598) (xy 215.550246 -328.305613)
			(xy 215.512673 -328.357328) (xy 215.468916 -328.403925) (xy 215.419663 -328.44467) (xy 215.365692 -328.478921)
			(xy 215.307853 -328.506138) (xy 215.24706 -328.525891) (xy 215.18427 -328.537869) (xy 215.120474 -328.541883)
			(xy 215.056678 -328.537869) (xy 214.993888 -328.525891) (xy 214.933095 -328.506138) (xy 214.875256 -328.478921)
			(xy 214.821285 -328.44467) (xy 214.772032 -328.403925) (xy 214.728275 -328.357328) (xy 214.690702 -328.305613)
			(xy 214.659908 -328.249598) (xy 214.636376 -328.190165) (xy 214.620479 -328.128251) (xy 214.612468 -328.064833)
			(xy 214.611966 -328.032872) (xy 214.612485 -328.000493) (xy 214.620699 -327.93626) (xy 214.637002 -327.873589)
			(xy 214.661132 -327.813495) (xy 214.692697 -327.756952) (xy 214.711534 -327.730612) (xy 214.718646 -327.72096)
			(xy 214.72271 -327.697084) (xy 214.691722 -327.595992) (xy 214.675212 -327.578466) (xy 214.663782 -327.574402)
			(xy 214.634418 -327.56356) (xy 214.578415 -327.535596) (xy 214.526269 -327.500967) (xy 214.478769 -327.460197)
			(xy 214.436635 -327.413904) (xy 214.400504 -327.362787) (xy 214.370923 -327.307621) (xy 214.348339 -327.24924)
			(xy 214.333095 -327.188527) (xy 214.325421 -327.126403) (xy 214.324946 -327.095104) (xy 197.046596 -327.095104)
			(xy 196.83984 -327.30186) (xy 196.832999 -327.30926) (xy 196.82528 -327.327858) (xy 196.824854 -327.337928)
			(xy 196.824854 -328.00417) (xy 212.132162 -328.00417) (xy 212.136233 -327.948548) (xy 212.148359 -327.894111)
			(xy 212.168282 -327.84202) (xy 212.195578 -327.793385) (xy 212.229664 -327.749242) (xy 212.269813 -327.710533)
			(xy 212.315171 -327.678082) (xy 212.364771 -327.652581) (xy 212.417555 -327.634574) (xy 212.472398 -327.624444)
			(xy 212.528132 -327.622407) (xy 212.583569 -327.628507) (xy 212.637526 -327.642613) (xy 212.688855 -327.664425)
			(xy 212.736461 -327.693479) (xy 212.779329 -327.729154) (xy 212.816546 -327.770691) (xy 212.847319 -327.817204)
			(xy 212.870991 -327.867701) (xy 212.887059 -327.921108) (xy 212.895179 -327.976284) (xy 212.895688 -328.00417)
			(xy 212.895179 -328.032056) (xy 212.887059 -328.087232) (xy 212.870991 -328.140639) (xy 212.847319 -328.191136)
			(xy 212.816546 -328.237649) (xy 212.779329 -328.279186) (xy 212.736461 -328.314861) (xy 212.688855 -328.343915)
			(xy 212.637526 -328.365727) (xy 212.583569 -328.379833) (xy 212.528132 -328.385933) (xy 212.472398 -328.383896)
			(xy 212.417555 -328.373766) (xy 212.364771 -328.355759) (xy 212.315171 -328.330258) (xy 212.269813 -328.297807)
			(xy 212.229664 -328.259098) (xy 212.195578 -328.214955) (xy 212.168282 -328.16632) (xy 212.148359 -328.114229)
			(xy 212.136233 -328.059792) (xy 212.132162 -328.00417) (xy 196.824854 -328.00417) (xy 196.824854 -329.014582)
			(xy 212.11108 -329.014582) (xy 212.115151 -328.95896) (xy 212.127277 -328.904523) (xy 212.1472 -328.852432)
			(xy 212.174496 -328.803797) (xy 212.208582 -328.759654) (xy 212.248731 -328.720945) (xy 212.294089 -328.688494)
			(xy 212.343689 -328.662993) (xy 212.396473 -328.644986) (xy 212.451316 -328.634856) (xy 212.50705 -328.632819)
			(xy 212.562487 -328.638919) (xy 212.616444 -328.653025) (xy 212.667773 -328.674837) (xy 212.715379 -328.703891)
			(xy 212.758247 -328.739566) (xy 212.795464 -328.781103) (xy 212.826237 -328.827616) (xy 212.849909 -328.878113)
			(xy 212.865977 -328.93152) (xy 212.874097 -328.986696) (xy 212.874606 -329.014582) (xy 212.874097 -329.042468)
			(xy 212.865977 -329.097644) (xy 212.849909 -329.151051) (xy 212.826237 -329.201548) (xy 212.819894 -329.211135)
			(xy 214.603324 -329.211135) (xy 214.603324 -329.147213) (xy 214.611335 -329.083795) (xy 214.627232 -329.021881)
			(xy 214.650764 -328.962448) (xy 214.681558 -328.906433) (xy 214.719131 -328.854718) (xy 214.762888 -328.808121)
			(xy 214.812141 -328.767376) (xy 214.866112 -328.733125) (xy 214.923951 -328.705908) (xy 214.984744 -328.686155)
			(xy 215.047534 -328.674177) (xy 215.11133 -328.670164) (xy 215.175126 -328.674177) (xy 215.237916 -328.686155)
			(xy 215.298709 -328.705908) (xy 215.356548 -328.733125) (xy 215.410519 -328.767376) (xy 215.459772 -328.808121)
			(xy 215.503529 -328.854718) (xy 215.541102 -328.906433) (xy 215.571896 -328.962448) (xy 215.595428 -329.021881)
			(xy 215.611325 -329.083795) (xy 215.619336 -329.147213) (xy 215.619838 -329.179174) (xy 215.619336 -329.211135)
			(xy 215.611325 -329.274553) (xy 215.595428 -329.336467) (xy 215.571896 -329.3959) (xy 215.541102 -329.451915)
			(xy 215.503529 -329.50363) (xy 215.459772 -329.550227) (xy 215.410519 -329.590972) (xy 215.356548 -329.625223)
			(xy 215.298709 -329.65244) (xy 215.237916 -329.672193) (xy 215.175126 -329.684171) (xy 215.11133 -329.688185)
			(xy 215.047534 -329.684171) (xy 214.984744 -329.672193) (xy 214.923951 -329.65244) (xy 214.866112 -329.625223)
			(xy 214.812141 -329.590972) (xy 214.762888 -329.550227) (xy 214.719131 -329.50363) (xy 214.681558 -329.451915)
			(xy 214.650764 -329.3959) (xy 214.627232 -329.336467) (xy 214.611335 -329.274553) (xy 214.603324 -329.211135)
			(xy 212.819894 -329.211135) (xy 212.795464 -329.248061) (xy 212.758247 -329.289598) (xy 212.715379 -329.325273)
			(xy 212.667773 -329.354327) (xy 212.616444 -329.376139) (xy 212.562487 -329.390245) (xy 212.50705 -329.396345)
			(xy 212.451316 -329.394308) (xy 212.396473 -329.384178) (xy 212.343689 -329.366171) (xy 212.294089 -329.34067)
			(xy 212.248731 -329.308219) (xy 212.208582 -329.26951) (xy 212.174496 -329.225367) (xy 212.1472 -329.176732)
			(xy 212.127277 -329.124641) (xy 212.115151 -329.070204) (xy 212.11108 -329.014582) (xy 196.824854 -329.014582)
			(xy 196.824854 -330.558394) (xy 196.825278 -330.568464) (xy 196.832996 -330.587064) (xy 196.83984 -330.594462)
			(xy 197.062852 -330.817474) (xy 197.070252 -330.824315) (xy 197.088851 -330.832034) (xy 197.09892 -330.83246)
		)
		(stroke
			(width 0)
			(type solid)
		)
		(fill yes)
		(layer "In13.Cu")
		(net "PVDD_33_S5")
	)
	(gr_poly
		(pts
			(xy 430.552098 -407.90622) (xy 430.562169 -407.905798) (xy 430.580776 -407.898086) (xy 430.588166 -407.891234)
			(xy 431.726594 -406.752806) (xy 431.733442 -406.745408) (xy 431.74118 -406.72681) (xy 431.74158 -406.716738)
			(xy 431.74158 -391.930382) (xy 431.741153 -391.920314) (xy 431.733432 -391.901716) (xy 431.726594 -391.894314)
			(xy 430.542446 -390.710166) (xy 430.535048 -390.703321) (xy 430.516449 -390.695596) (xy 430.506378 -390.69518)
			(xy 428.188882 -390.69518) (xy 428.16018 -390.720072) (xy 428.15764 -390.738868) (xy 428.153407 -390.765889)
			(xy 428.138215 -390.818428) (xy 428.115677 -390.868261) (xy 428.086256 -390.914365) (xy 428.050554 -390.955796)
			(xy 428.009302 -390.991707) (xy 427.963347 -391.021359) (xy 427.913628 -391.044148) (xy 427.861166 -391.059604)
			(xy 427.807034 -391.067412) (xy 427.752342 -391.067412) (xy 427.69821 -391.059604) (xy 427.645748 -391.044148)
			(xy 427.596029 -391.021359) (xy 427.550074 -390.991707) (xy 427.508822 -390.955796) (xy 427.47312 -390.914365)
			(xy 427.443699 -390.868261) (xy 427.421161 -390.818428) (xy 427.405969 -390.765889) (xy 427.401736 -390.738868)
			(xy 427.399196 -390.720072) (xy 427.370494 -390.69518) (xy 426.406056 -390.69518) (xy 426.37837 -390.717532)
			(xy 426.374306 -390.735058) (xy 426.367058 -390.76547) (xy 426.346114 -390.824379) (xy 426.318107 -390.880276)
			(xy 426.28346 -390.932319) (xy 426.242695 -390.979722) (xy 426.196427 -391.021772) (xy 426.145354 -391.057833)
			(xy 426.090246 -391.087362) (xy 426.031934 -391.109913) (xy 425.971297 -391.125147) (xy 425.90925 -391.132834)
			(xy 425.87799 -391.13333) (xy 425.84509 -391.132811) (xy 425.779841 -391.124324) (xy 425.71623 -391.107494)
			(xy 425.655321 -391.082602) (xy 425.598131 -391.050062) (xy 425.545614 -391.010419) (xy 425.498649 -390.964335)
			(xy 425.47794 -390.938766) (xy 425.47159 -390.930638) (xy 425.454318 -390.920732) (xy 425.362878 -390.909556)
			(xy 425.343828 -390.914636) (xy 425.3357 -390.920986) (xy 425.31557 -390.93609) (xy 425.272091 -390.961436)
			(xy 425.225657 -390.980842) (xy 425.177072 -390.993971) (xy 425.127183 -391.000594) (xy 425.10202 -391.000996)
			(xy 425.075007 -391.000521) (xy 425.021523 -390.992888) (xy 424.96965 -390.977785) (xy 424.920427 -390.955515)
			(xy 424.874839 -390.926523) (xy 424.833796 -390.89139) (xy 424.798121 -390.850818) (xy 424.768527 -390.805618)
			(xy 424.745605 -390.756695) (xy 424.737276 -390.730994) (xy 424.732196 -390.714992) (xy 424.705272 -390.69518)
			(xy 398.184116 -390.69518) (xy 398.172366 -390.695785) (xy 398.151331 -390.706261) (xy 398.14373 -390.715246)
			(xy 398.087596 -390.78916) (xy 398.083024 -390.812528) (xy 398.086326 -390.823958) (xy 398.092861 -390.849042)
			(xy 398.099869 -390.900402) (xy 398.100296 -390.92632) (xy 398.099808 -390.95357) (xy 398.092049 -391.007515)
			(xy 398.076693 -391.059806) (xy 398.05405 -391.10938) (xy 398.024583 -391.155227) (xy 397.988891 -391.196414)
			(xy 397.947702 -391.232102) (xy 397.901852 -391.261565) (xy 397.852276 -391.284204) (xy 397.799984 -391.299556)
			(xy 397.746038 -391.307311) (xy 397.718788 -391.307828) (xy 397.694716 -391.307477) (xy 397.646951 -391.301446)
			(xy 397.600328 -391.289442) (xy 397.577818 -391.280904) (xy 397.565372 -391.275824) (xy 397.539464 -391.279126)
			(xy 397.490373 -391.315291) (xy 400.656761 -391.315291) (xy 400.656761 -391.263309) (xy 400.664893 -391.211968)
			(xy 400.680956 -391.162531) (xy 400.704556 -391.116215) (xy 400.73511 -391.074162) (xy 400.771866 -391.037406)
			(xy 400.81392 -391.006852) (xy 400.860236 -390.983254) (xy 400.909674 -390.967192) (xy 400.961015 -390.959061)
			(xy 400.987006 -390.958578) (xy 401.010204 -390.958963) (xy 401.056144 -390.965454) (xy 401.100728 -390.978295)
			(xy 401.143084 -390.997234) (xy 401.18238 -391.021899) (xy 401.200366 -391.036556) (xy 401.207478 -391.042652)
			(xy 401.225004 -391.048748) (xy 401.310602 -391.04697) (xy 401.327874 -391.039858) (xy 401.334732 -391.033508)
			(xy 401.353151 -391.017162) (xy 401.393931 -390.989558) (xy 401.438354 -390.968305) (xy 401.485436 -390.953873)
			(xy 401.534138 -390.94658) (xy 401.55876 -390.946132) (xy 401.583597 -390.946581) (xy 401.632714 -390.954)
			(xy 401.680166 -390.968691) (xy 401.724882 -390.990322) (xy 401.765854 -391.018407) (xy 401.784312 -391.035032)
			(xy 401.79139 -391.041056) (xy 401.80857 -391.0481) (xy 401.81784 -391.048748) (xy 401.849082 -391.04951)
			(xy 401.858337 -391.049352) (xy 401.87579 -391.043228) (xy 401.883118 -391.037572) (xy 401.905652 -391.019367)
			(xy 401.955793 -390.990359) (xy 402.010216 -390.970517) (xy 402.06726 -390.960444) (xy 402.096224 -390.959848)
			(xy 402.122206 -390.960448) (xy 402.173531 -390.96858) (xy 402.222952 -390.984641) (xy 402.269252 -391.008235)
			(xy 402.311291 -391.038781) (xy 402.348034 -391.075527) (xy 402.378578 -391.117569) (xy 402.402168 -391.16387)
			(xy 402.418225 -391.213292) (xy 402.425768 -391.260917) (xy 403.114004 -391.260917) (xy 403.114004 -391.208943)
			(xy 403.122134 -391.157608) (xy 403.138195 -391.108178) (xy 403.161791 -391.061868) (xy 403.192341 -391.01982)
			(xy 403.229092 -390.983069) (xy 403.27114 -390.952519) (xy 403.31745 -390.928923) (xy 403.36688 -390.912862)
			(xy 403.418215 -390.904732) (xy 403.470189 -390.904732) (xy 403.521524 -390.912862) (xy 403.570954 -390.928923)
			(xy 403.617264 -390.952519) (xy 403.659312 -390.983069) (xy 403.696063 -391.01982) (xy 403.726613 -391.061868)
			(xy 403.750209 -391.108178) (xy 403.76627 -391.157608) (xy 403.7744 -391.208943) (xy 403.77491 -391.23493)
			(xy 403.7744 -391.260917) (xy 404.314154 -391.260917) (xy 404.314154 -391.208943) (xy 404.322284 -391.157608)
			(xy 404.338345 -391.108178) (xy 404.361941 -391.061868) (xy 404.392491 -391.01982) (xy 404.429242 -390.983069)
			(xy 404.47129 -390.952519) (xy 404.5176 -390.928923) (xy 404.56703 -390.912862) (xy 404.618365 -390.904732)
			(xy 404.670339 -390.904732) (xy 404.721674 -390.912862) (xy 404.771104 -390.928923) (xy 404.817414 -390.952519)
			(xy 404.859462 -390.983069) (xy 404.896213 -391.01982) (xy 404.926763 -391.061868) (xy 404.950359 -391.108178)
			(xy 404.96642 -391.157608) (xy 404.97455 -391.208943) (xy 404.97506 -391.23493) (xy 404.97455 -391.260917)
			(xy 405.51405 -391.260917) (xy 405.51405 -391.208943) (xy 405.52218 -391.157608) (xy 405.538241 -391.108178)
			(xy 405.561837 -391.061868) (xy 405.592387 -391.01982) (xy 405.629138 -390.983069) (xy 405.671186 -390.952519)
			(xy 405.717496 -390.928923) (xy 405.766926 -390.912862) (xy 405.818261 -390.904732) (xy 405.870235 -390.904732)
			(xy 405.92157 -390.912862) (xy 405.971 -390.928923) (xy 406.01731 -390.952519) (xy 406.059358 -390.983069)
			(xy 406.096109 -391.01982) (xy 406.126659 -391.061868) (xy 406.150255 -391.108178) (xy 406.166316 -391.157608)
			(xy 406.174446 -391.208943) (xy 406.174956 -391.23493) (xy 406.174446 -391.260917) (xy 406.713946 -391.260917)
			(xy 406.713946 -391.208943) (xy 406.722076 -391.157608) (xy 406.738137 -391.108178) (xy 406.761733 -391.061868)
			(xy 406.792283 -391.01982) (xy 406.829034 -390.983069) (xy 406.871082 -390.952519) (xy 406.917392 -390.928923)
			(xy 406.966822 -390.912862) (xy 407.018157 -390.904732) (xy 407.070131 -390.904732) (xy 407.121466 -390.912862)
			(xy 407.170896 -390.928923) (xy 407.217206 -390.952519) (xy 407.259254 -390.983069) (xy 407.296005 -391.01982)
			(xy 407.326555 -391.061868) (xy 407.350151 -391.108178) (xy 407.366212 -391.157608) (xy 407.374342 -391.208943)
			(xy 407.374852 -391.23493) (xy 407.374342 -391.260917) (xy 407.914096 -391.260917) (xy 407.914096 -391.208943)
			(xy 407.922226 -391.157608) (xy 407.938287 -391.108178) (xy 407.961883 -391.061868) (xy 407.992433 -391.01982)
			(xy 408.029184 -390.983069) (xy 408.071232 -390.952519) (xy 408.117542 -390.928923) (xy 408.166972 -390.912862)
			(xy 408.218307 -390.904732) (xy 408.270281 -390.904732) (xy 408.321616 -390.912862) (xy 408.371046 -390.928923)
			(xy 408.417356 -390.952519) (xy 408.459404 -390.983069) (xy 408.496155 -391.01982) (xy 408.526705 -391.061868)
			(xy 408.550301 -391.108178) (xy 408.566362 -391.157608) (xy 408.574492 -391.208943) (xy 408.575002 -391.23493)
			(xy 408.574492 -391.260917) (xy 409.113992 -391.260917) (xy 409.113992 -391.208943) (xy 409.122122 -391.157608)
			(xy 409.138183 -391.108178) (xy 409.161779 -391.061868) (xy 409.192329 -391.01982) (xy 409.22908 -390.983069)
			(xy 409.271128 -390.952519) (xy 409.317438 -390.928923) (xy 409.366868 -390.912862) (xy 409.418203 -390.904732)
			(xy 409.470177 -390.904732) (xy 409.521512 -390.912862) (xy 409.570942 -390.928923) (xy 409.617252 -390.952519)
			(xy 409.6593 -390.983069) (xy 409.696051 -391.01982) (xy 409.726601 -391.061868) (xy 409.750197 -391.108178)
			(xy 409.766258 -391.157608) (xy 409.774388 -391.208943) (xy 409.774898 -391.23493) (xy 409.774388 -391.260917)
			(xy 410.314142 -391.260917) (xy 410.314142 -391.208943) (xy 410.322272 -391.157608) (xy 410.338333 -391.108178)
			(xy 410.361929 -391.061868) (xy 410.392479 -391.01982) (xy 410.42923 -390.983069) (xy 410.471278 -390.952519)
			(xy 410.517588 -390.928923) (xy 410.567018 -390.912862) (xy 410.618353 -390.904732) (xy 410.670327 -390.904732)
			(xy 410.721662 -390.912862) (xy 410.771092 -390.928923) (xy 410.817402 -390.952519) (xy 410.85945 -390.983069)
			(xy 410.896201 -391.01982) (xy 410.926751 -391.061868) (xy 410.950347 -391.108178) (xy 410.966408 -391.157608)
			(xy 410.974538 -391.208943) (xy 410.975048 -391.23493) (xy 410.974538 -391.260917) (xy 411.514038 -391.260917)
			(xy 411.514038 -391.208943) (xy 411.522168 -391.157608) (xy 411.538229 -391.108178) (xy 411.561825 -391.061868)
			(xy 411.592375 -391.01982) (xy 411.629126 -390.983069) (xy 411.671174 -390.952519) (xy 411.717484 -390.928923)
			(xy 411.766914 -390.912862) (xy 411.818249 -390.904732) (xy 411.870223 -390.904732) (xy 411.921558 -390.912862)
			(xy 411.970988 -390.928923) (xy 412.017298 -390.952519) (xy 412.059346 -390.983069) (xy 412.096097 -391.01982)
			(xy 412.126647 -391.061868) (xy 412.150243 -391.108178) (xy 412.166304 -391.157608) (xy 412.174434 -391.208943)
			(xy 412.174944 -391.23493) (xy 412.174434 -391.260917) (xy 412.713934 -391.260917) (xy 412.713934 -391.208943)
			(xy 412.722064 -391.157608) (xy 412.738125 -391.108178) (xy 412.761721 -391.061868) (xy 412.792271 -391.01982)
			(xy 412.829022 -390.983069) (xy 412.87107 -390.952519) (xy 412.91738 -390.928923) (xy 412.96681 -390.912862)
			(xy 413.018145 -390.904732) (xy 413.070119 -390.904732) (xy 413.121454 -390.912862) (xy 413.170884 -390.928923)
			(xy 413.217194 -390.952519) (xy 413.259242 -390.983069) (xy 413.295993 -391.01982) (xy 413.326543 -391.061868)
			(xy 413.350139 -391.108178) (xy 413.3662 -391.157608) (xy 413.37433 -391.208943) (xy 413.37484 -391.23493)
			(xy 413.37433 -391.260917) (xy 413.914084 -391.260917) (xy 413.914084 -391.208943) (xy 413.922214 -391.157608)
			(xy 413.938275 -391.108178) (xy 413.961871 -391.061868) (xy 413.992421 -391.01982) (xy 414.029172 -390.983069)
			(xy 414.07122 -390.952519) (xy 414.11753 -390.928923) (xy 414.16696 -390.912862) (xy 414.218295 -390.904732)
			(xy 414.270269 -390.904732) (xy 414.321604 -390.912862) (xy 414.371034 -390.928923) (xy 414.417344 -390.952519)
			(xy 414.459392 -390.983069) (xy 414.496143 -391.01982) (xy 414.526693 -391.061868) (xy 414.550289 -391.108178)
			(xy 414.56635 -391.157608) (xy 414.57448 -391.208943) (xy 414.57499 -391.23493) (xy 414.57448 -391.260917)
			(xy 415.11398 -391.260917) (xy 415.11398 -391.208943) (xy 415.12211 -391.157608) (xy 415.138171 -391.108178)
			(xy 415.161767 -391.061868) (xy 415.192317 -391.01982) (xy 415.229068 -390.983069) (xy 415.271116 -390.952519)
			(xy 415.317426 -390.928923) (xy 415.366856 -390.912862) (xy 415.418191 -390.904732) (xy 415.470165 -390.904732)
			(xy 415.5215 -390.912862) (xy 415.57093 -390.928923) (xy 415.61724 -390.952519) (xy 415.659288 -390.983069)
			(xy 415.696039 -391.01982) (xy 415.726589 -391.061868) (xy 415.750185 -391.108178) (xy 415.766246 -391.157608)
			(xy 415.774376 -391.208943) (xy 415.774886 -391.23493) (xy 415.774376 -391.260917) (xy 416.31413 -391.260917)
			(xy 416.31413 -391.208943) (xy 416.32226 -391.157608) (xy 416.338321 -391.108178) (xy 416.361917 -391.061868)
			(xy 416.392467 -391.01982) (xy 416.429218 -390.983069) (xy 416.471266 -390.952519) (xy 416.517576 -390.928923)
			(xy 416.567006 -390.912862) (xy 416.618341 -390.904732) (xy 416.670315 -390.904732) (xy 416.72165 -390.912862)
			(xy 416.77108 -390.928923) (xy 416.81739 -390.952519) (xy 416.859438 -390.983069) (xy 416.896189 -391.01982)
			(xy 416.926739 -391.061868) (xy 416.950335 -391.108178) (xy 416.966396 -391.157608) (xy 416.974526 -391.208943)
			(xy 416.975036 -391.23493) (xy 416.974526 -391.260917) (xy 417.514026 -391.260917) (xy 417.514026 -391.208943)
			(xy 417.522156 -391.157608) (xy 417.538217 -391.108178) (xy 417.561813 -391.061868) (xy 417.592363 -391.01982)
			(xy 417.629114 -390.983069) (xy 417.671162 -390.952519) (xy 417.717472 -390.928923) (xy 417.766902 -390.912862)
			(xy 417.818237 -390.904732) (xy 417.870211 -390.904732) (xy 417.921546 -390.912862) (xy 417.970976 -390.928923)
			(xy 418.017286 -390.952519) (xy 418.059334 -390.983069) (xy 418.096085 -391.01982) (xy 418.126635 -391.061868)
			(xy 418.150231 -391.108178) (xy 418.166292 -391.157608) (xy 418.174422 -391.208943) (xy 418.174932 -391.23493)
			(xy 418.174422 -391.260917) (xy 418.713922 -391.260917) (xy 418.713922 -391.208943) (xy 418.722052 -391.157608)
			(xy 418.738113 -391.108178) (xy 418.761709 -391.061868) (xy 418.792259 -391.01982) (xy 418.82901 -390.983069)
			(xy 418.871058 -390.952519) (xy 418.917368 -390.928923) (xy 418.966798 -390.912862) (xy 419.018133 -390.904732)
			(xy 419.070107 -390.904732) (xy 419.121442 -390.912862) (xy 419.170872 -390.928923) (xy 419.217182 -390.952519)
			(xy 419.25923 -390.983069) (xy 419.295981 -391.01982) (xy 419.326531 -391.061868) (xy 419.350127 -391.108178)
			(xy 419.366188 -391.157608) (xy 419.374318 -391.208943) (xy 419.374828 -391.23493) (xy 419.374318 -391.260917)
			(xy 419.914072 -391.260917) (xy 419.914072 -391.208943) (xy 419.922202 -391.157608) (xy 419.938263 -391.108178)
			(xy 419.961859 -391.061868) (xy 419.992409 -391.01982) (xy 420.02916 -390.983069) (xy 420.071208 -390.952519)
			(xy 420.117518 -390.928923) (xy 420.166948 -390.912862) (xy 420.218283 -390.904732) (xy 420.270257 -390.904732)
			(xy 420.321592 -390.912862) (xy 420.371022 -390.928923) (xy 420.417332 -390.952519) (xy 420.45938 -390.983069)
			(xy 420.496131 -391.01982) (xy 420.526681 -391.061868) (xy 420.550277 -391.108178) (xy 420.566338 -391.157608)
			(xy 420.574468 -391.208943) (xy 420.574978 -391.23493) (xy 420.574468 -391.260917) (xy 421.113968 -391.260917)
			(xy 421.113968 -391.208943) (xy 421.122098 -391.157608) (xy 421.138159 -391.108178) (xy 421.161755 -391.061868)
			(xy 421.192305 -391.01982) (xy 421.229056 -390.983069) (xy 421.271104 -390.952519) (xy 421.317414 -390.928923)
			(xy 421.366844 -390.912862) (xy 421.418179 -390.904732) (xy 421.470153 -390.904732) (xy 421.521488 -390.912862)
			(xy 421.570918 -390.928923) (xy 421.617228 -390.952519) (xy 421.659276 -390.983069) (xy 421.696027 -391.01982)
			(xy 421.726577 -391.061868) (xy 421.750173 -391.108178) (xy 421.766234 -391.157608) (xy 421.774364 -391.208943)
			(xy 421.774874 -391.23493) (xy 421.774364 -391.260917) (xy 421.771945 -391.276193) (xy 422.180945 -391.276193)
			(xy 422.180945 -391.224207) (xy 422.189078 -391.172862) (xy 422.205143 -391.123422) (xy 422.228744 -391.077103)
			(xy 422.259302 -391.035047) (xy 422.296062 -390.998289) (xy 422.33812 -390.967734) (xy 422.38444 -390.944135)
			(xy 422.433882 -390.928073) (xy 422.485227 -390.919944) (xy 422.51122 -390.919462) (xy 422.534995 -390.919841)
			(xy 422.582056 -390.926649) (xy 422.627654 -390.940136) (xy 422.670846 -390.960022) (xy 422.71074 -390.985897)
			(xy 422.728898 -391.00125) (xy 422.736003 -391.006957) (xy 422.753065 -391.013328) (xy 422.762172 -391.013696)
			(xy 422.793668 -391.013696) (xy 422.802767 -391.013286) (xy 422.819817 -391.006923) (xy 422.826942 -391.00125)
			(xy 422.845126 -390.985933) (xy 422.885021 -390.960072) (xy 422.928208 -390.940191) (xy 422.973797 -390.926701)
			(xy 423.020848 -390.91988) (xy 423.04462 -390.919462) (xy 423.070604 -390.920033) (xy 423.121931 -390.928165)
			(xy 423.171355 -390.944227) (xy 423.217657 -390.967821) (xy 423.259699 -390.998369) (xy 423.296444 -391.035116)
			(xy 423.326989 -391.07716) (xy 423.350581 -391.123464) (xy 423.366639 -391.172888) (xy 423.374769 -391.224216)
			(xy 423.374769 -391.276184) (xy 423.366639 -391.327512) (xy 423.350581 -391.376936) (xy 423.326989 -391.42324)
			(xy 423.296444 -391.465284) (xy 423.259699 -391.502031) (xy 423.217657 -391.532579) (xy 423.171355 -391.556173)
			(xy 423.121931 -391.572235) (xy 423.070604 -391.580367) (xy 423.04462 -391.580878) (xy 423.020846 -391.580465)
			(xy 422.973787 -391.573664) (xy 422.92819 -391.560185) (xy 422.884998 -391.540306) (xy 422.845102 -391.514439)
			(xy 422.826942 -391.49909) (xy 422.81983 -391.493393) (xy 422.802773 -391.487018) (xy 422.793668 -391.486644)
			(xy 422.762172 -391.486644) (xy 422.753069 -391.487016) (xy 422.736018 -391.493405) (xy 422.728898 -391.49909)
			(xy 422.710742 -391.514442) (xy 422.670839 -391.540297) (xy 422.627645 -391.56017) (xy 422.58205 -391.573652)
			(xy 422.534993 -391.580465) (xy 422.51122 -391.580878) (xy 422.485227 -391.580456) (xy 422.433882 -391.572327)
			(xy 422.38444 -391.556265) (xy 422.33812 -391.532666) (xy 422.296062 -391.502111) (xy 422.259302 -391.465353)
			(xy 422.228744 -391.423297) (xy 422.205143 -391.376978) (xy 422.189078 -391.327538) (xy 422.180945 -391.276193)
			(xy 421.771945 -391.276193) (xy 421.766234 -391.312252) (xy 421.750173 -391.361682) (xy 421.726577 -391.407992)
			(xy 421.696027 -391.45004) (xy 421.659276 -391.486791) (xy 421.617228 -391.517341) (xy 421.570918 -391.540937)
			(xy 421.521488 -391.556998) (xy 421.470153 -391.565128) (xy 421.418179 -391.565128) (xy 421.366844 -391.556998)
			(xy 421.317414 -391.540937) (xy 421.271104 -391.517341) (xy 421.229056 -391.486791) (xy 421.192305 -391.45004)
			(xy 421.161755 -391.407992) (xy 421.138159 -391.361682) (xy 421.122098 -391.312252) (xy 421.113968 -391.260917)
			(xy 420.574468 -391.260917) (xy 420.566338 -391.312252) (xy 420.550277 -391.361682) (xy 420.526681 -391.407992)
			(xy 420.496131 -391.45004) (xy 420.45938 -391.486791) (xy 420.417332 -391.517341) (xy 420.371022 -391.540937)
			(xy 420.321592 -391.556998) (xy 420.270257 -391.565128) (xy 420.218283 -391.565128) (xy 420.166948 -391.556998)
			(xy 420.117518 -391.540937) (xy 420.071208 -391.517341) (xy 420.02916 -391.486791) (xy 419.992409 -391.45004)
			(xy 419.961859 -391.407992) (xy 419.938263 -391.361682) (xy 419.922202 -391.312252) (xy 419.914072 -391.260917)
			(xy 419.374318 -391.260917) (xy 419.366188 -391.312252) (xy 419.350127 -391.361682) (xy 419.326531 -391.407992)
			(xy 419.295981 -391.45004) (xy 419.25923 -391.486791) (xy 419.217182 -391.517341) (xy 419.170872 -391.540937)
			(xy 419.121442 -391.556998) (xy 419.070107 -391.565128) (xy 419.018133 -391.565128) (xy 418.966798 -391.556998)
			(xy 418.917368 -391.540937) (xy 418.871058 -391.517341) (xy 418.82901 -391.486791) (xy 418.792259 -391.45004)
			(xy 418.761709 -391.407992) (xy 418.738113 -391.361682) (xy 418.722052 -391.312252) (xy 418.713922 -391.260917)
			(xy 418.174422 -391.260917) (xy 418.166292 -391.312252) (xy 418.150231 -391.361682) (xy 418.126635 -391.407992)
			(xy 418.096085 -391.45004) (xy 418.059334 -391.486791) (xy 418.017286 -391.517341) (xy 417.970976 -391.540937)
			(xy 417.921546 -391.556998) (xy 417.870211 -391.565128) (xy 417.818237 -391.565128) (xy 417.766902 -391.556998)
			(xy 417.717472 -391.540937) (xy 417.671162 -391.517341) (xy 417.629114 -391.486791) (xy 417.592363 -391.45004)
			(xy 417.561813 -391.407992) (xy 417.538217 -391.361682) (xy 417.522156 -391.312252) (xy 417.514026 -391.260917)
			(xy 416.974526 -391.260917) (xy 416.966396 -391.312252) (xy 416.950335 -391.361682) (xy 416.926739 -391.407992)
			(xy 416.896189 -391.45004) (xy 416.859438 -391.486791) (xy 416.81739 -391.517341) (xy 416.77108 -391.540937)
			(xy 416.72165 -391.556998) (xy 416.670315 -391.565128) (xy 416.618341 -391.565128) (xy 416.567006 -391.556998)
			(xy 416.517576 -391.540937) (xy 416.471266 -391.517341) (xy 416.429218 -391.486791) (xy 416.392467 -391.45004)
			(xy 416.361917 -391.407992) (xy 416.338321 -391.361682) (xy 416.32226 -391.312252) (xy 416.31413 -391.260917)
			(xy 415.774376 -391.260917) (xy 415.766246 -391.312252) (xy 415.750185 -391.361682) (xy 415.726589 -391.407992)
			(xy 415.696039 -391.45004) (xy 415.659288 -391.486791) (xy 415.61724 -391.517341) (xy 415.57093 -391.540937)
			(xy 415.5215 -391.556998) (xy 415.470165 -391.565128) (xy 415.418191 -391.565128) (xy 415.366856 -391.556998)
			(xy 415.317426 -391.540937) (xy 415.271116 -391.517341) (xy 415.229068 -391.486791) (xy 415.192317 -391.45004)
			(xy 415.161767 -391.407992) (xy 415.138171 -391.361682) (xy 415.12211 -391.312252) (xy 415.11398 -391.260917)
			(xy 414.57448 -391.260917) (xy 414.56635 -391.312252) (xy 414.550289 -391.361682) (xy 414.526693 -391.407992)
			(xy 414.496143 -391.45004) (xy 414.459392 -391.486791) (xy 414.417344 -391.517341) (xy 414.371034 -391.540937)
			(xy 414.321604 -391.556998) (xy 414.270269 -391.565128) (xy 414.218295 -391.565128) (xy 414.16696 -391.556998)
			(xy 414.11753 -391.540937) (xy 414.07122 -391.517341) (xy 414.029172 -391.486791) (xy 413.992421 -391.45004)
			(xy 413.961871 -391.407992) (xy 413.938275 -391.361682) (xy 413.922214 -391.312252) (xy 413.914084 -391.260917)
			(xy 413.37433 -391.260917) (xy 413.3662 -391.312252) (xy 413.350139 -391.361682) (xy 413.326543 -391.407992)
			(xy 413.295993 -391.45004) (xy 413.259242 -391.486791) (xy 413.217194 -391.517341) (xy 413.170884 -391.540937)
			(xy 413.121454 -391.556998) (xy 413.070119 -391.565128) (xy 413.018145 -391.565128) (xy 412.96681 -391.556998)
			(xy 412.91738 -391.540937) (xy 412.87107 -391.517341) (xy 412.829022 -391.486791) (xy 412.792271 -391.45004)
			(xy 412.761721 -391.407992) (xy 412.738125 -391.361682) (xy 412.722064 -391.312252) (xy 412.713934 -391.260917)
			(xy 412.174434 -391.260917) (xy 412.166304 -391.312252) (xy 412.150243 -391.361682) (xy 412.126647 -391.407992)
			(xy 412.096097 -391.45004) (xy 412.059346 -391.486791) (xy 412.017298 -391.517341) (xy 411.970988 -391.540937)
			(xy 411.921558 -391.556998) (xy 411.870223 -391.565128) (xy 411.818249 -391.565128) (xy 411.766914 -391.556998)
			(xy 411.717484 -391.540937) (xy 411.671174 -391.517341) (xy 411.629126 -391.486791) (xy 411.592375 -391.45004)
			(xy 411.561825 -391.407992) (xy 411.538229 -391.361682) (xy 411.522168 -391.312252) (xy 411.514038 -391.260917)
			(xy 410.974538 -391.260917) (xy 410.966408 -391.312252) (xy 410.950347 -391.361682) (xy 410.926751 -391.407992)
			(xy 410.896201 -391.45004) (xy 410.85945 -391.486791) (xy 410.817402 -391.517341) (xy 410.771092 -391.540937)
			(xy 410.721662 -391.556998) (xy 410.670327 -391.565128) (xy 410.618353 -391.565128) (xy 410.567018 -391.556998)
			(xy 410.517588 -391.540937) (xy 410.471278 -391.517341) (xy 410.42923 -391.486791) (xy 410.392479 -391.45004)
			(xy 410.361929 -391.407992) (xy 410.338333 -391.361682) (xy 410.322272 -391.312252) (xy 410.314142 -391.260917)
			(xy 409.774388 -391.260917) (xy 409.766258 -391.312252) (xy 409.750197 -391.361682) (xy 409.726601 -391.407992)
			(xy 409.696051 -391.45004) (xy 409.6593 -391.486791) (xy 409.617252 -391.517341) (xy 409.570942 -391.540937)
			(xy 409.521512 -391.556998) (xy 409.470177 -391.565128) (xy 409.418203 -391.565128) (xy 409.366868 -391.556998)
			(xy 409.317438 -391.540937) (xy 409.271128 -391.517341) (xy 409.22908 -391.486791) (xy 409.192329 -391.45004)
			(xy 409.161779 -391.407992) (xy 409.138183 -391.361682) (xy 409.122122 -391.312252) (xy 409.113992 -391.260917)
			(xy 408.574492 -391.260917) (xy 408.566362 -391.312252) (xy 408.550301 -391.361682) (xy 408.526705 -391.407992)
			(xy 408.496155 -391.45004) (xy 408.459404 -391.486791) (xy 408.417356 -391.517341) (xy 408.371046 -391.540937)
			(xy 408.321616 -391.556998) (xy 408.270281 -391.565128) (xy 408.218307 -391.565128) (xy 408.166972 -391.556998)
			(xy 408.117542 -391.540937) (xy 408.071232 -391.517341) (xy 408.029184 -391.486791) (xy 407.992433 -391.45004)
			(xy 407.961883 -391.407992) (xy 407.938287 -391.361682) (xy 407.922226 -391.312252) (xy 407.914096 -391.260917)
			(xy 407.374342 -391.260917) (xy 407.366212 -391.312252) (xy 407.350151 -391.361682) (xy 407.326555 -391.407992)
			(xy 407.296005 -391.45004) (xy 407.259254 -391.486791) (xy 407.217206 -391.517341) (xy 407.170896 -391.540937)
			(xy 407.121466 -391.556998) (xy 407.070131 -391.565128) (xy 407.018157 -391.565128) (xy 406.966822 -391.556998)
			(xy 406.917392 -391.540937) (xy 406.871082 -391.517341) (xy 406.829034 -391.486791) (xy 406.792283 -391.45004)
			(xy 406.761733 -391.407992) (xy 406.738137 -391.361682) (xy 406.722076 -391.312252) (xy 406.713946 -391.260917)
			(xy 406.174446 -391.260917) (xy 406.166316 -391.312252) (xy 406.150255 -391.361682) (xy 406.126659 -391.407992)
			(xy 406.096109 -391.45004) (xy 406.059358 -391.486791) (xy 406.01731 -391.517341) (xy 405.971 -391.540937)
			(xy 405.92157 -391.556998) (xy 405.870235 -391.565128) (xy 405.818261 -391.565128) (xy 405.766926 -391.556998)
			(xy 405.717496 -391.540937) (xy 405.671186 -391.517341) (xy 405.629138 -391.486791) (xy 405.592387 -391.45004)
			(xy 405.561837 -391.407992) (xy 405.538241 -391.361682) (xy 405.52218 -391.312252) (xy 405.51405 -391.260917)
			(xy 404.97455 -391.260917) (xy 404.96642 -391.312252) (xy 404.950359 -391.361682) (xy 404.926763 -391.407992)
			(xy 404.896213 -391.45004) (xy 404.859462 -391.486791) (xy 404.817414 -391.517341) (xy 404.771104 -391.540937)
			(xy 404.721674 -391.556998) (xy 404.670339 -391.565128) (xy 404.618365 -391.565128) (xy 404.56703 -391.556998)
			(xy 404.5176 -391.540937) (xy 404.47129 -391.517341) (xy 404.429242 -391.486791) (xy 404.392491 -391.45004)
			(xy 404.361941 -391.407992) (xy 404.338345 -391.361682) (xy 404.322284 -391.312252) (xy 404.314154 -391.260917)
			(xy 403.7744 -391.260917) (xy 403.76627 -391.312252) (xy 403.750209 -391.361682) (xy 403.726613 -391.407992)
			(xy 403.696063 -391.45004) (xy 403.659312 -391.486791) (xy 403.617264 -391.517341) (xy 403.570954 -391.540937)
			(xy 403.521524 -391.556998) (xy 403.470189 -391.565128) (xy 403.418215 -391.565128) (xy 403.36688 -391.556998)
			(xy 403.31745 -391.540937) (xy 403.27114 -391.517341) (xy 403.229092 -391.486791) (xy 403.192341 -391.45004)
			(xy 403.161791 -391.407992) (xy 403.138195 -391.361682) (xy 403.122134 -391.312252) (xy 403.114004 -391.260917)
			(xy 402.425768 -391.260917) (xy 402.426354 -391.264618) (xy 402.426354 -391.316582) (xy 402.418225 -391.367908)
			(xy 402.402168 -391.41733) (xy 402.378578 -391.463631) (xy 402.348034 -391.505673) (xy 402.311291 -391.542419)
			(xy 402.269252 -391.572965) (xy 402.222952 -391.596559) (xy 402.173531 -391.61262) (xy 402.122206 -391.620752)
			(xy 402.096224 -391.621264) (xy 402.071386 -391.620825) (xy 402.022269 -391.613404) (xy 401.974817 -391.598711)
			(xy 401.930101 -391.577077) (xy 401.889129 -391.54899) (xy 401.870672 -391.532364) (xy 401.8636 -391.526333)
			(xy 401.846415 -391.519293) (xy 401.837144 -391.518648) (xy 401.805902 -391.517886) (xy 401.796646 -391.518037)
			(xy 401.779193 -391.524166) (xy 401.771866 -391.529824) (xy 401.749302 -391.54799) (xy 401.699172 -391.577006)
			(xy 401.644758 -391.596859) (xy 401.587721 -391.606945) (xy 401.55876 -391.607548) (xy 401.535564 -391.607119)
			(xy 401.489626 -391.600637) (xy 401.445042 -391.587807) (xy 401.402686 -391.568878) (xy 401.363387 -391.544222)
			(xy 401.3454 -391.52957) (xy 401.338288 -391.523474) (xy 401.320762 -391.517378) (xy 401.235164 -391.519156)
			(xy 401.217892 -391.526268) (xy 401.211034 -391.532618) (xy 401.192593 -391.548937) (xy 401.151818 -391.576545)
			(xy 401.107401 -391.597802) (xy 401.060324 -391.612241) (xy 401.011627 -391.619541) (xy 400.987006 -391.619994)
			(xy 400.961015 -391.619539) (xy 400.909674 -391.611408) (xy 400.860236 -391.595346) (xy 400.81392 -391.571748)
			(xy 400.771866 -391.541194) (xy 400.73511 -391.504438) (xy 400.704556 -391.462385) (xy 400.680956 -391.416069)
			(xy 400.664893 -391.366632) (xy 400.656761 -391.315291) (xy 397.490373 -391.315291) (xy 397.448786 -391.345928)
			(xy 397.437864 -391.36955) (xy 397.43888 -391.382758) (xy 397.439896 -391.41146) (xy 397.43941 -391.438711)
			(xy 397.431654 -391.492659) (xy 397.416299 -391.544954) (xy 397.393657 -391.594531) (xy 397.364191 -391.640381)
			(xy 397.3285 -391.681572) (xy 397.287309 -391.717263) (xy 397.241459 -391.746729) (xy 397.191882 -391.769371)
			(xy 397.139587 -391.784726) (xy 397.085639 -391.792482) (xy 397.031137 -391.792482) (xy 396.977189 -391.784726)
			(xy 396.924894 -391.769371) (xy 396.875317 -391.746729) (xy 396.829467 -391.717263) (xy 396.788276 -391.681572)
			(xy 396.752585 -391.640381) (xy 396.723119 -391.594531) (xy 396.700477 -391.544954) (xy 396.685122 -391.492659)
			(xy 396.677366 -391.438711) (xy 396.67688 -391.41146) (xy 396.677896 -391.382758) (xy 396.678912 -391.36955)
			(xy 396.66799 -391.345928) (xy 396.577312 -391.279126) (xy 396.551404 -391.275824) (xy 396.538958 -391.280904)
			(xy 396.516448 -391.289438) (xy 396.469821 -391.301423) (xy 396.422059 -391.307456) (xy 396.397988 -391.307828)
			(xy 396.369819 -391.307329) (xy 396.314092 -391.299052) (xy 396.26019 -391.282667) (xy 396.209285 -391.258529)
			(xy 396.162485 -391.227164) (xy 396.12081 -391.189255) (xy 396.085166 -391.145626) (xy 396.056329 -391.097228)
			(xy 396.045182 -391.071354) (xy 396.039086 -391.056876) (xy 396.013686 -391.039604) (xy 395.916912 -391.039604)
			(xy 395.884401 -391.039144) (xy 395.819789 -391.031857) (xy 395.756399 -391.017384) (xy 395.695026 -390.995908)
			(xy 395.636443 -390.967699) (xy 395.581385 -390.933109) (xy 395.530544 -390.892576) (xy 395.50721 -390.869932)
			(xy 395.34719 -390.710166) (xy 395.339847 -390.70335) (xy 395.321384 -390.695611) (xy 395.311376 -390.69518)
			(xy 387.655816 -390.69518) (xy 387.645827 -390.695714) (xy 387.627389 -390.703421) (xy 387.620002 -390.710166)
			(xy 387.500114 -390.830054) (xy 387.482414 -390.847134) (xy 387.44264 -390.87607) (xy 387.398826 -390.89842)
			(xy 387.352052 -390.913632) (xy 387.303473 -390.921332) (xy 387.27888 -390.921748) (xy 386.893308 -390.921748)
			(xy 386.88447 -390.922072) (xy 386.867816 -390.927986) (xy 386.854169 -390.939215) (xy 386.849366 -390.94664)
			(xy 386.798312 -391.03427) (xy 386.798058 -391.061194) (xy 386.804662 -391.072878) (xy 386.818004 -391.097781)
			(xy 386.83692 -391.151012) (xy 386.846516 -391.206684) (xy 386.84708 -391.23493) (xy 386.84657 -391.260917)
			(xy 387.386324 -391.260917) (xy 387.386324 -391.208943) (xy 387.394454 -391.157608) (xy 387.410515 -391.108178)
			(xy 387.434111 -391.061868) (xy 387.464661 -391.01982) (xy 387.501412 -390.983069) (xy 387.54346 -390.952519)
			(xy 387.58977 -390.928923) (xy 387.6392 -390.912862) (xy 387.690535 -390.904732) (xy 387.742509 -390.904732)
			(xy 387.793844 -390.912862) (xy 387.843274 -390.928923) (xy 387.889584 -390.952519) (xy 387.931632 -390.983069)
			(xy 387.968383 -391.01982) (xy 387.998933 -391.061868) (xy 388.022529 -391.108178) (xy 388.03859 -391.157608)
			(xy 388.04672 -391.208943) (xy 388.04723 -391.23493) (xy 388.04672 -391.260917) (xy 388.58622 -391.260917)
			(xy 388.58622 -391.208943) (xy 388.59435 -391.157608) (xy 388.610411 -391.108178) (xy 388.634007 -391.061868)
			(xy 388.664557 -391.01982) (xy 388.701308 -390.983069) (xy 388.743356 -390.952519) (xy 388.789666 -390.928923)
			(xy 388.839096 -390.912862) (xy 388.890431 -390.904732) (xy 388.942405 -390.904732) (xy 388.99374 -390.912862)
			(xy 389.04317 -390.928923) (xy 389.08948 -390.952519) (xy 389.131528 -390.983069) (xy 389.168279 -391.01982)
			(xy 389.198829 -391.061868) (xy 389.222425 -391.108178) (xy 389.238486 -391.157608) (xy 389.246616 -391.208943)
			(xy 389.247126 -391.23493) (xy 389.246616 -391.260917) (xy 389.244198 -391.276188) (xy 389.653272 -391.276188)
			(xy 389.653272 -391.224212) (xy 389.661402 -391.172875) (xy 389.677463 -391.123443) (xy 389.701058 -391.077131)
			(xy 389.731608 -391.03508) (xy 389.768359 -390.998326) (xy 389.810407 -390.967773) (xy 389.856717 -390.944173)
			(xy 389.906148 -390.928109) (xy 389.957484 -390.919974) (xy 389.983472 -390.919462) (xy 390.007246 -390.91987)
			(xy 390.054306 -390.926671) (xy 390.099903 -390.940151) (xy 390.143096 -390.960031) (xy 390.182991 -390.9859)
			(xy 390.20115 -391.00125) (xy 390.208269 -391.006937) (xy 390.22532 -391.01332) (xy 390.234424 -391.013696)
			(xy 390.26592 -391.013696) (xy 390.275022 -391.013311) (xy 390.292072 -391.00693) (xy 390.299194 -391.00125)
			(xy 390.317359 -390.985908) (xy 390.357258 -390.960051) (xy 390.400451 -390.940175) (xy 390.446044 -390.926691)
			(xy 390.493099 -390.919877) (xy 390.516872 -390.919462) (xy 390.54286 -390.920003) (xy 390.594198 -390.92813)
			(xy 390.643631 -390.944188) (xy 390.689944 -390.967782) (xy 390.731996 -390.998331) (xy 390.76875 -391.035083)
			(xy 390.799303 -391.077132) (xy 390.822901 -391.123443) (xy 390.838963 -391.172875) (xy 390.847095 -391.224212)
			(xy 390.847095 -391.276188) (xy 390.838963 -391.327525) (xy 390.822901 -391.376957) (xy 390.799303 -391.423268)
			(xy 390.76875 -391.465317) (xy 390.731996 -391.502069) (xy 390.689944 -391.532618) (xy 390.643631 -391.556212)
			(xy 390.594198 -391.57227) (xy 390.54286 -391.580397) (xy 390.516872 -391.580878) (xy 390.493097 -391.580494)
			(xy 390.446037 -391.573686) (xy 390.40044 -391.5602) (xy 390.357247 -391.540315) (xy 390.317353 -391.514442)
			(xy 390.299194 -391.49909) (xy 390.292096 -391.493372) (xy 390.275028 -391.487009) (xy 390.26592 -391.486644)
			(xy 390.234424 -391.486644) (xy 390.225324 -391.487042) (xy 390.208273 -391.493413) (xy 390.20115 -391.49909)
			(xy 390.182974 -391.514418) (xy 390.143077 -391.540276) (xy 390.099888 -391.560154) (xy 390.054297 -391.573642)
			(xy 390.007244 -391.580461) (xy 389.983472 -391.580878) (xy 389.957484 -391.580426) (xy 389.906148 -391.572291)
			(xy 389.856717 -391.556227) (xy 389.810407 -391.532627) (xy 389.768359 -391.502074) (xy 389.731608 -391.46532)
			(xy 389.701058 -391.423269) (xy 389.677463 -391.376957) (xy 389.661402 -391.327525) (xy 389.653272 -391.276188)
			(xy 389.244198 -391.276188) (xy 389.238486 -391.312252) (xy 389.222425 -391.361682) (xy 389.198829 -391.407992)
			(xy 389.168279 -391.45004) (xy 389.131528 -391.486791) (xy 389.08948 -391.517341) (xy 389.04317 -391.540937)
			(xy 388.99374 -391.556998) (xy 388.942405 -391.565128) (xy 388.890431 -391.565128) (xy 388.839096 -391.556998)
			(xy 388.789666 -391.540937) (xy 388.743356 -391.517341) (xy 388.701308 -391.486791) (xy 388.664557 -391.45004)
			(xy 388.634007 -391.407992) (xy 388.610411 -391.361682) (xy 388.59435 -391.312252) (xy 388.58622 -391.260917)
			(xy 388.04672 -391.260917) (xy 388.03859 -391.312252) (xy 388.022529 -391.361682) (xy 387.998933 -391.407992)
			(xy 387.968383 -391.45004) (xy 387.931632 -391.486791) (xy 387.889584 -391.517341) (xy 387.843274 -391.540937)
			(xy 387.793844 -391.556998) (xy 387.742509 -391.565128) (xy 387.690535 -391.565128) (xy 387.6392 -391.556998)
			(xy 387.58977 -391.540937) (xy 387.54346 -391.517341) (xy 387.501412 -391.486791) (xy 387.464661 -391.45004)
			(xy 387.434111 -391.407992) (xy 387.410515 -391.361682) (xy 387.394454 -391.312252) (xy 387.386324 -391.260917)
			(xy 386.84657 -391.260917) (xy 386.83844 -391.312252) (xy 386.822379 -391.361682) (xy 386.798783 -391.407992)
			(xy 386.768233 -391.45004) (xy 386.731482 -391.486791) (xy 386.689434 -391.517341) (xy 386.643124 -391.540937)
			(xy 386.593694 -391.556998) (xy 386.542359 -391.565128) (xy 386.490385 -391.565128) (xy 386.43905 -391.556998)
			(xy 386.38962 -391.540937) (xy 386.34331 -391.517341) (xy 386.301262 -391.486791) (xy 386.264511 -391.45004)
			(xy 386.233961 -391.407992) (xy 386.210365 -391.361682) (xy 386.194304 -391.312252) (xy 386.186174 -391.260917)
			(xy 386.185664 -391.23493) (xy 386.186235 -391.206683) (xy 386.195823 -391.15101) (xy 386.214726 -391.097774)
			(xy 386.228082 -391.072878) (xy 386.234686 -391.061194) (xy 386.234432 -391.03427) (xy 386.183378 -390.94664)
			(xy 386.178545 -390.939242) (xy 386.164904 -390.928031) (xy 386.148267 -390.922119) (xy 386.139436 -390.921748)
			(xy 385.693412 -390.921748) (xy 385.684573 -390.922071) (xy 385.667918 -390.927984) (xy 385.65427 -390.939213)
			(xy 385.64947 -390.94664) (xy 385.598416 -391.03427) (xy 385.598162 -391.061194) (xy 385.604766 -391.072878)
			(xy 385.618108 -391.097781) (xy 385.637024 -391.151012) (xy 385.646619 -391.206684) (xy 385.647184 -391.23493)
			(xy 385.646674 -391.260917) (xy 385.638544 -391.312252) (xy 385.622483 -391.361682) (xy 385.598887 -391.407992)
			(xy 385.568337 -391.45004) (xy 385.531586 -391.486791) (xy 385.489538 -391.517341) (xy 385.443228 -391.540937)
			(xy 385.393798 -391.556998) (xy 385.342463 -391.565128) (xy 385.290489 -391.565128) (xy 385.239154 -391.556998)
			(xy 385.189724 -391.540937) (xy 385.143414 -391.517341) (xy 385.101366 -391.486791) (xy 385.064615 -391.45004)
			(xy 385.034065 -391.407992) (xy 385.010469 -391.361682) (xy 384.994408 -391.312252) (xy 384.986278 -391.260917)
			(xy 384.985768 -391.23493) (xy 384.986339 -391.206683) (xy 384.995927 -391.15101) (xy 385.014831 -391.097774)
			(xy 385.028186 -391.072878) (xy 385.03479 -391.061194) (xy 385.034536 -391.03427) (xy 384.983482 -390.94664)
			(xy 384.978649 -390.939242) (xy 384.965009 -390.928029) (xy 384.948371 -390.922117) (xy 384.93954 -390.921748)
			(xy 384.493516 -390.921748) (xy 384.484686 -390.922087) (xy 384.468055 -390.928021) (xy 384.454434 -390.939257)
			(xy 384.449574 -390.94664) (xy 384.39852 -391.03427) (xy 384.398266 -391.061194) (xy 384.40487 -391.072878)
			(xy 384.418212 -391.097781) (xy 384.437128 -391.151012) (xy 384.446723 -391.206684) (xy 384.447288 -391.23493)
			(xy 384.446778 -391.260917) (xy 384.438648 -391.312252) (xy 384.422587 -391.361682) (xy 384.398991 -391.407992)
			(xy 384.368441 -391.45004) (xy 384.33169 -391.486791) (xy 384.289642 -391.517341) (xy 384.243332 -391.540937)
			(xy 384.193902 -391.556998) (xy 384.142567 -391.565128) (xy 384.090593 -391.565128) (xy 384.039258 -391.556998)
			(xy 383.989828 -391.540937) (xy 383.943518 -391.517341) (xy 383.90147 -391.486791) (xy 383.864719 -391.45004)
			(xy 383.834169 -391.407992) (xy 383.810573 -391.361682) (xy 383.794512 -391.312252) (xy 383.786382 -391.260917)
			(xy 383.785872 -391.23493) (xy 383.786443 -391.206684) (xy 383.796032 -391.15101) (xy 383.814935 -391.097774)
			(xy 383.82829 -391.072878) (xy 383.834894 -391.061194) (xy 383.83464 -391.03427) (xy 383.783586 -390.94664)
			(xy 383.778753 -390.939241) (xy 383.765113 -390.928028) (xy 383.748475 -390.922114) (xy 383.739644 -390.921748)
			(xy 383.293366 -390.921748) (xy 383.284531 -390.922079) (xy 383.267888 -390.928002) (xy 383.254253 -390.939234)
			(xy 383.249424 -390.94664) (xy 383.19837 -391.03427) (xy 383.198116 -391.061194) (xy 383.20472 -391.072878)
			(xy 383.21806 -391.097782) (xy 383.236973 -391.151013) (xy 383.246566 -391.206684) (xy 383.247138 -391.23493)
			(xy 383.246628 -391.260917) (xy 383.238498 -391.312252) (xy 383.222437 -391.361682) (xy 383.198841 -391.407992)
			(xy 383.168291 -391.45004) (xy 383.13154 -391.486791) (xy 383.089492 -391.517341) (xy 383.043182 -391.540937)
			(xy 382.993752 -391.556998) (xy 382.942417 -391.565128) (xy 382.890443 -391.565128) (xy 382.839108 -391.556998)
			(xy 382.789678 -391.540937) (xy 382.743368 -391.517341) (xy 382.70132 -391.486791) (xy 382.664569 -391.45004)
			(xy 382.634019 -391.407992) (xy 382.610423 -391.361682) (xy 382.594362 -391.312252) (xy 382.586232 -391.260917)
			(xy 382.585722 -391.23493) (xy 382.586293 -391.206684) (xy 382.595883 -391.151011) (xy 382.614789 -391.097776)
			(xy 382.62814 -391.072878) (xy 382.634744 -391.061194) (xy 382.63449 -391.03427) (xy 382.583436 -390.94664)
			(xy 382.578606 -390.939236) (xy 382.564968 -390.928009) (xy 382.548328 -390.922079) (xy 382.539494 -390.921748)
			(xy 382.09347 -390.921748) (xy 382.084635 -390.922078) (xy 382.067991 -390.928) (xy 382.054354 -390.939232)
			(xy 382.049528 -390.94664) (xy 381.998474 -391.03427) (xy 381.99822 -391.061194) (xy 382.004824 -391.072878)
			(xy 382.018164 -391.097782) (xy 382.037077 -391.151013) (xy 382.04667 -391.206684) (xy 382.047242 -391.23493)
			(xy 382.046732 -391.260917) (xy 382.038602 -391.312252) (xy 382.022541 -391.361682) (xy 381.998945 -391.407992)
			(xy 381.968395 -391.45004) (xy 381.931644 -391.486791) (xy 381.889596 -391.517341) (xy 381.843286 -391.540937)
			(xy 381.793856 -391.556998) (xy 381.742521 -391.565128) (xy 381.690547 -391.565128) (xy 381.639212 -391.556998)
			(xy 381.589782 -391.540937) (xy 381.543472 -391.517341) (xy 381.501424 -391.486791) (xy 381.464673 -391.45004)
			(xy 381.434123 -391.407992) (xy 381.410527 -391.361682) (xy 381.394466 -391.312252) (xy 381.386336 -391.260917)
			(xy 381.385826 -391.23493) (xy 381.386397 -391.206684) (xy 381.395987 -391.151011) (xy 381.414893 -391.097776)
			(xy 381.428244 -391.072878) (xy 381.434848 -391.061194) (xy 381.434594 -391.03427) (xy 381.38354 -390.94664)
			(xy 381.37871 -390.939235) (xy 381.365072 -390.928007) (xy 381.348432 -390.922076) (xy 381.339598 -390.921748)
			(xy 380.89332 -390.921748) (xy 380.884489 -390.922086) (xy 380.867858 -390.928019) (xy 380.854235 -390.939255)
			(xy 380.849378 -390.94664) (xy 380.798324 -391.03427) (xy 380.79807 -391.061194) (xy 380.804674 -391.072878)
			(xy 380.818016 -391.097781) (xy 380.836931 -391.151012) (xy 380.846526 -391.206684) (xy 380.847092 -391.23493)
			(xy 380.846582 -391.260917) (xy 380.838452 -391.312252) (xy 380.822391 -391.361682) (xy 380.798795 -391.407992)
			(xy 380.768245 -391.45004) (xy 380.731494 -391.486791) (xy 380.689446 -391.517341) (xy 380.643136 -391.540937)
			(xy 380.593706 -391.556998) (xy 380.542371 -391.565128) (xy 380.490397 -391.565128) (xy 380.439062 -391.556998)
			(xy 380.389632 -391.540937) (xy 380.343322 -391.517341) (xy 380.301274 -391.486791) (xy 380.264523 -391.45004)
			(xy 380.233973 -391.407992) (xy 380.210377 -391.361682) (xy 380.194316 -391.312252) (xy 380.186186 -391.260917)
			(xy 380.185676 -391.23493) (xy 380.186247 -391.206684) (xy 380.195836 -391.15101) (xy 380.214739 -391.097774)
			(xy 380.228094 -391.072878) (xy 380.234698 -391.061194) (xy 380.234444 -391.03427) (xy 380.18339 -390.94664)
			(xy 380.178558 -390.939241) (xy 380.164917 -390.928026) (xy 380.148279 -390.922111) (xy 380.139448 -390.921748)
			(xy 379.693424 -390.921748) (xy 379.684593 -390.922085) (xy 379.66796 -390.928018) (xy 379.654337 -390.939253)
			(xy 379.649482 -390.94664) (xy 379.598428 -391.03427) (xy 379.598174 -391.061194) (xy 379.604778 -391.072878)
			(xy 379.61812 -391.097781) (xy 379.637035 -391.151013) (xy 379.64663 -391.206684) (xy 379.647196 -391.23493)
			(xy 379.646686 -391.260917) (xy 379.638556 -391.312252) (xy 379.622495 -391.361682) (xy 379.598899 -391.407992)
			(xy 379.568349 -391.45004) (xy 379.531598 -391.486791) (xy 379.48955 -391.517341) (xy 379.44324 -391.540937)
			(xy 379.39381 -391.556998) (xy 379.342475 -391.565128) (xy 379.290501 -391.565128) (xy 379.239166 -391.556998)
			(xy 379.189736 -391.540937) (xy 379.143426 -391.517341) (xy 379.101378 -391.486791) (xy 379.064627 -391.45004)
			(xy 379.034077 -391.407992) (xy 379.010481 -391.361682) (xy 378.99442 -391.312252) (xy 378.98629 -391.260917)
			(xy 378.98578 -391.23493) (xy 378.986351 -391.206684) (xy 378.99594 -391.15101) (xy 379.014844 -391.097774)
			(xy 379.028198 -391.072878) (xy 379.034802 -391.061194) (xy 379.034548 -391.03427) (xy 378.983494 -390.94664)
			(xy 378.978662 -390.939241) (xy 378.965022 -390.928025) (xy 378.948383 -390.922108) (xy 378.939552 -390.921748)
			(xy 378.493528 -390.921748) (xy 378.484697 -390.922085) (xy 378.468063 -390.928016) (xy 378.454438 -390.939251)
			(xy 378.449586 -390.94664) (xy 378.398532 -391.03427) (xy 378.398278 -391.061194) (xy 378.404882 -391.072878)
			(xy 378.418223 -391.097781) (xy 378.437139 -391.151013) (xy 378.446733 -391.206684) (xy 378.4473 -391.23493)
			(xy 378.44679 -391.260917) (xy 378.43866 -391.312252) (xy 378.422599 -391.361682) (xy 378.399003 -391.407992)
			(xy 378.368453 -391.45004) (xy 378.331702 -391.486791) (xy 378.289654 -391.517341) (xy 378.243344 -391.540937)
			(xy 378.193914 -391.556998) (xy 378.142579 -391.565128) (xy 378.090605 -391.565128) (xy 378.03927 -391.556998)
			(xy 377.98984 -391.540937) (xy 377.94353 -391.517341) (xy 377.901482 -391.486791) (xy 377.864731 -391.45004)
			(xy 377.834181 -391.407992) (xy 377.810585 -391.361682) (xy 377.794524 -391.312252) (xy 377.786394 -391.260917)
			(xy 377.785884 -391.23493) (xy 377.786455 -391.206684) (xy 377.796044 -391.15101) (xy 377.814948 -391.097774)
			(xy 377.828302 -391.072878) (xy 377.834906 -391.061194) (xy 377.834652 -391.03427) (xy 377.783598 -390.94664)
			(xy 377.778766 -390.93924) (xy 377.765126 -390.928023) (xy 377.748488 -390.922106) (xy 377.739656 -390.921748)
			(xy 377.293378 -390.921748) (xy 377.284542 -390.922077) (xy 377.267896 -390.927997) (xy 377.254257 -390.939229)
			(xy 377.249436 -390.94664) (xy 377.198382 -391.03427) (xy 377.198128 -391.061194) (xy 377.204732 -391.072878)
			(xy 377.218075 -391.097781) (xy 377.236993 -391.151012) (xy 377.246589 -391.206684) (xy 377.24715 -391.23493)
			(xy 377.24664 -391.260917) (xy 377.23851 -391.312252) (xy 377.222449 -391.361682) (xy 377.198853 -391.407992)
			(xy 377.168303 -391.45004) (xy 377.131552 -391.486791) (xy 377.089504 -391.517341) (xy 377.043194 -391.540937)
			(xy 376.993764 -391.556998) (xy 376.942429 -391.565128) (xy 376.890455 -391.565128) (xy 376.83912 -391.556998)
			(xy 376.78969 -391.540937) (xy 376.74338 -391.517341) (xy 376.701332 -391.486791) (xy 376.664581 -391.45004)
			(xy 376.634031 -391.407992) (xy 376.610435 -391.361682) (xy 376.594374 -391.312252) (xy 376.586244 -391.260917)
			(xy 376.585734 -391.23493) (xy 376.586306 -391.206684) (xy 376.595896 -391.151011) (xy 376.614802 -391.097777)
			(xy 376.628152 -391.072878) (xy 376.634756 -391.061194) (xy 376.634502 -391.03427) (xy 376.583448 -390.94664)
			(xy 376.578618 -390.939235) (xy 376.564981 -390.928004) (xy 376.548341 -390.92207) (xy 376.539506 -390.921748)
			(xy 376.093482 -390.921748) (xy 376.084646 -390.922076) (xy 376.067999 -390.927996) (xy 376.054359 -390.939227)
			(xy 376.04954 -390.94664) (xy 375.998486 -391.03427) (xy 375.998232 -391.061194) (xy 376.004836 -391.072878)
			(xy 376.018179 -391.097781) (xy 376.037097 -391.151012) (xy 376.046693 -391.206684) (xy 376.047254 -391.23493)
			(xy 376.046744 -391.260917) (xy 376.038614 -391.312252) (xy 376.022553 -391.361682) (xy 375.998957 -391.407992)
			(xy 375.968407 -391.45004) (xy 375.931656 -391.486791) (xy 375.889608 -391.517341) (xy 375.843298 -391.540937)
			(xy 375.793868 -391.556998) (xy 375.742533 -391.565128) (xy 375.690559 -391.565128) (xy 375.639224 -391.556998)
			(xy 375.589794 -391.540937) (xy 375.543484 -391.517341) (xy 375.501436 -391.486791) (xy 375.464685 -391.45004)
			(xy 375.434135 -391.407992) (xy 375.410539 -391.361682) (xy 375.394478 -391.312252) (xy 375.386348 -391.260917)
			(xy 375.385838 -391.23493) (xy 375.386409 -391.206683) (xy 375.395997 -391.15101) (xy 375.414898 -391.097772)
			(xy 375.428256 -391.072878) (xy 375.43486 -391.061194) (xy 375.434606 -391.03427) (xy 375.383552 -390.94664)
			(xy 375.378723 -390.939234) (xy 375.365085 -390.928003) (xy 375.348445 -390.922068) (xy 375.33961 -390.921748)
			(xy 374.893332 -390.921748) (xy 374.8845 -390.922084) (xy 374.867866 -390.928015) (xy 374.85424 -390.93925)
			(xy 374.84939 -390.94664) (xy 374.798336 -391.03427) (xy 374.798082 -391.061194) (xy 374.804686 -391.072878)
			(xy 374.818027 -391.097781) (xy 374.836942 -391.151013) (xy 374.846537 -391.206684) (xy 374.847104 -391.23493)
			(xy 374.846594 -391.260917) (xy 374.838464 -391.312252) (xy 374.822403 -391.361682) (xy 374.798807 -391.407992)
			(xy 374.768257 -391.45004) (xy 374.731506 -391.486791) (xy 374.689458 -391.517341) (xy 374.643148 -391.540937)
			(xy 374.593718 -391.556998) (xy 374.542383 -391.565128) (xy 374.490409 -391.565128) (xy 374.439074 -391.556998)
			(xy 374.389644 -391.540937) (xy 374.343334 -391.517341) (xy 374.301286 -391.486791) (xy 374.264535 -391.45004)
			(xy 374.233985 -391.407992) (xy 374.210389 -391.361682) (xy 374.194328 -391.312252) (xy 374.186198 -391.260917)
			(xy 374.185688 -391.23493) (xy 374.186259 -391.206684) (xy 374.195848 -391.151011) (xy 374.214752 -391.097775)
			(xy 374.228106 -391.072878) (xy 374.23471 -391.061194) (xy 374.234456 -391.03427) (xy 374.183402 -390.94664)
			(xy 374.17857 -390.93924) (xy 374.164931 -390.928022) (xy 374.148292 -390.922103) (xy 374.13946 -390.921748)
			(xy 373.693436 -390.921748) (xy 373.684604 -390.922084) (xy 373.667968 -390.928013) (xy 373.654341 -390.939248)
			(xy 373.649494 -390.94664) (xy 373.59844 -391.03427) (xy 373.598186 -391.061194) (xy 373.60479 -391.072878)
			(xy 373.618131 -391.097781) (xy 373.637046 -391.151013) (xy 373.64664 -391.206684) (xy 373.647208 -391.23493)
			(xy 373.646698 -391.260917) (xy 373.638568 -391.312252) (xy 373.622507 -391.361682) (xy 373.598911 -391.407992)
			(xy 373.568361 -391.45004) (xy 373.53161 -391.486791) (xy 373.489562 -391.517341) (xy 373.443252 -391.540937)
			(xy 373.393822 -391.556998) (xy 373.342487 -391.565128) (xy 373.290513 -391.565128) (xy 373.239178 -391.556998)
			(xy 373.189748 -391.540937) (xy 373.143438 -391.517341) (xy 373.10139 -391.486791) (xy 373.064639 -391.45004)
			(xy 373.034089 -391.407992) (xy 373.010493 -391.361682) (xy 372.994432 -391.312252) (xy 372.986302 -391.260917)
			(xy 372.985792 -391.23493) (xy 372.986363 -391.206684) (xy 372.995952 -391.151011) (xy 373.014857 -391.097775)
			(xy 373.02821 -391.072878) (xy 373.034814 -391.061194) (xy 373.03456 -391.03427) (xy 372.983506 -390.94664)
			(xy 372.978674 -390.939239) (xy 372.965035 -390.92802) (xy 372.948396 -390.9221) (xy 372.939564 -390.921748)
			(xy 372.49354 -390.921748) (xy 372.484708 -390.922083) (xy 372.468071 -390.928012) (xy 372.454443 -390.939246)
			(xy 372.449598 -390.94664) (xy 372.398544 -391.03427) (xy 372.39829 -391.061194) (xy 372.404894 -391.072878)
			(xy 372.418235 -391.097781) (xy 372.437149 -391.151013) (xy 372.446744 -391.206684) (xy 372.447312 -391.23493)
			(xy 372.446802 -391.260917) (xy 372.438672 -391.312252) (xy 372.422611 -391.361682) (xy 372.399015 -391.407992)
			(xy 372.368465 -391.45004) (xy 372.331714 -391.486791) (xy 372.289666 -391.517341) (xy 372.243356 -391.540937)
			(xy 372.193926 -391.556998) (xy 372.142591 -391.565128) (xy 372.090617 -391.565128) (xy 372.039282 -391.556998)
			(xy 371.989852 -391.540937) (xy 371.943542 -391.517341) (xy 371.901494 -391.486791) (xy 371.864743 -391.45004)
			(xy 371.834193 -391.407992) (xy 371.810597 -391.361682) (xy 371.794536 -391.312252) (xy 371.786406 -391.260917)
			(xy 371.785896 -391.23493) (xy 371.786467 -391.206684) (xy 371.796056 -391.151011) (xy 371.814961 -391.097775)
			(xy 371.828314 -391.072878) (xy 371.834918 -391.061194) (xy 371.834664 -391.03427) (xy 371.78361 -390.94664)
			(xy 371.778778 -390.939239) (xy 371.765139 -390.928019) (xy 371.7485 -390.922097) (xy 371.739668 -390.921748)
			(xy 371.29339 -390.921748) (xy 371.284553 -390.922075) (xy 371.267904 -390.927993) (xy 371.254262 -390.939223)
			(xy 371.249448 -390.94664) (xy 371.198394 -391.03427) (xy 371.19814 -391.061194) (xy 371.204744 -391.072878)
			(xy 371.218087 -391.097781) (xy 371.237004 -391.151012) (xy 371.2466 -391.206684) (xy 371.247162 -391.23493)
			(xy 371.246652 -391.260917) (xy 371.238522 -391.312252) (xy 371.222461 -391.361682) (xy 371.198865 -391.407992)
			(xy 371.168315 -391.45004) (xy 371.131564 -391.486791) (xy 371.089516 -391.517341) (xy 371.043206 -391.540937)
			(xy 370.993776 -391.556998) (xy 370.942441 -391.565128) (xy 370.890467 -391.565128) (xy 370.839132 -391.556998)
			(xy 370.789702 -391.540937) (xy 370.743392 -391.517341) (xy 370.701344 -391.486791) (xy 370.664593 -391.45004)
			(xy 370.634043 -391.407992) (xy 370.610447 -391.361682) (xy 370.594386 -391.312252) (xy 370.586256 -391.260917)
			(xy 370.585746 -391.23493) (xy 370.586317 -391.206683) (xy 370.595905 -391.15101) (xy 370.614807 -391.097773)
			(xy 370.628164 -391.072878) (xy 370.634768 -391.061194) (xy 370.634514 -391.03427) (xy 370.58346 -390.94664)
			(xy 370.578626 -390.939244) (xy 370.564985 -390.928038) (xy 370.548348 -390.922132) (xy 370.539518 -390.921748)
			(xy 369.908582 -390.921748) (xy 369.899104 -390.922205) (xy 369.881442 -390.929093) (xy 369.86746 -390.941895)
			(xy 369.862862 -390.950196) (xy 369.81638 -391.0457) (xy 369.819682 -391.074402) (xy 369.828572 -391.085832)
			(xy 369.845139 -391.107828) (xy 369.871494 -391.156173) (xy 369.889482 -391.208215) (xy 369.898606 -391.262517)
			(xy 369.899184 -391.290048) (xy 369.898671 -391.316032) (xy 369.890534 -391.367359) (xy 369.874469 -391.416782)
			(xy 369.85087 -391.463083) (xy 369.820319 -391.505123) (xy 369.783568 -391.541866) (xy 369.741522 -391.572408)
			(xy 369.695215 -391.595996) (xy 369.645789 -391.612051) (xy 369.59446 -391.620177) (xy 369.568476 -391.620756)
			(xy 369.539879 -391.620156) (xy 369.483537 -391.610326) (xy 369.429728 -391.590947) (xy 369.380056 -391.562596)
			(xy 369.357656 -391.54481) (xy 369.350798 -391.539222) (xy 369.334034 -391.533126) (xy 369.251738 -391.533126)
			(xy 369.234974 -391.538968) (xy 369.228116 -391.544556) (xy 369.205761 -391.562207) (xy 369.15625 -391.590359)
			(xy 369.102645 -391.609606) (xy 369.046535 -391.619379) (xy 369.018058 -391.619994) (xy 368.994825 -391.619598)
			(xy 368.948818 -391.613089) (xy 368.904174 -391.600207) (xy 368.861772 -391.581203) (xy 368.822447 -391.556453)
			(xy 368.804444 -391.541762) (xy 368.797332 -391.535666) (xy 368.780822 -391.52957) (xy 368.696494 -391.52957)
			(xy 368.679984 -391.535666) (xy 368.672872 -391.541762) (xy 368.654882 -391.55647) (xy 368.615556 -391.581227)
			(xy 368.573152 -391.600232) (xy 368.528504 -391.613112) (xy 368.482492 -391.619613) (xy 368.459258 -391.619994)
			(xy 368.433273 -391.619481) (xy 368.381945 -391.611345) (xy 368.332521 -391.595281) (xy 368.286218 -391.571682)
			(xy 368.244177 -391.541132) (xy 368.207432 -391.504381) (xy 368.176888 -391.462334) (xy 368.153298 -391.416027)
			(xy 368.137241 -391.366601) (xy 368.129114 -391.315271) (xy 368.12855 -391.289286) (xy 368.129111 -391.261871)
			(xy 368.138188 -391.207797) (xy 368.156043 -391.155954) (xy 368.182188 -391.107758) (xy 368.198654 -391.085832)
			(xy 368.207544 -391.074148) (xy 368.210592 -391.045446) (xy 368.16411 -390.950196) (xy 368.159537 -390.941932)
			(xy 368.145637 -390.929171) (xy 368.128076 -390.922264) (xy 368.118644 -390.921748) (xy 366.797082 -390.921748)
			(xy 366.787117 -390.922227) (xy 366.768685 -390.929807) (xy 366.761268 -390.93648) (xy 366.235742 -391.462006)
			(xy 366.228122 -391.482834) (xy 366.228884 -391.49401) (xy 366.230408 -391.53338) (xy 366.229906 -391.565341)
			(xy 366.221895 -391.628759) (xy 366.205998 -391.690673) (xy 366.182466 -391.750106) (xy 366.151672 -391.806121)
			(xy 366.114099 -391.857836) (xy 366.070342 -391.904433) (xy 366.021089 -391.945178) (xy 365.967118 -391.979429)
			(xy 365.909279 -392.006646) (xy 365.848486 -392.026399) (xy 365.785696 -392.038377) (xy 365.7219 -392.042391)
			(xy 365.658104 -392.038377) (xy 365.595314 -392.026399) (xy 365.534521 -392.006646) (xy 365.476682 -391.979429)
			(xy 365.422711 -391.945178) (xy 365.373458 -391.904433) (xy 365.329701 -391.857836) (xy 365.292128 -391.806121)
			(xy 365.261334 -391.750106) (xy 365.237802 -391.690673) (xy 365.221905 -391.628759) (xy 365.213894 -391.565341)
			(xy 365.213392 -391.53338) (xy 365.213757 -391.506437) (xy 365.219483 -391.452857) (xy 365.224822 -391.426446)
			(xy 365.227108 -391.415778) (xy 365.22279 -391.395204) (xy 365.167672 -391.316718) (xy 365.149892 -391.305796)
			(xy 365.139224 -391.304272) (xy 365.116379 -391.3008) (xy 365.071679 -391.289088) (xy 365.05007 -391.280904)
			(xy 365.037624 -391.275824) (xy 365.011716 -391.279126) (xy 364.921038 -391.345928) (xy 364.910116 -391.36955)
			(xy 364.911132 -391.382758) (xy 364.912148 -391.41146) (xy 364.911662 -391.438711) (xy 364.903906 -391.492659)
			(xy 364.888551 -391.544954) (xy 364.865909 -391.594531) (xy 364.836443 -391.640381) (xy 364.800752 -391.681572)
			(xy 364.759561 -391.717263) (xy 364.713711 -391.746729) (xy 364.664134 -391.769371) (xy 364.611839 -391.784726)
			(xy 364.557891 -391.792482) (xy 364.503389 -391.792482) (xy 364.449441 -391.784726) (xy 364.397146 -391.769371)
			(xy 364.347569 -391.746729) (xy 364.301719 -391.717263) (xy 364.260528 -391.681572) (xy 364.224837 -391.640381)
			(xy 364.195371 -391.594531) (xy 364.172729 -391.544954) (xy 364.157374 -391.492659) (xy 364.149618 -391.438711)
			(xy 364.149132 -391.41146) (xy 364.150148 -391.382758) (xy 364.151164 -391.36955) (xy 364.140242 -391.345928)
			(xy 364.049564 -391.279126) (xy 364.023656 -391.275824) (xy 364.01121 -391.280904) (xy 363.9887 -391.289441)
			(xy 363.942074 -391.301432) (xy 363.894312 -391.307472) (xy 363.87024 -391.307828) (xy 363.842985 -391.307368)
			(xy 363.789028 -391.299616) (xy 363.736724 -391.284263) (xy 363.687138 -391.261623) (xy 363.641278 -391.232157)
			(xy 363.600079 -391.196463) (xy 363.564379 -391.15527) (xy 363.534905 -391.109415) (xy 363.512258 -391.059832)
			(xy 363.496897 -391.00753) (xy 363.489136 -390.953575) (xy 363.488732 -390.92632) (xy 363.489169 -390.900403)
			(xy 363.49618 -390.849045) (xy 363.502702 -390.823958) (xy 363.506004 -390.812528) (xy 363.501432 -390.78916)
			(xy 363.445298 -390.715246) (xy 363.437699 -390.706273) (xy 363.416655 -390.695841) (xy 363.404912 -390.69518)
			(xy 361.723686 -390.69518) (xy 361.717844 -390.696704) (xy 361.695885 -390.701615) (xy 361.65119 -390.706838)
			(xy 361.62869 -390.707118) (xy 361.606191 -390.706818) (xy 361.561498 -390.701597) (xy 361.539536 -390.696704)
			(xy 361.533694 -390.69518) (xy 360.959908 -390.69518) (xy 360.949919 -390.695715) (xy 360.931483 -390.703424)
			(xy 360.924094 -390.710166) (xy 360.847386 -390.786874) (xy 360.829685 -390.803951) (xy 360.78991 -390.832882)
			(xy 360.746095 -390.855226) (xy 360.699322 -390.870434) (xy 360.650744 -390.878129) (xy 360.626152 -390.878568)
			(xy 358.8639 -390.878568) (xy 358.853932 -390.879041) (xy 358.835487 -390.886609) (xy 358.828086 -390.8933)
			(xy 357.852726 -391.86866) (xy 357.845922 -391.876007) (xy 357.838207 -391.89447) (xy 357.83774 -391.904474)
			(xy 357.83774 -391.935716) (xy 357.838163 -391.945732) (xy 357.845837 -391.964237) (xy 357.86001 -391.978394)
			(xy 357.878523 -391.986048) (xy 357.88854 -391.986516) (xy 357.893366 -391.986516) (xy 357.897938 -391.985754)
			(xy 357.920722 -391.981831) (xy 357.966768 -391.977632) (xy 357.989886 -391.977372) (xy 358.02914 -391.978121)
			(xy 358.106705 -391.990246) (xy 358.144318 -392.001502) (xy 358.156764 -392.005312) (xy 358.182672 -392.000232)
			(xy 358.26827 -391.927334) (xy 358.277668 -391.902696) (xy 358.275636 -391.889742) (xy 358.273725 -391.875915)
			(xy 358.271693 -391.848074) (xy 358.271572 -391.834116) (xy 358.272058 -391.806865) (xy 358.279814 -391.752917)
			(xy 358.295169 -391.700622) (xy 358.317811 -391.651045) (xy 358.347277 -391.605195) (xy 358.382968 -391.564004)
			(xy 358.424159 -391.528313) (xy 358.470009 -391.498847) (xy 358.519586 -391.476205) (xy 358.571881 -391.46085)
			(xy 358.625829 -391.453094) (xy 358.680331 -391.453094) (xy 358.734279 -391.46085) (xy 358.786574 -391.476205)
			(xy 358.836151 -391.498847) (xy 358.882001 -391.528313) (xy 358.923192 -391.564004) (xy 358.958883 -391.605195)
			(xy 358.988349 -391.651045) (xy 359.010991 -391.700622) (xy 359.026346 -391.752917) (xy 359.034102 -391.806865)
			(xy 359.034588 -391.834116) (xy 359.033964 -391.865767) (xy 359.023488 -391.928196) (xy 359.01376 -391.958322)
			(xy 359.011313 -391.966614) (xy 359.011574 -391.983889) (xy 359.014268 -391.992104) (xy 359.024428 -392.020298)
			(xy 359.027798 -392.028497) (xy 359.039089 -392.042146) (xy 359.046526 -392.046968) (xy 359.074863 -392.064128)
			(xy 359.127251 -392.104676) (xy 359.147629 -392.1252) (xy 366.783872 -392.1252) (xy 366.787943 -392.069578)
			(xy 366.800069 -392.015141) (xy 366.819992 -391.96305) (xy 366.847288 -391.914415) (xy 366.881374 -391.870272)
			(xy 366.921523 -391.831563) (xy 366.966881 -391.799112) (xy 367.016481 -391.773611) (xy 367.069265 -391.755604)
			(xy 367.124108 -391.745474) (xy 367.179842 -391.743437) (xy 367.235279 -391.749537) (xy 367.289236 -391.763643)
			(xy 367.340565 -391.785455) (xy 367.388171 -391.814509) (xy 367.431039 -391.850184) (xy 367.468256 -391.891721)
			(xy 367.499029 -391.938234) (xy 367.522701 -391.988731) (xy 367.538769 -392.042138) (xy 367.546889 -392.097314)
			(xy 367.547398 -392.1252) (xy 367.546889 -392.153086) (xy 367.538769 -392.208262) (xy 367.522701 -392.261669)
			(xy 367.499029 -392.312166) (xy 367.468256 -392.358679) (xy 367.431039 -392.400216) (xy 367.388171 -392.435891)
			(xy 367.340565 -392.464945) (xy 367.289236 -392.486757) (xy 367.235279 -392.500863) (xy 367.179842 -392.506963)
			(xy 367.124108 -392.504926) (xy 367.069265 -392.494796) (xy 367.016481 -392.476789) (xy 366.966881 -392.451288)
			(xy 366.921523 -392.418837) (xy 366.881374 -392.380128) (xy 366.847288 -392.335985) (xy 366.819992 -392.28735)
			(xy 366.800069 -392.235259) (xy 366.787943 -392.180822) (xy 366.783872 -392.1252) (xy 359.147629 -392.1252)
			(xy 359.173927 -392.151687) (xy 359.214098 -392.204364) (xy 359.247086 -392.261813) (xy 359.272329 -392.323062)
			(xy 359.2894 -392.387072) (xy 359.29801 -392.452757) (xy 359.298494 -392.48588) (xy 359.29805 -392.515991)
			(xy 359.290937 -392.57579) (xy 359.276807 -392.63433) (xy 359.255858 -392.69079) (xy 359.228385 -392.744379)
			(xy 359.194771 -392.794347) (xy 359.155489 -392.839992) (xy 359.111089 -392.880676) (xy 359.086912 -392.89863)
			(xy 359.07749 -392.906292) (xy 359.066492 -392.927905) (xy 359.06583 -392.940032) (xy 359.06583 -393.022328)
			(xy 359.066462 -393.034459) (xy 359.071676 -393.04468) (xy 366.783872 -393.04468) (xy 366.787943 -392.989058)
			(xy 366.800069 -392.934621) (xy 366.819992 -392.88253) (xy 366.847288 -392.833895) (xy 366.881374 -392.789752)
			(xy 366.921523 -392.751043) (xy 366.966881 -392.718592) (xy 367.016481 -392.693091) (xy 367.069265 -392.675084)
			(xy 367.124108 -392.664954) (xy 367.179842 -392.662917) (xy 367.235279 -392.669017) (xy 367.289236 -392.683123)
			(xy 367.340565 -392.704935) (xy 367.388171 -392.733989) (xy 367.43065 -392.76934) (xy 368.04395 -392.76934)
			(xy 368.04395 -392.709404) (xy 368.051773 -392.649982) (xy 368.067286 -392.592089) (xy 368.090222 -392.536716)
			(xy 368.120189 -392.48481) (xy 368.156676 -392.43726) (xy 368.199056 -392.39488) (xy 368.246606 -392.358393)
			(xy 368.298512 -392.328426) (xy 368.353885 -392.30549) (xy 368.411778 -392.289977) (xy 368.4712 -392.282154)
			(xy 368.531136 -392.282154) (xy 368.590558 -392.289977) (xy 368.648451 -392.30549) (xy 368.703824 -392.328426)
			(xy 368.75573 -392.358393) (xy 368.80328 -392.39488) (xy 368.84566 -392.43726) (xy 368.882147 -392.48481)
			(xy 368.912114 -392.536716) (xy 368.93505 -392.592089) (xy 368.950563 -392.649982) (xy 368.958386 -392.709404)
			(xy 368.958876 -392.739372) (xy 368.958386 -392.76934) (xy 368.950563 -392.828762) (xy 368.93505 -392.886655)
			(xy 368.912114 -392.942028) (xy 368.882147 -392.993934) (xy 368.84566 -393.041484) (xy 368.80328 -393.083864)
			(xy 368.75573 -393.120351) (xy 368.703824 -393.150318) (xy 368.648451 -393.173254) (xy 368.590558 -393.188767)
			(xy 368.531136 -393.19659) (xy 368.4712 -393.19659) (xy 368.411778 -393.188767) (xy 368.353885 -393.173254)
			(xy 368.298512 -393.150318) (xy 368.246606 -393.120351) (xy 368.199056 -393.083864) (xy 368.156676 -393.041484)
			(xy 368.120189 -392.993934) (xy 368.090222 -392.942028) (xy 368.067286 -392.886655) (xy 368.051773 -392.828762)
			(xy 368.04395 -392.76934) (xy 367.43065 -392.76934) (xy 367.431039 -392.769664) (xy 367.468256 -392.811201)
			(xy 367.499029 -392.857714) (xy 367.522701 -392.908211) (xy 367.538769 -392.961618) (xy 367.546889 -393.016794)
			(xy 367.547398 -393.04468) (xy 367.546889 -393.072566) (xy 367.538769 -393.127742) (xy 367.522701 -393.181149)
			(xy 367.499029 -393.231646) (xy 367.468256 -393.278159) (xy 367.431039 -393.319696) (xy 367.388171 -393.355371)
			(xy 367.340565 -393.384425) (xy 367.289236 -393.406237) (xy 367.235279 -393.420343) (xy 367.179842 -393.426443)
			(xy 367.124108 -393.424406) (xy 367.069265 -393.414276) (xy 367.016481 -393.396269) (xy 366.966881 -393.370768)
			(xy 366.921523 -393.338317) (xy 366.881374 -393.299608) (xy 366.847288 -393.255465) (xy 366.819992 -393.20683)
			(xy 366.800069 -393.154739) (xy 366.787943 -393.100302) (xy 366.783872 -393.04468) (xy 359.071676 -393.04468)
			(xy 359.077484 -393.056066) (xy 359.086912 -393.06373) (xy 359.111091 -393.081677) (xy 359.155473 -393.122374)
			(xy 359.194739 -393.168028) (xy 359.228341 -393.217998) (xy 359.255807 -393.271587) (xy 359.276753 -393.328043)
			(xy 359.290887 -393.386578) (xy 359.298011 -393.446372) (xy 359.298494 -393.47648) (xy 359.29805 -393.507213)
			(xy 359.290643 -393.56823) (xy 359.275935 -393.627909) (xy 359.254141 -393.685381) (xy 359.225577 -393.739806)
			(xy 359.190662 -393.790391) (xy 359.149903 -393.836399) (xy 359.103896 -393.877158) (xy 359.053311 -393.912074)
			(xy 358.998886 -393.940638) (xy 358.941415 -393.962433) (xy 358.881736 -393.977142) (xy 358.820719 -393.984549)
			(xy 358.789986 -393.984988) (xy 358.75967 -393.984565) (xy 358.699464 -393.977386) (xy 358.64054 -393.963095)
			(xy 358.583734 -393.941896) (xy 358.529854 -393.914089) (xy 358.479665 -393.88007) (xy 358.456484 -393.860528)
			(xy 358.449626 -393.854178) (xy 358.432608 -393.848082) (xy 358.347264 -393.848082) (xy 358.330246 -393.854178)
			(xy 358.323388 -393.860528) (xy 358.295956 -393.882626) (xy 358.286608 -393.89053) (xy 358.276004 -393.912553)
			(xy 358.275636 -393.92479) (xy 358.276652 -393.956286) (xy 358.277795 -393.968526) (xy 358.289862 -393.9899)
			(xy 358.291976 -393.991454) (xy 366.784838 -393.991454) (xy 366.784838 -393.936946) (xy 366.792595 -393.882994)
			(xy 366.807951 -393.830694) (xy 366.830594 -393.781113) (xy 366.860062 -393.735258) (xy 366.895757 -393.694064)
			(xy 366.93695 -393.658368) (xy 366.982804 -393.628899) (xy 367.032385 -393.606255) (xy 367.084684 -393.590897)
			(xy 367.138636 -393.583139) (xy 367.16589 -393.582652) (xy 367.194525 -393.583129) (xy 367.251151 -393.591702)
			(xy 367.30586 -393.60864) (xy 367.357424 -393.633564) (xy 367.404683 -393.665913) (xy 367.446577 -393.704963)
			(xy 367.482166 -393.749834) (xy 367.496852 -393.774422) (xy 367.503964 -393.786614) (xy 367.52784 -393.80033)
			(xy 367.644934 -393.798044) (xy 367.668302 -393.78382) (xy 367.674906 -393.771374) (xy 367.689842 -393.744121)
			(xy 367.725972 -393.693556) (xy 367.768616 -393.648348) (xy 367.816987 -393.609329) (xy 367.870195 -393.577217)
			(xy 367.92726 -393.552604) (xy 367.987132 -393.535943) (xy 368.048708 -393.527541) (xy 368.079782 -393.527026)
			(xy 368.109752 -393.527478) (xy 368.169179 -393.5353) (xy 368.227077 -393.550812) (xy 368.282455 -393.57375)
			(xy 368.334365 -393.60372) (xy 368.381918 -393.640209) (xy 368.424301 -393.682594) (xy 368.460789 -393.730149)
			(xy 368.490757 -393.782059) (xy 368.513693 -393.837438) (xy 368.529203 -393.895336) (xy 368.537023 -393.954764)
			(xy 368.53749 -393.984734) (xy 368.536981 -394.015614) (xy 368.528666 -394.076811) (xy 368.512191 -394.136333)
			(xy 368.487858 -394.193096) (xy 368.456107 -394.246069) (xy 368.446935 -394.25753) (xy 369.933982 -394.25753)
			(xy 369.934503 -394.231542) (xy 369.942629 -394.180205) (xy 369.958687 -394.130772) (xy 369.98228 -394.08446)
			(xy 370.012828 -394.042408) (xy 370.049578 -394.005654) (xy 370.091626 -393.975101) (xy 370.137935 -393.951502)
			(xy 370.187366 -393.935439) (xy 370.238702 -393.927306) (xy 370.26469 -393.926822) (xy 370.281123 -393.92704)
			(xy 370.313823 -393.930353) (xy 370.329968 -393.933426) (xy 370.342922 -393.935966) (xy 370.368068 -393.928092)
			(xy 370.445284 -393.846304) (xy 370.451888 -393.820904) (xy 370.448586 -393.808204) (xy 370.441579 -393.779762)
			(xy 370.434062 -393.721669) (xy 370.4336 -393.69238) (xy 370.434126 -393.661492) (xy 370.442431 -393.600277)
			(xy 370.458888 -393.540733) (xy 370.483198 -393.483941) (xy 370.498624 -393.457176) (xy 370.504466 -393.44727)
			(xy 370.506752 -393.424918) (xy 370.473478 -393.329668) (xy 370.45773 -393.313666) (xy 370.447062 -393.309602)
			(xy 370.423673 -393.300436) (xy 370.379777 -393.276013) (xy 370.340082 -393.245229) (xy 370.305502 -393.208793)
			(xy 370.276834 -393.167544) (xy 370.254737 -393.122432) (xy 370.239721 -393.074495) (xy 370.232132 -393.024839)
			(xy 370.23167 -392.999722) (xy 370.23218 -392.973735) (xy 370.24031 -392.9224) (xy 370.256371 -392.87297)
			(xy 370.279967 -392.82666) (xy 370.310517 -392.784612) (xy 370.347268 -392.747861) (xy 370.389316 -392.717311)
			(xy 370.435626 -392.693715) (xy 370.485056 -392.677654) (xy 370.536391 -392.669524) (xy 370.588365 -392.669524)
			(xy 370.6397 -392.677654) (xy 370.68913 -392.693715) (xy 370.73544 -392.717311) (xy 370.777488 -392.747861)
			(xy 370.814239 -392.784612) (xy 370.844789 -392.82666) (xy 370.868385 -392.87297) (xy 370.884446 -392.9224)
			(xy 370.892576 -392.973735) (xy 370.893086 -392.999722) (xy 371.431566 -392.999722) (xy 371.432076 -392.973735)
			(xy 371.440206 -392.9224) (xy 371.456267 -392.87297) (xy 371.479863 -392.82666) (xy 371.510413 -392.784612)
			(xy 371.547164 -392.747861) (xy 371.589212 -392.717311) (xy 371.635522 -392.693715) (xy 371.684952 -392.677654)
			(xy 371.736287 -392.669524) (xy 371.788261 -392.669524) (xy 371.839596 -392.677654) (xy 371.889026 -392.693715)
			(xy 371.935336 -392.717311) (xy 371.977384 -392.747861) (xy 372.014135 -392.784612) (xy 372.044685 -392.82666)
			(xy 372.068281 -392.87297) (xy 372.084342 -392.9224) (xy 372.092472 -392.973735) (xy 372.092982 -392.999722)
			(xy 372.631716 -392.999722) (xy 372.632226 -392.973735) (xy 372.640356 -392.9224) (xy 372.656417 -392.87297)
			(xy 372.680013 -392.82666) (xy 372.710563 -392.784612) (xy 372.747314 -392.747861) (xy 372.789362 -392.717311)
			(xy 372.835672 -392.693715) (xy 372.885102 -392.677654) (xy 372.936437 -392.669524) (xy 372.988411 -392.669524)
			(xy 373.039746 -392.677654) (xy 373.089176 -392.693715) (xy 373.135486 -392.717311) (xy 373.177534 -392.747861)
			(xy 373.214285 -392.784612) (xy 373.244835 -392.82666) (xy 373.268431 -392.87297) (xy 373.284492 -392.9224)
			(xy 373.292622 -392.973735) (xy 373.293132 -392.999722) (xy 373.831612 -392.999722) (xy 373.832122 -392.973735)
			(xy 373.840252 -392.9224) (xy 373.856313 -392.87297) (xy 373.879909 -392.82666) (xy 373.910459 -392.784612)
			(xy 373.94721 -392.747861) (xy 373.989258 -392.717311) (xy 374.035568 -392.693715) (xy 374.084998 -392.677654)
			(xy 374.136333 -392.669524) (xy 374.188307 -392.669524) (xy 374.239642 -392.677654) (xy 374.289072 -392.693715)
			(xy 374.335382 -392.717311) (xy 374.37743 -392.747861) (xy 374.414181 -392.784612) (xy 374.444731 -392.82666)
			(xy 374.468327 -392.87297) (xy 374.484388 -392.9224) (xy 374.492518 -392.973735) (xy 374.493028 -392.999722)
			(xy 375.031762 -392.999722) (xy 375.032272 -392.973735) (xy 375.040402 -392.9224) (xy 375.056463 -392.87297)
			(xy 375.080059 -392.82666) (xy 375.110609 -392.784612) (xy 375.14736 -392.747861) (xy 375.189408 -392.717311)
			(xy 375.235718 -392.693715) (xy 375.285148 -392.677654) (xy 375.336483 -392.669524) (xy 375.388457 -392.669524)
			(xy 375.439792 -392.677654) (xy 375.489222 -392.693715) (xy 375.535532 -392.717311) (xy 375.57758 -392.747861)
			(xy 375.614331 -392.784612) (xy 375.644881 -392.82666) (xy 375.668477 -392.87297) (xy 375.684538 -392.9224)
			(xy 375.692668 -392.973735) (xy 375.693178 -392.999722) (xy 376.231658 -392.999722) (xy 376.232168 -392.973735)
			(xy 376.240298 -392.9224) (xy 376.256359 -392.87297) (xy 376.279955 -392.82666) (xy 376.310505 -392.784612)
			(xy 376.347256 -392.747861) (xy 376.389304 -392.717311) (xy 376.435614 -392.693715) (xy 376.485044 -392.677654)
			(xy 376.536379 -392.669524) (xy 376.588353 -392.669524) (xy 376.639688 -392.677654) (xy 376.689118 -392.693715)
			(xy 376.735428 -392.717311) (xy 376.777476 -392.747861) (xy 376.814227 -392.784612) (xy 376.844777 -392.82666)
			(xy 376.868373 -392.87297) (xy 376.884434 -392.9224) (xy 376.892564 -392.973735) (xy 376.893074 -392.999722)
			(xy 377.431554 -392.999722) (xy 377.432064 -392.973735) (xy 377.440194 -392.9224) (xy 377.456255 -392.87297)
			(xy 377.479851 -392.82666) (xy 377.510401 -392.784612) (xy 377.547152 -392.747861) (xy 377.5892 -392.717311)
			(xy 377.63551 -392.693715) (xy 377.68494 -392.677654) (xy 377.736275 -392.669524) (xy 377.788249 -392.669524)
			(xy 377.839584 -392.677654) (xy 377.889014 -392.693715) (xy 377.935324 -392.717311) (xy 377.977372 -392.747861)
			(xy 378.014123 -392.784612) (xy 378.044673 -392.82666) (xy 378.068269 -392.87297) (xy 378.08433 -392.9224)
			(xy 378.09246 -392.973735) (xy 378.09297 -392.999722) (xy 378.631704 -392.999722) (xy 378.632214 -392.973735)
			(xy 378.640344 -392.9224) (xy 378.656405 -392.87297) (xy 378.680001 -392.82666) (xy 378.710551 -392.784612)
			(xy 378.747302 -392.747861) (xy 378.78935 -392.717311) (xy 378.83566 -392.693715) (xy 378.88509 -392.677654)
			(xy 378.936425 -392.669524) (xy 378.988399 -392.669524) (xy 379.039734 -392.677654) (xy 379.089164 -392.693715)
			(xy 379.135474 -392.717311) (xy 379.177522 -392.747861) (xy 379.214273 -392.784612) (xy 379.244823 -392.82666)
			(xy 379.268419 -392.87297) (xy 379.28448 -392.9224) (xy 379.29261 -392.973735) (xy 379.29312 -392.999722)
			(xy 379.8316 -392.999722) (xy 379.83211 -392.973735) (xy 379.84024 -392.9224) (xy 379.856301 -392.87297)
			(xy 379.879897 -392.82666) (xy 379.910447 -392.784612) (xy 379.947198 -392.747861) (xy 379.989246 -392.717311)
			(xy 380.035556 -392.693715) (xy 380.084986 -392.677654) (xy 380.136321 -392.669524) (xy 380.188295 -392.669524)
			(xy 380.23963 -392.677654) (xy 380.28906 -392.693715) (xy 380.33537 -392.717311) (xy 380.377418 -392.747861)
			(xy 380.414169 -392.784612) (xy 380.444719 -392.82666) (xy 380.468315 -392.87297) (xy 380.484376 -392.9224)
			(xy 380.492506 -392.973735) (xy 380.493016 -392.999722) (xy 381.03175 -392.999722) (xy 381.03226 -392.973735)
			(xy 381.04039 -392.9224) (xy 381.056451 -392.87297) (xy 381.080047 -392.82666) (xy 381.110597 -392.784612)
			(xy 381.147348 -392.747861) (xy 381.189396 -392.717311) (xy 381.235706 -392.693715) (xy 381.285136 -392.677654)
			(xy 381.336471 -392.669524) (xy 381.388445 -392.669524) (xy 381.43978 -392.677654) (xy 381.48921 -392.693715)
			(xy 381.53552 -392.717311) (xy 381.577568 -392.747861) (xy 381.614319 -392.784612) (xy 381.644869 -392.82666)
			(xy 381.668465 -392.87297) (xy 381.684526 -392.9224) (xy 381.692656 -392.973735) (xy 381.693166 -392.999722)
			(xy 382.231646 -392.999722) (xy 382.232156 -392.973735) (xy 382.240286 -392.9224) (xy 382.256347 -392.87297)
			(xy 382.279943 -392.82666) (xy 382.310493 -392.784612) (xy 382.347244 -392.747861) (xy 382.389292 -392.717311)
			(xy 382.435602 -392.693715) (xy 382.485032 -392.677654) (xy 382.536367 -392.669524) (xy 382.588341 -392.669524)
			(xy 382.639676 -392.677654) (xy 382.689106 -392.693715) (xy 382.735416 -392.717311) (xy 382.777464 -392.747861)
			(xy 382.814215 -392.784612) (xy 382.844765 -392.82666) (xy 382.868361 -392.87297) (xy 382.884422 -392.9224)
			(xy 382.892552 -392.973735) (xy 382.893062 -392.999722) (xy 383.431542 -392.999722) (xy 383.432052 -392.973735)
			(xy 383.440182 -392.9224) (xy 383.456243 -392.87297) (xy 383.479839 -392.82666) (xy 383.510389 -392.784612)
			(xy 383.54714 -392.747861) (xy 383.589188 -392.717311) (xy 383.635498 -392.693715) (xy 383.684928 -392.677654)
			(xy 383.736263 -392.669524) (xy 383.788237 -392.669524) (xy 383.839572 -392.677654) (xy 383.889002 -392.693715)
			(xy 383.935312 -392.717311) (xy 383.97736 -392.747861) (xy 384.014111 -392.784612) (xy 384.044661 -392.82666)
			(xy 384.068257 -392.87297) (xy 384.084318 -392.9224) (xy 384.092448 -392.973735) (xy 384.092958 -392.999722)
			(xy 384.631692 -392.999722) (xy 384.632202 -392.973735) (xy 384.640332 -392.9224) (xy 384.656393 -392.87297)
			(xy 384.679989 -392.82666) (xy 384.710539 -392.784612) (xy 384.74729 -392.747861) (xy 384.789338 -392.717311)
			(xy 384.835648 -392.693715) (xy 384.885078 -392.677654) (xy 384.936413 -392.669524) (xy 384.988387 -392.669524)
			(xy 385.039722 -392.677654) (xy 385.089152 -392.693715) (xy 385.135462 -392.717311) (xy 385.17751 -392.747861)
			(xy 385.214261 -392.784612) (xy 385.244811 -392.82666) (xy 385.268407 -392.87297) (xy 385.284468 -392.9224)
			(xy 385.292598 -392.973735) (xy 385.293108 -392.999722) (xy 385.831588 -392.999722) (xy 385.832098 -392.973735)
			(xy 385.840228 -392.9224) (xy 385.856289 -392.87297) (xy 385.879885 -392.82666) (xy 385.910435 -392.784612)
			(xy 385.947186 -392.747861) (xy 385.989234 -392.717311) (xy 386.035544 -392.693715) (xy 386.084974 -392.677654)
			(xy 386.136309 -392.669524) (xy 386.188283 -392.669524) (xy 386.239618 -392.677654) (xy 386.289048 -392.693715)
			(xy 386.335358 -392.717311) (xy 386.377406 -392.747861) (xy 386.414157 -392.784612) (xy 386.444707 -392.82666)
			(xy 386.468303 -392.87297) (xy 386.484364 -392.9224) (xy 386.492494 -392.973735) (xy 386.493004 -392.999722)
			(xy 387.031738 -392.999722) (xy 387.032248 -392.973735) (xy 387.040378 -392.9224) (xy 387.056439 -392.87297)
			(xy 387.080035 -392.82666) (xy 387.110585 -392.784612) (xy 387.147336 -392.747861) (xy 387.189384 -392.717311)
			(xy 387.235694 -392.693715) (xy 387.285124 -392.677654) (xy 387.336459 -392.669524) (xy 387.388433 -392.669524)
			(xy 387.439768 -392.677654) (xy 387.489198 -392.693715) (xy 387.535508 -392.717311) (xy 387.577556 -392.747861)
			(xy 387.614307 -392.784612) (xy 387.644857 -392.82666) (xy 387.668453 -392.87297) (xy 387.684514 -392.9224)
			(xy 387.692644 -392.973735) (xy 387.693154 -392.999722) (xy 388.231634 -392.999722) (xy 388.232144 -392.973735)
			(xy 388.240274 -392.9224) (xy 388.256335 -392.87297) (xy 388.279931 -392.82666) (xy 388.310481 -392.784612)
			(xy 388.347232 -392.747861) (xy 388.38928 -392.717311) (xy 388.43559 -392.693715) (xy 388.48502 -392.677654)
			(xy 388.536355 -392.669524) (xy 388.588329 -392.669524) (xy 388.639664 -392.677654) (xy 388.689094 -392.693715)
			(xy 388.735404 -392.717311) (xy 388.777452 -392.747861) (xy 388.814203 -392.784612) (xy 388.844753 -392.82666)
			(xy 388.868349 -392.87297) (xy 388.88441 -392.9224) (xy 388.89254 -392.973735) (xy 388.89305 -392.999722)
			(xy 388.89252 -393.026824) (xy 388.883711 -393.080307) (xy 388.875524 -393.106148) (xy 388.871714 -393.11707)
			(xy 388.874254 -393.139422) (xy 388.926832 -393.225274) (xy 388.945882 -393.23772) (xy 388.957058 -393.239498)
			(xy 388.98638 -393.244184) (xy 389.04355 -393.260236) (xy 389.098164 -393.283549) (xy 389.149303 -393.313731)
			(xy 389.196109 -393.350274) (xy 389.237793 -393.392565) (xy 389.273657 -393.439894) (xy 389.303096 -393.491464)
			(xy 389.319442 -393.531344) (xy 390.402318 -393.531344) (xy 390.402744 -393.502708) (xy 390.409901 -393.445886)
			(xy 390.424083 -393.390398) (xy 390.44507 -393.33711) (xy 390.472534 -393.286854) (xy 390.488932 -393.263374)
			(xy 390.494609 -393.254857) (xy 390.499219 -393.23493) (xy 390.495651 -393.214791) (xy 390.490456 -393.20597)
			(xy 390.472968 -393.177993) (xy 390.445339 -393.11808) (xy 390.426594 -393.054823) (xy 390.417121 -392.98953)
			(xy 390.416542 -392.956542) (xy 390.417008 -392.927301) (xy 390.424441 -392.869294) (xy 390.439202 -392.812707)
			(xy 390.461052 -392.758461) (xy 390.489635 -392.70744) (xy 390.524485 -392.660477) (xy 390.565034 -392.618336)
			(xy 390.61062 -392.581704) (xy 390.660503 -392.551179) (xy 390.713867 -392.527256) (xy 390.769844 -392.510327)
			(xy 390.827522 -392.500667) (xy 390.856724 -392.499088) (xy 390.866376 -392.498834) (xy 390.883902 -392.491214)
			(xy 390.946386 -392.428222) (xy 390.954006 -392.41095) (xy 390.95426 -392.401044) (xy 390.955853 -392.368494)
			(xy 390.966342 -392.304173) (xy 390.984963 -392.241719) (xy 391.01141 -392.182156) (xy 391.04525 -392.12646)
			(xy 391.085928 -392.075543) (xy 391.132777 -392.030241) (xy 391.18503 -391.991295) (xy 391.241831 -391.959344)
			(xy 391.302248 -391.934911) (xy 391.365292 -391.918398) (xy 391.429929 -391.910074) (xy 391.462514 -391.909554)
			(xy 391.496097 -391.910127) (xy 391.56268 -391.918952) (xy 391.62752 -391.936472) (xy 391.689486 -391.962382)
			(xy 391.747498 -391.996231) (xy 391.800545 -392.037428) (xy 391.847702 -392.085255) (xy 391.888146 -392.138879)
			(xy 391.921173 -392.197363) (xy 391.934192 -392.228324) (xy 391.93978 -392.24204) (xy 391.963402 -392.259058)
			(xy 392.08456 -392.266678) (xy 392.110214 -392.252454) (xy 392.117326 -392.2395) (xy 392.134272 -392.210171)
			(xy 392.174678 -392.15581) (xy 392.22194 -392.10729) (xy 392.275222 -392.065469) (xy 392.333581 -392.031087)
			(xy 392.395986 -392.004752) (xy 392.461333 -391.986929) (xy 392.528467 -391.977934) (xy 392.562334 -391.977372)
			(xy 392.601586 -391.978139) (xy 392.679151 -391.990257) (xy 392.716766 -392.001502) (xy 392.729212 -392.005312)
			(xy 392.75512 -392.000232) (xy 392.840718 -391.927334) (xy 392.850116 -391.902696) (xy 392.848084 -391.889742)
			(xy 392.846185 -391.875914) (xy 392.84415 -391.848073) (xy 392.84402 -391.834116) (xy 392.844506 -391.806865)
			(xy 392.852262 -391.752917) (xy 392.867617 -391.700622) (xy 392.890259 -391.651045) (xy 392.919725 -391.605195)
			(xy 392.955416 -391.564004) (xy 392.996607 -391.528313) (xy 393.042457 -391.498847) (xy 393.092034 -391.476205)
			(xy 393.144329 -391.46085) (xy 393.198277 -391.453094) (xy 393.252779 -391.453094) (xy 393.306727 -391.46085)
			(xy 393.359022 -391.476205) (xy 393.408599 -391.498847) (xy 393.454449 -391.528313) (xy 393.49564 -391.564004)
			(xy 393.531331 -391.605195) (xy 393.560797 -391.651045) (xy 393.583439 -391.700622) (xy 393.598794 -391.752917)
			(xy 393.60655 -391.806865) (xy 393.607036 -391.834116) (xy 393.606362 -391.865763) (xy 393.595889 -391.928185)
			(xy 393.586208 -391.958322) (xy 393.583801 -391.96662) (xy 393.584057 -391.983884) (xy 393.586716 -391.992104)
			(xy 393.596876 -392.020298) (xy 393.60017 -392.028542) (xy 393.61148 -392.042209) (xy 393.618974 -392.046968)
			(xy 393.647294 -392.064152) (xy 393.699674 -392.1047) (xy 393.720025 -392.1252) (xy 399.31162 -392.1252)
			(xy 399.315691 -392.069578) (xy 399.327817 -392.015141) (xy 399.34774 -391.96305) (xy 399.375036 -391.914415)
			(xy 399.409122 -391.870272) (xy 399.449271 -391.831563) (xy 399.494629 -391.799112) (xy 399.544229 -391.773611)
			(xy 399.597013 -391.755604) (xy 399.651856 -391.745474) (xy 399.70759 -391.743437) (xy 399.763027 -391.749537)
			(xy 399.816984 -391.763643) (xy 399.868313 -391.785455) (xy 399.915919 -391.814509) (xy 399.958787 -391.850184)
			(xy 399.996004 -391.891721) (xy 400.026777 -391.938234) (xy 400.050449 -391.988731) (xy 400.066517 -392.042138)
			(xy 400.074637 -392.097314) (xy 400.075146 -392.1252) (xy 400.074637 -392.153086) (xy 400.066517 -392.208262)
			(xy 400.050449 -392.261669) (xy 400.026777 -392.312166) (xy 399.996004 -392.358679) (xy 399.958787 -392.400216)
			(xy 399.915919 -392.435891) (xy 399.868313 -392.464945) (xy 399.816984 -392.486757) (xy 399.763027 -392.500863)
			(xy 399.70759 -392.506963) (xy 399.651856 -392.504926) (xy 399.597013 -392.494796) (xy 399.544229 -392.476789)
			(xy 399.494629 -392.451288) (xy 399.449271 -392.418837) (xy 399.409122 -392.380128) (xy 399.375036 -392.335985)
			(xy 399.34774 -392.28735) (xy 399.327817 -392.235259) (xy 399.315691 -392.180822) (xy 399.31162 -392.1252)
			(xy 393.720025 -392.1252) (xy 393.746343 -392.15171) (xy 393.786509 -392.204385) (xy 393.819491 -392.261831)
			(xy 393.84473 -392.323076) (xy 393.861799 -392.38708) (xy 393.870407 -392.452759) (xy 393.870942 -392.48588)
			(xy 393.870485 -392.515989) (xy 393.863354 -392.575783) (xy 393.849215 -392.634318) (xy 393.828264 -392.690774)
			(xy 393.800794 -392.744361) (xy 393.767191 -392.794331) (xy 393.727923 -392.839985) (xy 393.68354 -392.880683)
			(xy 393.65936 -392.89863) (xy 393.649895 -392.906255) (xy 393.638895 -392.927892) (xy 393.638278 -392.940032)
			(xy 393.638278 -393.022328) (xy 393.638886 -393.034463) (xy 393.644102 -393.04468) (xy 399.31162 -393.04468)
			(xy 399.315691 -392.989058) (xy 399.327817 -392.934621) (xy 399.34774 -392.88253) (xy 399.375036 -392.833895)
			(xy 399.409122 -392.789752) (xy 399.449271 -392.751043) (xy 399.494629 -392.718592) (xy 399.544229 -392.693091)
			(xy 399.597013 -392.675084) (xy 399.651856 -392.664954) (xy 399.70759 -392.662917) (xy 399.763027 -392.669017)
			(xy 399.816984 -392.683123) (xy 399.868313 -392.704935) (xy 399.915919 -392.733989) (xy 399.958398 -392.76934)
			(xy 400.571698 -392.76934) (xy 400.571698 -392.709404) (xy 400.579521 -392.649982) (xy 400.595034 -392.592089)
			(xy 400.61797 -392.536716) (xy 400.647937 -392.48481) (xy 400.684424 -392.43726) (xy 400.726804 -392.39488)
			(xy 400.774354 -392.358393) (xy 400.82626 -392.328426) (xy 400.881633 -392.30549) (xy 400.939526 -392.289977)
			(xy 400.998948 -392.282154) (xy 401.058884 -392.282154) (xy 401.118306 -392.289977) (xy 401.176199 -392.30549)
			(xy 401.231572 -392.328426) (xy 401.283478 -392.358393) (xy 401.331028 -392.39488) (xy 401.373408 -392.43726)
			(xy 401.409895 -392.48481) (xy 401.439862 -392.536716) (xy 401.462798 -392.592089) (xy 401.478311 -392.649982)
			(xy 401.486134 -392.709404) (xy 401.486624 -392.739372) (xy 401.486134 -392.76934) (xy 401.478311 -392.828762)
			(xy 401.462798 -392.886655) (xy 401.439862 -392.942028) (xy 401.409895 -392.993934) (xy 401.373408 -393.041484)
			(xy 401.331028 -393.083864) (xy 401.283478 -393.120351) (xy 401.231572 -393.150318) (xy 401.176199 -393.173254)
			(xy 401.118306 -393.188767) (xy 401.058884 -393.19659) (xy 400.998948 -393.19659) (xy 400.939526 -393.188767)
			(xy 400.881633 -393.173254) (xy 400.82626 -393.150318) (xy 400.774354 -393.120351) (xy 400.726804 -393.083864)
			(xy 400.684424 -393.041484) (xy 400.647937 -392.993934) (xy 400.61797 -392.942028) (xy 400.595034 -392.886655)
			(xy 400.579521 -392.828762) (xy 400.571698 -392.76934) (xy 399.958398 -392.76934) (xy 399.958787 -392.769664)
			(xy 399.996004 -392.811201) (xy 400.026777 -392.857714) (xy 400.050449 -392.908211) (xy 400.066517 -392.961618)
			(xy 400.074637 -393.016794) (xy 400.075146 -393.04468) (xy 400.074637 -393.072566) (xy 400.066517 -393.127742)
			(xy 400.050449 -393.181149) (xy 400.026777 -393.231646) (xy 399.996004 -393.278159) (xy 399.958787 -393.319696)
			(xy 399.915919 -393.355371) (xy 399.868313 -393.384425) (xy 399.816984 -393.406237) (xy 399.763027 -393.420343)
			(xy 399.70759 -393.426443) (xy 399.651856 -393.424406) (xy 399.597013 -393.414276) (xy 399.544229 -393.396269)
			(xy 399.494629 -393.370768) (xy 399.449271 -393.338317) (xy 399.409122 -393.299608) (xy 399.375036 -393.255465)
			(xy 399.34774 -393.20683) (xy 399.327817 -393.154739) (xy 399.315691 -393.100302) (xy 399.31162 -393.04468)
			(xy 393.644102 -393.04468) (xy 393.64992 -393.056076) (xy 393.65936 -393.06373) (xy 393.683553 -393.081663)
			(xy 393.727956 -393.122348) (xy 393.767238 -393.167996) (xy 393.800851 -393.217966) (xy 393.828323 -393.271559)
			(xy 393.849268 -393.328022) (xy 393.863394 -393.386566) (xy 393.870502 -393.446368) (xy 393.870942 -393.47648)
			(xy 393.870425 -393.507209) (xy 393.86302 -393.56822) (xy 393.848314 -393.627893) (xy 393.826523 -393.685359)
			(xy 393.797965 -393.739779) (xy 393.763055 -393.79036) (xy 393.722303 -393.836365) (xy 393.676303 -393.877122)
			(xy 393.625725 -393.912037) (xy 393.571308 -393.940601) (xy 393.513845 -393.962398) (xy 393.454173 -393.97711)
			(xy 393.393163 -393.984522) (xy 393.362434 -393.984988) (xy 393.330309 -393.984519) (xy 393.266573 -393.976408)
			(xy 393.204365 -393.960336) (xy 393.144676 -393.936559) (xy 393.088457 -393.905456) (xy 393.036601 -393.867521)
			(xy 393.01293 -393.845796) (xy 393.005585 -393.83945) (xy 392.987574 -393.83226) (xy 392.977878 -393.831826)
			(xy 392.94689 -393.831826) (xy 392.937188 -393.83225) (xy 392.919162 -393.839421) (xy 392.911838 -393.845796)
			(xy 392.89609 -393.860274) (xy 392.8872 -393.867894) (xy 392.87831 -393.888468) (xy 392.881612 -393.990576)
			(xy 392.882058 -393.991457) (xy 399.312515 -393.991457) (xy 399.312515 -393.936943) (xy 399.320274 -393.882983)
			(xy 399.335633 -393.830676) (xy 399.358281 -393.781088) (xy 399.387756 -393.735228) (xy 399.423457 -393.69403)
			(xy 399.464659 -393.658333) (xy 399.510522 -393.628863) (xy 399.560112 -393.60622) (xy 399.61242 -393.590866)
			(xy 399.66638 -393.583112) (xy 399.693638 -393.582652) (xy 399.722272 -393.583171) (xy 399.778896 -393.591735)
			(xy 399.833604 -393.608666) (xy 399.885167 -393.633583) (xy 399.932427 -393.665927) (xy 399.974323 -393.70497)
			(xy 400.009913 -393.749836) (xy 400.0246 -393.774422) (xy 400.031712 -393.786614) (xy 400.055588 -393.80033)
			(xy 400.172682 -393.798044) (xy 400.19605 -393.78382) (xy 400.202654 -393.771374) (xy 400.217628 -393.744143)
			(xy 400.253754 -393.693578) (xy 400.296392 -393.64837) (xy 400.344757 -393.609349) (xy 400.397959 -393.577235)
			(xy 400.455019 -393.552619) (xy 400.514886 -393.535953) (xy 400.576458 -393.527545) (xy 400.60753 -393.527026)
			(xy 400.637501 -393.527433) (xy 400.69693 -393.535261) (xy 400.754829 -393.550779) (xy 400.810207 -393.573722)
			(xy 400.862116 -393.603697) (xy 400.909669 -393.64019) (xy 400.952052 -393.682579) (xy 400.988539 -393.730137)
			(xy 401.018506 -393.782051) (xy 401.041441 -393.837432) (xy 401.056951 -393.895333) (xy 401.064771 -393.954763)
			(xy 401.065238 -393.984734) (xy 401.064745 -394.015614) (xy 401.056429 -394.076813) (xy 401.039952 -394.136336)
			(xy 401.015616 -394.1931) (xy 400.983862 -394.246072) (xy 400.974691 -394.25753) (xy 402.46173 -394.25753)
			(xy 402.462203 -394.23154) (xy 402.470331 -394.180198) (xy 402.486391 -394.130761) (xy 402.509989 -394.084445)
			(xy 402.540542 -394.042392) (xy 402.577298 -394.005637) (xy 402.619352 -393.975085) (xy 402.665669 -393.951488)
			(xy 402.715106 -393.935429) (xy 402.766448 -393.927302) (xy 402.792438 -393.926822) (xy 402.808871 -393.927048)
			(xy 402.841571 -393.930355) (xy 402.857716 -393.933426) (xy 402.87067 -393.935966) (xy 402.895816 -393.928092)
			(xy 402.973032 -393.846304) (xy 402.979636 -393.820904) (xy 402.976334 -393.808204) (xy 402.969328 -393.779762)
			(xy 402.96181 -393.721669) (xy 402.961348 -393.69238) (xy 402.961867 -393.661492) (xy 402.970173 -393.600276)
			(xy 402.986632 -393.540732) (xy 403.010944 -393.48394) (xy 403.026372 -393.457176) (xy 403.032214 -393.44727)
			(xy 403.0345 -393.424918) (xy 403.001226 -393.329668) (xy 402.985478 -393.313666) (xy 402.97481 -393.309602)
			(xy 402.951432 -393.300411) (xy 402.907534 -393.275993) (xy 402.867837 -393.245214) (xy 402.833255 -393.208782)
			(xy 402.804585 -393.167536) (xy 402.782487 -393.122427) (xy 402.76747 -393.074493) (xy 402.75988 -393.024838)
			(xy 402.759418 -392.999722) (xy 402.759928 -392.973735) (xy 402.768058 -392.9224) (xy 402.784119 -392.87297)
			(xy 402.807715 -392.82666) (xy 402.838265 -392.784612) (xy 402.875016 -392.747861) (xy 402.917064 -392.717311)
			(xy 402.963374 -392.693715) (xy 403.012804 -392.677654) (xy 403.064139 -392.669524) (xy 403.116113 -392.669524)
			(xy 403.167448 -392.677654) (xy 403.216878 -392.693715) (xy 403.263188 -392.717311) (xy 403.305236 -392.747861)
			(xy 403.341987 -392.784612) (xy 403.372537 -392.82666) (xy 403.396133 -392.87297) (xy 403.412194 -392.9224)
			(xy 403.420324 -392.973735) (xy 403.420834 -392.999722) (xy 403.959314 -392.999722) (xy 403.959824 -392.973735)
			(xy 403.967954 -392.9224) (xy 403.984015 -392.87297) (xy 404.007611 -392.82666) (xy 404.038161 -392.784612)
			(xy 404.074912 -392.747861) (xy 404.11696 -392.717311) (xy 404.16327 -392.693715) (xy 404.2127 -392.677654)
			(xy 404.264035 -392.669524) (xy 404.316009 -392.669524) (xy 404.367344 -392.677654) (xy 404.416774 -392.693715)
			(xy 404.463084 -392.717311) (xy 404.505132 -392.747861) (xy 404.541883 -392.784612) (xy 404.572433 -392.82666)
			(xy 404.596029 -392.87297) (xy 404.61209 -392.9224) (xy 404.62022 -392.973735) (xy 404.62073 -392.999722)
			(xy 405.159464 -392.999722) (xy 405.159974 -392.973735) (xy 405.168104 -392.9224) (xy 405.184165 -392.87297)
			(xy 405.207761 -392.82666) (xy 405.238311 -392.784612) (xy 405.275062 -392.747861) (xy 405.31711 -392.717311)
			(xy 405.36342 -392.693715) (xy 405.41285 -392.677654) (xy 405.464185 -392.669524) (xy 405.516159 -392.669524)
			(xy 405.567494 -392.677654) (xy 405.616924 -392.693715) (xy 405.663234 -392.717311) (xy 405.705282 -392.747861)
			(xy 405.742033 -392.784612) (xy 405.772583 -392.82666) (xy 405.796179 -392.87297) (xy 405.81224 -392.9224)
			(xy 405.82037 -392.973735) (xy 405.82088 -392.999722) (xy 406.35936 -392.999722) (xy 406.35987 -392.973735)
			(xy 406.368 -392.9224) (xy 406.384061 -392.87297) (xy 406.407657 -392.82666) (xy 406.438207 -392.784612)
			(xy 406.474958 -392.747861) (xy 406.517006 -392.717311) (xy 406.563316 -392.693715) (xy 406.612746 -392.677654)
			(xy 406.664081 -392.669524) (xy 406.716055 -392.669524) (xy 406.76739 -392.677654) (xy 406.81682 -392.693715)
			(xy 406.86313 -392.717311) (xy 406.905178 -392.747861) (xy 406.941929 -392.784612) (xy 406.972479 -392.82666)
			(xy 406.996075 -392.87297) (xy 407.012136 -392.9224) (xy 407.020266 -392.973735) (xy 407.020776 -392.999722)
			(xy 407.55951 -392.999722) (xy 407.56002 -392.973735) (xy 407.56815 -392.9224) (xy 407.584211 -392.87297)
			(xy 407.607807 -392.82666) (xy 407.638357 -392.784612) (xy 407.675108 -392.747861) (xy 407.717156 -392.717311)
			(xy 407.763466 -392.693715) (xy 407.812896 -392.677654) (xy 407.864231 -392.669524) (xy 407.916205 -392.669524)
			(xy 407.96754 -392.677654) (xy 408.01697 -392.693715) (xy 408.06328 -392.717311) (xy 408.105328 -392.747861)
			(xy 408.142079 -392.784612) (xy 408.172629 -392.82666) (xy 408.196225 -392.87297) (xy 408.212286 -392.9224)
			(xy 408.220416 -392.973735) (xy 408.220926 -392.999722) (xy 408.759406 -392.999722) (xy 408.759916 -392.973735)
			(xy 408.768046 -392.9224) (xy 408.784107 -392.87297) (xy 408.807703 -392.82666) (xy 408.838253 -392.784612)
			(xy 408.875004 -392.747861) (xy 408.917052 -392.717311) (xy 408.963362 -392.693715) (xy 409.012792 -392.677654)
			(xy 409.064127 -392.669524) (xy 409.116101 -392.669524) (xy 409.167436 -392.677654) (xy 409.216866 -392.693715)
			(xy 409.263176 -392.717311) (xy 409.305224 -392.747861) (xy 409.341975 -392.784612) (xy 409.372525 -392.82666)
			(xy 409.396121 -392.87297) (xy 409.412182 -392.9224) (xy 409.420312 -392.973735) (xy 409.420822 -392.999722)
			(xy 409.959302 -392.999722) (xy 409.959812 -392.973735) (xy 409.967942 -392.9224) (xy 409.984003 -392.87297)
			(xy 410.007599 -392.82666) (xy 410.038149 -392.784612) (xy 410.0749 -392.747861) (xy 410.116948 -392.717311)
			(xy 410.163258 -392.693715) (xy 410.212688 -392.677654) (xy 410.264023 -392.669524) (xy 410.315997 -392.669524)
			(xy 410.367332 -392.677654) (xy 410.416762 -392.693715) (xy 410.463072 -392.717311) (xy 410.50512 -392.747861)
			(xy 410.541871 -392.784612) (xy 410.572421 -392.82666) (xy 410.596017 -392.87297) (xy 410.612078 -392.9224)
			(xy 410.620208 -392.973735) (xy 410.620718 -392.999722) (xy 411.159452 -392.999722) (xy 411.159962 -392.973735)
			(xy 411.168092 -392.9224) (xy 411.184153 -392.87297) (xy 411.207749 -392.82666) (xy 411.238299 -392.784612)
			(xy 411.27505 -392.747861) (xy 411.317098 -392.717311) (xy 411.363408 -392.693715) (xy 411.412838 -392.677654)
			(xy 411.464173 -392.669524) (xy 411.516147 -392.669524) (xy 411.567482 -392.677654) (xy 411.616912 -392.693715)
			(xy 411.663222 -392.717311) (xy 411.70527 -392.747861) (xy 411.742021 -392.784612) (xy 411.772571 -392.82666)
			(xy 411.796167 -392.87297) (xy 411.812228 -392.9224) (xy 411.820358 -392.973735) (xy 411.820868 -392.999722)
			(xy 412.359348 -392.999722) (xy 412.359858 -392.973735) (xy 412.367988 -392.9224) (xy 412.384049 -392.87297)
			(xy 412.407645 -392.82666) (xy 412.438195 -392.784612) (xy 412.474946 -392.747861) (xy 412.516994 -392.717311)
			(xy 412.563304 -392.693715) (xy 412.612734 -392.677654) (xy 412.664069 -392.669524) (xy 412.716043 -392.669524)
			(xy 412.767378 -392.677654) (xy 412.816808 -392.693715) (xy 412.863118 -392.717311) (xy 412.905166 -392.747861)
			(xy 412.941917 -392.784612) (xy 412.972467 -392.82666) (xy 412.996063 -392.87297) (xy 413.012124 -392.9224)
			(xy 413.020254 -392.973735) (xy 413.020764 -392.999722) (xy 413.559498 -392.999722) (xy 413.560008 -392.973735)
			(xy 413.568138 -392.9224) (xy 413.584199 -392.87297) (xy 413.607795 -392.82666) (xy 413.638345 -392.784612)
			(xy 413.675096 -392.747861) (xy 413.717144 -392.717311) (xy 413.763454 -392.693715) (xy 413.812884 -392.677654)
			(xy 413.864219 -392.669524) (xy 413.916193 -392.669524) (xy 413.967528 -392.677654) (xy 414.016958 -392.693715)
			(xy 414.063268 -392.717311) (xy 414.105316 -392.747861) (xy 414.142067 -392.784612) (xy 414.172617 -392.82666)
			(xy 414.196213 -392.87297) (xy 414.212274 -392.9224) (xy 414.220404 -392.973735) (xy 414.220914 -392.999722)
			(xy 414.759394 -392.999722) (xy 414.759904 -392.973735) (xy 414.768034 -392.9224) (xy 414.784095 -392.87297)
			(xy 414.807691 -392.82666) (xy 414.838241 -392.784612) (xy 414.874992 -392.747861) (xy 414.91704 -392.717311)
			(xy 414.96335 -392.693715) (xy 415.01278 -392.677654) (xy 415.064115 -392.669524) (xy 415.116089 -392.669524)
			(xy 415.167424 -392.677654) (xy 415.216854 -392.693715) (xy 415.263164 -392.717311) (xy 415.305212 -392.747861)
			(xy 415.341963 -392.784612) (xy 415.372513 -392.82666) (xy 415.396109 -392.87297) (xy 415.41217 -392.9224)
			(xy 415.4203 -392.973735) (xy 415.42081 -392.999722) (xy 415.95929 -392.999722) (xy 415.9598 -392.973735)
			(xy 415.96793 -392.9224) (xy 415.983991 -392.87297) (xy 416.007587 -392.82666) (xy 416.038137 -392.784612)
			(xy 416.074888 -392.747861) (xy 416.116936 -392.717311) (xy 416.163246 -392.693715) (xy 416.212676 -392.677654)
			(xy 416.264011 -392.669524) (xy 416.315985 -392.669524) (xy 416.36732 -392.677654) (xy 416.41675 -392.693715)
			(xy 416.46306 -392.717311) (xy 416.505108 -392.747861) (xy 416.541859 -392.784612) (xy 416.572409 -392.82666)
			(xy 416.596005 -392.87297) (xy 416.612066 -392.9224) (xy 416.620196 -392.973735) (xy 416.620706 -392.999722)
			(xy 417.15944 -392.999722) (xy 417.15995 -392.973735) (xy 417.16808 -392.9224) (xy 417.184141 -392.87297)
			(xy 417.207737 -392.82666) (xy 417.238287 -392.784612) (xy 417.275038 -392.747861) (xy 417.317086 -392.717311)
			(xy 417.363396 -392.693715) (xy 417.412826 -392.677654) (xy 417.464161 -392.669524) (xy 417.516135 -392.669524)
			(xy 417.56747 -392.677654) (xy 417.6169 -392.693715) (xy 417.66321 -392.717311) (xy 417.705258 -392.747861)
			(xy 417.742009 -392.784612) (xy 417.772559 -392.82666) (xy 417.796155 -392.87297) (xy 417.812216 -392.9224)
			(xy 417.820346 -392.973735) (xy 417.820856 -392.999722) (xy 418.359336 -392.999722) (xy 418.359846 -392.973735)
			(xy 418.367976 -392.9224) (xy 418.384037 -392.87297) (xy 418.407633 -392.82666) (xy 418.438183 -392.784612)
			(xy 418.474934 -392.747861) (xy 418.516982 -392.717311) (xy 418.563292 -392.693715) (xy 418.612722 -392.677654)
			(xy 418.664057 -392.669524) (xy 418.716031 -392.669524) (xy 418.767366 -392.677654) (xy 418.816796 -392.693715)
			(xy 418.863106 -392.717311) (xy 418.905154 -392.747861) (xy 418.941905 -392.784612) (xy 418.972455 -392.82666)
			(xy 418.996051 -392.87297) (xy 419.012112 -392.9224) (xy 419.020242 -392.973735) (xy 419.020752 -392.999722)
			(xy 419.559486 -392.999722) (xy 419.559996 -392.973735) (xy 419.568126 -392.9224) (xy 419.584187 -392.87297)
			(xy 419.607783 -392.82666) (xy 419.638333 -392.784612) (xy 419.675084 -392.747861) (xy 419.717132 -392.717311)
			(xy 419.763442 -392.693715) (xy 419.812872 -392.677654) (xy 419.864207 -392.669524) (xy 419.916181 -392.669524)
			(xy 419.967516 -392.677654) (xy 420.016946 -392.693715) (xy 420.063256 -392.717311) (xy 420.105304 -392.747861)
			(xy 420.142055 -392.784612) (xy 420.172605 -392.82666) (xy 420.196201 -392.87297) (xy 420.212262 -392.9224)
			(xy 420.220392 -392.973735) (xy 420.220902 -392.999722) (xy 420.759382 -392.999722) (xy 420.759892 -392.973735)
			(xy 420.768022 -392.9224) (xy 420.784083 -392.87297) (xy 420.807679 -392.82666) (xy 420.838229 -392.784612)
			(xy 420.87498 -392.747861) (xy 420.917028 -392.717311) (xy 420.963338 -392.693715) (xy 421.012768 -392.677654)
			(xy 421.064103 -392.669524) (xy 421.116077 -392.669524) (xy 421.167412 -392.677654) (xy 421.216842 -392.693715)
			(xy 421.263152 -392.717311) (xy 421.3052 -392.747861) (xy 421.341951 -392.784612) (xy 421.372501 -392.82666)
			(xy 421.396097 -392.87297) (xy 421.412158 -392.9224) (xy 421.420288 -392.973735) (xy 421.420798 -392.999722)
			(xy 421.420266 -393.026824) (xy 421.411457 -393.080306) (xy 421.403272 -393.106148) (xy 421.399462 -393.11707)
			(xy 421.402002 -393.139422) (xy 421.45458 -393.225274) (xy 421.47363 -393.23772) (xy 421.484806 -393.239498)
			(xy 421.514121 -393.244225) (xy 421.571291 -393.26027) (xy 421.625905 -393.283577) (xy 421.677045 -393.313754)
			(xy 421.723851 -393.350293) (xy 421.765537 -393.39258) (xy 421.801402 -393.439905) (xy 421.830842 -393.491472)
			(xy 421.847186 -393.531344) (xy 422.930066 -393.531344) (xy 422.930502 -393.502709) (xy 422.937657 -393.445887)
			(xy 422.951838 -393.3904) (xy 422.972822 -393.337112) (xy 423.000283 -393.286854) (xy 423.01668 -393.263374)
			(xy 423.022354 -393.254856) (xy 423.02696 -393.23493) (xy 423.023396 -393.214792) (xy 423.018204 -393.20597)
			(xy 423.000721 -393.17799) (xy 422.97309 -393.118078) (xy 422.954343 -393.054822) (xy 422.944869 -392.98953)
			(xy 422.94429 -392.956542) (xy 422.9448 -392.926574) (xy 422.952619 -392.86715) (xy 422.968127 -392.809255)
			(xy 422.991059 -392.75388) (xy 423.021024 -392.701972) (xy 423.057508 -392.65442) (xy 423.099887 -392.612037)
			(xy 423.147436 -392.575548) (xy 423.199341 -392.545579) (xy 423.254714 -392.522641) (xy 423.312607 -392.507127)
			(xy 423.37203 -392.499303) (xy 423.401998 -392.498834) (xy 423.43181 -392.499299) (xy 423.490929 -392.507036)
			(xy 423.548544 -392.52238) (xy 423.603681 -392.545071) (xy 423.655407 -392.574725) (xy 423.702847 -392.610842)
			(xy 423.745199 -392.652809) (xy 423.781746 -392.699917) (xy 423.797222 -392.725402) (xy 423.804334 -392.737848)
			(xy 423.82948 -392.75131) (xy 423.948352 -392.744706) (xy 423.971974 -392.72845) (xy 423.977562 -392.715242)
			(xy 423.99122 -392.685623) (xy 424.025068 -392.629869) (xy 424.065764 -392.578897) (xy 424.112641 -392.533545)
			(xy 424.16493 -392.494556) (xy 424.221773 -392.462569) (xy 424.282238 -392.43811) (xy 424.345333 -392.421579)
			(xy 424.410024 -392.413247) (xy 424.442636 -392.412728) (xy 424.473369 -392.413122) (xy 424.534387 -392.420535)
			(xy 424.594066 -392.435249) (xy 424.651537 -392.45705) (xy 424.693394 -392.479022) (xy 430.282348 -392.479022)
			(xy 430.286419 -392.4234) (xy 430.298545 -392.368963) (xy 430.318468 -392.316872) (xy 430.345764 -392.268237)
			(xy 430.37985 -392.224094) (xy 430.419999 -392.185385) (xy 430.465357 -392.152934) (xy 430.514957 -392.127433)
			(xy 430.567741 -392.109426) (xy 430.622584 -392.099296) (xy 430.678318 -392.097259) (xy 430.733755 -392.103359)
			(xy 430.787712 -392.117465) (xy 430.839041 -392.139277) (xy 430.886647 -392.168331) (xy 430.929515 -392.204006)
			(xy 430.966732 -392.245543) (xy 430.997505 -392.292056) (xy 431.021177 -392.342553) (xy 431.037245 -392.39596)
			(xy 431.045365 -392.451136) (xy 431.045874 -392.479022) (xy 431.045365 -392.506908) (xy 431.037245 -392.562084)
			(xy 431.021177 -392.615491) (xy 430.997505 -392.665988) (xy 430.966732 -392.712501) (xy 430.929515 -392.754038)
			(xy 430.886647 -392.789713) (xy 430.839041 -392.818767) (xy 430.787712 -392.840579) (xy 430.733755 -392.854685)
			(xy 430.678318 -392.860785) (xy 430.622584 -392.858748) (xy 430.567741 -392.848618) (xy 430.514957 -392.830611)
			(xy 430.465357 -392.80511) (xy 430.419999 -392.772659) (xy 430.37985 -392.73395) (xy 430.345764 -392.689807)
			(xy 430.318468 -392.641172) (xy 430.298545 -392.589081) (xy 430.286419 -392.534644) (xy 430.282348 -392.479022)
			(xy 424.693394 -392.479022) (xy 424.70596 -392.485618) (xy 424.756544 -392.520539) (xy 424.802549 -392.561302)
			(xy 424.843306 -392.607313) (xy 424.878219 -392.657901) (xy 424.90678 -392.712329) (xy 424.928572 -392.769803)
			(xy 424.943278 -392.829484) (xy 424.950683 -392.890503) (xy 424.951144 -392.921236) (xy 424.950552 -392.956294)
			(xy 424.940904 -393.025744) (xy 424.92181 -393.093212) (xy 424.893633 -393.157418) (xy 424.856904 -393.217146)
			(xy 424.835066 -393.244578) (xy 424.828055 -393.25399) (xy 424.822746 -393.276828) (xy 424.82808 -393.299661)
			(xy 424.835066 -393.309094) (xy 424.856907 -393.336526) (xy 424.893649 -393.396247) (xy 424.921833 -393.460452)
			(xy 424.940924 -393.527923) (xy 424.950558 -393.597377) (xy 424.951144 -393.632436) (xy 424.950662 -393.663132)
			(xy 424.943261 -393.724076) (xy 424.92857 -393.783685) (xy 424.906804 -393.841089) (xy 424.87828 -393.895452)
			(xy 424.861228 -393.92098) (xy 424.855723 -393.929714) (xy 424.851602 -393.94993) (xy 424.855746 -393.970141)
			(xy 424.861228 -393.978892) (xy 424.878249 -394.004439) (xy 424.906762 -394.058804) (xy 424.928529 -394.116204)
			(xy 424.943233 -394.175805) (xy 424.950661 -394.236742) (xy 424.951144 -394.267436) (xy 424.950662 -394.298132)
			(xy 424.943261 -394.359076) (xy 424.935047 -394.392404) (xy 426.988476 -394.392404) (xy 426.992547 -394.336782)
			(xy 427.004673 -394.282345) (xy 427.024596 -394.230254) (xy 427.051892 -394.181619) (xy 427.085978 -394.137476)
			(xy 427.126127 -394.098767) (xy 427.171485 -394.066316) (xy 427.221085 -394.040815) (xy 427.273869 -394.022808)
			(xy 427.328712 -394.012678) (xy 427.384446 -394.010641) (xy 427.439883 -394.016741) (xy 427.49384 -394.030847)
			(xy 427.545169 -394.052659) (xy 427.592775 -394.081713) (xy 427.635643 -394.117388) (xy 427.67286 -394.158925)
			(xy 427.703633 -394.205438) (xy 427.727305 -394.255935) (xy 427.743373 -394.309342) (xy 427.751493 -394.364518)
			(xy 427.752002 -394.392404) (xy 427.751493 -394.42029) (xy 427.743373 -394.475466) (xy 427.727305 -394.528873)
			(xy 427.724838 -394.534136) (xy 428.518318 -394.534136) (xy 428.522389 -394.478514) (xy 428.534515 -394.424077)
			(xy 428.554438 -394.371986) (xy 428.581734 -394.323351) (xy 428.61582 -394.279208) (xy 428.655969 -394.240499)
			(xy 428.701327 -394.208048) (xy 428.750927 -394.182547) (xy 428.803711 -394.16454) (xy 428.858554 -394.15441)
			(xy 428.914288 -394.152373) (xy 428.969725 -394.158473) (xy 429.023682 -394.172579) (xy 429.075011 -394.194391)
			(xy 429.122617 -394.223445) (xy 429.165485 -394.25912) (xy 429.202702 -394.300657) (xy 429.233475 -394.34717)
			(xy 429.257147 -394.397667) (xy 429.273215 -394.451074) (xy 429.281335 -394.50625) (xy 429.281844 -394.534136)
			(xy 429.281335 -394.562022) (xy 429.273215 -394.617198) (xy 429.257147 -394.670605) (xy 429.233475 -394.721102)
			(xy 429.202702 -394.767615) (xy 429.165485 -394.809152) (xy 429.122617 -394.844827) (xy 429.075011 -394.873881)
			(xy 429.023682 -394.895693) (xy 428.969725 -394.909799) (xy 428.914288 -394.915899) (xy 428.858554 -394.913862)
			(xy 428.803711 -394.903732) (xy 428.750927 -394.885725) (xy 428.701327 -394.860224) (xy 428.655969 -394.827773)
			(xy 428.61582 -394.789064) (xy 428.581734 -394.744921) (xy 428.554438 -394.696286) (xy 428.534515 -394.644195)
			(xy 428.522389 -394.589758) (xy 428.518318 -394.534136) (xy 427.724838 -394.534136) (xy 427.703633 -394.57937)
			(xy 427.67286 -394.625883) (xy 427.635643 -394.66742) (xy 427.592775 -394.703095) (xy 427.545169 -394.732149)
			(xy 427.49384 -394.753961) (xy 427.439883 -394.768067) (xy 427.384446 -394.774167) (xy 427.328712 -394.77213)
			(xy 427.273869 -394.762) (xy 427.221085 -394.743993) (xy 427.171485 -394.718492) (xy 427.126127 -394.686041)
			(xy 427.085978 -394.647332) (xy 427.051892 -394.603189) (xy 427.024596 -394.554554) (xy 427.004673 -394.502463)
			(xy 426.992547 -394.448026) (xy 426.988476 -394.392404) (xy 424.935047 -394.392404) (xy 424.92857 -394.418685)
			(xy 424.906804 -394.476089) (xy 424.87828 -394.530452) (xy 424.861228 -394.55598) (xy 424.855723 -394.564714)
			(xy 424.851602 -394.58493) (xy 424.855746 -394.605141) (xy 424.861228 -394.613892) (xy 424.878249 -394.639439)
			(xy 424.906762 -394.693804) (xy 424.928529 -394.751204) (xy 424.943233 -394.810805) (xy 424.950661 -394.871742)
			(xy 424.951144 -394.902436) (xy 424.950662 -394.933132) (xy 424.943261 -394.994076) (xy 424.92857 -395.053685)
			(xy 424.906804 -395.111089) (xy 424.888875 -395.14526) (xy 426.479714 -395.14526) (xy 426.483785 -395.089638)
			(xy 426.495911 -395.035201) (xy 426.515834 -394.98311) (xy 426.54313 -394.934475) (xy 426.577216 -394.890332)
			(xy 426.617365 -394.851623) (xy 426.662723 -394.819172) (xy 426.712323 -394.793671) (xy 426.765107 -394.775664)
			(xy 426.81995 -394.765534) (xy 426.875684 -394.763497) (xy 426.931121 -394.769597) (xy 426.985078 -394.783703)
			(xy 427.036407 -394.805515) (xy 427.084013 -394.834569) (xy 427.126881 -394.870244) (xy 427.164098 -394.911781)
			(xy 427.194871 -394.958294) (xy 427.218543 -395.008791) (xy 427.228804 -395.042898) (xy 429.271174 -395.042898)
			(xy 429.275245 -394.987276) (xy 429.287371 -394.932839) (xy 429.307294 -394.880748) (xy 429.33459 -394.832113)
			(xy 429.368676 -394.78797) (xy 429.408825 -394.749261) (xy 429.454183 -394.71681) (xy 429.503783 -394.691309)
			(xy 429.556567 -394.673302) (xy 429.61141 -394.663172) (xy 429.667144 -394.661135) (xy 429.722581 -394.667235)
			(xy 429.776538 -394.681341) (xy 429.827867 -394.703153) (xy 429.875473 -394.732207) (xy 429.918341 -394.767882)
			(xy 429.955558 -394.809419) (xy 429.986331 -394.855932) (xy 430.010003 -394.906429) (xy 430.026071 -394.959836)
			(xy 430.034191 -395.015012) (xy 430.0347 -395.042898) (xy 430.034191 -395.070784) (xy 430.026071 -395.12596)
			(xy 430.010003 -395.179367) (xy 429.986331 -395.229864) (xy 429.955558 -395.276377) (xy 429.918341 -395.317914)
			(xy 429.875473 -395.353589) (xy 429.827867 -395.382643) (xy 429.776538 -395.404455) (xy 429.722581 -395.418561)
			(xy 429.667144 -395.424661) (xy 429.61141 -395.422624) (xy 429.556567 -395.412494) (xy 429.503783 -395.394487)
			(xy 429.454183 -395.368986) (xy 429.408825 -395.336535) (xy 429.368676 -395.297826) (xy 429.33459 -395.253683)
			(xy 429.307294 -395.205048) (xy 429.287371 -395.152957) (xy 429.275245 -395.09852) (xy 429.271174 -395.042898)
			(xy 427.228804 -395.042898) (xy 427.234611 -395.062198) (xy 427.242731 -395.117374) (xy 427.24324 -395.14526)
			(xy 427.242731 -395.173146) (xy 427.234611 -395.228322) (xy 427.218543 -395.281729) (xy 427.194871 -395.332226)
			(xy 427.164098 -395.378739) (xy 427.126881 -395.420276) (xy 427.084013 -395.455951) (xy 427.036407 -395.485005)
			(xy 426.985078 -395.506817) (xy 426.931121 -395.520923) (xy 426.875684 -395.527023) (xy 426.81995 -395.524986)
			(xy 426.765107 -395.514856) (xy 426.712323 -395.496849) (xy 426.662723 -395.471348) (xy 426.617365 -395.438897)
			(xy 426.577216 -395.400188) (xy 426.54313 -395.356045) (xy 426.515834 -395.30741) (xy 426.495911 -395.255319)
			(xy 426.483785 -395.200882) (xy 426.479714 -395.14526) (xy 424.888875 -395.14526) (xy 424.87828 -395.165452)
			(xy 424.861228 -395.19098) (xy 424.855723 -395.199714) (xy 424.851602 -395.21993) (xy 424.855746 -395.240141)
			(xy 424.861228 -395.248892) (xy 424.878249 -395.274439) (xy 424.906762 -395.328804) (xy 424.928529 -395.386204)
			(xy 424.943233 -395.445805) (xy 424.950661 -395.506742) (xy 424.951144 -395.537436) (xy 424.950725 -395.567177)
			(xy 424.943778 -395.626253) (xy 424.929985 -395.684114) (xy 424.920156 -395.712188) (xy 424.91533 -395.725142)
			(xy 424.920156 -395.751558) (xy 424.994324 -395.840458) (xy 425.01947 -395.849602) (xy 425.033186 -395.847062)
			(xy 425.055042 -395.843463) (xy 425.099175 -395.839651) (xy 425.121324 -395.839442) (xy 425.152054 -395.839933)
			(xy 425.213064 -395.847344) (xy 425.272737 -395.862053) (xy 425.330202 -395.883848) (xy 425.384622 -395.912409)
			(xy 425.435202 -395.947322) (xy 425.481206 -395.988076) (xy 425.521962 -396.034078) (xy 425.556877 -396.084656)
			(xy 425.585441 -396.139074) (xy 425.607239 -396.196538) (xy 425.621952 -396.25621) (xy 425.629365 -396.31722)
			(xy 425.629832 -396.34795) (xy 425.629274 -396.381899) (xy 425.620244 -396.449194) (xy 425.602337 -396.514688)
			(xy 425.575873 -396.577216) (xy 425.541321 -396.635665) (xy 425.499298 -396.688996) (xy 425.450551 -396.736259)
			(xy 425.423584 -396.75689) (xy 425.414948 -396.76324) (xy 425.404788 -396.78102) (xy 425.393358 -396.875762)
			(xy 425.3992 -396.89532) (xy 425.406058 -396.903702) (xy 425.422695 -396.924376) (xy 425.450719 -396.96944)
			(xy 425.472236 -397.017948) (xy 425.486832 -397.068968) (xy 425.494225 -397.121517) (xy 425.494479 -397.135604)
			(xy 426.361098 -397.135604) (xy 426.361527 -397.105494) (xy 426.368659 -397.045698) (xy 426.382802 -396.987162)
			(xy 426.403757 -396.930706) (xy 426.43123 -396.877118) (xy 426.464838 -396.827148) (xy 426.50411 -396.781496)
			(xy 426.548498 -396.7408) (xy 426.57268 -396.722854) (xy 426.582142 -396.715225) (xy 426.593147 -396.693592)
			(xy 426.593762 -396.681452) (xy 426.593762 -396.599156) (xy 426.593089 -396.58703) (xy 426.582099 -396.565417)
			(xy 426.57268 -396.557754) (xy 426.548466 -396.539849) (xy 426.504066 -396.499158) (xy 426.464787 -396.453505)
			(xy 426.431177 -396.40353) (xy 426.403708 -396.349934) (xy 426.382766 -396.293467) (xy 426.368643 -396.234921)
			(xy 426.361537 -396.175117) (xy 426.361098 -396.145004) (xy 426.3616 -396.113043) (xy 426.369611 -396.049625)
			(xy 426.385508 -395.987711) (xy 426.40904 -395.928278) (xy 426.439834 -395.872263) (xy 426.477407 -395.820548)
			(xy 426.521164 -395.773951) (xy 426.570417 -395.733206) (xy 426.624388 -395.698955) (xy 426.682227 -395.671738)
			(xy 426.74302 -395.651985) (xy 426.80581 -395.640007) (xy 426.869606 -395.635994) (xy 426.933402 -395.640007)
			(xy 426.996192 -395.651985) (xy 427.056985 -395.671738) (xy 427.114824 -395.698955) (xy 427.168795 -395.733206)
			(xy 427.218048 -395.773951) (xy 427.261805 -395.820548) (xy 427.299378 -395.872263) (xy 427.330172 -395.928278)
			(xy 427.353704 -395.987711) (xy 427.369601 -396.049625) (xy 427.377612 -396.113043) (xy 427.377715 -396.119604)
			(xy 429.189386 -396.119604) (xy 429.193457 -396.063982) (xy 429.205583 -396.009545) (xy 429.225506 -395.957454)
			(xy 429.252802 -395.908819) (xy 429.286888 -395.864676) (xy 429.327037 -395.825967) (xy 429.372395 -395.793516)
			(xy 429.421995 -395.768015) (xy 429.474779 -395.750008) (xy 429.529622 -395.739878) (xy 429.585356 -395.737841)
			(xy 429.640793 -395.743941) (xy 429.69475 -395.758047) (xy 429.746079 -395.779859) (xy 429.793685 -395.808913)
			(xy 429.836553 -395.844588) (xy 429.87377 -395.886125) (xy 429.904543 -395.932638) (xy 429.928215 -395.983135)
			(xy 429.944283 -396.036542) (xy 429.952403 -396.091718) (xy 429.952912 -396.119604) (xy 429.952403 -396.14749)
			(xy 429.944283 -396.202666) (xy 429.928215 -396.256073) (xy 429.904543 -396.30657) (xy 429.87377 -396.353083)
			(xy 429.836553 -396.39462) (xy 429.793685 -396.430295) (xy 429.746079 -396.459349) (xy 429.69475 -396.481161)
			(xy 429.640793 -396.495267) (xy 429.585356 -396.501367) (xy 429.529622 -396.49933) (xy 429.474779 -396.4892)
			(xy 429.421995 -396.471193) (xy 429.372395 -396.445692) (xy 429.327037 -396.413241) (xy 429.286888 -396.374532)
			(xy 429.252802 -396.330389) (xy 429.225506 -396.281754) (xy 429.205583 -396.229663) (xy 429.193457 -396.175226)
			(xy 429.189386 -396.119604) (xy 427.377715 -396.119604) (xy 427.378114 -396.145004) (xy 427.377686 -396.175114)
			(xy 427.370553 -396.23491) (xy 427.35641 -396.293445) (xy 427.335455 -396.349902) (xy 427.307981 -396.40349)
			(xy 427.274373 -396.453459) (xy 427.235101 -396.499112) (xy 427.190714 -396.539808) (xy 427.166532 -396.557754)
			(xy 427.157097 -396.56541) (xy 427.146082 -396.587023) (xy 427.14545 -396.599156) (xy 427.14545 -396.681452)
			(xy 427.146114 -396.693579) (xy 427.15711 -396.715193) (xy 427.166532 -396.722854) (xy 427.190753 -396.740751)
			(xy 427.235152 -396.781443) (xy 427.274431 -396.827098) (xy 427.308039 -396.877074) (xy 427.335507 -396.930671)
			(xy 427.356448 -396.987139) (xy 427.370571 -397.045686) (xy 427.377675 -397.105491) (xy 427.378114 -397.135604)
			(xy 429.189386 -397.135604) (xy 429.193457 -397.079982) (xy 429.205583 -397.025545) (xy 429.225506 -396.973454)
			(xy 429.252802 -396.924819) (xy 429.286888 -396.880676) (xy 429.327037 -396.841967) (xy 429.372395 -396.809516)
			(xy 429.421995 -396.784015) (xy 429.474779 -396.766008) (xy 429.529622 -396.755878) (xy 429.585356 -396.753841)
			(xy 429.640793 -396.759941) (xy 429.69475 -396.774047) (xy 429.746079 -396.795859) (xy 429.793685 -396.824913)
			(xy 429.836553 -396.860588) (xy 429.87377 -396.902125) (xy 429.904543 -396.948638) (xy 429.928215 -396.999135)
			(xy 429.944283 -397.052542) (xy 429.952403 -397.107718) (xy 429.952912 -397.135604) (xy 429.952403 -397.16349)
			(xy 429.944283 -397.218666) (xy 429.928215 -397.272073) (xy 429.904543 -397.32257) (xy 429.87377 -397.369083)
			(xy 429.836553 -397.41062) (xy 429.793685 -397.446295) (xy 429.746079 -397.475349) (xy 429.69475 -397.497161)
			(xy 429.640793 -397.511267) (xy 429.585356 -397.517367) (xy 429.529622 -397.51533) (xy 429.474779 -397.5052)
			(xy 429.421995 -397.487193) (xy 429.372395 -397.461692) (xy 429.327037 -397.429241) (xy 429.286888 -397.390532)
			(xy 429.252802 -397.346389) (xy 429.225506 -397.297754) (xy 429.205583 -397.245663) (xy 429.193457 -397.191226)
			(xy 429.189386 -397.135604) (xy 427.378114 -397.135604) (xy 427.377612 -397.167565) (xy 427.369601 -397.230983)
			(xy 427.353704 -397.292897) (xy 427.330172 -397.35233) (xy 427.299378 -397.408345) (xy 427.261805 -397.46006)
			(xy 427.218048 -397.506657) (xy 427.168795 -397.547402) (xy 427.114824 -397.581653) (xy 427.056985 -397.60887)
			(xy 426.996192 -397.628623) (xy 426.933402 -397.640601) (xy 426.869606 -397.644615) (xy 426.80581 -397.640601)
			(xy 426.74302 -397.628623) (xy 426.682227 -397.60887) (xy 426.624388 -397.581653) (xy 426.570417 -397.547402)
			(xy 426.521164 -397.506657) (xy 426.477407 -397.46006) (xy 426.439834 -397.408345) (xy 426.40904 -397.35233)
			(xy 426.385508 -397.292897) (xy 426.369611 -397.230983) (xy 426.3616 -397.167565) (xy 426.361098 -397.135604)
			(xy 425.494479 -397.135604) (xy 425.494704 -397.14805) (xy 425.494218 -397.175301) (xy 425.486462 -397.229249)
			(xy 425.471107 -397.281544) (xy 425.448465 -397.331121) (xy 425.418999 -397.376971) (xy 425.383308 -397.418162)
			(xy 425.342117 -397.453853) (xy 425.296267 -397.483319) (xy 425.24669 -397.505961) (xy 425.194395 -397.521316)
			(xy 425.140447 -397.529072) (xy 425.085945 -397.529072) (xy 425.031997 -397.521316) (xy 424.979702 -397.505961)
			(xy 424.930125 -397.483319) (xy 424.884275 -397.453853) (xy 424.843084 -397.418162) (xy 424.807393 -397.376971)
			(xy 424.777927 -397.331121) (xy 424.755285 -397.281544) (xy 424.73993 -397.229249) (xy 424.732174 -397.175301)
			(xy 424.731688 -397.14805) (xy 424.732163 -397.120716) (xy 424.739971 -397.06661) (xy 424.755419 -397.014171)
			(xy 424.778193 -396.964473) (xy 424.807825 -396.918534) (xy 424.825414 -396.897606) (xy 424.832272 -396.889478)
			(xy 424.838622 -396.86992) (xy 424.829224 -396.775178) (xy 424.819318 -396.757144) (xy 424.810682 -396.75054)
			(xy 424.784708 -396.72986) (xy 424.73787 -396.682802) (xy 424.697555 -396.630048) (xy 424.664449 -396.572496)
			(xy 424.639116 -396.511125) (xy 424.621986 -396.446978) (xy 424.613351 -396.381147) (xy 424.612816 -396.34795)
			(xy 424.613228 -396.318208) (xy 424.620176 -396.259132) (xy 424.633973 -396.201271) (xy 424.643804 -396.173198)
			(xy 424.64863 -396.160244) (xy 424.643804 -396.133828) (xy 424.569636 -396.044928) (xy 424.54449 -396.035784)
			(xy 424.530774 -396.038324) (xy 424.508917 -396.041915) (xy 424.464785 -396.045733) (xy 424.442636 -396.045944)
			(xy 424.411907 -396.04541) (xy 424.350897 -396.038007) (xy 424.291224 -396.023303) (xy 424.233759 -396.001514)
			(xy 424.179339 -395.972957) (xy 424.128758 -395.938049) (xy 424.082753 -395.897298) (xy 424.041996 -395.851299)
			(xy 424.00708 -395.800723) (xy 423.978516 -395.746307) (xy 423.956718 -395.688845) (xy 423.942006 -395.629174)
			(xy 423.934594 -395.568165) (xy 423.934128 -395.537436) (xy 423.934583 -395.506739) (xy 423.941989 -395.445793)
			(xy 423.956685 -395.386184) (xy 423.978457 -395.328781) (xy 424.006988 -395.274419) (xy 424.024044 -395.248892)
			(xy 424.029482 -395.240122) (xy 424.033617 -395.21993) (xy 424.029505 -395.199733) (xy 424.024044 -395.19098)
			(xy 424.014808 -395.177372) (xy 423.997905 -395.149155) (xy 423.990262 -395.134592) (xy 423.985161 -395.125598)
			(xy 423.969316 -395.112346) (xy 423.949522 -395.106442) (xy 423.939208 -395.10716) (xy 423.924969 -395.108685)
			(xy 423.896378 -395.110339) (xy 423.882058 -395.110462) (xy 423.851323 -395.110102) (xy 423.790302 -395.102687)
			(xy 423.73062 -395.087972) (xy 423.673147 -395.066169) (xy 423.618721 -395.037598) (xy 423.568135 -395.002675)
			(xy 423.522128 -394.96191) (xy 423.48137 -394.915895) (xy 423.446456 -394.865304) (xy 423.417894 -394.810873)
			(xy 423.396102 -394.753396) (xy 423.381397 -394.693711) (xy 423.373993 -394.632689) (xy 423.37355 -394.601954)
			(xy 423.373986 -394.571416) (xy 423.381297 -394.510779) (xy 423.395821 -394.451455) (xy 423.417349 -394.394298)
			(xy 423.44557 -394.340133) (xy 423.46245 -394.31468) (xy 423.468241 -394.305288) (xy 423.47199 -394.283571)
			(xy 423.466288 -394.262283) (xy 423.459656 -394.253466) (xy 423.439433 -394.228369) (xy 423.404793 -394.174015)
			(xy 423.377308 -394.115716) (xy 423.35742 -394.054407) (xy 423.350944 -394.022834) (xy 423.348583 -394.012827)
			(xy 423.337102 -393.995789) (xy 423.319842 -393.984644) (xy 423.309796 -393.982448) (xy 423.28116 -393.977081)
			(xy 423.225478 -393.959928) (xy 423.172421 -393.935851) (xy 423.122847 -393.905238) (xy 423.077557 -393.868584)
			(xy 423.037282 -393.826482) (xy 423.002673 -393.779611) (xy 422.974288 -393.728729) (xy 422.952587 -393.674657)
			(xy 422.93792 -393.618269) (xy 422.930524 -393.560476) (xy 422.930066 -393.531344) (xy 421.847186 -393.531344)
			(xy 421.853364 -393.546414) (xy 421.868589 -393.603809) (xy 421.876261 -393.66269) (xy 421.876728 -393.69238)
			(xy 421.876202 -393.723443) (xy 421.867789 -393.784996) (xy 421.859964 -393.815062) (xy 421.85717 -393.825222)
			(xy 421.85971 -393.845034) (xy 421.907208 -393.92733) (xy 421.92321 -393.939522) (xy 421.93337 -393.942062)
			(xy 421.962483 -393.95005) (xy 422.018449 -393.972686) (xy 422.070954 -394.002482) (xy 422.119087 -394.038922)
			(xy 422.162013 -394.081372) (xy 422.198986 -394.129096) (xy 422.229366 -394.181265) (xy 422.252624 -394.236976)
			(xy 422.268358 -394.29526) (xy 422.276295 -394.355107) (xy 422.276778 -394.385292) (xy 422.276676 -394.399042)
			(xy 422.275024 -394.426493) (xy 422.273476 -394.440156) (xy 422.272765 -394.448844) (xy 422.276534 -394.465852)
			(xy 422.280842 -394.47343) (xy 422.296844 -394.49883) (xy 422.301631 -394.505853) (xy 422.314862 -394.516502)
			(xy 422.322752 -394.519658) (xy 422.346515 -394.528613) (xy 422.391165 -394.552798) (xy 422.431593 -394.583527)
			(xy 422.466846 -394.620076) (xy 422.496097 -394.661585) (xy 422.518656 -394.707079) (xy 422.533994 -394.755487)
			(xy 422.541749 -394.805672) (xy 422.542208 -394.831062) (xy 422.54169 -394.85705) (xy 422.533564 -394.908388)
			(xy 422.517507 -394.957821) (xy 422.493914 -395.004135) (xy 422.463366 -395.046186) (xy 422.426615 -395.082941)
			(xy 422.384567 -395.113494) (xy 422.338257 -395.137093) (xy 422.288825 -395.153155) (xy 422.237488 -395.161287)
			(xy 422.2115 -395.16177) (xy 422.186591 -395.161319) (xy 422.137335 -395.15386) (xy 422.089755 -395.139097)
			(xy 422.044928 -395.117364) (xy 422.003869 -395.089152) (xy 421.967506 -395.055099) (xy 421.936664 -395.015978)
			(xy 421.912039 -394.972672) (xy 421.894189 -394.926162) (xy 421.888412 -394.901928) (xy 421.886262 -394.893704)
			(xy 421.877443 -394.879184) (xy 421.87114 -394.87348) (xy 421.847772 -394.85443) (xy 421.840897 -394.849204)
			(xy 421.824651 -394.843373) (xy 421.816022 -394.843) (xy 421.786184 -394.842345) (xy 421.72706 -394.83419)
			(xy 421.669498 -394.81842) (xy 421.614473 -394.795302) (xy 421.56292 -394.765228) (xy 421.515713 -394.72871)
			(xy 421.473653 -394.686365) (xy 421.437453 -394.638913) (xy 421.407728 -394.587158) (xy 421.384981 -394.531979)
			(xy 421.369599 -394.474311) (xy 421.361843 -394.415134) (xy 421.361362 -394.385292) (xy 421.361883 -394.354229)
			(xy 421.370299 -394.292675) (xy 421.378126 -394.26261) (xy 421.38092 -394.25245) (xy 421.37838 -394.232638)
			(xy 421.330882 -394.150342) (xy 421.31488 -394.13815) (xy 421.30472 -394.13561) (xy 421.275598 -394.127654)
			(xy 421.21963 -394.105015) (xy 421.167124 -394.075215) (xy 421.118991 -394.038772) (xy 421.076065 -393.996319)
			(xy 421.039093 -393.948591) (xy 421.008715 -393.896417) (xy 420.985458 -393.840704) (xy 420.969727 -393.782416)
			(xy 420.961793 -393.722567) (xy 420.961312 -393.69238) (xy 420.961836 -393.661492) (xy 420.970141 -393.600276)
			(xy 420.986599 -393.540732) (xy 421.010909 -393.483941) (xy 421.026336 -393.457176) (xy 421.032178 -393.44727)
			(xy 421.034464 -393.424918) (xy 421.00119 -393.329668) (xy 420.985442 -393.313666) (xy 420.974774 -393.309602)
			(xy 420.951388 -393.30043) (xy 420.907491 -393.276008) (xy 420.867796 -393.245225) (xy 420.833215 -393.20879)
			(xy 420.804546 -393.167542) (xy 420.78245 -393.12243) (xy 420.767433 -393.074495) (xy 420.759844 -393.024838)
			(xy 420.759382 -392.999722) (xy 420.220902 -392.999722) (xy 420.220369 -393.026824) (xy 420.211561 -393.080306)
			(xy 420.203376 -393.106148) (xy 420.199566 -393.11707) (xy 420.202106 -393.139422) (xy 420.254684 -393.225274)
			(xy 420.273734 -393.23772) (xy 420.28491 -393.239498) (xy 420.314225 -393.244222) (xy 420.371396 -393.260268)
			(xy 420.42601 -393.283575) (xy 420.47715 -393.313752) (xy 420.523956 -393.350291) (xy 420.565641 -393.392579)
			(xy 420.601506 -393.439904) (xy 420.630946 -393.491471) (xy 420.653468 -393.546414) (xy 420.668693 -393.603808)
			(xy 420.676365 -393.66269) (xy 420.676832 -393.69238) (xy 420.67631 -393.723506) (xy 420.667903 -393.785188)
			(xy 420.660068 -393.815316) (xy 420.657274 -393.825476) (xy 420.659814 -393.845542) (xy 420.707058 -393.92733)
			(xy 420.72306 -393.939522) (xy 420.73322 -393.942062) (xy 420.762323 -393.950083) (xy 420.81829 -393.972714)
			(xy 420.870796 -394.002505) (xy 420.91893 -394.038939) (xy 420.961857 -394.081385) (xy 420.998832 -394.129106)
			(xy 421.029213 -394.181273) (xy 421.052473 -394.236981) (xy 421.068207 -394.295263) (xy 421.076144 -394.355108)
			(xy 421.076628 -394.385292) (xy 421.076503 -394.399427) (xy 421.074721 -394.427641) (xy 421.073072 -394.44168)
			(xy 421.072309 -394.450287) (xy 421.07595 -394.467167) (xy 421.080184 -394.4747) (xy 421.095932 -394.5001)
			(xy 421.100628 -394.50717) (xy 421.113743 -394.517934) (xy 421.121586 -394.521182) (xy 421.144958 -394.530389)
			(xy 421.188855 -394.554804) (xy 421.228552 -394.585581) (xy 421.263134 -394.622011) (xy 421.291805 -394.663254)
			(xy 421.313904 -394.708362) (xy 421.328923 -394.756294) (xy 421.336515 -394.805947) (xy 421.336978 -394.831062)
			(xy 421.336556 -394.855264) (xy 421.329482 -394.903149) (xy 421.315495 -394.949489) (xy 421.294894 -394.993291)
			(xy 421.28186 -395.013688) (xy 421.277071 -395.021644) (xy 421.273038 -395.039756) (xy 421.273986 -395.048994)
			(xy 421.278304 -395.079982) (xy 421.279985 -395.089278) (xy 421.289266 -395.10572) (xy 421.296338 -395.111986)
			(xy 421.318421 -395.130674) (xy 421.358194 -395.172684) (xy 421.392357 -395.219371) (xy 421.420365 -395.26999)
			(xy 421.441773 -395.323734) (xy 421.456239 -395.379747) (xy 421.463533 -395.437137) (xy 421.463978 -395.466062)
			(xy 421.463385 -395.499383) (xy 421.453723 -395.565322) (xy 421.434599 -395.629161) (xy 421.421052 -395.65961)
			(xy 421.41678 -395.670068) (xy 421.416893 -395.692636) (xy 421.426642 -395.71299) (xy 421.435022 -395.72057)
			(xy 421.457257 -395.739257) (xy 421.49732 -395.781311) (xy 421.531741 -395.828095) (xy 421.559967 -395.878858)
			(xy 421.581545 -395.932784) (xy 421.596127 -395.989006) (xy 421.603479 -396.046621) (xy 421.603932 -396.075662)
			(xy 421.603462 -396.104667) (xy 421.596151 -396.162215) (xy 421.581629 -396.218378) (xy 421.560127 -396.272256)
			(xy 421.531992 -396.322987) (xy 421.497673 -396.369757) (xy 421.45772 -396.411816) (xy 421.43553 -396.4305)
			(xy 421.428418 -396.436088) (xy 421.419274 -396.451328) (xy 421.404034 -396.534132) (xy 421.406828 -396.551404)
			(xy 421.4114 -396.559532) (xy 421.423972 -396.58272) (xy 421.441848 -396.632341) (xy 421.448672 -396.671292)
			(xy 422.996614 -396.671292) (xy 422.997054 -396.641322) (xy 423.004879 -396.581895) (xy 423.020394 -396.523997)
			(xy 423.043333 -396.46862) (xy 423.073305 -396.416711) (xy 423.109795 -396.369158) (xy 423.152181 -396.326776)
			(xy 423.199736 -396.290288) (xy 423.251647 -396.26032) (xy 423.307026 -396.237384) (xy 423.364924 -396.221873)
			(xy 423.424352 -396.214052) (xy 423.454322 -396.213584) (xy 423.484318 -396.214083) (xy 423.543793 -396.221934)
			(xy 423.601733 -396.237487) (xy 423.657145 -396.260475) (xy 423.70908 -396.290504) (xy 423.756648 -396.327058)
			(xy 423.799034 -396.369513) (xy 423.835511 -396.417141) (xy 423.865455 -396.469125) (xy 423.888352 -396.524574)
			(xy 423.896536 -396.553436) (xy 423.899508 -396.562745) (xy 423.911187 -396.578382) (xy 423.92787 -396.58851)
			(xy 423.93743 -396.59052) (xy 423.966232 -396.595759) (xy 424.022285 -396.612646) (xy 424.075729 -396.63654)
			(xy 424.125691 -396.667051) (xy 424.171358 -396.703681) (xy 424.211983 -396.745833) (xy 424.246904 -396.792818)
			(xy 424.275552 -396.843872) (xy 424.29746 -396.89816) (xy 424.31227 -396.954798) (xy 424.31974 -397.012861)
			(xy 424.320208 -397.042132) (xy 424.319687 -397.073248) (xy 424.311276 -397.134909) (xy 424.294585 -397.194862)
			(xy 424.269924 -397.251999) (xy 424.237746 -397.305267) (xy 424.198647 -397.353682) (xy 424.153346 -397.396352)
			(xy 424.102681 -397.432489) (xy 424.047586 -397.461426) (xy 423.989077 -397.482629) (xy 423.958766 -397.48968)
			(xy 423.94964 -397.491997) (xy 423.933935 -397.502367) (xy 423.923062 -397.517727) (xy 423.920412 -397.526764)
			(xy 423.912514 -397.555642) (xy 423.890196 -397.611196) (xy 423.860829 -397.663367) (xy 423.824912 -397.711267)
			(xy 423.804334 -397.733012) (xy 423.797792 -397.740341) (xy 423.790353 -397.758506) (xy 423.789856 -397.768318)
			(xy 423.789602 -397.82115) (xy 423.79138 -397.822928) (xy 423.799131 -397.829569) (xy 423.818257 -397.836646)
			(xy 423.828464 -397.836644) (xy 423.860214 -397.835374) (xy 423.870416 -397.834481) (xy 423.888898 -397.825707)
			(xy 423.896028 -397.818356) (xy 423.917816 -397.794698) (xy 423.966906 -397.753144) (xy 424.021332 -397.718874)
			(xy 424.080021 -397.692565) (xy 424.141816 -397.674735) (xy 424.2055 -397.665736) (xy 424.237658 -397.665194)
			(xy 424.267629 -397.665656) (xy 424.327059 -397.673475) (xy 424.384959 -397.688985) (xy 424.44034 -397.71192)
			(xy 424.492253 -397.741888) (xy 424.53981 -397.778375) (xy 424.582197 -397.820759) (xy 424.618689 -397.868312)
			(xy 424.648661 -397.920223) (xy 424.671601 -397.975601) (xy 424.687116 -398.0335) (xy 424.694941 -398.092929)
			(xy 424.694941 -398.152871) (xy 424.687116 -398.2123) (xy 424.671601 -398.270199) (xy 424.648661 -398.325577)
			(xy 424.639852 -398.340834) (xy 426.971458 -398.340834) (xy 426.975529 -398.285212) (xy 426.987655 -398.230775)
			(xy 427.007578 -398.178684) (xy 427.034874 -398.130049) (xy 427.06896 -398.085906) (xy 427.109109 -398.047197)
			(xy 427.154467 -398.014746) (xy 427.204067 -397.989245) (xy 427.256851 -397.971238) (xy 427.311694 -397.961108)
			(xy 427.367428 -397.959071) (xy 427.422865 -397.965171) (xy 427.476822 -397.979277) (xy 427.528151 -398.001089)
			(xy 427.575757 -398.030143) (xy 427.618625 -398.065818) (xy 427.655842 -398.107355) (xy 427.686615 -398.153868)
			(xy 427.710287 -398.204365) (xy 427.726355 -398.257772) (xy 427.734475 -398.312948) (xy 427.734984 -398.340834)
			(xy 427.734475 -398.36872) (xy 427.726355 -398.423896) (xy 427.710287 -398.477303) (xy 427.686615 -398.5278)
			(xy 427.655842 -398.574313) (xy 427.618625 -398.61585) (xy 427.575757 -398.651525) (xy 427.528151 -398.680579)
			(xy 427.476822 -398.702391) (xy 427.422865 -398.716497) (xy 427.367428 -398.722597) (xy 427.311694 -398.72056)
			(xy 427.256851 -398.71043) (xy 427.204067 -398.692423) (xy 427.154467 -398.666922) (xy 427.109109 -398.634471)
			(xy 427.06896 -398.595762) (xy 427.034874 -398.551619) (xy 427.007578 -398.502984) (xy 426.987655 -398.450893)
			(xy 426.975529 -398.396456) (xy 426.971458 -398.340834) (xy 424.639852 -398.340834) (xy 424.618689 -398.377488)
			(xy 424.582197 -398.425041) (xy 424.53981 -398.467425) (xy 424.492253 -398.503912) (xy 424.44034 -398.53388)
			(xy 424.384959 -398.556815) (xy 424.327059 -398.572325) (xy 424.267629 -398.580144) (xy 424.237658 -398.58061)
			(xy 424.20923 -398.580196) (xy 424.152806 -398.5732) (xy 424.09768 -398.559282) (xy 424.071034 -398.549368)
			(xy 424.058842 -398.544542) (xy 424.032934 -398.547844) (xy 423.942764 -398.6149) (xy 423.931842 -398.638776)
			(xy 423.932858 -398.651984) (xy 423.934382 -398.68856) (xy 423.933843 -398.720304) (xy 423.925067 -398.783184)
			(xy 423.907692 -398.844249) (xy 423.882051 -398.90233) (xy 423.865802 -398.929606) (xy 423.86147 -398.937166)
			(xy 423.857741 -398.954176) (xy 423.859915 -398.971454) (xy 423.863516 -398.97939) (xy 423.877486 -399.006568)
			(xy 423.881746 -399.014211) (xy 423.894439 -399.026238) (xy 423.910446 -399.033278) (xy 423.919142 -399.034254)
			(xy 423.925492 -399.034762) (xy 423.935838 -399.035195) (xy 423.955479 -399.028699) (xy 423.970951 -399.014965)
			(xy 423.975784 -399.005806) (xy 423.989881 -398.977165) (xy 424.024143 -398.923304) (xy 424.064879 -398.874156)
			(xy 424.111449 -398.830495) (xy 424.163118 -398.793008) (xy 424.219075 -398.762286) (xy 424.278438 -398.738812)
			(xy 424.340273 -398.722956) (xy 424.403606 -398.714966) (xy 424.435524 -398.714468) (xy 424.466255 -398.714933)
			(xy 424.527267 -398.722344) (xy 424.586942 -398.737055) (xy 424.644409 -398.758851) (xy 424.698829 -398.787414)
			(xy 424.749411 -398.822329) (xy 424.795415 -398.863085) (xy 424.836171 -398.909089) (xy 424.871086 -398.959671)
			(xy 424.899649 -399.014091) (xy 424.921445 -399.071558) (xy 424.926901 -399.09369) (xy 426.462696 -399.09369)
			(xy 426.466767 -399.038068) (xy 426.478893 -398.983631) (xy 426.498816 -398.93154) (xy 426.526112 -398.882905)
			(xy 426.560198 -398.838762) (xy 426.600347 -398.800053) (xy 426.645705 -398.767602) (xy 426.695305 -398.742101)
			(xy 426.748089 -398.724094) (xy 426.802932 -398.713964) (xy 426.858666 -398.711927) (xy 426.914103 -398.718027)
			(xy 426.96806 -398.732133) (xy 427.019389 -398.753945) (xy 427.066995 -398.782999) (xy 427.109863 -398.818674)
			(xy 427.14708 -398.860211) (xy 427.177853 -398.906724) (xy 427.201525 -398.957221) (xy 427.217593 -399.010628)
			(xy 427.225713 -399.065804) (xy 427.226222 -399.09369) (xy 427.225713 -399.121576) (xy 427.217593 -399.176752)
			(xy 427.201525 -399.230159) (xy 427.177853 -399.280656) (xy 427.161735 -399.305018) (xy 428.847502 -399.305018)
			(xy 428.851573 -399.249396) (xy 428.863699 -399.194959) (xy 428.883622 -399.142868) (xy 428.910918 -399.094233)
			(xy 428.945004 -399.05009) (xy 428.985153 -399.011381) (xy 429.030511 -398.97893) (xy 429.080111 -398.953429)
			(xy 429.132895 -398.935422) (xy 429.187738 -398.925292) (xy 429.243472 -398.923255) (xy 429.298909 -398.929355)
			(xy 429.352866 -398.943461) (xy 429.404195 -398.965273) (xy 429.451801 -398.994327) (xy 429.494669 -399.030002)
			(xy 429.531886 -399.071539) (xy 429.562659 -399.118052) (xy 429.586331 -399.168549) (xy 429.602399 -399.221956)
			(xy 429.610519 -399.277132) (xy 429.611028 -399.305018) (xy 429.610519 -399.332904) (xy 429.602399 -399.38808)
			(xy 429.586331 -399.441487) (xy 429.562659 -399.491984) (xy 429.531886 -399.538497) (xy 429.494669 -399.580034)
			(xy 429.451801 -399.615709) (xy 429.404195 -399.644763) (xy 429.352866 -399.666575) (xy 429.298909 -399.680681)
			(xy 429.243472 -399.686781) (xy 429.187738 -399.684744) (xy 429.132895 -399.674614) (xy 429.080111 -399.656607)
			(xy 429.030511 -399.631106) (xy 428.985153 -399.598655) (xy 428.945004 -399.559946) (xy 428.910918 -399.515803)
			(xy 428.883622 -399.467168) (xy 428.863699 -399.415077) (xy 428.851573 -399.36064) (xy 428.847502 -399.305018)
			(xy 427.161735 -399.305018) (xy 427.14708 -399.327169) (xy 427.109863 -399.368706) (xy 427.066995 -399.404381)
			(xy 427.019389 -399.433435) (xy 426.96806 -399.455247) (xy 426.914103 -399.469353) (xy 426.858666 -399.475453)
			(xy 426.802932 -399.473416) (xy 426.748089 -399.463286) (xy 426.695305 -399.445279) (xy 426.645705 -399.419778)
			(xy 426.600347 -399.387327) (xy 426.560198 -399.348618) (xy 426.526112 -399.304475) (xy 426.498816 -399.25584)
			(xy 426.478893 -399.203749) (xy 426.466767 -399.149312) (xy 426.462696 -399.09369) (xy 424.926901 -399.09369)
			(xy 424.936156 -399.131233) (xy 424.943567 -399.192245) (xy 424.944032 -399.222976) (xy 424.943573 -399.253673)
			(xy 424.936166 -399.314618) (xy 424.92147 -399.374227) (xy 424.8997 -399.43163) (xy 424.871171 -399.485993)
			(xy 424.854116 -399.51152) (xy 424.848663 -399.520282) (xy 424.844526 -399.54048) (xy 424.848647 -399.560681)
			(xy 424.854116 -399.569432) (xy 424.871153 -399.594969) (xy 424.899664 -399.649336) (xy 424.921428 -399.706739)
			(xy 424.936128 -399.766342) (xy 424.943552 -399.827281) (xy 424.944032 -399.857976) (xy 424.943573 -399.888673)
			(xy 424.936166 -399.949618) (xy 424.92147 -400.009227) (xy 424.8997 -400.06663) (xy 424.891765 -400.08175)
			(xy 426.971458 -400.08175) (xy 426.975529 -400.026128) (xy 426.987655 -399.971691) (xy 427.007578 -399.9196)
			(xy 427.034874 -399.870965) (xy 427.06896 -399.826822) (xy 427.109109 -399.788113) (xy 427.154467 -399.755662)
			(xy 427.204067 -399.730161) (xy 427.256851 -399.712154) (xy 427.311694 -399.702024) (xy 427.367428 -399.699987)
			(xy 427.422865 -399.706087) (xy 427.476822 -399.720193) (xy 427.528151 -399.742005) (xy 427.575757 -399.771059)
			(xy 427.618625 -399.806734) (xy 427.655842 -399.848271) (xy 427.686615 -399.894784) (xy 427.710287 -399.945281)
			(xy 427.726355 -399.998688) (xy 427.734475 -400.053864) (xy 427.734984 -400.08175) (xy 427.734475 -400.109636)
			(xy 427.726355 -400.164812) (xy 427.710287 -400.218219) (xy 427.686615 -400.268716) (xy 427.655842 -400.315229)
			(xy 427.618625 -400.356766) (xy 427.575757 -400.392441) (xy 427.528151 -400.421495) (xy 427.476822 -400.443307)
			(xy 427.422865 -400.457413) (xy 427.367428 -400.463513) (xy 427.311694 -400.461476) (xy 427.256851 -400.451346)
			(xy 427.204067 -400.433339) (xy 427.154467 -400.407838) (xy 427.109109 -400.375387) (xy 427.06896 -400.336678)
			(xy 427.034874 -400.292535) (xy 427.007578 -400.2439) (xy 426.987655 -400.191809) (xy 426.975529 -400.137372)
			(xy 426.971458 -400.08175) (xy 424.891765 -400.08175) (xy 424.871171 -400.120993) (xy 424.854116 -400.14652)
			(xy 424.848663 -400.155282) (xy 424.844526 -400.17548) (xy 424.848647 -400.195681) (xy 424.854116 -400.204432)
			(xy 424.871153 -400.229969) (xy 424.899664 -400.284336) (xy 424.921428 -400.341739) (xy 424.936128 -400.401342)
			(xy 424.943552 -400.462281) (xy 424.944032 -400.492976) (xy 424.943521 -400.523706) (xy 424.936116 -400.584717)
			(xy 424.921411 -400.644391) (xy 424.89962 -400.701857) (xy 424.871061 -400.756278) (xy 424.836151 -400.806859)
			(xy 424.811572 -400.834606) (xy 426.462696 -400.834606) (xy 426.466767 -400.778984) (xy 426.478893 -400.724547)
			(xy 426.498816 -400.672456) (xy 426.526112 -400.623821) (xy 426.560198 -400.579678) (xy 426.600347 -400.540969)
			(xy 426.645705 -400.508518) (xy 426.695305 -400.483017) (xy 426.748089 -400.46501) (xy 426.802932 -400.45488)
			(xy 426.858666 -400.452843) (xy 426.914103 -400.458943) (xy 426.96806 -400.473049) (xy 427.019389 -400.494861)
			(xy 427.066995 -400.523915) (xy 427.109863 -400.55959) (xy 427.14708 -400.601127) (xy 427.177853 -400.64764)
			(xy 427.201525 -400.698137) (xy 427.217593 -400.751544) (xy 427.225713 -400.80672) (xy 427.226222 -400.834606)
			(xy 427.225713 -400.862492) (xy 427.217593 -400.917668) (xy 427.201525 -400.971075) (xy 427.177853 -401.021572)
			(xy 427.14708 -401.068085) (xy 427.109863 -401.109622) (xy 427.066995 -401.145297) (xy 427.019389 -401.174351)
			(xy 426.96806 -401.196163) (xy 426.914103 -401.210269) (xy 426.858666 -401.216369) (xy 426.802932 -401.214332)
			(xy 426.748089 -401.204202) (xy 426.695305 -401.186195) (xy 426.645705 -401.160694) (xy 426.600347 -401.128243)
			(xy 426.560198 -401.089534) (xy 426.526112 -401.045391) (xy 426.498816 -400.996756) (xy 426.478893 -400.944665)
			(xy 426.466767 -400.890228) (xy 426.462696 -400.834606) (xy 424.811572 -400.834606) (xy 424.795398 -400.852864)
			(xy 424.749397 -400.893621) (xy 424.698819 -400.928536) (xy 424.644401 -400.9571) (xy 424.586937 -400.978897)
			(xy 424.527264 -400.993608) (xy 424.466254 -401.001019) (xy 424.435524 -401.001484) (xy 424.403711 -401.001003)
			(xy 424.340582 -400.993068) (xy 424.278935 -400.977319) (xy 424.219736 -400.954003) (xy 424.163907 -400.923483)
			(xy 424.112323 -400.886236) (xy 424.065788 -400.842844) (xy 424.025031 -400.793987) (xy 423.990687 -400.740426)
			(xy 423.976546 -400.711924) (xy 423.971672 -400.702799) (xy 423.956202 -400.689098) (xy 423.936591 -400.682584)
			(xy 423.926254 -400.682968) (xy 423.881804 -400.685) (xy 423.851072 -400.684559) (xy 423.790055 -400.67715)
			(xy 423.730376 -400.662441) (xy 423.672906 -400.640645) (xy 423.618482 -400.612081) (xy 423.567897 -400.577165)
			(xy 423.52189 -400.536407) (xy 423.481132 -400.4904) (xy 423.446216 -400.439815) (xy 423.417653 -400.38539)
			(xy 423.395858 -400.32792) (xy 423.381149 -400.268241) (xy 423.373741 -400.207224) (xy 423.373296 -400.176492)
			(xy 423.373785 -400.145796) (xy 423.381184 -400.084852) (xy 423.395872 -400.025243) (xy 423.417637 -399.967839)
			(xy 423.44616 -399.913476) (xy 423.463212 -399.887948) (xy 423.46869 -399.8792) (xy 423.472815 -399.858993)
			(xy 423.468685 -399.838788) (xy 423.463212 -399.830036) (xy 423.445762 -399.803924) (xy 423.41674 -399.748226)
			(xy 423.394794 -399.68938) (xy 423.380259 -399.628279) (xy 423.376344 -399.597118) (xy 423.374994 -399.588192)
			(xy 423.366928 -399.572056) (xy 423.360596 -399.565622) (xy 423.338498 -399.544794) (xy 423.331853 -399.539033)
			(xy 423.315746 -399.532011) (xy 423.307002 -399.531078) (xy 423.282163 -399.52904) (xy 423.233471 -399.518414)
			(xy 423.186927 -399.5006) (xy 423.143583 -399.476) (xy 423.104424 -399.445173) (xy 423.070336 -399.408817)
			(xy 423.042092 -399.367755) (xy 423.020332 -399.322919) (xy 423.005549 -399.275325) (xy 422.998078 -399.226051)
			(xy 422.99763 -399.201132) (xy 422.998025 -399.177394) (xy 423.004822 -399.130406) (xy 423.018267 -399.084873)
			(xy 423.038084 -399.04173) (xy 423.063865 -399.001863) (xy 423.079164 -398.983708) (xy 423.085729 -398.975286)
			(xy 423.091902 -398.954866) (xy 423.089268 -398.933697) (xy 423.084244 -398.924272) (xy 423.068742 -398.897465)
			(xy 423.044304 -398.840565) (xy 423.027776 -398.780887) (xy 423.019458 -398.719523) (xy 423.018966 -398.68856)
			(xy 423.019485 -398.656958) (xy 423.028187 -398.594357) (xy 423.045435 -398.533552) (xy 423.070897 -398.475704)
			(xy 423.087038 -398.44853) (xy 423.09162 -398.440328) (xy 423.095034 -398.421866) (xy 423.091595 -398.403408)
			(xy 423.087038 -398.39519) (xy 423.070917 -398.368008) (xy 423.045489 -398.310151) (xy 423.028248 -398.249351)
			(xy 423.01952 -398.186758) (xy 423.018966 -398.15516) (xy 423.01953 -398.121926) (xy 423.029139 -398.056155)
			(xy 423.048163 -397.992467) (xy 423.076202 -397.932202) (xy 423.112666 -397.876628) (xy 423.134282 -397.851376)
			(xy 423.140632 -397.844264) (xy 423.147236 -397.826992) (xy 423.147236 -397.740886) (xy 423.140632 -397.723614)
			(xy 423.134282 -397.716502) (xy 423.112721 -397.691252) (xy 423.076345 -397.635709) (xy 423.048375 -397.575493)
			(xy 423.029397 -397.511868) (xy 423.01981 -397.446169) (xy 423.01922 -397.412972) (xy 423.019747 -397.381146)
			(xy 423.028571 -397.31811) (xy 423.046044 -397.256903) (xy 423.071829 -397.198709) (xy 423.105429 -397.144648)
			(xy 423.125392 -397.119856) (xy 423.131234 -397.112744) (xy 423.13733 -397.095218) (xy 423.13479 -397.009112)
			(xy 423.127678 -396.992094) (xy 423.121328 -396.985236) (xy 423.101836 -396.96397) (xy 423.067845 -396.91736)
			(xy 423.039981 -396.866847) (xy 423.018687 -396.813233) (xy 423.004301 -396.757367) (xy 422.997052 -396.700136)
			(xy 422.996614 -396.671292) (xy 421.448672 -396.671292) (xy 421.45095 -396.684292) (xy 421.451532 -396.710662)
			(xy 421.451463 -396.720021) (xy 421.45032 -396.738703) (xy 421.449246 -396.748) (xy 421.44823 -396.75689)
			(xy 421.45204 -396.773654) (xy 421.495982 -396.843504) (xy 421.509698 -396.853918) (xy 421.51808 -396.856712)
			(xy 421.542096 -396.865212) (xy 421.58727 -396.888756) (xy 421.628077 -396.919249) (xy 421.663459 -396.955898)
			(xy 421.692497 -396.997752) (xy 421.714438 -397.043726) (xy 421.722042 -397.06804) (xy 421.723566 -397.073882)
			(xy 422.04386 -397.627602) (xy 422.047924 -397.63192) (xy 422.06412 -397.649635) (xy 422.091544 -397.689024)
			(xy 422.112688 -397.732112) (xy 422.127064 -397.777905) (xy 422.13434 -397.825346) (xy 422.134792 -397.849344)
			(xy 422.134347 -397.874148) (xy 422.126576 -397.923145) (xy 422.111234 -397.970321) (xy 422.088699 -398.014516)
			(xy 422.059524 -398.054639) (xy 422.02443 -398.089703) (xy 421.984282 -398.118842) (xy 421.940068 -398.141339)
			(xy 421.892878 -398.15664) (xy 421.843875 -398.164368) (xy 421.81907 -398.164812) (xy 421.793675 -398.164338)
			(xy 421.74354 -398.156203) (xy 421.695354 -398.140147) (xy 421.650359 -398.116585) (xy 421.609717 -398.086123)
			(xy 421.574475 -398.049549) (xy 421.545542 -398.007805) (xy 421.523664 -397.961968) (xy 421.516048 -397.937736)
			(xy 421.514524 -397.931894) (xy 421.19423 -397.378174) (xy 421.190166 -397.373856) (xy 421.174009 -397.35612)
			(xy 421.14664 -397.316719) (xy 421.125548 -397.27363) (xy 421.111221 -397.227845) (xy 421.103986 -397.180419)
			(xy 421.103552 -397.156432) (xy 421.103633 -397.144384) (xy 421.105415 -397.120355) (xy 421.107108 -397.108426)
			(xy 421.108378 -397.099536) (xy 421.10533 -397.082518) (xy 421.063166 -397.011652) (xy 421.049958 -397.000476)
			(xy 421.041576 -396.997428) (xy 421.01983 -396.989029) (xy 420.978971 -396.966589) (xy 420.942 -396.938197)
			(xy 420.909777 -396.904512) (xy 420.883052 -396.866318) (xy 420.862445 -396.824505) (xy 420.848437 -396.780044)
			(xy 420.841354 -396.73397) (xy 420.840916 -396.710662) (xy 420.84148 -396.684289) (xy 420.850563 -396.63233)
			(xy 420.868453 -396.58271) (xy 420.881048 -396.559532) (xy 420.88562 -396.551404) (xy 420.888414 -396.534132)
			(xy 420.873174 -396.451328) (xy 420.86403 -396.436088) (xy 420.856918 -396.4305) (xy 420.834751 -396.41179)
			(xy 420.794803 -396.369729) (xy 420.760485 -396.322962) (xy 420.732345 -396.272237) (xy 420.710835 -396.218365)
			(xy 420.696298 -396.162208) (xy 420.688967 -396.104666) (xy 420.688516 -396.075662) (xy 420.689118 -396.042341)
			(xy 420.698776 -395.976403) (xy 420.717897 -395.912564) (xy 420.731442 -395.882114) (xy 420.735693 -395.871648)
			(xy 420.735589 -395.849086) (xy 420.725848 -395.828734) (xy 420.717472 -395.821154) (xy 420.695199 -395.80251)
			(xy 420.655138 -395.760448) (xy 420.620721 -395.713657) (xy 420.5925 -395.662886) (xy 420.570929 -395.608954)
			(xy 420.556354 -395.552726) (xy 420.54901 -395.495105) (xy 420.548562 -395.466062) (xy 420.54901 -395.437135)
			(xy 420.556294 -395.379743) (xy 420.570753 -395.323726) (xy 420.592157 -395.269978) (xy 420.620165 -395.219357)
			(xy 420.654329 -395.172669) (xy 420.694106 -395.130659) (xy 420.716202 -395.111986) (xy 420.72318 -395.105645)
			(xy 420.732433 -395.089236) (xy 420.734236 -395.079982) (xy 420.738554 -395.048994) (xy 420.739457 -395.039757)
			(xy 420.735433 -395.021658) (xy 420.73068 -395.013688) (xy 420.71437 -394.987844) (xy 420.690468 -394.931607)
			(xy 420.683182 -394.901928) (xy 420.681128 -394.893764) (xy 420.672424 -394.879364) (xy 420.666164 -394.873734)
			(xy 420.64305 -394.854684) (xy 420.636151 -394.849466) (xy 420.619935 -394.843483) (xy 420.6113 -394.843)
			(xy 420.581665 -394.841956) (xy 420.523001 -394.833311) (xy 420.465945 -394.817165) (xy 420.41145 -394.793786)
			(xy 420.360431 -394.763567) (xy 420.313741 -394.727014) (xy 420.272161 -394.684737) (xy 420.236388 -394.637446)
			(xy 420.207021 -394.585932) (xy 420.184552 -394.531057) (xy 420.169355 -394.47374) (xy 420.161687 -394.41494)
			(xy 420.161212 -394.385292) (xy 420.161734 -394.354229) (xy 420.170149 -394.292675) (xy 420.177976 -394.26261)
			(xy 420.18077 -394.25245) (xy 420.17823 -394.232638) (xy 420.130732 -394.150342) (xy 420.11473 -394.13815)
			(xy 420.10457 -394.13561) (xy 420.075489 -394.127554) (xy 420.019561 -394.104892) (xy 419.967095 -394.07508)
			(xy 419.919 -394.038634) (xy 419.876109 -393.996187) (xy 419.839165 -393.948473) (xy 419.808809 -393.89632)
			(xy 419.785566 -393.840631) (xy 419.76984 -393.782372) (xy 419.761903 -393.722552) (xy 419.761416 -393.69238)
			(xy 419.76194 -393.661492) (xy 419.770245 -393.600276) (xy 419.786702 -393.540732) (xy 419.811013 -393.483941)
			(xy 419.82644 -393.457176) (xy 419.832282 -393.44727) (xy 419.834568 -393.424918) (xy 419.801294 -393.329668)
			(xy 419.785546 -393.313666) (xy 419.774878 -393.309602) (xy 419.751493 -393.300428) (xy 419.707596 -393.276007)
			(xy 419.6679 -393.245224) (xy 419.63332 -393.208789) (xy 419.604651 -393.167541) (xy 419.582554 -393.12243)
			(xy 419.567537 -393.074494) (xy 419.559948 -393.024838) (xy 419.559486 -392.999722) (xy 419.020752 -392.999722)
			(xy 419.020222 -393.026824) (xy 419.011413 -393.080307) (xy 419.003226 -393.106148) (xy 418.999416 -393.11707)
			(xy 419.001956 -393.139422) (xy 419.054534 -393.225274) (xy 419.073584 -393.23772) (xy 419.08476 -393.239498)
			(xy 419.114082 -393.244182) (xy 419.171253 -393.260235) (xy 419.225867 -393.283548) (xy 419.277006 -393.31373)
			(xy 419.323811 -393.350273) (xy 419.365495 -393.392565) (xy 419.401359 -393.439893) (xy 419.430798 -393.491463)
			(xy 419.453319 -393.546408) (xy 419.468544 -393.603805) (xy 419.476215 -393.662689) (xy 419.476682 -393.69238)
			(xy 419.476155 -393.723443) (xy 419.467743 -393.784996) (xy 419.459918 -393.815062) (xy 419.457124 -393.825222)
			(xy 419.459664 -393.845034) (xy 419.507162 -393.92733) (xy 419.523164 -393.939522) (xy 419.533324 -393.942062)
			(xy 419.562428 -393.950081) (xy 419.618395 -393.972711) (xy 419.670901 -394.002503) (xy 419.719035 -394.038938)
			(xy 419.761962 -394.081384) (xy 419.798936 -394.129105) (xy 419.829317 -394.181272) (xy 419.852577 -394.23698)
			(xy 419.868312 -394.295263) (xy 419.876248 -394.355108) (xy 419.876732 -394.385292) (xy 419.876607 -394.399427)
			(xy 419.874825 -394.427641) (xy 419.873176 -394.44168) (xy 419.872412 -394.450287) (xy 419.876054 -394.467167)
			(xy 419.880288 -394.4747) (xy 419.896036 -394.5001) (xy 419.900731 -394.507171) (xy 419.913847 -394.517934)
			(xy 419.92169 -394.521182) (xy 419.945063 -394.530387) (xy 419.98896 -394.554802) (xy 420.028656 -394.58558)
			(xy 420.063238 -394.62201) (xy 420.091909 -394.663254) (xy 420.114008 -394.708361) (xy 420.129027 -394.756294)
			(xy 420.136619 -394.805947) (xy 420.137082 -394.831062) (xy 420.13666 -394.855264) (xy 420.129586 -394.903149)
			(xy 420.115599 -394.949489) (xy 420.094998 -394.993291) (xy 420.081964 -395.013688) (xy 420.077175 -395.021644)
			(xy 420.073142 -395.039756) (xy 420.07409 -395.048994) (xy 420.078408 -395.079982) (xy 420.080087 -395.089279)
			(xy 420.08937 -395.10572) (xy 420.096442 -395.111986) (xy 420.118526 -395.130673) (xy 420.158298 -395.172684)
			(xy 420.192461 -395.219371) (xy 420.22047 -395.269989) (xy 420.241877 -395.323734) (xy 420.256343 -395.379747)
			(xy 420.263637 -395.437136) (xy 420.264082 -395.466062) (xy 420.263488 -395.499383) (xy 420.253827 -395.565321)
			(xy 420.234702 -395.629161) (xy 420.221156 -395.65961) (xy 420.216882 -395.670068) (xy 420.216996 -395.692636)
			(xy 420.226745 -395.71299) (xy 420.235126 -395.72057) (xy 420.257362 -395.739256) (xy 420.297425 -395.78131)
			(xy 420.331845 -395.828095) (xy 420.360071 -395.878858) (xy 420.381649 -395.932783) (xy 420.396231 -395.989006)
			(xy 420.403583 -396.046621) (xy 420.404036 -396.075662) (xy 420.403565 -396.104667) (xy 420.396254 -396.162215)
			(xy 420.381731 -396.218378) (xy 420.36023 -396.272256) (xy 420.332095 -396.322987) (xy 420.297776 -396.369756)
			(xy 420.257824 -396.411816) (xy 420.235634 -396.4305) (xy 420.228522 -396.436088) (xy 420.219378 -396.451328)
			(xy 420.204138 -396.534132) (xy 420.206932 -396.551404) (xy 420.211504 -396.559532) (xy 420.224076 -396.58272)
			(xy 420.241952 -396.632341) (xy 420.251054 -396.684292) (xy 420.251636 -396.710662) (xy 420.251567 -396.720021)
			(xy 420.250424 -396.738703) (xy 420.24935 -396.748) (xy 420.248334 -396.75689) (xy 420.252144 -396.773654)
			(xy 420.296086 -396.843504) (xy 420.309802 -396.853918) (xy 420.318184 -396.856712) (xy 420.342278 -396.865201)
			(xy 420.38757 -396.888824) (xy 420.428465 -396.919433) (xy 420.463897 -396.956229) (xy 420.492941 -396.99825)
			(xy 420.514838 -397.044401) (xy 420.5224 -397.068802) (xy 420.523924 -397.074644) (xy 420.84371 -397.627602)
			(xy 420.847774 -397.63192) (xy 420.863974 -397.649618) (xy 420.891336 -397.68903) (xy 420.912418 -397.732129)
			(xy 420.926736 -397.777922) (xy 420.93396 -397.825354) (xy 420.934388 -397.849344) (xy 420.933923 -397.874134)
			(xy 420.926161 -397.923102) (xy 420.910835 -397.970254) (xy 420.888323 -398.014428) (xy 420.859178 -398.054537)
			(xy 420.824119 -398.089594) (xy 420.784007 -398.118736) (xy 420.739832 -398.141244) (xy 420.692679 -398.156566)
			(xy 420.64371 -398.164325) (xy 420.61892 -398.164812) (xy 420.593526 -398.164294) (xy 420.543393 -398.156166)
			(xy 420.495208 -398.140118) (xy 420.450214 -398.116562) (xy 420.409571 -398.086107) (xy 420.374328 -398.049538)
			(xy 420.345394 -398.007799) (xy 420.323515 -397.961966) (xy 420.315898 -397.937736) (xy 420.314374 -397.931894)
			(xy 419.993826 -397.377412) (xy 419.989762 -397.373094) (xy 419.973665 -397.355432) (xy 419.946476 -397.316133)
			(xy 419.925523 -397.273185) (xy 419.911286 -397.227568) (xy 419.904091 -397.180326) (xy 419.903656 -397.156432)
			(xy 419.903737 -397.144384) (xy 419.905519 -397.120355) (xy 419.907212 -397.108426) (xy 419.908482 -397.099536)
			(xy 419.905434 -397.082518) (xy 419.86327 -397.011652) (xy 419.850062 -397.000476) (xy 419.84168 -396.997428)
			(xy 419.819934 -396.989027) (xy 419.779076 -396.966588) (xy 419.742105 -396.938195) (xy 419.709881 -396.904511)
			(xy 419.683156 -396.866318) (xy 419.662549 -396.824504) (xy 419.648542 -396.780044) (xy 419.641458 -396.73397)
			(xy 419.64102 -396.710662) (xy 419.641583 -396.684289) (xy 419.650667 -396.63233) (xy 419.668556 -396.58271)
			(xy 419.681152 -396.559532) (xy 419.685724 -396.551404) (xy 419.688518 -396.534132) (xy 419.673278 -396.451328)
			(xy 419.664134 -396.436088) (xy 419.657022 -396.4305) (xy 419.634856 -396.411789) (xy 419.594908 -396.369729)
			(xy 419.560589 -396.322962) (xy 419.53245 -396.272237) (xy 419.510939 -396.218365) (xy 419.496402 -396.162208)
			(xy 419.489071 -396.104666) (xy 419.48862 -396.075662) (xy 419.489222 -396.042341) (xy 419.49888 -395.976403)
			(xy 419.518001 -395.912564) (xy 419.531546 -395.882114) (xy 419.535796 -395.871648) (xy 419.535691 -395.849086)
			(xy 419.525952 -395.828735) (xy 419.517576 -395.821154) (xy 419.495304 -395.802509) (xy 419.455243 -395.760448)
			(xy 419.420825 -395.713656) (xy 419.392604 -395.662886) (xy 419.371033 -395.608954) (xy 419.356458 -395.552726)
			(xy 419.349114 -395.495105) (xy 419.348666 -395.466062) (xy 419.349112 -395.437135) (xy 419.356396 -395.379743)
			(xy 419.370856 -395.323726) (xy 419.39226 -395.269978) (xy 419.420268 -395.219356) (xy 419.454433 -395.172669)
			(xy 419.49421 -395.130659) (xy 419.516306 -395.111986) (xy 419.523285 -395.105646) (xy 419.532537 -395.089236)
			(xy 419.53434 -395.079982) (xy 419.538658 -395.048994) (xy 419.53956 -395.039757) (xy 419.535537 -395.021658)
			(xy 419.530784 -395.013688) (xy 419.514474 -394.987843) (xy 419.490572 -394.931607) (xy 419.483286 -394.901928)
			(xy 419.481231 -394.893765) (xy 419.472527 -394.879364) (xy 419.466268 -394.873734) (xy 419.443154 -394.854684)
			(xy 419.436254 -394.849467) (xy 419.420039 -394.843484) (xy 419.411404 -394.843) (xy 419.381769 -394.841952)
			(xy 419.323105 -394.833308) (xy 419.266049 -394.817162) (xy 419.211555 -394.793784) (xy 419.160536 -394.763565)
			(xy 419.113845 -394.727012) (xy 419.072266 -394.684736) (xy 419.036493 -394.637445) (xy 419.007125 -394.585931)
			(xy 418.984656 -394.531056) (xy 418.969459 -394.473739) (xy 418.961791 -394.41494) (xy 418.961316 -394.385292)
			(xy 418.961838 -394.354229) (xy 418.970253 -394.292675) (xy 418.97808 -394.26261) (xy 418.980874 -394.25245)
			(xy 418.978334 -394.232638) (xy 418.930836 -394.150342) (xy 418.914834 -394.13815) (xy 418.904674 -394.13561)
			(xy 418.875562 -394.127618) (xy 418.819594 -394.104985) (xy 418.767087 -394.075191) (xy 418.718952 -394.038753)
			(xy 418.676025 -393.996304) (xy 418.639051 -393.94858) (xy 418.608671 -393.89641) (xy 418.585414 -393.840698)
			(xy 418.569682 -393.782413) (xy 418.561748 -393.722566) (xy 418.561266 -393.69238) (xy 418.561783 -393.661492)
			(xy 418.570089 -393.600275) (xy 418.586548 -393.540731) (xy 418.610861 -393.48394) (xy 418.62629 -393.457176)
			(xy 418.632132 -393.44727) (xy 418.634418 -393.424918) (xy 418.601144 -393.329668) (xy 418.585396 -393.313666)
			(xy 418.574728 -393.309602) (xy 418.551332 -393.300455) (xy 418.507437 -393.276027) (xy 418.467743 -393.24524)
			(xy 418.433164 -393.2088) (xy 418.404497 -393.167549) (xy 418.382402 -393.122435) (xy 418.367387 -393.074497)
			(xy 418.359798 -393.024839) (xy 418.359336 -392.999722) (xy 417.820856 -392.999722) (xy 417.820326 -393.026824)
			(xy 417.811516 -393.080307) (xy 417.80333 -393.106148) (xy 417.79952 -393.11707) (xy 417.80206 -393.139422)
			(xy 417.854638 -393.225274) (xy 417.873688 -393.23772) (xy 417.884864 -393.239498) (xy 417.914187 -393.244179)
			(xy 417.971357 -393.260232) (xy 418.025971 -393.283545) (xy 418.07711 -393.313728) (xy 418.123915 -393.350272)
			(xy 418.1656 -393.392564) (xy 418.201463 -393.439892) (xy 418.230902 -393.491463) (xy 418.253424 -393.546408)
			(xy 418.268648 -393.603805) (xy 418.276319 -393.662689) (xy 418.276786 -393.69238) (xy 418.276262 -393.723506)
			(xy 418.267857 -393.785188) (xy 418.260022 -393.815316) (xy 418.257228 -393.825476) (xy 418.259768 -393.845542)
			(xy 418.307012 -393.92733) (xy 418.323014 -393.939522) (xy 418.333174 -393.942062) (xy 418.362288 -393.950047)
			(xy 418.418254 -393.972684) (xy 418.470759 -394.002481) (xy 418.518892 -394.03892) (xy 418.561817 -394.081371)
			(xy 418.59879 -394.129095) (xy 418.62917 -394.181265) (xy 418.652428 -394.236975) (xy 418.668162 -394.29526)
			(xy 418.676099 -394.355107) (xy 418.676582 -394.385292) (xy 418.676457 -394.399427) (xy 418.674675 -394.427641)
			(xy 418.673026 -394.44168) (xy 418.67227 -394.450287) (xy 418.675907 -394.467166) (xy 418.680138 -394.4747)
			(xy 418.695886 -394.5001) (xy 418.700597 -394.507159) (xy 418.713702 -394.517928) (xy 418.72154 -394.521182)
			(xy 418.744923 -394.53036) (xy 418.788819 -394.554782) (xy 418.828514 -394.585564) (xy 418.863094 -394.621999)
			(xy 418.891763 -394.663246) (xy 418.91386 -394.708356) (xy 418.928878 -394.756291) (xy 418.936469 -394.805946)
			(xy 418.936932 -394.831062) (xy 418.936518 -394.855265) (xy 418.929443 -394.90315) (xy 418.915454 -394.94949)
			(xy 418.89485 -394.993291) (xy 418.881814 -395.013688) (xy 418.877022 -395.021642) (xy 418.872992 -395.039755)
			(xy 418.87394 -395.048994) (xy 418.878258 -395.079982) (xy 418.879953 -395.089275) (xy 418.889226 -395.105717)
			(xy 418.896292 -395.111986) (xy 418.918365 -395.130685) (xy 418.95814 -395.172692) (xy 418.992306 -395.219376)
			(xy 419.020316 -395.269993) (xy 419.041726 -395.323736) (xy 419.056193 -395.379748) (xy 419.063487 -395.437137)
			(xy 419.063932 -395.466062) (xy 419.063343 -395.499383) (xy 419.05368 -395.565322) (xy 419.034554 -395.629161)
			(xy 419.021006 -395.65961) (xy 419.016749 -395.670072) (xy 419.016862 -395.692635) (xy 419.026602 -395.712987)
			(xy 419.034976 -395.72057) (xy 419.057201 -395.739269) (xy 419.097267 -395.781319) (xy 419.13169 -395.828101)
			(xy 419.159918 -395.878862) (xy 419.181497 -395.932786) (xy 419.19608 -395.989007) (xy 419.203433 -396.046621)
			(xy 419.203886 -396.075662) (xy 419.203397 -396.104666) (xy 419.196087 -396.162213) (xy 419.181566 -396.218374)
			(xy 419.160067 -396.272252) (xy 419.131935 -396.322983) (xy 419.09762 -396.369753) (xy 419.057672 -396.411814)
			(xy 419.035484 -396.4305) (xy 419.028372 -396.436088) (xy 419.019228 -396.451328) (xy 419.003988 -396.534132)
			(xy 419.006782 -396.551404) (xy 419.011354 -396.559532) (xy 419.02393 -396.582718) (xy 419.041804 -396.63234)
			(xy 419.050904 -396.684291) (xy 419.051486 -396.710662) (xy 419.051418 -396.720021) (xy 419.050274 -396.738703)
			(xy 419.0492 -396.748) (xy 419.048184 -396.75689) (xy 419.051994 -396.773654) (xy 419.095936 -396.843504)
			(xy 419.109652 -396.853918) (xy 419.118034 -396.856712) (xy 419.142061 -396.865183) (xy 419.187234 -396.888735)
			(xy 419.228039 -396.919234) (xy 419.263418 -396.955888) (xy 419.292454 -396.997747) (xy 419.314393 -397.043725)
			(xy 419.321996 -397.06804) (xy 419.32352 -397.073882) (xy 419.643814 -397.627602) (xy 419.647878 -397.63192)
			(xy 419.664079 -397.649618) (xy 419.69144 -397.68903) (xy 419.712522 -397.732129) (xy 419.72684 -397.777922)
			(xy 419.734064 -397.825354) (xy 419.734492 -397.849344) (xy 419.734023 -397.874134) (xy 419.726261 -397.923102)
			(xy 419.710936 -397.970253) (xy 419.688424 -398.014427) (xy 419.65928 -398.054536) (xy 419.624221 -398.089593)
			(xy 419.58411 -398.118734) (xy 419.539934 -398.141243) (xy 419.492782 -398.156566) (xy 419.443814 -398.164324)
			(xy 419.419024 -398.164812) (xy 419.39363 -398.16429) (xy 419.343498 -398.156164) (xy 419.295313 -398.140116)
			(xy 419.250318 -398.11656) (xy 419.209675 -398.086106) (xy 419.174432 -398.049537) (xy 419.145498 -398.007798)
			(xy 419.123619 -397.961966) (xy 419.116002 -397.937736) (xy 419.114478 -397.931894) (xy 418.794184 -397.378174)
			(xy 418.79012 -397.373856) (xy 418.77392 -397.356144) (xy 418.746495 -397.316755) (xy 418.725351 -397.273666)
			(xy 418.710976 -397.227873) (xy 418.703702 -397.18043) (xy 418.703252 -397.156432) (xy 418.703393 -397.14438)
			(xy 418.7053 -397.12035) (xy 418.707062 -397.108426) (xy 418.708332 -397.099536) (xy 418.705284 -397.082518)
			(xy 418.66312 -397.011652) (xy 418.649912 -397.000476) (xy 418.64153 -396.997428) (xy 418.619774 -396.989055)
			(xy 418.578916 -396.966609) (xy 418.541947 -396.938211) (xy 418.509726 -396.904522) (xy 418.483002 -396.866325)
			(xy 418.462398 -396.824509) (xy 418.448391 -396.780046) (xy 418.441308 -396.733971) (xy 418.44087 -396.710662)
			(xy 418.44144 -396.684289) (xy 418.450522 -396.632331) (xy 418.468408 -396.582711) (xy 418.481002 -396.559532)
			(xy 418.485574 -396.551404) (xy 418.488368 -396.534132) (xy 418.473128 -396.451328) (xy 418.463984 -396.436088)
			(xy 418.456872 -396.4305) (xy 418.434696 -396.411801) (xy 418.39475 -396.369737) (xy 418.360434 -396.322968)
			(xy 418.332296 -396.272241) (xy 418.310787 -396.218367) (xy 418.296251 -396.16221) (xy 418.288921 -396.104666)
			(xy 418.28847 -396.075662) (xy 418.289067 -396.042341) (xy 418.298727 -395.976403) (xy 418.31785 -395.912563)
			(xy 418.331396 -395.882114) (xy 418.33563 -395.871644) (xy 418.335525 -395.849088) (xy 418.325795 -395.828738)
			(xy 418.317426 -395.821154) (xy 418.295164 -395.802497) (xy 418.255101 -395.760439) (xy 418.220681 -395.71365)
			(xy 418.192458 -395.662882) (xy 418.170885 -395.608951) (xy 418.156309 -395.552724) (xy 418.148964 -395.495105)
			(xy 418.148516 -395.466062) (xy 418.148981 -395.437136) (xy 418.156264 -395.379745) (xy 418.170721 -395.323729)
			(xy 418.192123 -395.269982) (xy 418.220128 -395.21936) (xy 418.254289 -395.172672) (xy 418.294062 -395.130661)
			(xy 418.316156 -395.111986) (xy 418.323127 -395.105638) (xy 418.332386 -395.089235) (xy 418.33419 -395.079982)
			(xy 418.338508 -395.048994) (xy 418.339418 -395.039758) (xy 418.335391 -395.021657) (xy 418.330634 -395.013688)
			(xy 418.314329 -394.987841) (xy 418.290424 -394.931606) (xy 418.283136 -394.901928) (xy 418.281067 -394.893769)
			(xy 418.272373 -394.879367) (xy 418.266118 -394.873734) (xy 418.243004 -394.854684) (xy 418.236118 -394.849447)
			(xy 418.219892 -394.843476) (xy 418.211254 -394.843) (xy 418.181617 -394.841998) (xy 418.122952 -394.833348)
			(xy 418.065895 -394.817196) (xy 418.011401 -394.793813) (xy 417.960382 -394.763589) (xy 417.913692 -394.727031)
			(xy 417.872113 -394.684751) (xy 417.836341 -394.637457) (xy 417.806974 -394.58594) (xy 417.784505 -394.531062)
			(xy 417.769309 -394.473743) (xy 417.761641 -394.414942) (xy 417.761166 -394.385292) (xy 417.761687 -394.354229)
			(xy 417.770103 -394.292675) (xy 417.77793 -394.26261) (xy 417.780724 -394.25245) (xy 417.778184 -394.232638)
			(xy 417.730686 -394.150342) (xy 417.714684 -394.13815) (xy 417.704524 -394.13561) (xy 417.675434 -394.127584)
			(xy 417.619507 -394.104916) (xy 417.567042 -394.0751) (xy 417.518948 -394.03865) (xy 417.476058 -393.996199)
			(xy 417.439115 -393.948482) (xy 417.40876 -393.896326) (xy 417.385519 -393.840636) (xy 417.369794 -393.782375)
			(xy 417.361857 -393.722553) (xy 417.36137 -393.69238) (xy 417.3619 -393.661492) (xy 417.370204 -393.600277)
			(xy 417.38666 -393.540733) (xy 417.410968 -393.483941) (xy 417.426394 -393.457176) (xy 417.432236 -393.44727)
			(xy 417.434522 -393.424918) (xy 417.401248 -393.329668) (xy 417.3855 -393.313666) (xy 417.374832 -393.309602)
			(xy 417.351437 -393.300453) (xy 417.307541 -393.276026) (xy 417.267847 -393.245238) (xy 417.233269 -393.2088)
			(xy 417.204602 -393.167548) (xy 417.182506 -393.122434) (xy 417.167491 -393.074497) (xy 417.159902 -393.024839)
			(xy 417.15944 -392.999722) (xy 416.620706 -392.999722) (xy 416.620173 -393.026824) (xy 416.611365 -393.080306)
			(xy 416.60318 -393.106148) (xy 416.59937 -393.11707) (xy 416.60191 -393.139422) (xy 416.654488 -393.225274)
			(xy 416.673538 -393.23772) (xy 416.684714 -393.239498) (xy 416.71403 -393.244218) (xy 416.7712 -393.260265)
			(xy 416.825814 -393.283573) (xy 416.876954 -393.31375) (xy 416.92376 -393.35029) (xy 416.965446 -393.392578)
			(xy 417.00131 -393.439903) (xy 417.030751 -393.491471) (xy 417.053273 -393.546413) (xy 417.068497 -393.603808)
			(xy 417.076169 -393.66269) (xy 417.076636 -393.69238) (xy 417.07611 -393.723443) (xy 417.067697 -393.784996)
			(xy 417.059872 -393.815062) (xy 417.057078 -393.825222) (xy 417.059618 -393.845034) (xy 417.107116 -393.92733)
			(xy 417.123118 -393.939522) (xy 417.133278 -393.942062) (xy 417.162392 -393.950044) (xy 417.218358 -393.972682)
			(xy 417.270863 -394.002479) (xy 417.318996 -394.038919) (xy 417.361922 -394.08137) (xy 417.398895 -394.129094)
			(xy 417.429274 -394.181264) (xy 417.452533 -394.236975) (xy 417.468266 -394.29526) (xy 417.476203 -394.355107)
			(xy 417.476686 -394.385292) (xy 417.476561 -394.399427) (xy 417.474779 -394.427641) (xy 417.47313 -394.44168)
			(xy 417.472373 -394.450287) (xy 417.476011 -394.467166) (xy 417.480242 -394.4747) (xy 417.49599 -394.5001)
			(xy 417.5007 -394.50716) (xy 417.513805 -394.517929) (xy 417.521644 -394.521182) (xy 417.545028 -394.530358)
			(xy 417.588924 -394.55478) (xy 417.628618 -394.585563) (xy 417.663198 -394.621998) (xy 417.691867 -394.663245)
			(xy 417.713964 -394.708356) (xy 417.728982 -394.756291) (xy 417.736573 -394.805946) (xy 417.737036 -394.831062)
			(xy 417.736621 -394.855265) (xy 417.729546 -394.90315) (xy 417.715557 -394.94949) (xy 417.694953 -394.993291)
			(xy 417.681918 -395.013688) (xy 417.677127 -395.021643) (xy 417.673096 -395.039755) (xy 417.674044 -395.048994)
			(xy 417.678362 -395.079982) (xy 417.680055 -395.089275) (xy 417.689329 -395.105717) (xy 417.696396 -395.111986)
			(xy 417.71847 -395.130684) (xy 417.758245 -395.172692) (xy 417.79241 -395.219376) (xy 417.82042 -395.269993)
			(xy 417.84183 -395.323736) (xy 417.856297 -395.379748) (xy 417.863591 -395.437137) (xy 417.864036 -395.466062)
			(xy 417.863447 -395.499383) (xy 417.853784 -395.565322) (xy 417.834658 -395.629161) (xy 417.82111 -395.65961)
			(xy 417.816851 -395.670072) (xy 417.816965 -395.692635) (xy 417.826705 -395.712987) (xy 417.83508 -395.72057)
			(xy 417.857306 -395.739268) (xy 417.897371 -395.781319) (xy 417.931794 -395.8281) (xy 417.960022 -395.878861)
			(xy 417.981601 -395.932786) (xy 417.996184 -395.989007) (xy 418.003537 -396.046621) (xy 418.00399 -396.075662)
			(xy 418.003499 -396.104666) (xy 417.996189 -396.162212) (xy 417.981669 -396.218374) (xy 417.96017 -396.272252)
			(xy 417.932038 -396.322982) (xy 417.897723 -396.369753) (xy 417.857776 -396.411814) (xy 417.835588 -396.4305)
			(xy 417.828476 -396.436088) (xy 417.819332 -396.451328) (xy 417.804092 -396.534132) (xy 417.806886 -396.551404)
			(xy 417.811458 -396.559532) (xy 417.824035 -396.582718) (xy 417.841908 -396.63234) (xy 417.851008 -396.684291)
			(xy 417.85159 -396.710662) (xy 417.851522 -396.720021) (xy 417.850378 -396.738703) (xy 417.849304 -396.748)
			(xy 417.848288 -396.75689) (xy 417.852098 -396.773654) (xy 417.89604 -396.843504) (xy 417.909756 -396.853918)
			(xy 417.918138 -396.856712) (xy 417.942243 -396.865172) (xy 417.987533 -396.888802) (xy 418.028427 -396.919418)
			(xy 418.063857 -396.956219) (xy 418.092898 -396.998245) (xy 418.114793 -397.0444) (xy 418.122354 -397.068802)
			(xy 418.123878 -397.074644) (xy 418.443664 -397.627602) (xy 418.447728 -397.63192) (xy 418.463924 -397.649634)
			(xy 418.491349 -397.689024) (xy 418.512492 -397.732112) (xy 418.526868 -397.777905) (xy 418.534144 -397.825346)
			(xy 418.534596 -397.849344) (xy 418.534147 -397.874148) (xy 418.526377 -397.923144) (xy 418.511035 -397.97032)
			(xy 418.488499 -398.014515) (xy 418.459325 -398.054638) (xy 418.424232 -398.089701) (xy 418.384084 -398.118841)
			(xy 418.339871 -398.141338) (xy 418.292681 -398.15664) (xy 418.243678 -398.164368) (xy 418.218874 -398.164812)
			(xy 418.193479 -398.164334) (xy 418.143344 -398.1562) (xy 418.095158 -398.140145) (xy 418.050164 -398.116583)
			(xy 418.009521 -398.086122) (xy 417.974279 -398.049548) (xy 417.945346 -398.007805) (xy 417.923468 -397.961967)
			(xy 417.915852 -397.937736) (xy 417.914328 -397.931894) (xy 417.59378 -397.377412) (xy 417.589716 -397.373094)
			(xy 417.573624 -397.355415) (xy 417.546371 -397.316139) (xy 417.525358 -397.273202) (xy 417.511063 -397.227585)
			(xy 417.503815 -397.180334) (xy 417.503356 -397.156432) (xy 417.503497 -397.14438) (xy 417.505404 -397.12035)
			(xy 417.507166 -397.108426) (xy 417.508436 -397.099536) (xy 417.505388 -397.082518) (xy 417.463224 -397.011652)
			(xy 417.450016 -397.000476) (xy 417.441634 -396.997428) (xy 417.419878 -396.989052) (xy 417.379021 -396.966607)
			(xy 417.342052 -396.93821) (xy 417.30983 -396.904521) (xy 417.283107 -396.866325) (xy 417.262502 -396.824509)
			(xy 417.248495 -396.780046) (xy 417.241412 -396.73397) (xy 417.240974 -396.710662) (xy 417.241543 -396.684289)
			(xy 417.250625 -396.632331) (xy 417.268512 -396.58271) (xy 417.281106 -396.559532) (xy 417.285678 -396.551404)
			(xy 417.288472 -396.534132) (xy 417.273232 -396.451328) (xy 417.264088 -396.436088) (xy 417.256976 -396.4305)
			(xy 417.2348 -396.4118) (xy 417.194854 -396.369737) (xy 417.160538 -396.322967) (xy 417.1324 -396.27224)
			(xy 417.110891 -396.218367) (xy 417.096355 -396.162209) (xy 417.089025 -396.104666) (xy 417.088574 -396.075662)
			(xy 417.089171 -396.042341) (xy 417.09883 -395.976403) (xy 417.117954 -395.912563) (xy 417.1315 -395.882114)
			(xy 417.135732 -395.871644) (xy 417.135627 -395.849088) (xy 417.125898 -395.828738) (xy 417.11753 -395.821154)
			(xy 417.095269 -395.802496) (xy 417.055206 -395.760438) (xy 417.020785 -395.71365) (xy 416.992562 -395.662882)
			(xy 416.970989 -395.608951) (xy 416.956413 -395.552724) (xy 416.949068 -395.495105) (xy 416.94862 -395.466062)
			(xy 416.949083 -395.437136) (xy 416.956366 -395.379745) (xy 416.970824 -395.323729) (xy 416.992226 -395.269981)
			(xy 417.020231 -395.21936) (xy 417.054393 -395.172672) (xy 417.094166 -395.130661) (xy 417.11626 -395.111986)
			(xy 417.123232 -395.105639) (xy 417.13249 -395.089235) (xy 417.134294 -395.079982) (xy 417.138612 -395.048994)
			(xy 417.139522 -395.039758) (xy 417.135494 -395.021657) (xy 417.130738 -395.013688) (xy 417.114433 -394.987841)
			(xy 417.090528 -394.931606) (xy 417.08324 -394.901928) (xy 417.08117 -394.893769) (xy 417.072476 -394.879367)
			(xy 417.066222 -394.873734) (xy 417.043108 -394.854684) (xy 417.036221 -394.849449) (xy 417.019996 -394.843477)
			(xy 417.011358 -394.843) (xy 416.981721 -394.841994) (xy 416.923056 -394.833345) (xy 416.865999 -394.817193)
			(xy 416.811505 -394.79381) (xy 416.760486 -394.763587) (xy 416.713796 -394.72703) (xy 416.672217 -394.68475)
			(xy 416.636445 -394.637456) (xy 416.607078 -394.585939) (xy 416.584609 -394.531062) (xy 416.569413 -394.473743)
			(xy 416.561745 -394.414941) (xy 416.56127 -394.385292) (xy 416.561791 -394.354229) (xy 416.570207 -394.292675)
			(xy 416.578034 -394.26261) (xy 416.580828 -394.25245) (xy 416.578288 -394.232638) (xy 416.53079 -394.150342)
			(xy 416.514788 -394.13815) (xy 416.504628 -394.13561) (xy 416.475507 -394.127649) (xy 416.419539 -394.105011)
			(xy 416.367033 -394.075212) (xy 416.3189 -394.03877) (xy 416.275974 -393.996317) (xy 416.239001 -393.948589)
			(xy 416.208623 -393.896416) (xy 416.185366 -393.840703) (xy 416.169635 -393.782416) (xy 416.161701 -393.722566)
			(xy 416.16122 -393.69238) (xy 416.161743 -393.661492) (xy 416.170048 -393.600276) (xy 416.186506 -393.540732)
			(xy 416.210817 -393.483941) (xy 416.226244 -393.457176) (xy 416.232086 -393.44727) (xy 416.234372 -393.424918)
			(xy 416.201098 -393.329668) (xy 416.18535 -393.313666) (xy 416.174682 -393.309602) (xy 416.151298 -393.300426)
			(xy 416.107401 -393.276005) (xy 416.067705 -393.245223) (xy 416.033124 -393.208789) (xy 416.004455 -393.167541)
			(xy 415.982358 -393.12243) (xy 415.967342 -393.074494) (xy 415.959752 -393.024838) (xy 415.95929 -392.999722)
			(xy 415.42081 -392.999722) (xy 415.420277 -393.026824) (xy 415.411469 -393.080306) (xy 415.403284 -393.106148)
			(xy 415.399474 -393.11707) (xy 415.402014 -393.139422) (xy 415.454592 -393.225274) (xy 415.473642 -393.23772)
			(xy 415.484818 -393.239498) (xy 415.514134 -393.244215) (xy 415.571305 -393.260262) (xy 415.625919 -393.283571)
			(xy 415.677059 -393.313748) (xy 415.723865 -393.350288) (xy 415.76555 -393.392577) (xy 415.801414 -393.439902)
			(xy 415.830855 -393.49147) (xy 415.853377 -393.546413) (xy 415.868601 -393.603808) (xy 415.876273 -393.66269)
			(xy 415.87674 -393.69238) (xy 415.876214 -393.723443) (xy 415.867801 -393.784996) (xy 415.859976 -393.815062)
			(xy 415.857182 -393.825222) (xy 415.859722 -393.845034) (xy 415.90722 -393.92733) (xy 415.923222 -393.939522)
			(xy 415.933382 -393.942062) (xy 415.962497 -393.950042) (xy 416.018463 -393.97268) (xy 416.070968 -394.002477)
			(xy 416.119101 -394.038918) (xy 416.162026 -394.081369) (xy 416.198999 -394.129093) (xy 416.229378 -394.181264)
			(xy 416.252637 -394.236975) (xy 416.268371 -394.295259) (xy 416.276307 -394.355106) (xy 416.27679 -394.385292)
			(xy 416.276665 -394.399427) (xy 416.274883 -394.427641) (xy 416.273234 -394.44168) (xy 416.272477 -394.450287)
			(xy 416.276115 -394.467167) (xy 416.280346 -394.4747) (xy 416.296094 -394.5001) (xy 416.30079 -394.507173)
			(xy 416.313898 -394.517947) (xy 416.321748 -394.521182) (xy 416.3451 -394.5304) (xy 416.388943 -394.554857)
			(xy 416.428586 -394.585659) (xy 416.46312 -394.622097) (xy 416.491751 -394.663335) (xy 416.513822 -394.708427)
			(xy 416.528825 -394.756335) (xy 416.536417 -394.805961) (xy 416.536886 -394.831062) (xy 416.536463 -394.855264)
			(xy 416.529389 -394.903149) (xy 416.515402 -394.949489) (xy 416.494802 -394.993291) (xy 416.481768 -395.013688)
			(xy 416.47698 -395.021645) (xy 416.472946 -395.039756) (xy 416.473894 -395.048994) (xy 416.478212 -395.079982)
			(xy 416.47989 -395.089279) (xy 416.489174 -395.10572) (xy 416.496246 -395.111986) (xy 416.518331 -395.130672)
			(xy 416.558103 -395.172683) (xy 416.592266 -395.21937) (xy 416.620274 -395.269989) (xy 416.641682 -395.323733)
			(xy 416.656148 -395.379747) (xy 416.663441 -395.437136) (xy 416.663886 -395.466062) (xy 416.663292 -395.499383)
			(xy 416.653631 -395.565321) (xy 416.634506 -395.629161) (xy 416.62096 -395.65961) (xy 416.616685 -395.670068)
			(xy 416.616798 -395.692636) (xy 416.626549 -395.71299) (xy 416.63493 -395.72057) (xy 416.657167 -395.739255)
			(xy 416.697229 -395.78131) (xy 416.73165 -395.828094) (xy 416.759876 -395.878857) (xy 416.781453 -395.932783)
			(xy 416.796035 -395.989006) (xy 416.803387 -396.046621) (xy 416.80384 -396.075662) (xy 416.803368 -396.104667)
			(xy 416.796057 -396.162215) (xy 416.781534 -396.218378) (xy 416.760033 -396.272256) (xy 416.731898 -396.322986)
			(xy 416.69758 -396.369756) (xy 416.657628 -396.411816) (xy 416.635438 -396.4305) (xy 416.628326 -396.436088)
			(xy 416.619182 -396.451328) (xy 416.603942 -396.534132) (xy 416.606736 -396.551404) (xy 416.611308 -396.559532)
			(xy 416.62388 -396.58272) (xy 416.641756 -396.632341) (xy 416.650858 -396.684292) (xy 416.65144 -396.710662)
			(xy 416.651371 -396.720021) (xy 416.650228 -396.738703) (xy 416.649154 -396.748) (xy 416.648138 -396.75689)
			(xy 416.651948 -396.773654) (xy 416.69589 -396.843504) (xy 416.709606 -396.853918) (xy 416.717988 -396.856712)
			(xy 416.742006 -396.865208) (xy 416.78718 -396.888753) (xy 416.827986 -396.919246) (xy 416.863368 -396.955896)
			(xy 416.892405 -396.997751) (xy 416.914346 -397.043726) (xy 416.92195 -397.06804) (xy 416.923474 -397.073882)
			(xy 417.243768 -397.627602) (xy 417.247832 -397.63192) (xy 417.264029 -397.649634) (xy 417.291453 -397.689024)
			(xy 417.312597 -397.732112) (xy 417.326972 -397.777905) (xy 417.334248 -397.825346) (xy 417.3347 -397.849344)
			(xy 417.334247 -397.874148) (xy 417.326477 -397.923143) (xy 417.311135 -397.970319) (xy 417.2886 -398.014513)
			(xy 417.259427 -398.054636) (xy 417.224334 -398.0897) (xy 417.184186 -398.118839) (xy 417.139973 -398.141337)
			(xy 417.092784 -398.156639) (xy 417.043782 -398.164368) (xy 417.018978 -398.164812) (xy 416.993583 -398.164331)
			(xy 416.943448 -398.156197) (xy 416.895263 -398.140142) (xy 416.850268 -398.116581) (xy 416.809626 -398.086121)
			(xy 416.774383 -398.049547) (xy 416.74545 -398.007804) (xy 416.723572 -397.961967) (xy 416.715956 -397.937736)
			(xy 416.714432 -397.931894) (xy 416.394138 -397.378174) (xy 416.390074 -397.373856) (xy 416.373918 -397.356119)
			(xy 416.346549 -397.316718) (xy 416.325457 -397.273629) (xy 416.311129 -397.227845) (xy 416.303894 -397.180419)
			(xy 416.30346 -397.156432) (xy 416.303541 -397.144384) (xy 416.305323 -397.120355) (xy 416.307016 -397.108426)
			(xy 416.308286 -397.099536) (xy 416.305238 -397.082518) (xy 416.263074 -397.011652) (xy 416.249866 -397.000476)
			(xy 416.241484 -396.997428) (xy 416.219739 -396.989025) (xy 416.17888 -396.966586) (xy 416.141909 -396.938194)
			(xy 416.109686 -396.90451) (xy 416.08296 -396.866317) (xy 416.062354 -396.824504) (xy 416.048346 -396.780043)
			(xy 416.041262 -396.73397) (xy 416.040824 -396.710662) (xy 416.041387 -396.684289) (xy 416.05047 -396.63233)
			(xy 416.06836 -396.58271) (xy 416.080956 -396.559532) (xy 416.085528 -396.551404) (xy 416.088322 -396.534132)
			(xy 416.073082 -396.451328) (xy 416.063938 -396.436088) (xy 416.056826 -396.4305) (xy 416.034661 -396.411788)
			(xy 415.994712 -396.369728) (xy 415.960394 -396.322962) (xy 415.932254 -396.272236) (xy 415.910743 -396.218365)
			(xy 415.896206 -396.162208) (xy 415.888875 -396.104666) (xy 415.888424 -396.075662) (xy 415.889025 -396.042341)
			(xy 415.898684 -395.976403) (xy 415.917805 -395.912563) (xy 415.93135 -395.882114) (xy 415.935599 -395.871648)
			(xy 415.935494 -395.849086) (xy 415.925755 -395.828735) (xy 415.91738 -395.821154) (xy 415.895109 -395.802508)
			(xy 415.855048 -395.760447) (xy 415.82063 -395.713656) (xy 415.792408 -395.662886) (xy 415.770837 -395.608954)
			(xy 415.756262 -395.552725) (xy 415.748918 -395.495105) (xy 415.74847 -395.466062) (xy 415.748915 -395.437135)
			(xy 415.756199 -395.379743) (xy 415.770658 -395.323725) (xy 415.792063 -395.269978) (xy 415.820071 -395.219356)
			(xy 415.854236 -395.172668) (xy 415.894014 -395.130659) (xy 415.91611 -395.111986) (xy 415.92309 -395.105647)
			(xy 415.932342 -395.089237) (xy 415.934144 -395.079982) (xy 415.938462 -395.048994) (xy 415.939364 -395.039757)
			(xy 415.93534 -395.021658) (xy 415.930588 -395.013688) (xy 415.914279 -394.987843) (xy 415.890376 -394.931607)
			(xy 415.88309 -394.901928) (xy 415.881034 -394.893765) (xy 415.872331 -394.879364) (xy 415.866072 -394.873734)
			(xy 415.842958 -394.854684) (xy 415.836142 -394.849456) (xy 415.820039 -394.843499) (xy 415.811462 -394.843)
			(xy 415.781825 -394.841991) (xy 415.723161 -394.833342) (xy 415.666103 -394.817191) (xy 415.611609 -394.793808)
			(xy 415.56059 -394.763585) (xy 415.5139 -394.727028) (xy 415.472321 -394.684749) (xy 415.436549 -394.637455)
			(xy 415.407182 -394.585938) (xy 415.384713 -394.531061) (xy 415.369517 -394.473742) (xy 415.361849 -394.414941)
			(xy 415.361374 -394.385292) (xy 415.361894 -394.354229) (xy 415.370311 -394.292675) (xy 415.378138 -394.26261)
			(xy 415.380932 -394.25245) (xy 415.378392 -394.232638) (xy 415.330894 -394.150342) (xy 415.314892 -394.13815)
			(xy 415.304732 -394.13561) (xy 415.275612 -394.127646) (xy 415.219644 -394.105008) (xy 415.167138 -394.07521)
			(xy 415.119004 -394.038768) (xy 415.076079 -393.996315) (xy 415.039106 -393.948589) (xy 415.008727 -393.896416)
			(xy 414.98547 -393.840702) (xy 414.969739 -393.782415) (xy 414.961805 -393.722566) (xy 414.961324 -393.69238)
			(xy 414.961846 -393.661492) (xy 414.970152 -393.600276) (xy 414.98661 -393.540732) (xy 415.010921 -393.483941)
			(xy 415.026348 -393.457176) (xy 415.03219 -393.44727) (xy 415.034476 -393.424918) (xy 415.001202 -393.329668)
			(xy 414.985454 -393.313666) (xy 414.974786 -393.309602) (xy 414.951403 -393.300423) (xy 414.907506 -393.276003)
			(xy 414.867809 -393.245222) (xy 414.833229 -393.208788) (xy 414.804559 -393.16754) (xy 414.782462 -393.122429)
			(xy 414.767446 -393.074494) (xy 414.759856 -393.024838) (xy 414.759394 -392.999722) (xy 414.220914 -392.999722)
			(xy 414.220381 -393.026824) (xy 414.211573 -393.080306) (xy 414.203388 -393.106148) (xy 414.199578 -393.11707)
			(xy 414.202118 -393.139422) (xy 414.254696 -393.225528) (xy 414.273492 -393.23772) (xy 414.284922 -393.239498)
			(xy 414.314208 -393.244322) (xy 414.371342 -393.260393) (xy 414.425919 -393.283716) (xy 414.477022 -393.313899)
			(xy 414.523794 -393.350437) (xy 414.565449 -393.392714) (xy 414.601288 -393.440023) (xy 414.63071 -393.491569)
			(xy 414.65322 -393.546485) (xy 414.668441 -393.603852) (xy 414.676117 -393.662704) (xy 414.67659 -393.69238)
			(xy 414.676062 -393.723443) (xy 414.667651 -393.784996) (xy 414.659826 -393.815062) (xy 414.657032 -393.825222)
			(xy 414.659572 -393.845034) (xy 414.70707 -393.92733) (xy 414.723072 -393.939522) (xy 414.733232 -393.942062)
			(xy 414.762338 -393.950075) (xy 414.818304 -393.972707) (xy 414.87081 -394.002499) (xy 414.918944 -394.038935)
			(xy 414.961871 -394.081382) (xy 414.998845 -394.129103) (xy 415.029226 -394.181271) (xy 415.052485 -394.23698)
			(xy 415.06822 -394.295262) (xy 415.076156 -394.355107) (xy 415.07664 -394.385292) (xy 415.076515 -394.399427)
			(xy 415.074733 -394.427641) (xy 415.073084 -394.44168) (xy 415.072319 -394.450287) (xy 415.075961 -394.467168)
			(xy 415.080196 -394.4747) (xy 415.095944 -394.5001) (xy 415.100637 -394.507173) (xy 415.113754 -394.517935)
			(xy 415.121598 -394.521182) (xy 415.144972 -394.530383) (xy 415.188869 -394.554799) (xy 415.228566 -394.585577)
			(xy 415.263147 -394.622008) (xy 415.291818 -394.663252) (xy 415.313917 -394.708361) (xy 415.328935 -394.756293)
			(xy 415.336527 -394.805947) (xy 415.33699 -394.831062) (xy 415.336566 -394.855264) (xy 415.329493 -394.903149)
			(xy 415.315506 -394.949489) (xy 415.294905 -394.993291) (xy 415.281872 -395.013688) (xy 415.277084 -395.021645)
			(xy 415.27305 -395.039756) (xy 415.273998 -395.048994) (xy 415.278316 -395.079982) (xy 415.279993 -395.089279)
			(xy 415.289277 -395.105721) (xy 415.29635 -395.111986) (xy 415.318436 -395.130671) (xy 415.358208 -395.172682)
			(xy 415.39237 -395.219369) (xy 415.420379 -395.269989) (xy 415.441786 -395.323733) (xy 415.456252 -395.379747)
			(xy 415.463545 -395.437136) (xy 415.46399 -395.466062) (xy 415.463396 -395.499383) (xy 415.453734 -395.565321)
			(xy 415.43461 -395.629161) (xy 415.421064 -395.65961) (xy 415.416821 -395.670076) (xy 415.416935 -395.692633)
			(xy 415.426666 -395.712984) (xy 415.435034 -395.72057) (xy 415.457271 -395.739254) (xy 415.497334 -395.781309)
			(xy 415.531754 -395.828094) (xy 415.55998 -395.878857) (xy 415.581557 -395.932783) (xy 415.596139 -395.989005)
			(xy 415.603491 -396.046621) (xy 415.603944 -396.075662) (xy 415.60347 -396.104667) (xy 415.596159 -396.162214)
			(xy 415.581637 -396.218377) (xy 415.560136 -396.272255) (xy 415.532001 -396.322986) (xy 415.497683 -396.369756)
			(xy 415.457732 -396.411816) (xy 415.435542 -396.4305) (xy 415.42843 -396.436088) (xy 415.419286 -396.451328)
			(xy 415.404046 -396.534132) (xy 415.40684 -396.551404) (xy 415.411412 -396.559532) (xy 415.423985 -396.58272)
			(xy 415.44186 -396.632341) (xy 415.450962 -396.684291) (xy 415.451544 -396.710662) (xy 415.451475 -396.720021)
			(xy 415.450332 -396.738703) (xy 415.449258 -396.748) (xy 415.448242 -396.75689) (xy 415.452052 -396.773654)
			(xy 415.495994 -396.843504) (xy 415.50971 -396.853918) (xy 415.518092 -396.856712) (xy 415.542111 -396.865205)
			(xy 415.587284 -396.888752) (xy 415.628091 -396.919245) (xy 415.663472 -396.955896) (xy 415.69251 -396.997751)
			(xy 415.71445 -397.043726) (xy 415.722054 -397.06804) (xy 415.723578 -397.073882) (xy 416.043872 -397.627602)
			(xy 416.047936 -397.63192) (xy 416.064134 -397.649633) (xy 416.091558 -397.689023) (xy 416.112701 -397.732112)
			(xy 416.127076 -397.777904) (xy 416.134352 -397.825346) (xy 416.134804 -397.849344) (xy 416.134347 -397.874148)
			(xy 416.126577 -397.923143) (xy 416.111236 -397.970319) (xy 416.088701 -398.014512) (xy 416.059528 -398.054635)
			(xy 416.024435 -398.089698) (xy 415.984288 -398.118838) (xy 415.940076 -398.141336) (xy 415.892888 -398.156638)
			(xy 415.843886 -398.164367) (xy 415.819082 -398.164812) (xy 415.793687 -398.164327) (xy 415.743553 -398.156194)
			(xy 415.695367 -398.14014) (xy 415.650372 -398.116579) (xy 415.60973 -398.08612) (xy 415.574487 -398.049547)
			(xy 415.545554 -398.007804) (xy 415.523676 -397.961967) (xy 415.51606 -397.937736) (xy 415.514536 -397.931894)
			(xy 415.194242 -397.378174) (xy 415.190178 -397.373856) (xy 415.174023 -397.356118) (xy 415.146653 -397.316718)
			(xy 415.125561 -397.273629) (xy 415.111233 -397.227845) (xy 415.103998 -397.180419) (xy 415.103564 -397.156432)
			(xy 415.103644 -397.144384) (xy 415.105427 -397.120355) (xy 415.10712 -397.108426) (xy 415.10839 -397.099536)
			(xy 415.105342 -397.082518) (xy 415.063178 -397.011652) (xy 415.04997 -397.000476) (xy 415.041588 -396.997428)
			(xy 415.019844 -396.989023) (xy 414.978985 -396.966584) (xy 414.942014 -396.938193) (xy 414.90979 -396.904509)
			(xy 414.883064 -396.866316) (xy 414.862458 -396.824504) (xy 414.84845 -396.780043) (xy 414.841366 -396.73397)
			(xy 414.840928 -396.710662) (xy 414.84149 -396.684289) (xy 414.850574 -396.63233) (xy 414.868464 -396.58271)
			(xy 414.88106 -396.559532) (xy 414.885632 -396.551404) (xy 414.888426 -396.534132) (xy 414.873186 -396.451328)
			(xy 414.864042 -396.436088) (xy 414.85693 -396.4305) (xy 414.834766 -396.411787) (xy 414.794817 -396.369727)
			(xy 414.760498 -396.322961) (xy 414.732358 -396.272236) (xy 414.710847 -396.218364) (xy 414.69631 -396.162208)
			(xy 414.688979 -396.104666) (xy 414.688528 -396.075662) (xy 414.689129 -396.042341) (xy 414.698787 -395.976403)
			(xy 414.717909 -395.912563) (xy 414.731454 -395.882114) (xy 414.735702 -395.871647) (xy 414.735597 -395.849086)
			(xy 414.725859 -395.828735) (xy 414.717484 -395.821154) (xy 414.695214 -395.802507) (xy 414.655152 -395.760446)
			(xy 414.620734 -395.713655) (xy 414.592513 -395.662886) (xy 414.570941 -395.608953) (xy 414.556366 -395.552725)
			(xy 414.549022 -395.495105) (xy 414.548574 -395.466062) (xy 414.549017 -395.437135) (xy 414.556301 -395.379742)
			(xy 414.570761 -395.323725) (xy 414.592166 -395.269977) (xy 414.620174 -395.219356) (xy 414.65434 -395.172668)
			(xy 414.694117 -395.130659) (xy 414.716214 -395.111986) (xy 414.723178 -395.105631) (xy 414.732442 -395.089233)
			(xy 414.734248 -395.079982) (xy 414.738566 -395.048994) (xy 414.739467 -395.039757) (xy 414.735444 -395.021658)
			(xy 414.730692 -395.013688) (xy 414.714383 -394.987843) (xy 414.69048 -394.931607) (xy 414.683194 -394.901928)
			(xy 414.681137 -394.893765) (xy 414.672435 -394.879364) (xy 414.666176 -394.873734) (xy 414.643062 -394.854684)
			(xy 414.636187 -394.849431) (xy 414.619953 -394.84347) (xy 414.611312 -394.843) (xy 414.581677 -394.841945)
			(xy 414.523014 -394.833302) (xy 414.465957 -394.817157) (xy 414.411463 -394.79378) (xy 414.360444 -394.763562)
			(xy 414.313754 -394.727009) (xy 414.272174 -394.684734) (xy 414.236401 -394.637443) (xy 414.207034 -394.58593)
			(xy 414.184564 -394.531055) (xy 414.169367 -394.473739) (xy 414.161699 -394.41494) (xy 414.161224 -394.385292)
			(xy 414.161746 -394.354229) (xy 414.170161 -394.292675) (xy 414.177988 -394.26261) (xy 414.180782 -394.25245)
			(xy 414.178242 -394.232638) (xy 414.130744 -394.150342) (xy 414.114742 -394.13815) (xy 414.104582 -394.13561)
			(xy 414.075471 -394.127613) (xy 414.019503 -394.104981) (xy 413.966996 -394.075188) (xy 413.918861 -394.038751)
			(xy 413.875934 -393.996302) (xy 413.83896 -393.948578) (xy 413.80858 -393.896408) (xy 413.785322 -393.840698)
			(xy 413.76959 -393.782413) (xy 413.761656 -393.722565) (xy 413.761174 -393.69238) (xy 413.761642 -393.661457)
			(xy 413.769926 -393.60017) (xy 413.786392 -393.540558) (xy 413.810742 -393.483709) (xy 413.826198 -393.456922)
			(xy 413.832294 -393.44727) (xy 413.83458 -393.424918) (xy 413.801052 -393.329668) (xy 413.785304 -393.313666)
			(xy 413.774636 -393.309602) (xy 413.751275 -393.300406) (xy 413.707432 -393.275945) (xy 413.667789 -393.24514)
			(xy 413.633256 -393.208698) (xy 413.604626 -393.167457) (xy 413.582557 -393.122363) (xy 413.567555 -393.074452)
			(xy 413.559966 -393.024824) (xy 413.559498 -392.999722) (xy 413.020764 -392.999722) (xy 413.020233 -393.026824)
			(xy 413.011424 -393.080307) (xy 413.003238 -393.106148) (xy 412.999428 -393.11707) (xy 413.001968 -393.139422)
			(xy 413.054546 -393.225274) (xy 413.073596 -393.23772) (xy 413.084772 -393.239498) (xy 413.114096 -393.244173)
			(xy 413.171266 -393.260227) (xy 413.22588 -393.283541) (xy 413.277019 -393.313724) (xy 413.323824 -393.350269)
			(xy 413.365508 -393.392561) (xy 413.401371 -393.439891) (xy 413.430811 -393.491462) (xy 413.453332 -393.546407)
			(xy 413.468556 -393.603805) (xy 413.476227 -393.662689) (xy 413.476694 -393.69238) (xy 413.476169 -393.723443)
			(xy 413.467756 -393.784997) (xy 413.45993 -393.815062) (xy 413.457136 -393.825222) (xy 413.459676 -393.845034)
			(xy 413.507174 -393.92733) (xy 413.523176 -393.939522) (xy 413.533336 -393.942062) (xy 413.562442 -393.950073)
			(xy 413.618409 -393.972705) (xy 413.670915 -394.002498) (xy 413.719048 -394.038934) (xy 413.761975 -394.081381)
			(xy 413.798949 -394.129103) (xy 413.82933 -394.18127) (xy 413.852589 -394.236979) (xy 413.868324 -394.295262)
			(xy 413.87626 -394.355107) (xy 413.876744 -394.385292) (xy 413.876619 -394.399427) (xy 413.874837 -394.427641)
			(xy 413.873188 -394.44168) (xy 413.872423 -394.450287) (xy 413.876065 -394.467168) (xy 413.8803 -394.4747)
			(xy 413.896048 -394.5001) (xy 413.900759 -394.507162) (xy 413.913857 -394.517941) (xy 413.921702 -394.521182)
			(xy 413.945044 -394.530425) (xy 413.988888 -394.554876) (xy 414.028533 -394.585673) (xy 414.063069 -394.622107)
			(xy 414.091702 -394.663342) (xy 414.113774 -394.708431) (xy 414.128779 -394.756338) (xy 414.136371 -394.805961)
			(xy 414.13684 -394.831062) (xy 414.136425 -394.855265) (xy 414.12935 -394.90315) (xy 414.115361 -394.94949)
			(xy 414.094757 -394.993291) (xy 414.081722 -395.013688) (xy 414.076931 -395.021643) (xy 414.0729 -395.039755)
			(xy 414.073848 -395.048994) (xy 414.078166 -395.079982) (xy 414.079858 -395.089275) (xy 414.089133 -395.105717)
			(xy 414.0962 -395.111986) (xy 414.118275 -395.130684) (xy 414.15805 -395.172691) (xy 414.192214 -395.219376)
			(xy 414.220225 -395.269993) (xy 414.241634 -395.323736) (xy 414.256101 -395.379748) (xy 414.263395 -395.437137)
			(xy 414.26384 -395.466062) (xy 414.26325 -395.499383) (xy 414.253588 -395.565322) (xy 414.234462 -395.629161)
			(xy 414.220914 -395.65961) (xy 414.216654 -395.670072) (xy 414.216768 -395.692635) (xy 414.226509 -395.712988)
			(xy 414.234884 -395.72057) (xy 414.257111 -395.739267) (xy 414.297176 -395.781318) (xy 414.331599 -395.8281)
			(xy 414.359826 -395.878861) (xy 414.381405 -395.932785) (xy 414.395988 -395.989007) (xy 414.403341 -396.046621)
			(xy 414.403794 -396.075662) (xy 414.403302 -396.104666) (xy 414.395992 -396.162212) (xy 414.381471 -396.218374)
			(xy 414.359973 -396.272252) (xy 414.331841 -396.322982) (xy 414.297527 -396.369753) (xy 414.25758 -396.411814)
			(xy 414.235392 -396.4305) (xy 414.22828 -396.436088) (xy 414.219136 -396.451328) (xy 414.203896 -396.534132)
			(xy 414.20669 -396.551404) (xy 414.211262 -396.559532) (xy 414.223839 -396.582718) (xy 414.241712 -396.63234)
			(xy 414.250812 -396.684291) (xy 414.251394 -396.710662) (xy 414.251326 -396.720021) (xy 414.250182 -396.738703)
			(xy 414.249108 -396.748) (xy 414.248092 -396.75689) (xy 414.251902 -396.773654) (xy 414.295844 -396.843504)
			(xy 414.30956 -396.853918) (xy 414.317942 -396.856712) (xy 414.341971 -396.865179) (xy 414.387143 -396.888732)
			(xy 414.427948 -396.919232) (xy 414.463327 -396.955887) (xy 414.492362 -396.997746) (xy 414.514301 -397.043724)
			(xy 414.521904 -397.06804) (xy 414.523428 -397.073882) (xy 414.843722 -397.627602) (xy 414.847786 -397.63192)
			(xy 414.863988 -397.649616) (xy 414.891349 -397.689029) (xy 414.912431 -397.732129) (xy 414.926748 -397.777922)
			(xy 414.933972 -397.825354) (xy 414.9344 -397.849344) (xy 414.933923 -397.874133) (xy 414.926161 -397.9231)
			(xy 414.910836 -397.970251) (xy 414.888325 -398.014424) (xy 414.859182 -398.054533) (xy 414.824124 -398.08959)
			(xy 414.784014 -398.118731) (xy 414.73984 -398.141241) (xy 414.692689 -398.156564) (xy 414.643721 -398.164324)
			(xy 414.618932 -398.164812) (xy 414.593539 -398.164283) (xy 414.543406 -398.156158) (xy 414.495221 -398.140111)
			(xy 414.450227 -398.116557) (xy 414.409584 -398.086103) (xy 414.374341 -398.049536) (xy 414.345406 -398.007797)
			(xy 414.323527 -397.961965) (xy 414.31591 -397.937736) (xy 414.314386 -397.931894) (xy 413.994092 -397.378174)
			(xy 413.990028 -397.373856) (xy 413.97383 -397.356143) (xy 413.946403 -397.316754) (xy 413.925259 -397.273666)
			(xy 413.910884 -397.227873) (xy 413.903611 -397.18043) (xy 413.90316 -397.156432) (xy 413.903301 -397.14438)
			(xy 413.905208 -397.12035) (xy 413.90697 -397.108426) (xy 413.90824 -397.099536) (xy 413.905192 -397.082518)
			(xy 413.863028 -397.011652) (xy 413.84982 -397.000476) (xy 413.841438 -396.997428) (xy 413.819683 -396.98905)
			(xy 413.778826 -396.966605) (xy 413.741856 -396.938208) (xy 413.709635 -396.90452) (xy 413.682911 -396.866324)
			(xy 413.662306 -396.824508) (xy 413.648299 -396.780046) (xy 413.641216 -396.73397) (xy 413.640778 -396.710662)
			(xy 413.641347 -396.684289) (xy 413.650429 -396.632331) (xy 413.668316 -396.58271) (xy 413.68091 -396.559532)
			(xy 413.685482 -396.551404) (xy 413.688276 -396.534132) (xy 413.673036 -396.451328) (xy 413.663892 -396.436088)
			(xy 413.65678 -396.4305) (xy 413.634605 -396.411799) (xy 413.594659 -396.369736) (xy 413.560343 -396.322967)
			(xy 413.532205 -396.27224) (xy 413.510695 -396.218367) (xy 413.496159 -396.162209) (xy 413.488829 -396.104666)
			(xy 413.488378 -396.075662) (xy 413.488975 -396.042341) (xy 413.498634 -395.976402) (xy 413.517757 -395.912563)
			(xy 413.531304 -395.882114) (xy 413.535535 -395.871643) (xy 413.53543 -395.849088) (xy 413.525702 -395.828738)
			(xy 413.517334 -395.821154) (xy 413.495074 -395.802495) (xy 413.45501 -395.760438) (xy 413.42059 -395.713649)
			(xy 413.392366 -395.662882) (xy 413.370793 -395.608951) (xy 413.356217 -395.552724) (xy 413.348872 -395.495105)
			(xy 413.348424 -395.466062) (xy 413.348886 -395.437136) (xy 413.356169 -395.379745) (xy 413.370627 -395.323728)
			(xy 413.392029 -395.269981) (xy 413.420034 -395.21936) (xy 413.454196 -395.172671) (xy 413.493969 -395.13066)
			(xy 413.516064 -395.111986) (xy 413.523036 -395.105639) (xy 413.532294 -395.089235) (xy 413.534098 -395.079982)
			(xy 413.538416 -395.048994) (xy 413.539325 -395.039758) (xy 413.535298 -395.021657) (xy 413.530542 -395.013688)
			(xy 413.514238 -394.98784) (xy 413.490332 -394.931606) (xy 413.483044 -394.901928) (xy 413.480973 -394.89377)
			(xy 413.47228 -394.879367) (xy 413.466026 -394.873734) (xy 413.442912 -394.854684) (xy 413.436082 -394.849478)
			(xy 413.419989 -394.843508) (xy 413.411416 -394.843) (xy 413.381781 -394.841941) (xy 413.323118 -394.833299)
			(xy 413.266062 -394.817154) (xy 413.211568 -394.793777) (xy 413.160549 -394.76356) (xy 413.113858 -394.727007)
			(xy 413.072278 -394.684732) (xy 413.036505 -394.637442) (xy 413.007138 -394.585929) (xy 412.984668 -394.531055)
			(xy 412.969471 -394.473739) (xy 412.961803 -394.41494) (xy 412.961328 -394.385292) (xy 412.961849 -394.354229)
			(xy 412.970265 -394.292675) (xy 412.978092 -394.26261) (xy 412.980886 -394.25245) (xy 412.978346 -394.232638)
			(xy 412.930848 -394.150342) (xy 412.914846 -394.13815) (xy 412.904686 -394.13561) (xy 412.875576 -394.12761)
			(xy 412.819608 -394.104979) (xy 412.767101 -394.075186) (xy 412.718966 -394.038749) (xy 412.676038 -393.996301)
			(xy 412.639064 -393.948578) (xy 412.608684 -393.896408) (xy 412.585426 -393.840697) (xy 412.569694 -393.782412)
			(xy 412.56176 -393.722565) (xy 412.561278 -393.69238) (xy 412.561807 -393.661492) (xy 412.570111 -393.600277)
			(xy 412.586567 -393.540733) (xy 412.610876 -393.483941) (xy 412.626302 -393.457176) (xy 412.632144 -393.44727)
			(xy 412.63443 -393.424918) (xy 412.601156 -393.329668) (xy 412.585408 -393.313666) (xy 412.57474 -393.309602)
			(xy 412.551346 -393.300448) (xy 412.507451 -393.276022) (xy 412.467757 -393.245236) (xy 412.433178 -393.208798)
			(xy 412.40451 -393.167547) (xy 412.382414 -393.122434) (xy 412.367399 -393.074496) (xy 412.35981 -393.024839)
			(xy 412.359348 -392.999722) (xy 411.820868 -392.999722) (xy 411.820337 -393.026824) (xy 411.811528 -393.080307)
			(xy 411.803342 -393.106148) (xy 411.799532 -393.11707) (xy 411.802072 -393.139422) (xy 411.85465 -393.225274)
			(xy 411.8737 -393.23772) (xy 411.884876 -393.239498) (xy 411.9142 -393.24417) (xy 411.971371 -393.260224)
			(xy 412.025985 -393.283539) (xy 412.077124 -393.313722) (xy 412.123928 -393.350268) (xy 412.165613 -393.39256)
			(xy 412.201476 -393.43989) (xy 412.230915 -393.491461) (xy 412.253436 -393.546407) (xy 412.26866 -393.603804)
			(xy 412.276331 -393.662689) (xy 412.276798 -393.69238) (xy 412.276274 -393.723506) (xy 412.267869 -393.785188)
			(xy 412.260034 -393.815316) (xy 412.25724 -393.825476) (xy 412.25978 -393.845542) (xy 412.307024 -393.92733)
			(xy 412.323026 -393.939522) (xy 412.333186 -393.942062) (xy 412.362302 -393.950039) (xy 412.418268 -393.972677)
			(xy 412.470773 -394.002475) (xy 412.518905 -394.038916) (xy 412.56183 -394.081367) (xy 412.598803 -394.129092)
			(xy 412.629183 -394.181263) (xy 412.652441 -394.236974) (xy 412.668175 -394.295259) (xy 412.676111 -394.355106)
			(xy 412.676594 -394.385292) (xy 412.676469 -394.399427) (xy 412.674687 -394.427641) (xy 412.673038 -394.44168)
			(xy 412.67228 -394.450287) (xy 412.675918 -394.467167) (xy 412.68015 -394.4747) (xy 412.695898 -394.5001)
			(xy 412.700605 -394.507162) (xy 412.713713 -394.51793) (xy 412.721552 -394.521182) (xy 412.744938 -394.530353)
			(xy 412.788833 -394.554777) (xy 412.828528 -394.585561) (xy 412.863107 -394.621996) (xy 412.891776 -394.663244)
			(xy 412.913873 -394.708355) (xy 412.92889 -394.75629) (xy 412.936481 -394.805946) (xy 412.936944 -394.831062)
			(xy 412.936528 -394.855265) (xy 412.929453 -394.90315) (xy 412.915464 -394.94949) (xy 412.894861 -394.993291)
			(xy 412.881826 -395.013688) (xy 412.877035 -395.021643) (xy 412.873004 -395.039756) (xy 412.873952 -395.048994)
			(xy 412.87827 -395.079982) (xy 412.879961 -395.089276) (xy 412.889236 -395.105718) (xy 412.896304 -395.111986)
			(xy 412.91838 -395.130683) (xy 412.958154 -395.17269) (xy 412.992319 -395.219375) (xy 413.020329 -395.269992)
			(xy 413.041738 -395.323736) (xy 413.056205 -395.379748) (xy 413.063499 -395.437137) (xy 413.063944 -395.466062)
			(xy 413.063354 -395.499383) (xy 413.053691 -395.565322) (xy 413.034566 -395.629161) (xy 413.021018 -395.65961)
			(xy 413.016757 -395.670071) (xy 413.01687 -395.692635) (xy 413.026612 -395.712988) (xy 413.034988 -395.72057)
			(xy 413.057216 -395.739266) (xy 413.097281 -395.781317) (xy 413.131703 -395.828099) (xy 413.159931 -395.878861)
			(xy 413.181509 -395.932785) (xy 413.196092 -395.989007) (xy 413.203445 -396.046621) (xy 413.203898 -396.075662)
			(xy 413.20344 -396.104668) (xy 413.196129 -396.162216) (xy 413.181605 -396.21838) (xy 413.160102 -396.272259)
			(xy 413.131964 -396.322989) (xy 413.097642 -396.369758) (xy 413.057687 -396.411816) (xy 413.035496 -396.4305)
			(xy 413.028384 -396.436088) (xy 413.01924 -396.451328) (xy 413.004 -396.534132) (xy 413.006794 -396.551404)
			(xy 413.011366 -396.559532) (xy 413.023943 -396.582718) (xy 413.041816 -396.63234) (xy 413.050916 -396.684291)
			(xy 413.051498 -396.710662) (xy 413.05143 -396.720021) (xy 413.050286 -396.738703) (xy 413.049212 -396.748)
			(xy 413.048196 -396.75689) (xy 413.052006 -396.773654) (xy 413.095948 -396.843504) (xy 413.109664 -396.853918)
			(xy 413.118046 -396.856712) (xy 413.142076 -396.865177) (xy 413.187248 -396.88873) (xy 413.228052 -396.91923)
			(xy 413.263431 -396.955886) (xy 413.292467 -396.997746) (xy 413.314405 -397.043724) (xy 413.322008 -397.06804)
			(xy 413.323532 -397.073882) (xy 413.643826 -397.627602) (xy 413.64789 -397.63192) (xy 413.664093 -397.649616)
			(xy 413.691453 -397.689029) (xy 413.712535 -397.732129) (xy 413.726852 -397.777922) (xy 413.734076 -397.825354)
			(xy 413.734504 -397.849344) (xy 413.734023 -397.874133) (xy 413.726261 -397.9231) (xy 413.710937 -397.97025)
			(xy 413.688426 -398.014423) (xy 413.659283 -398.054532) (xy 413.624226 -398.089588) (xy 413.584116 -398.11873)
			(xy 413.539943 -398.14124) (xy 413.492792 -398.156563) (xy 413.443825 -398.164323) (xy 413.419036 -398.164812)
			(xy 413.393643 -398.16428) (xy 413.343511 -398.156155) (xy 413.295326 -398.140109) (xy 413.250331 -398.116555)
			(xy 413.209688 -398.086102) (xy 413.174445 -398.049535) (xy 413.14551 -398.007797) (xy 413.123631 -397.961965)
			(xy 413.116014 -397.937736) (xy 413.11449 -397.931894) (xy 412.794196 -397.378174) (xy 412.790132 -397.373856)
			(xy 412.773917 -397.356158) (xy 412.746497 -397.316763) (xy 412.725358 -397.273671) (xy 412.710986 -397.227875)
			(xy 412.703714 -397.180431) (xy 412.703264 -397.156432) (xy 412.703405 -397.14438) (xy 412.705312 -397.12035)
			(xy 412.707074 -397.108426) (xy 412.708344 -397.099536) (xy 412.705296 -397.082518) (xy 412.663132 -397.011652)
			(xy 412.649924 -397.000476) (xy 412.641542 -396.997428) (xy 412.619788 -396.989048) (xy 412.57893 -396.966604)
			(xy 412.541961 -396.938207) (xy 412.509739 -396.904519) (xy 412.483015 -396.866324) (xy 412.46241 -396.824508)
			(xy 412.448403 -396.780046) (xy 412.44132 -396.73397) (xy 412.440882 -396.710662) (xy 412.44145 -396.684289)
			(xy 412.450532 -396.632331) (xy 412.46842 -396.58271) (xy 412.481014 -396.559532) (xy 412.485586 -396.551404)
			(xy 412.48838 -396.534132) (xy 412.47314 -396.451328) (xy 412.463996 -396.436088) (xy 412.456884 -396.4305)
			(xy 412.43471 -396.411798) (xy 412.394764 -396.369735) (xy 412.360447 -396.322967) (xy 412.332309 -396.27224)
			(xy 412.3108 -396.218367) (xy 412.296263 -396.162209) (xy 412.288933 -396.104666) (xy 412.288482 -396.075662)
			(xy 412.289078 -396.042341) (xy 412.298738 -395.976402) (xy 412.317861 -395.912563) (xy 412.331408 -395.882114)
			(xy 412.335638 -395.871643) (xy 412.335532 -395.849088) (xy 412.325805 -395.828739) (xy 412.317438 -395.821154)
			(xy 412.295179 -395.802494) (xy 412.255115 -395.760437) (xy 412.220694 -395.713649) (xy 412.19247 -395.662881)
			(xy 412.170897 -395.608951) (xy 412.156321 -395.552724) (xy 412.148976 -395.495105) (xy 412.148528 -395.466062)
			(xy 412.148988 -395.437136) (xy 412.156271 -395.379744) (xy 412.17073 -395.323728) (xy 412.192132 -395.269981)
			(xy 412.220138 -395.219359) (xy 412.2543 -395.172671) (xy 412.294073 -395.13066) (xy 412.316168 -395.111986)
			(xy 412.323141 -395.10564) (xy 412.332398 -395.089235) (xy 412.334202 -395.079982) (xy 412.33852 -395.048994)
			(xy 412.339428 -395.039757) (xy 412.335402 -395.021657) (xy 412.330646 -395.013688) (xy 412.314342 -394.98784)
			(xy 412.290436 -394.931606) (xy 412.283148 -394.901928) (xy 412.281076 -394.89377) (xy 412.272383 -394.879368)
			(xy 412.26613 -394.873734) (xy 412.243016 -394.854684) (xy 412.236127 -394.849452) (xy 412.219903 -394.843478)
			(xy 412.211266 -394.843) (xy 412.18163 -394.841987) (xy 412.122965 -394.833338) (xy 412.065908 -394.817188)
			(xy 412.011414 -394.793806) (xy 411.960394 -394.763583) (xy 411.913705 -394.727027) (xy 411.872125 -394.684748)
			(xy 411.836353 -394.637454) (xy 411.806986 -394.585938) (xy 411.784517 -394.531061) (xy 411.769321 -394.473742)
			(xy 411.761653 -394.414941) (xy 411.761178 -394.385292) (xy 411.761698 -394.354229) (xy 411.770115 -394.292675)
			(xy 411.777942 -394.26261) (xy 411.780736 -394.25245) (xy 411.778196 -394.232638) (xy 411.730698 -394.150342)
			(xy 411.714696 -394.13815) (xy 411.704536 -394.13561) (xy 411.675448 -394.127576) (xy 411.619521 -394.10491)
			(xy 411.567056 -394.075094) (xy 411.518962 -394.038646) (xy 411.476071 -393.996196) (xy 411.439128 -393.94848)
			(xy 411.408773 -393.896325) (xy 411.385531 -393.840635) (xy 411.369806 -393.782374) (xy 411.361869 -393.722553)
			(xy 411.361382 -393.69238) (xy 411.36191 -393.661492) (xy 411.370215 -393.600277) (xy 411.386671 -393.540733)
			(xy 411.41098 -393.483941) (xy 411.426406 -393.457176) (xy 411.432248 -393.44727) (xy 411.434534 -393.424918)
			(xy 411.40126 -393.329668) (xy 411.385512 -393.313666) (xy 411.374844 -393.309602) (xy 411.351451 -393.300446)
			(xy 411.307556 -393.276021) (xy 411.267861 -393.245235) (xy 411.233282 -393.208797) (xy 411.204614 -393.167547)
			(xy 411.182518 -393.122433) (xy 411.167503 -393.074496) (xy 411.159914 -393.024839) (xy 411.159452 -392.999722)
			(xy 410.620718 -392.999722) (xy 410.620185 -393.026824) (xy 410.611377 -393.080306) (xy 410.603192 -393.106148)
			(xy 410.599382 -393.11707) (xy 410.601922 -393.139422) (xy 410.6545 -393.225274) (xy 410.67355 -393.23772)
			(xy 410.684726 -393.239498) (xy 410.714043 -393.244209) (xy 410.771214 -393.260257) (xy 410.825828 -393.283566)
			(xy 410.876968 -393.313745) (xy 410.923773 -393.350286) (xy 410.965459 -393.392574) (xy 411.001323 -393.439901)
			(xy 411.030763 -393.491469) (xy 411.053285 -393.546412) (xy 411.068509 -393.603807) (xy 411.076181 -393.66269)
			(xy 411.076648 -393.69238) (xy 411.076121 -393.723443) (xy 411.067709 -393.784996) (xy 411.059884 -393.815062)
			(xy 411.05709 -393.825222) (xy 411.05963 -393.845034) (xy 411.107128 -393.92733) (xy 411.12313 -393.939522)
			(xy 411.13329 -393.942062) (xy 411.162407 -393.950036) (xy 411.218373 -393.972675) (xy 411.270877 -394.002474)
			(xy 411.31901 -394.038915) (xy 411.361935 -394.081366) (xy 411.398908 -394.129092) (xy 411.429287 -394.181263)
			(xy 411.452545 -394.236974) (xy 411.468279 -394.295259) (xy 411.476215 -394.355106) (xy 411.476698 -394.385292)
			(xy 411.476573 -394.399427) (xy 411.474791 -394.427641) (xy 411.473142 -394.44168) (xy 411.472383 -394.450287)
			(xy 411.476022 -394.467167) (xy 411.480254 -394.4747) (xy 411.496002 -394.5001) (xy 411.500708 -394.507163)
			(xy 411.513816 -394.51793) (xy 411.521656 -394.521182) (xy 411.545043 -394.530351) (xy 411.588938 -394.554775)
			(xy 411.628632 -394.585559) (xy 411.663212 -394.621995) (xy 411.69188 -394.663244) (xy 411.713977 -394.708355)
			(xy 411.728994 -394.75629) (xy 411.736585 -394.805946) (xy 411.737048 -394.831062) (xy 411.736631 -394.855264)
			(xy 411.729557 -394.90315) (xy 411.715568 -394.94949) (xy 411.694965 -394.993291) (xy 411.68193 -395.013688)
			(xy 411.677139 -395.021643) (xy 411.673108 -395.039756) (xy 411.674056 -395.048994) (xy 411.678374 -395.079982)
			(xy 411.680064 -395.089276) (xy 411.68934 -395.105718) (xy 411.696408 -395.111986) (xy 411.718484 -395.130682)
			(xy 411.758259 -395.17269) (xy 411.792423 -395.219375) (xy 411.820433 -395.269992) (xy 411.841842 -395.323735)
			(xy 411.856309 -395.379748) (xy 411.863603 -395.437137) (xy 411.864048 -395.466062) (xy 411.863458 -395.499383)
			(xy 411.853795 -395.565322) (xy 411.834669 -395.629161) (xy 411.821122 -395.65961) (xy 411.81686 -395.670071)
			(xy 411.816973 -395.692635) (xy 411.826716 -395.712988) (xy 411.835092 -395.72057) (xy 411.857321 -395.739265)
			(xy 411.897385 -395.781316) (xy 411.931808 -395.828099) (xy 411.960035 -395.87886) (xy 411.981613 -395.932785)
			(xy 411.996196 -395.989006) (xy 412.003549 -396.046621) (xy 412.004002 -396.075662) (xy 412.003543 -396.104668)
			(xy 411.996231 -396.162216) (xy 411.981708 -396.21838) (xy 411.960205 -396.272259) (xy 411.932067 -396.322989)
			(xy 411.897746 -396.369758) (xy 411.857791 -396.411816) (xy 411.8356 -396.4305) (xy 411.828488 -396.436088)
			(xy 411.819344 -396.451328) (xy 411.804104 -396.534132) (xy 411.806898 -396.551404) (xy 411.81147 -396.559532)
			(xy 411.824039 -396.582722) (xy 411.841917 -396.632341) (xy 411.85102 -396.684292) (xy 411.851602 -396.710662)
			(xy 411.851534 -396.720021) (xy 411.85039 -396.738703) (xy 411.849316 -396.748) (xy 411.8483 -396.75689)
			(xy 411.85211 -396.773654) (xy 411.896052 -396.843504) (xy 411.909768 -396.853918) (xy 411.91815 -396.856712)
			(xy 411.942238 -396.865219) (xy 411.98753 -396.888837) (xy 412.028427 -396.919442) (xy 412.06386 -396.956235)
			(xy 412.092905 -396.998254) (xy 412.114803 -397.044402) (xy 412.122366 -397.068802) (xy 412.12389 -397.074644)
			(xy 412.443676 -397.627602) (xy 412.44774 -397.63192) (xy 412.463938 -397.649633) (xy 412.491362 -397.689023)
			(xy 412.512505 -397.732111) (xy 412.52688 -397.777904) (xy 412.534156 -397.825346) (xy 412.534608 -397.849344)
			(xy 412.534147 -397.874147) (xy 412.526377 -397.923142) (xy 412.511036 -397.970318) (xy 412.488501 -398.014511)
			(xy 412.459329 -398.054634) (xy 412.424237 -398.089697) (xy 412.384091 -398.118836) (xy 412.339879 -398.141335)
			(xy 412.292691 -398.156637) (xy 412.24369 -398.164367) (xy 412.218886 -398.164812) (xy 412.193491 -398.164324)
			(xy 412.143357 -398.156191) (xy 412.095171 -398.140138) (xy 412.050177 -398.116577) (xy 412.009534 -398.086118)
			(xy 411.974292 -398.049546) (xy 411.945358 -398.007803) (xy 411.92348 -397.961967) (xy 411.915864 -397.937736)
			(xy 411.91434 -397.931894) (xy 411.593792 -397.377412) (xy 411.589728 -397.373094) (xy 411.573621 -397.355428)
			(xy 411.546374 -397.316148) (xy 411.525364 -397.273206) (xy 411.511073 -397.227587) (xy 411.503826 -397.180334)
			(xy 411.503368 -397.156432) (xy 411.50351 -397.14438) (xy 411.505416 -397.12035) (xy 411.507178 -397.108426)
			(xy 411.508448 -397.099536) (xy 411.5054 -397.082518) (xy 411.463236 -397.011652) (xy 411.450028 -397.000476)
			(xy 411.441646 -396.997428) (xy 411.419893 -396.989046) (xy 411.379035 -396.966602) (xy 411.342066 -396.938206)
			(xy 411.309844 -396.904518) (xy 411.283119 -396.866323) (xy 411.262514 -396.824508) (xy 411.248507 -396.780045)
			(xy 411.241424 -396.73397) (xy 411.240986 -396.710662) (xy 411.241554 -396.684289) (xy 411.250636 -396.632331)
			(xy 411.268524 -396.58271) (xy 411.281118 -396.559532) (xy 411.28569 -396.551404) (xy 411.288484 -396.534132)
			(xy 411.273244 -396.451328) (xy 411.2641 -396.436088) (xy 411.256988 -396.4305) (xy 411.234815 -396.411797)
			(xy 411.194868 -396.369735) (xy 411.160551 -396.322966) (xy 411.132413 -396.272239) (xy 411.110904 -396.218366)
			(xy 411.096367 -396.162209) (xy 411.089037 -396.104666) (xy 411.088586 -396.075662) (xy 411.089182 -396.042341)
			(xy 411.098841 -395.976402) (xy 411.117965 -395.912563) (xy 411.131512 -395.882114) (xy 411.135741 -395.871643)
			(xy 411.135636 -395.849088) (xy 411.125909 -395.828739) (xy 411.117542 -395.821154) (xy 411.095284 -395.802493)
			(xy 411.055219 -395.760436) (xy 411.020799 -395.713648) (xy 410.992575 -395.662881) (xy 410.971001 -395.608951)
			(xy 410.956425 -395.552724) (xy 410.94908 -395.495105) (xy 410.948632 -395.466062) (xy 410.949091 -395.437136)
			(xy 410.956374 -395.379744) (xy 410.970832 -395.323728) (xy 410.992235 -395.269981) (xy 411.020241 -395.219359)
			(xy 411.054403 -395.172671) (xy 411.094177 -395.13066) (xy 411.116272 -395.111986) (xy 411.123246 -395.105641)
			(xy 411.132502 -395.089235) (xy 411.134306 -395.079982) (xy 411.138624 -395.048994) (xy 411.139532 -395.039757)
			(xy 411.135505 -395.021657) (xy 411.13075 -395.013688) (xy 411.114438 -394.987845) (xy 411.090537 -394.931608)
			(xy 411.083252 -394.901928) (xy 411.081179 -394.89377) (xy 411.072487 -394.879368) (xy 411.066234 -394.873734)
			(xy 411.04312 -394.854684) (xy 411.036229 -394.849454) (xy 411.020007 -394.843479) (xy 411.01137 -394.843)
			(xy 410.981734 -394.841983) (xy 410.923069 -394.833335) (xy 410.866012 -394.817185) (xy 410.811518 -394.793804)
			(xy 410.760499 -394.763582) (xy 410.713809 -394.727025) (xy 410.67223 -394.684746) (xy 410.636457 -394.637453)
			(xy 410.607091 -394.585937) (xy 410.584621 -394.53106) (xy 410.569425 -394.473742) (xy 410.561757 -394.414941)
			(xy 410.561282 -394.385292) (xy 410.561802 -394.354229) (xy 410.570219 -394.292675) (xy 410.578046 -394.26261)
			(xy 410.58084 -394.25245) (xy 410.5783 -394.232638) (xy 410.530802 -394.150342) (xy 410.5148 -394.13815)
			(xy 410.50464 -394.13561) (xy 410.475521 -394.127641) (xy 410.419554 -394.105004) (xy 410.367047 -394.075206)
			(xy 410.318913 -394.038765) (xy 410.275987 -393.996313) (xy 410.239014 -393.948587) (xy 410.208635 -393.896415)
			(xy 410.185378 -393.840702) (xy 410.169647 -393.782415) (xy 410.161713 -393.722566) (xy 410.161232 -393.69238)
			(xy 410.161753 -393.661492) (xy 410.170059 -393.600276) (xy 410.186517 -393.540732) (xy 410.210829 -393.48394)
			(xy 410.226256 -393.457176) (xy 410.232098 -393.44727) (xy 410.234384 -393.424918) (xy 410.20111 -393.329668)
			(xy 410.185362 -393.313666) (xy 410.174694 -393.309602) (xy 410.151312 -393.300419) (xy 410.107415 -393.276)
			(xy 410.067719 -393.245219) (xy 410.033137 -393.208786) (xy 410.004468 -393.167539) (xy 409.98237 -393.122428)
			(xy 409.967354 -393.074493) (xy 409.959764 -393.024838) (xy 409.959302 -392.999722) (xy 409.420822 -392.999722)
			(xy 409.420293 -393.026824) (xy 409.411483 -393.080307) (xy 409.403296 -393.106148) (xy 409.399486 -393.11707)
			(xy 409.402026 -393.139422) (xy 409.454604 -393.225274) (xy 409.473654 -393.23772) (xy 409.48483 -393.239498)
			(xy 409.514148 -393.244206) (xy 409.571319 -393.260254) (xy 409.625933 -393.283564) (xy 409.677072 -393.313743)
			(xy 409.723878 -393.350284) (xy 409.765563 -393.392573) (xy 409.801427 -393.4399) (xy 409.830867 -393.491468)
			(xy 409.853389 -393.546412) (xy 409.868613 -393.603807) (xy 409.876285 -393.66269) (xy 409.876752 -393.69238)
			(xy 409.876225 -393.723443) (xy 409.867813 -393.784996) (xy 409.859988 -393.815062) (xy 409.857194 -393.825222)
			(xy 409.859734 -393.845034) (xy 409.907232 -393.92733) (xy 409.923234 -393.939522) (xy 409.933394 -393.942062)
			(xy 409.962511 -393.950034) (xy 410.018477 -393.972673) (xy 410.070982 -394.002472) (xy 410.119114 -394.038913)
			(xy 410.162039 -394.081365) (xy 410.199012 -394.129091) (xy 410.229391 -394.181262) (xy 410.252649 -394.236974)
			(xy 410.268383 -394.295259) (xy 410.276319 -394.355106) (xy 410.276802 -394.385292) (xy 410.276677 -394.399427)
			(xy 410.274895 -394.427641) (xy 410.273246 -394.44168) (xy 410.272487 -394.450287) (xy 410.276126 -394.467167)
			(xy 410.280358 -394.4747) (xy 410.296106 -394.5001) (xy 410.300798 -394.507176) (xy 410.313909 -394.517948)
			(xy 410.32176 -394.521182) (xy 410.345115 -394.530394) (xy 410.388957 -394.554852) (xy 410.4286 -394.585655)
			(xy 410.463133 -394.622095) (xy 410.491764 -394.663334) (xy 410.513834 -394.708425) (xy 410.528838 -394.756334)
			(xy 410.536429 -394.80596) (xy 410.536898 -394.831062) (xy 410.536473 -394.855264) (xy 410.5294 -394.903149)
			(xy 410.515413 -394.949488) (xy 410.494813 -394.99329) (xy 410.48178 -395.013688) (xy 410.476993 -395.021645)
			(xy 410.472958 -395.039756) (xy 410.473906 -395.048994) (xy 410.478224 -395.079982) (xy 410.479899 -395.08928)
			(xy 410.489184 -395.105721) (xy 410.496258 -395.111986) (xy 410.518345 -395.130669) (xy 410.558117 -395.172681)
			(xy 410.592279 -395.219368) (xy 410.620287 -395.269988) (xy 410.641694 -395.323733) (xy 410.65616 -395.379747)
			(xy 410.663453 -395.437136) (xy 410.663898 -395.466062) (xy 410.663312 -395.499384) (xy 410.653649 -395.565322)
			(xy 410.634521 -395.629161) (xy 410.620972 -395.65961) (xy 410.616726 -395.670075) (xy 410.61684 -395.692634)
			(xy 410.626573 -395.712985) (xy 410.634942 -395.72057) (xy 410.65716 -395.739277) (xy 410.697227 -395.781325)
			(xy 410.731652 -395.828105) (xy 410.759882 -395.878864) (xy 410.781462 -395.932787) (xy 410.796046 -395.989008)
			(xy 410.803399 -396.046621) (xy 410.803852 -396.075662) (xy 410.803375 -396.104667) (xy 410.796064 -396.162214)
			(xy 410.781542 -396.218377) (xy 410.760042 -396.272255) (xy 410.731908 -396.322985) (xy 410.69759 -396.369755)
			(xy 410.657639 -396.411815) (xy 410.63545 -396.4305) (xy 410.628338 -396.436088) (xy 410.619194 -396.451328)
			(xy 410.603954 -396.534132) (xy 410.606748 -396.551404) (xy 410.61132 -396.559532) (xy 410.623893 -396.582719)
			(xy 410.641769 -396.63234) (xy 410.65087 -396.684291) (xy 410.651452 -396.710662) (xy 410.651383 -396.720021)
			(xy 410.65024 -396.738703) (xy 410.649166 -396.748) (xy 410.64815 -396.75689) (xy 410.65196 -396.773654)
			(xy 410.695902 -396.843504) (xy 410.709618 -396.853918) (xy 410.718 -396.856712) (xy 410.74202 -396.865201)
			(xy 410.787194 -396.888748) (xy 410.828 -396.919243) (xy 410.863381 -396.955894) (xy 410.892418 -396.99775)
			(xy 410.914358 -397.043726) (xy 410.921962 -397.06804) (xy 410.923486 -397.073882) (xy 411.24378 -397.627602)
			(xy 411.247844 -397.63192) (xy 411.264043 -397.649632) (xy 411.291466 -397.689023) (xy 411.312609 -397.732111)
			(xy 411.326984 -397.777904) (xy 411.33426 -397.825346) (xy 411.334712 -397.849344) (xy 411.334247 -397.874147)
			(xy 411.326477 -397.923142) (xy 411.311136 -397.970317) (xy 411.288602 -398.01451) (xy 411.25943 -398.054632)
			(xy 411.224339 -398.089695) (xy 411.184193 -398.118835) (xy 411.139982 -398.141334) (xy 411.092794 -398.156637)
			(xy 411.043794 -398.164367) (xy 411.01899 -398.164812) (xy 410.993595 -398.16432) (xy 410.943461 -398.156188)
			(xy 410.895276 -398.140135) (xy 410.850281 -398.116576) (xy 410.809639 -398.086117) (xy 410.774396 -398.049545)
			(xy 410.745463 -398.007803) (xy 410.723585 -397.961967) (xy 410.715968 -397.937736) (xy 410.714444 -397.931894)
			(xy 410.39415 -397.378174) (xy 410.390086 -397.373856) (xy 410.373932 -397.356117) (xy 410.346562 -397.316717)
			(xy 410.32547 -397.273629) (xy 410.311141 -397.227844) (xy 410.303906 -397.180419) (xy 410.303472 -397.156432)
			(xy 410.303552 -397.144384) (xy 410.305335 -397.120355) (xy 410.307028 -397.108426) (xy 410.308298 -397.099536)
			(xy 410.30525 -397.082518) (xy 410.263086 -397.011652) (xy 410.249878 -397.000476) (xy 410.241496 -396.997428)
			(xy 410.219754 -396.989019) (xy 410.178895 -396.966581) (xy 410.141923 -396.93819) (xy 410.109699 -396.904507)
			(xy 410.082973 -396.866315) (xy 410.062366 -396.824503) (xy 410.048358 -396.780043) (xy 410.041274 -396.733969)
			(xy 410.040836 -396.710662) (xy 410.041397 -396.684289) (xy 410.050481 -396.63233) (xy 410.068372 -396.58271)
			(xy 410.080968 -396.559532) (xy 410.08554 -396.551404) (xy 410.088334 -396.534132) (xy 410.073094 -396.451328)
			(xy 410.06395 -396.436088) (xy 410.056838 -396.4305) (xy 410.034675 -396.411785) (xy 409.994726 -396.369726)
			(xy 409.960407 -396.32296) (xy 409.932267 -396.272236) (xy 409.910756 -396.218364) (xy 409.896218 -396.162208)
			(xy 409.888887 -396.104666) (xy 409.888436 -396.075662) (xy 409.889036 -396.042341) (xy 409.898695 -395.976403)
			(xy 409.917817 -395.912563) (xy 409.931362 -395.882114) (xy 409.935607 -395.871647) (xy 409.935502 -395.849087)
			(xy 409.925766 -395.828735) (xy 409.917392 -395.821154) (xy 409.895123 -395.802505) (xy 409.855062 -395.760445)
			(xy 409.820643 -395.713654) (xy 409.792421 -395.662885) (xy 409.770849 -395.608953) (xy 409.756274 -395.552725)
			(xy 409.74893 -395.495105) (xy 409.748482 -395.466062) (xy 409.748922 -395.437135) (xy 409.756207 -395.379742)
			(xy 409.770667 -395.323725) (xy 409.792072 -395.269977) (xy 409.820081 -395.219355) (xy 409.854247 -395.172668)
			(xy 409.894025 -395.130659) (xy 409.916122 -395.111986) (xy 409.923088 -395.105632) (xy 409.93235 -395.089234)
			(xy 409.934156 -395.079982) (xy 409.938474 -395.048994) (xy 409.939374 -395.039757) (xy 409.935352 -395.021658)
			(xy 409.9306 -395.013688) (xy 409.914292 -394.987843) (xy 409.890388 -394.931607) (xy 409.883102 -394.901928)
			(xy 409.881042 -394.893766) (xy 409.872342 -394.879365) (xy 409.866084 -394.873734) (xy 409.84297 -394.854684)
			(xy 409.836151 -394.849461) (xy 409.82005 -394.843501) (xy 409.811474 -394.843) (xy 409.781838 -394.84198)
			(xy 409.723173 -394.833332) (xy 409.666116 -394.817183) (xy 409.611622 -394.793801) (xy 409.560603 -394.76358)
			(xy 409.513913 -394.727024) (xy 409.472334 -394.684745) (xy 409.436561 -394.637452) (xy 409.407195 -394.585936)
			(xy 409.384725 -394.53106) (xy 409.369529 -394.473742) (xy 409.361861 -394.414941) (xy 409.361386 -394.385292)
			(xy 409.361906 -394.354229) (xy 409.370322 -394.292675) (xy 409.37815 -394.26261) (xy 409.380944 -394.25245)
			(xy 409.378404 -394.232638) (xy 409.330906 -394.150342) (xy 409.314904 -394.13815) (xy 409.304744 -394.13561)
			(xy 409.275626 -394.127639) (xy 409.219658 -394.105002) (xy 409.167152 -394.075205) (xy 409.119018 -394.038764)
			(xy 409.076092 -393.996312) (xy 409.039118 -393.948586) (xy 409.00874 -393.896414) (xy 408.985483 -393.840701)
			(xy 408.969751 -393.782415) (xy 408.961817 -393.722566) (xy 408.961336 -393.69238) (xy 408.961857 -393.661492)
			(xy 408.970162 -393.600276) (xy 408.986621 -393.540732) (xy 409.010932 -393.48394) (xy 409.02636 -393.457176)
			(xy 409.032202 -393.44727) (xy 409.034488 -393.424918) (xy 409.001214 -393.329668) (xy 408.985466 -393.313666)
			(xy 408.974798 -393.309602) (xy 408.951417 -393.300417) (xy 408.90752 -393.275998) (xy 408.867823 -393.245218)
			(xy 408.833242 -393.208785) (xy 408.804572 -393.167538) (xy 408.782474 -393.122428) (xy 408.767458 -393.074493)
			(xy 408.759868 -393.024838) (xy 408.759406 -392.999722) (xy 408.220926 -392.999722) (xy 408.220397 -393.026824)
			(xy 408.211587 -393.080307) (xy 408.2034 -393.106148) (xy 408.19959 -393.11707) (xy 408.20213 -393.139422)
			(xy 408.254708 -393.225528) (xy 408.273504 -393.23772) (xy 408.284934 -393.239498) (xy 408.314222 -393.244313)
			(xy 408.371356 -393.260385) (xy 408.425933 -393.283709) (xy 408.477035 -393.313894) (xy 408.523807 -393.350432)
			(xy 408.565462 -393.392711) (xy 408.601301 -393.440021) (xy 408.630722 -393.491567) (xy 408.653232 -393.546484)
			(xy 408.668453 -393.603851) (xy 408.676129 -393.662704) (xy 408.676602 -393.69238) (xy 408.676077 -393.723443)
			(xy 408.667664 -393.784997) (xy 408.659838 -393.815062) (xy 408.657044 -393.825222) (xy 408.659584 -393.845034)
			(xy 408.707082 -393.92733) (xy 408.723084 -393.939522) (xy 408.733244 -393.942062) (xy 408.762352 -393.950067)
			(xy 408.818318 -393.9727) (xy 408.870824 -394.002494) (xy 408.918958 -394.038931) (xy 408.961884 -394.081379)
			(xy 408.998858 -394.129101) (xy 409.029239 -394.181269) (xy 409.052498 -394.236978) (xy 409.068232 -394.295261)
			(xy 409.076169 -394.355107) (xy 409.076652 -394.385292) (xy 409.076527 -394.399427) (xy 409.074745 -394.427641)
			(xy 409.073096 -394.44168) (xy 409.072329 -394.450287) (xy 409.075972 -394.467168) (xy 409.080208 -394.4747)
			(xy 409.095956 -394.5001) (xy 409.100676 -394.507152) (xy 409.113774 -394.517925) (xy 409.12161 -394.521182)
			(xy 409.144987 -394.530376) (xy 409.188883 -394.554794) (xy 409.228579 -394.585574) (xy 409.263161 -394.622005)
			(xy 409.291831 -394.663251) (xy 409.313929 -394.708359) (xy 409.328947 -394.756293) (xy 409.336539 -394.805946)
			(xy 409.337002 -394.831062) (xy 409.336576 -394.855264) (xy 409.329503 -394.903149) (xy 409.315517 -394.949488)
			(xy 409.294917 -394.99329) (xy 409.281884 -395.013688) (xy 409.277097 -395.021645) (xy 409.273062 -395.039756)
			(xy 409.27401 -395.048994) (xy 409.278328 -395.079982) (xy 409.280001 -395.08928) (xy 409.289288 -395.105722)
			(xy 409.296362 -395.111986) (xy 409.31845 -395.130668) (xy 409.358222 -395.17268) (xy 409.392384 -395.219368)
			(xy 409.420391 -395.269988) (xy 409.441799 -395.323733) (xy 409.456264 -395.379746) (xy 409.463557 -395.437136)
			(xy 409.464002 -395.466062) (xy 409.463416 -395.499384) (xy 409.453752 -395.565322) (xy 409.434625 -395.629161)
			(xy 409.421076 -395.65961) (xy 409.416829 -395.670075) (xy 409.416943 -395.692634) (xy 409.426676 -395.712985)
			(xy 409.435046 -395.72057) (xy 409.457265 -395.739276) (xy 409.497332 -395.781324) (xy 409.531757 -395.828104)
			(xy 409.559986 -395.878864) (xy 409.581566 -395.932787) (xy 409.59615 -395.989008) (xy 409.603503 -396.046621)
			(xy 409.603956 -396.075662) (xy 409.603478 -396.104667) (xy 409.596167 -396.162214) (xy 409.581645 -396.218376)
			(xy 409.560145 -396.272255) (xy 409.532011 -396.322985) (xy 409.497694 -396.369755) (xy 409.457743 -396.411815)
			(xy 409.435554 -396.4305) (xy 409.428442 -396.436088) (xy 409.419298 -396.451328) (xy 409.404058 -396.534132)
			(xy 409.406852 -396.551404) (xy 409.411424 -396.559532) (xy 409.423998 -396.582719) (xy 409.441873 -396.63234)
			(xy 409.450974 -396.684291) (xy 409.451556 -396.710662) (xy 409.451487 -396.720021) (xy 409.450344 -396.738703)
			(xy 409.44927 -396.748) (xy 409.448254 -396.75689) (xy 409.452064 -396.773654) (xy 409.496006 -396.843504)
			(xy 409.509722 -396.853918) (xy 409.518104 -396.856712) (xy 409.542125 -396.865199) (xy 409.587298 -396.888747)
			(xy 409.628105 -396.919242) (xy 409.663485 -396.955893) (xy 409.692522 -396.99775) (xy 409.714462 -397.043725)
			(xy 409.722066 -397.06804) (xy 409.72359 -397.073882) (xy 410.043884 -397.627602) (xy 410.047948 -397.63192)
			(xy 410.064148 -397.649631) (xy 410.091571 -397.689022) (xy 410.112713 -397.732111) (xy 410.127088 -397.777904)
			(xy 410.134364 -397.825346) (xy 410.134816 -397.849344) (xy 410.134347 -397.874147) (xy 410.126577 -397.923141)
			(xy 410.111237 -397.970316) (xy 410.088703 -398.014509) (xy 410.059531 -398.054631) (xy 410.02444 -398.089694)
			(xy 409.984295 -398.118834) (xy 409.940084 -398.141332) (xy 409.892898 -398.156636) (xy 409.843897 -398.164366)
			(xy 409.819094 -398.164812) (xy 409.793699 -398.164317) (xy 409.743566 -398.156185) (xy 409.69538 -398.140133)
			(xy 409.650386 -398.116574) (xy 409.609743 -398.086116) (xy 409.5745 -398.049544) (xy 409.545567 -398.007802)
			(xy 409.523689 -397.961967) (xy 409.516072 -397.937736) (xy 409.514548 -397.931894) (xy 409.194254 -397.378174)
			(xy 409.19019 -397.373856) (xy 409.174037 -397.356117) (xy 409.146666 -397.316717) (xy 409.125574 -397.273628)
			(xy 409.111245 -397.227844) (xy 409.10401 -397.180419) (xy 409.103576 -397.156432) (xy 409.103656 -397.144384)
			(xy 409.105439 -397.120355) (xy 409.107132 -397.108426) (xy 409.108402 -397.099536) (xy 409.105354 -397.082518)
			(xy 409.06319 -397.011652) (xy 409.049982 -397.000476) (xy 409.0416 -396.997428) (xy 409.019859 -396.989016)
			(xy 408.978999 -396.966579) (xy 408.942028 -396.938189) (xy 408.909804 -396.904506) (xy 408.883077 -396.866315)
			(xy 408.86247 -396.824502) (xy 408.848462 -396.780042) (xy 408.841378 -396.733969) (xy 408.84094 -396.710662)
			(xy 408.841501 -396.684289) (xy 408.850585 -396.63233) (xy 408.868476 -396.58271) (xy 408.881072 -396.559532)
			(xy 408.885644 -396.551404) (xy 408.888438 -396.534132) (xy 408.873198 -396.451328) (xy 408.864054 -396.436088)
			(xy 408.856942 -396.4305) (xy 408.83478 -396.411784) (xy 408.794831 -396.369725) (xy 408.760511 -396.32296)
			(xy 408.732371 -396.272235) (xy 408.71086 -396.218364) (xy 408.696322 -396.162208) (xy 408.688991 -396.104666)
			(xy 408.68854 -396.075662) (xy 408.68914 -396.042341) (xy 408.698799 -395.976403) (xy 408.717921 -395.912563)
			(xy 408.731466 -395.882114) (xy 408.73571 -395.871646) (xy 408.735605 -395.849087) (xy 408.725869 -395.828736)
			(xy 408.717496 -395.821154) (xy 408.695228 -395.802504) (xy 408.655166 -395.760444) (xy 408.620748 -395.713654)
			(xy 408.592526 -395.662885) (xy 408.570953 -395.608953) (xy 408.556378 -395.552725) (xy 408.549034 -395.495105)
			(xy 408.548586 -395.466062) (xy 408.549025 -395.437135) (xy 408.556309 -395.379742) (xy 408.570769 -395.323724)
			(xy 408.592175 -395.269976) (xy 408.620184 -395.219355) (xy 408.65435 -395.172667) (xy 408.694129 -395.130659)
			(xy 408.716226 -395.111986) (xy 408.723192 -395.105633) (xy 408.732454 -395.089234) (xy 408.73426 -395.079982)
			(xy 408.738578 -395.048994) (xy 408.739477 -395.039757) (xy 408.735455 -395.021658) (xy 408.730704 -395.013688)
			(xy 408.714396 -394.987842) (xy 408.690492 -394.931607) (xy 408.683206 -394.901928) (xy 408.681145 -394.893766)
			(xy 408.672445 -394.879365) (xy 408.666188 -394.873734) (xy 408.643074 -394.854684) (xy 408.636196 -394.849435)
			(xy 408.619964 -394.843471) (xy 408.611324 -394.843) (xy 408.581686 -394.842025) (xy 408.52302 -394.833372)
			(xy 408.465962 -394.817216) (xy 408.411468 -394.79383) (xy 408.360449 -394.763603) (xy 408.31376 -394.727043)
			(xy 408.272181 -394.684761) (xy 408.236409 -394.637464) (xy 408.207043 -394.585945) (xy 408.184574 -394.531066)
			(xy 408.169379 -394.473745) (xy 408.161711 -394.414942) (xy 408.161236 -394.385292) (xy 408.161757 -394.354229)
			(xy 408.170173 -394.292675) (xy 408.178 -394.26261) (xy 408.180794 -394.25245) (xy 408.178254 -394.232638)
			(xy 408.130756 -394.150342) (xy 408.114754 -394.13815) (xy 408.104594 -394.13561) (xy 408.075486 -394.127605)
			(xy 408.019517 -394.104974) (xy 407.96701 -394.075183) (xy 407.918875 -394.038747) (xy 407.875947 -393.996299)
			(xy 407.838973 -393.948576) (xy 407.808592 -393.896407) (xy 407.785334 -393.840696) (xy 407.769602 -393.782412)
			(xy 407.761668 -393.722565) (xy 407.761186 -393.69238) (xy 407.761653 -393.661457) (xy 407.769936 -393.60017)
			(xy 407.786403 -393.540558) (xy 407.810754 -393.483709) (xy 407.82621 -393.456922) (xy 407.832306 -393.44727)
			(xy 407.834592 -393.424918) (xy 407.801064 -393.329668) (xy 407.785316 -393.313666) (xy 407.774648 -393.309602)
			(xy 407.751289 -393.300399) (xy 407.707446 -393.27594) (xy 407.667803 -393.245136) (xy 407.633269 -393.208696)
			(xy 407.604639 -393.167455) (xy 407.582569 -393.122362) (xy 407.567567 -393.074451) (xy 407.559978 -393.024824)
			(xy 407.55951 -392.999722) (xy 407.020776 -392.999722) (xy 407.020245 -393.026824) (xy 407.011436 -393.080307)
			(xy 407.00325 -393.106148) (xy 406.99944 -393.11707) (xy 407.00198 -393.139422) (xy 407.054558 -393.225274)
			(xy 407.073608 -393.23772) (xy 407.084784 -393.239498) (xy 407.114109 -393.244164) (xy 407.17128 -393.260219)
			(xy 407.225894 -393.283535) (xy 407.277033 -393.313719) (xy 407.323837 -393.350265) (xy 407.365521 -393.392558)
			(xy 407.401384 -393.439888) (xy 407.430823 -393.49146) (xy 407.453344 -393.546406) (xy 407.468568 -393.603804)
			(xy 407.476239 -393.662689) (xy 407.476706 -393.69238) (xy 407.476181 -393.723443) (xy 407.467768 -393.784997)
			(xy 407.459942 -393.815062) (xy 407.457148 -393.825222) (xy 407.459688 -393.845034) (xy 407.507186 -393.92733)
			(xy 407.523188 -393.939522) (xy 407.533348 -393.942062) (xy 407.562457 -393.950064) (xy 407.618423 -393.972698)
			(xy 407.670929 -394.002492) (xy 407.719062 -394.038929) (xy 407.761989 -394.081377) (xy 407.798963 -394.1291)
			(xy 407.829343 -394.181269) (xy 407.852602 -394.236978) (xy 407.868336 -394.295261) (xy 407.876273 -394.355107)
			(xy 407.876756 -394.385292) (xy 407.876631 -394.399427) (xy 407.874849 -394.427641) (xy 407.8732 -394.44168)
			(xy 407.872433 -394.450287) (xy 407.876076 -394.467168) (xy 407.880312 -394.4747) (xy 407.89606 -394.5001)
			(xy 407.900767 -394.507165) (xy 407.913868 -394.517943) (xy 407.921714 -394.521182) (xy 407.945059 -394.530418)
			(xy 407.988903 -394.554871) (xy 408.028547 -394.585669) (xy 408.063082 -394.622105) (xy 408.091715 -394.663341)
			(xy 408.113787 -394.70843) (xy 408.128791 -394.756337) (xy 408.136383 -394.805961) (xy 408.136852 -394.831062)
			(xy 408.136435 -394.855264) (xy 408.12936 -394.90315) (xy 408.115372 -394.949489) (xy 408.094769 -394.993291)
			(xy 408.081734 -395.013688) (xy 408.076944 -395.021643) (xy 408.072912 -395.039756) (xy 408.07386 -395.048994)
			(xy 408.078178 -395.079982) (xy 408.079867 -395.089276) (xy 408.089143 -395.105718) (xy 408.096212 -395.111986)
			(xy 408.118289 -395.130681) (xy 408.158063 -395.172689) (xy 408.192228 -395.219374) (xy 408.220237 -395.269992)
			(xy 408.241646 -395.323735) (xy 408.256113 -395.379748) (xy 408.263407 -395.437137) (xy 408.263852 -395.466062)
			(xy 408.263261 -395.499383) (xy 408.253599 -395.565322) (xy 408.234473 -395.629161) (xy 408.220926 -395.65961)
			(xy 408.216662 -395.670071) (xy 408.216776 -395.692635) (xy 408.22652 -395.712988) (xy 408.234896 -395.72057)
			(xy 408.257125 -395.739264) (xy 408.29719 -395.781316) (xy 408.331612 -395.828098) (xy 408.359839 -395.87886)
			(xy 408.381418 -395.932785) (xy 408.396 -395.989006) (xy 408.403353 -396.046621) (xy 408.403806 -396.075662)
			(xy 408.403346 -396.104668) (xy 408.396034 -396.162216) (xy 408.381511 -396.21838) (xy 408.360008 -396.272259)
			(xy 408.331871 -396.322989) (xy 408.29755 -396.369758) (xy 408.257595 -396.411817) (xy 408.235404 -396.4305)
			(xy 408.228292 -396.436088) (xy 408.219148 -396.451328) (xy 408.203908 -396.534132) (xy 408.206702 -396.551404)
			(xy 408.211274 -396.559532) (xy 408.223844 -396.582721) (xy 408.241721 -396.632341) (xy 408.250824 -396.684292)
			(xy 408.251406 -396.710662) (xy 408.251337 -396.720021) (xy 408.250194 -396.738703) (xy 408.24912 -396.748)
			(xy 408.248104 -396.75689) (xy 408.251914 -396.773654) (xy 408.295856 -396.843504) (xy 408.309572 -396.853918)
			(xy 408.317954 -396.856712) (xy 408.341985 -396.865172) (xy 408.387157 -396.888727) (xy 408.427962 -396.919228)
			(xy 408.46334 -396.955885) (xy 408.492375 -396.997745) (xy 408.514313 -397.043724) (xy 408.521916 -397.06804)
			(xy 408.52344 -397.073882) (xy 408.843734 -397.627602) (xy 408.847798 -397.63192) (xy 408.863986 -397.64963)
			(xy 408.891352 -397.689037) (xy 408.912438 -397.732133) (xy 408.926758 -397.777924) (xy 408.933983 -397.825355)
			(xy 408.934412 -397.849344) (xy 408.933923 -397.874133) (xy 408.926162 -397.923099) (xy 408.910838 -397.970248)
			(xy 408.888327 -398.014421) (xy 408.859185 -398.054529) (xy 408.824129 -398.089585) (xy 408.784021 -398.118727)
			(xy 408.739848 -398.141238) (xy 408.692699 -398.156562) (xy 408.643733 -398.164323) (xy 408.618944 -398.164812)
			(xy 408.593551 -398.164273) (xy 408.543419 -398.156149) (xy 408.495234 -398.140104) (xy 408.45024 -398.116552)
			(xy 408.409597 -398.086099) (xy 408.374353 -398.049533) (xy 408.345419 -398.007796) (xy 408.323539 -397.961965)
			(xy 408.315922 -397.937736) (xy 408.314398 -397.931894) (xy 407.994104 -397.378174) (xy 407.99004 -397.373856)
			(xy 407.973827 -397.356156) (xy 407.946406 -397.316762) (xy 407.925266 -397.27367) (xy 407.910894 -397.227875)
			(xy 407.903622 -397.180431) (xy 407.903172 -397.156432) (xy 407.903314 -397.14438) (xy 407.90522 -397.12035)
			(xy 407.906982 -397.108426) (xy 407.908252 -397.099536) (xy 407.905204 -397.082518) (xy 407.86304 -397.011652)
			(xy 407.849832 -397.000476) (xy 407.84145 -396.997428) (xy 407.819698 -396.989044) (xy 407.77884 -396.9666)
			(xy 407.74187 -396.938205) (xy 407.709648 -396.904518) (xy 407.682924 -396.866322) (xy 407.662318 -396.824507)
			(xy 407.648311 -396.780045) (xy 407.641228 -396.73397) (xy 407.64079 -396.710662) (xy 407.641357 -396.684289)
			(xy 407.65044 -396.632331) (xy 407.668328 -396.58271) (xy 407.680922 -396.559532) (xy 407.685494 -396.551404)
			(xy 407.688288 -396.534132) (xy 407.673048 -396.451328) (xy 407.663904 -396.436088) (xy 407.656792 -396.4305)
			(xy 407.63462 -396.411796) (xy 407.594673 -396.369734) (xy 407.560356 -396.322966) (xy 407.532217 -396.272239)
			(xy 407.510708 -396.218366) (xy 407.496171 -396.162209) (xy 407.488841 -396.104666) (xy 407.48839 -396.075662)
			(xy 407.488985 -396.042341) (xy 407.498645 -395.976402) (xy 407.517769 -395.912563) (xy 407.531316 -395.882114)
			(xy 407.535543 -395.871642) (xy 407.535438 -395.849088) (xy 407.525712 -395.828739) (xy 407.517346 -395.821154)
			(xy 407.495089 -395.802492) (xy 407.455024 -395.760436) (xy 407.420603 -395.713648) (xy 407.392379 -395.662881)
			(xy 407.370805 -395.60895) (xy 407.356229 -395.552724) (xy 407.348884 -395.495105) (xy 407.348436 -395.466062)
			(xy 407.348893 -395.437136) (xy 407.356177 -395.379744) (xy 407.370635 -395.323728) (xy 407.392038 -395.26998)
			(xy 407.420044 -395.219359) (xy 407.454207 -395.172671) (xy 407.493981 -395.13066) (xy 407.516076 -395.111986)
			(xy 407.52305 -395.105641) (xy 407.532306 -395.089235) (xy 407.53411 -395.079982) (xy 407.538428 -395.048994)
			(xy 407.539335 -395.039757) (xy 407.535309 -395.021657) (xy 407.530554 -395.013688) (xy 407.514242 -394.987845)
			(xy 407.490341 -394.931608) (xy 407.483056 -394.901928) (xy 407.480982 -394.893771) (xy 407.472291 -394.879368)
			(xy 407.466038 -394.873734) (xy 407.442924 -394.854684) (xy 407.436091 -394.849483) (xy 407.42 -394.84351)
			(xy 407.411428 -394.843) (xy 407.38179 -394.842022) (xy 407.323124 -394.833369) (xy 407.266067 -394.817214)
			(xy 407.211572 -394.793827) (xy 407.160553 -394.763601) (xy 407.113864 -394.727041) (xy 407.072285 -394.684759)
			(xy 407.036513 -394.637463) (xy 407.007147 -394.585944) (xy 406.984678 -394.531065) (xy 406.969483 -394.473745)
			(xy 406.961815 -394.414942) (xy 406.96134 -394.385292) (xy 406.961861 -394.354229) (xy 406.970277 -394.292675)
			(xy 406.978104 -394.26261) (xy 406.980898 -394.25245) (xy 406.978358 -394.232638) (xy 406.93086 -394.150342)
			(xy 406.914858 -394.13815) (xy 406.904698 -394.13561) (xy 406.875571 -394.127669) (xy 406.819604 -394.105027)
			(xy 406.767099 -394.075225) (xy 406.718966 -394.03878) (xy 406.676041 -393.996324) (xy 406.639069 -393.948595)
			(xy 406.608692 -393.896421) (xy 406.585435 -393.840706) (xy 406.569704 -393.782417) (xy 406.561771 -393.722567)
			(xy 406.56129 -393.69238) (xy 406.561817 -393.661492) (xy 406.570122 -393.600277) (xy 406.586578 -393.540733)
			(xy 406.610888 -393.483941) (xy 406.626314 -393.457176) (xy 406.632156 -393.44727) (xy 406.634442 -393.424918)
			(xy 406.601168 -393.329668) (xy 406.58542 -393.313666) (xy 406.574752 -393.309602) (xy 406.551361 -393.300442)
			(xy 406.507465 -393.276017) (xy 406.46777 -393.245232) (xy 406.433191 -393.208795) (xy 406.404523 -393.167545)
			(xy 406.382427 -393.122433) (xy 406.367411 -393.074496) (xy 406.359822 -393.024839) (xy 406.35936 -392.999722)
			(xy 405.82088 -392.999722) (xy 405.820348 -393.026824) (xy 405.81154 -393.080307) (xy 405.803354 -393.106148)
			(xy 405.799544 -393.11707) (xy 405.802084 -393.139422) (xy 405.854662 -393.225274) (xy 405.873712 -393.23772)
			(xy 405.884888 -393.239498) (xy 405.9142 -393.244239) (xy 405.971371 -393.260282) (xy 406.025985 -393.283587)
			(xy 406.077125 -393.313762) (xy 406.123931 -393.350299) (xy 406.165618 -393.392585) (xy 406.201483 -393.439909)
			(xy 406.230924 -393.491475) (xy 406.253446 -393.546416) (xy 406.268671 -393.60381) (xy 406.276343 -393.662691)
			(xy 406.27681 -393.69238) (xy 406.276285 -393.723506) (xy 406.26788 -393.785188) (xy 406.260046 -393.815316)
			(xy 406.257252 -393.825476) (xy 406.259792 -393.845542) (xy 406.307036 -393.92733) (xy 406.323038 -393.939522)
			(xy 406.333198 -393.942062) (xy 406.362316 -393.950031) (xy 406.418282 -393.972671) (xy 406.470787 -394.00247)
			(xy 406.518919 -394.038912) (xy 406.561844 -394.081364) (xy 406.598816 -394.12909) (xy 406.629195 -394.181261)
			(xy 406.652453 -394.236973) (xy 406.668187 -394.295259) (xy 406.676123 -394.355106) (xy 406.676606 -394.385292)
			(xy 406.676481 -394.399427) (xy 406.674699 -394.427641) (xy 406.67305 -394.44168) (xy 406.67229 -394.450287)
			(xy 406.67593 -394.467167) (xy 406.680162 -394.4747) (xy 406.69591 -394.5001) (xy 406.700613 -394.507165)
			(xy 406.713723 -394.517931) (xy 406.721564 -394.521182) (xy 406.744953 -394.530347) (xy 406.788848 -394.554772)
			(xy 406.828541 -394.585557) (xy 406.86312 -394.621993) (xy 406.891788 -394.663242) (xy 406.913885 -394.708354)
			(xy 406.928902 -394.75629) (xy 406.936493 -394.805946) (xy 406.936956 -394.831062) (xy 406.936538 -394.855264)
			(xy 406.929464 -394.90315) (xy 406.915475 -394.949489) (xy 406.894873 -394.993291) (xy 406.881838 -395.013688)
			(xy 406.877048 -395.021643) (xy 406.873016 -395.039756) (xy 406.873964 -395.048994) (xy 406.878282 -395.079982)
			(xy 406.879969 -395.089277) (xy 406.889247 -395.105718) (xy 406.896316 -395.111986) (xy 406.918394 -395.13068)
			(xy 406.958168 -395.172688) (xy 406.992332 -395.219374) (xy 407.020342 -395.269991) (xy 407.04175 -395.323735)
			(xy 407.056217 -395.379748) (xy 407.063511 -395.437137) (xy 407.063956 -395.466062) (xy 407.063365 -395.499383)
			(xy 407.053703 -395.565322) (xy 407.034577 -395.629161) (xy 407.02103 -395.65961) (xy 407.016765 -395.67007)
			(xy 407.016879 -395.692635) (xy 407.026623 -395.712988) (xy 407.035 -395.72057) (xy 407.05723 -395.739263)
			(xy 407.097294 -395.781315) (xy 407.131717 -395.828098) (xy 407.159944 -395.87886) (xy 407.181522 -395.932785)
			(xy 407.196104 -395.989006) (xy 407.203457 -396.046621) (xy 407.20391 -396.075662) (xy 407.203449 -396.104668)
			(xy 407.196137 -396.162216) (xy 407.181614 -396.218379) (xy 407.160111 -396.272258) (xy 407.131974 -396.322989)
			(xy 407.097653 -396.369758) (xy 407.057699 -396.411816) (xy 407.035508 -396.4305) (xy 407.028396 -396.436088)
			(xy 407.019252 -396.451328) (xy 407.004012 -396.534132) (xy 407.006806 -396.551404) (xy 407.011378 -396.559532)
			(xy 407.023948 -396.582721) (xy 407.041825 -396.632341) (xy 407.050928 -396.684292) (xy 407.05151 -396.710662)
			(xy 407.051441 -396.720021) (xy 407.050298 -396.738703) (xy 407.049224 -396.748) (xy 407.048208 -396.75689)
			(xy 407.052018 -396.773654) (xy 407.09596 -396.843504) (xy 407.109676 -396.853918) (xy 407.118058 -396.856712)
			(xy 407.14209 -396.86517) (xy 407.187262 -396.888725) (xy 407.228066 -396.919227) (xy 407.263445 -396.955884)
			(xy 407.292479 -396.997745) (xy 407.314417 -397.043724) (xy 407.32202 -397.06804) (xy 407.323544 -397.073882)
			(xy 407.643838 -397.627602) (xy 407.647902 -397.63192) (xy 407.66409 -397.649629) (xy 407.691456 -397.689037)
			(xy 407.712542 -397.732133) (xy 407.726862 -397.777924) (xy 407.734087 -397.825355) (xy 407.734516 -397.849344)
			(xy 407.734023 -397.874132) (xy 407.726262 -397.923098) (xy 407.710938 -397.970247) (xy 407.688428 -398.01442)
			(xy 407.659287 -398.054528) (xy 407.624231 -398.089584) (xy 407.584123 -398.118726) (xy 407.539951 -398.141236)
			(xy 407.492802 -398.156561) (xy 407.443836 -398.164322) (xy 407.419048 -398.164812) (xy 407.393655 -398.164269)
			(xy 407.343523 -398.156146) (xy 407.295339 -398.140102) (xy 407.250345 -398.11655) (xy 407.209701 -398.086098)
			(xy 407.174458 -398.049532) (xy 407.145523 -398.007796) (xy 407.123643 -397.961965) (xy 407.116026 -397.937736)
			(xy 407.114502 -397.931894) (xy 406.794208 -397.378174) (xy 406.790144 -397.373856) (xy 406.773931 -397.356156)
			(xy 406.746511 -397.316762) (xy 406.72537 -397.27367) (xy 406.710999 -397.227875) (xy 406.703726 -397.180431)
			(xy 406.703276 -397.156432) (xy 406.703418 -397.14438) (xy 406.705324 -397.12035) (xy 406.707086 -397.108426)
			(xy 406.708356 -397.099536) (xy 406.705308 -397.082518) (xy 406.663144 -397.011652) (xy 406.649936 -397.000476)
			(xy 406.641554 -396.997428) (xy 406.619803 -396.989042) (xy 406.578945 -396.966599) (xy 406.541975 -396.938203)
			(xy 406.509753 -396.904517) (xy 406.483028 -396.866322) (xy 406.462422 -396.824507) (xy 406.448415 -396.780045)
			(xy 406.441332 -396.73397) (xy 406.440894 -396.710662) (xy 406.44146 -396.684289) (xy 406.450543 -396.632331)
			(xy 406.468431 -396.58271) (xy 406.481026 -396.559532) (xy 406.485598 -396.551404) (xy 406.488392 -396.534132)
			(xy 406.473152 -396.451328) (xy 406.464008 -396.436088) (xy 406.456896 -396.4305) (xy 406.434725 -396.411795)
			(xy 406.394778 -396.369733) (xy 406.36046 -396.322965) (xy 406.332322 -396.272239) (xy 406.310812 -396.218366)
			(xy 406.296275 -396.162209) (xy 406.288945 -396.104666) (xy 406.288494 -396.075662) (xy 406.289089 -396.042341)
			(xy 406.298749 -395.976402) (xy 406.317873 -395.912563) (xy 406.33142 -395.882114) (xy 406.335646 -395.871642)
			(xy 406.335541 -395.849088) (xy 406.325816 -395.828739) (xy 406.31745 -395.821154) (xy 406.295193 -395.802491)
			(xy 406.255129 -395.760435) (xy 406.220708 -395.713647) (xy 406.192483 -395.66288) (xy 406.170909 -395.60895)
			(xy 406.156333 -395.552724) (xy 406.148988 -395.495105) (xy 406.14854 -395.466062) (xy 406.148996 -395.437136)
			(xy 406.156279 -395.379744) (xy 406.170738 -395.323727) (xy 406.192141 -395.26998) (xy 406.220147 -395.219358)
			(xy 406.25431 -395.17267) (xy 406.294085 -395.13066) (xy 406.31618 -395.111986) (xy 406.323155 -395.105642)
			(xy 406.332411 -395.089236) (xy 406.334214 -395.079982) (xy 406.338532 -395.048994) (xy 406.339438 -395.039757)
			(xy 406.335413 -395.021657) (xy 406.330658 -395.013688) (xy 406.314346 -394.987845) (xy 406.290445 -394.931607)
			(xy 406.28316 -394.901928) (xy 406.281112 -394.893762) (xy 406.272404 -394.879362) (xy 406.266142 -394.873734)
			(xy 406.243028 -394.854684) (xy 406.236135 -394.849457) (xy 406.219915 -394.84348) (xy 406.211278 -394.843)
			(xy 406.181642 -394.841976) (xy 406.122978 -394.833329) (xy 406.065921 -394.81718) (xy 406.011427 -394.793799)
			(xy 405.960407 -394.763578) (xy 405.913717 -394.727022) (xy 405.872138 -394.684744) (xy 405.836366 -394.637451)
			(xy 405.806999 -394.585936) (xy 405.784529 -394.531059) (xy 405.769333 -394.473741) (xy 405.761665 -394.414941)
			(xy 405.76119 -394.385292) (xy 405.76171 -394.354229) (xy 405.770126 -394.292675) (xy 405.777954 -394.26261)
			(xy 405.780748 -394.25245) (xy 405.778208 -394.232638) (xy 405.73071 -394.150342) (xy 405.714708 -394.13815)
			(xy 405.704548 -394.13561) (xy 405.675463 -394.127568) (xy 405.619535 -394.104904) (xy 405.56707 -394.075089)
			(xy 405.518975 -394.038642) (xy 405.476084 -393.996192) (xy 405.439141 -393.948477) (xy 405.408786 -393.896323)
			(xy 405.385543 -393.840633) (xy 405.369818 -393.782373) (xy 405.361881 -393.722552) (xy 405.361394 -393.69238)
			(xy 405.361921 -393.661492) (xy 405.370226 -393.600277) (xy 405.386682 -393.540733) (xy 405.410992 -393.483941)
			(xy 405.426418 -393.457176) (xy 405.43226 -393.44727) (xy 405.434546 -393.424918) (xy 405.401272 -393.329668)
			(xy 405.385524 -393.313666) (xy 405.374856 -393.309602) (xy 405.351466 -393.30044) (xy 405.30757 -393.276016)
			(xy 405.267875 -393.245231) (xy 405.233295 -393.208794) (xy 405.204627 -393.167545) (xy 405.182531 -393.122432)
			(xy 405.167515 -393.074496) (xy 405.159926 -393.024839) (xy 405.159464 -392.999722) (xy 404.62073 -392.999722)
			(xy 404.620201 -393.026824) (xy 404.611391 -393.080307) (xy 404.603204 -393.106148) (xy 404.599394 -393.11707)
			(xy 404.601934 -393.139422) (xy 404.654512 -393.225274) (xy 404.673562 -393.23772) (xy 404.684738 -393.239498)
			(xy 404.714057 -393.2442) (xy 404.771228 -393.260249) (xy 404.825842 -393.28356) (xy 404.876981 -393.313739)
			(xy 404.923787 -393.350281) (xy 404.965472 -393.392571) (xy 405.001335 -393.439898) (xy 405.030776 -393.491467)
			(xy 405.053297 -393.546411) (xy 405.068521 -393.603807) (xy 405.076193 -393.66269) (xy 405.07666 -393.69238)
			(xy 405.076133 -393.723443) (xy 405.067721 -393.784996) (xy 405.059896 -393.815062) (xy 405.057102 -393.825222)
			(xy 405.059642 -393.845034) (xy 405.10714 -393.92733) (xy 405.123142 -393.939522) (xy 405.133302 -393.942062)
			(xy 405.162421 -393.950029) (xy 405.218387 -393.972669) (xy 405.270891 -394.002468) (xy 405.319023 -394.038911)
			(xy 405.361948 -394.081363) (xy 405.398921 -394.129089) (xy 405.429299 -394.181261) (xy 405.452557 -394.236973)
			(xy 405.468291 -394.295258) (xy 405.476227 -394.355106) (xy 405.47671 -394.385292) (xy 405.476585 -394.399427)
			(xy 405.474803 -394.427641) (xy 405.473154 -394.44168) (xy 405.472394 -394.450287) (xy 405.476033 -394.467167)
			(xy 405.480266 -394.4747) (xy 405.496014 -394.5001) (xy 405.500716 -394.507166) (xy 405.513827 -394.517932)
			(xy 405.521668 -394.521182) (xy 405.545058 -394.530345) (xy 405.588952 -394.55477) (xy 405.628646 -394.585556)
			(xy 405.663225 -394.621993) (xy 405.691893 -394.663242) (xy 405.713989 -394.708354) (xy 405.729006 -394.756289)
			(xy 405.736597 -394.805945) (xy 405.73706 -394.831062) (xy 405.736641 -394.855264) (xy 405.729567 -394.90315)
			(xy 405.715579 -394.949489) (xy 405.694977 -394.993291) (xy 405.681942 -395.013688) (xy 405.677152 -395.021644)
			(xy 405.67312 -395.039756) (xy 405.674068 -395.048994) (xy 405.678386 -395.079982) (xy 405.680072 -395.089277)
			(xy 405.689351 -395.105719) (xy 405.69642 -395.111986) (xy 405.718499 -395.130679) (xy 405.758273 -395.172688)
			(xy 405.792437 -395.219373) (xy 405.820446 -395.269991) (xy 405.841855 -395.323735) (xy 405.856321 -395.379748)
			(xy 405.863615 -395.437137) (xy 405.86406 -395.466062) (xy 405.863468 -395.499383) (xy 405.853806 -395.565322)
			(xy 405.834681 -395.629161) (xy 405.821134 -395.65961) (xy 405.816868 -395.67007) (xy 405.816981 -395.692636)
			(xy 405.826726 -395.712989) (xy 405.835104 -395.72057) (xy 405.857335 -395.739262) (xy 405.897399 -395.781314)
			(xy 405.931821 -395.828097) (xy 405.960048 -395.878859) (xy 405.981626 -395.932784) (xy 405.996209 -395.989006)
			(xy 406.003561 -396.046621) (xy 406.004014 -396.075662) (xy 406.003551 -396.104668) (xy 405.99624 -396.162216)
			(xy 405.981716 -396.218379) (xy 405.960214 -396.272258) (xy 405.932077 -396.322988) (xy 405.897757 -396.369758)
			(xy 405.857803 -396.411816) (xy 405.835612 -396.4305) (xy 405.8285 -396.436088) (xy 405.819356 -396.451328)
			(xy 405.804116 -396.534132) (xy 405.80691 -396.551404) (xy 405.811482 -396.559532) (xy 405.824052 -396.582721)
			(xy 405.841929 -396.632341) (xy 405.851032 -396.684292) (xy 405.851614 -396.710662) (xy 405.851545 -396.720021)
			(xy 405.850402 -396.738703) (xy 405.849328 -396.748) (xy 405.848312 -396.75689) (xy 405.852122 -396.773654)
			(xy 405.896064 -396.843504) (xy 405.90978 -396.853918) (xy 405.918162 -396.856712) (xy 405.942252 -396.865212)
			(xy 405.987544 -396.888832) (xy 406.02844 -396.919439) (xy 406.063873 -396.956232) (xy 406.092918 -396.998253)
			(xy 406.114815 -397.044402) (xy 406.122378 -397.068802) (xy 406.123902 -397.074644) (xy 406.443688 -397.627602)
			(xy 406.447752 -397.63192) (xy 406.463952 -397.649631) (xy 406.491375 -397.689022) (xy 406.512518 -397.732111)
			(xy 406.526892 -397.777904) (xy 406.534168 -397.825346) (xy 406.53462 -397.849344) (xy 406.534246 -397.874152)
			(xy 406.526474 -397.923155) (xy 406.511128 -397.970338) (xy 406.488585 -398.014537) (xy 406.459403 -398.054664)
			(xy 406.4243 -398.089728) (xy 406.384142 -398.118866) (xy 406.339918 -398.14136) (xy 406.292718 -398.156655)
			(xy 406.243706 -398.164374) (xy 406.218898 -398.164812) (xy 406.193504 -398.164313) (xy 406.14337 -398.156182)
			(xy 406.095184 -398.140131) (xy 406.05019 -398.116572) (xy 406.009547 -398.086114) (xy 405.974304 -398.049543)
			(xy 405.945371 -398.007802) (xy 405.923493 -397.961967) (xy 405.915876 -397.937736) (xy 405.914352 -397.931894)
			(xy 405.593804 -397.377412) (xy 405.58974 -397.373094) (xy 405.573635 -397.355426) (xy 405.546387 -397.316147)
			(xy 405.525377 -397.273206) (xy 405.511085 -397.227587) (xy 405.503838 -397.180334) (xy 405.50338 -397.156432)
			(xy 405.503522 -397.14438) (xy 405.505428 -397.12035) (xy 405.50719 -397.108426) (xy 405.50846 -397.099536)
			(xy 405.505412 -397.082518) (xy 405.463248 -397.011652) (xy 405.45004 -397.000476) (xy 405.441658 -396.997428)
			(xy 405.419908 -396.989039) (xy 405.379049 -396.966597) (xy 405.342079 -396.938202) (xy 405.309857 -396.904516)
			(xy 405.283132 -396.866321) (xy 405.262527 -396.824507) (xy 405.248519 -396.780045) (xy 405.241436 -396.73397)
			(xy 405.240998 -396.710662) (xy 405.241564 -396.684289) (xy 405.250647 -396.632331) (xy 405.268535 -396.58271)
			(xy 405.28113 -396.559532) (xy 405.285702 -396.551404) (xy 405.288496 -396.534132) (xy 405.273256 -396.451328)
			(xy 405.264112 -396.436088) (xy 405.257 -396.4305) (xy 405.234829 -396.411794) (xy 405.194882 -396.369733)
			(xy 405.160565 -396.322965) (xy 405.132426 -396.272239) (xy 405.110916 -396.218366) (xy 405.096379 -396.162209)
			(xy 405.089049 -396.104666) (xy 405.088598 -396.075662) (xy 405.089193 -396.042341) (xy 405.098853 -395.976402)
			(xy 405.117977 -395.912563) (xy 405.131524 -395.882114) (xy 405.135749 -395.871642) (xy 405.135643 -395.849089)
			(xy 405.125919 -395.828739) (xy 405.117554 -395.821154) (xy 405.095298 -395.80249) (xy 405.055233 -395.760434)
			(xy 405.020812 -395.713647) (xy 404.992588 -395.66288) (xy 404.971014 -395.60895) (xy 404.956437 -395.552724)
			(xy 404.949092 -395.495105) (xy 404.948644 -395.466062) (xy 404.949098 -395.437136) (xy 404.956382 -395.379744)
			(xy 404.970841 -395.323727) (xy 404.992244 -395.26998) (xy 405.02025 -395.219358) (xy 405.054414 -395.17267)
			(xy 405.094189 -395.13066) (xy 405.116284 -395.111986) (xy 405.12326 -395.105642) (xy 405.132515 -395.089236)
			(xy 405.134318 -395.079982) (xy 405.138636 -395.048994) (xy 405.139542 -395.039757) (xy 405.135516 -395.021657)
			(xy 405.130762 -395.013688) (xy 405.114451 -394.987845) (xy 405.09055 -394.931607) (xy 405.083264 -394.901928)
			(xy 405.081215 -394.893763) (xy 405.072508 -394.879363) (xy 405.066246 -394.873734) (xy 405.043132 -394.854684)
			(xy 405.036238 -394.849459) (xy 405.020018 -394.843481) (xy 405.011382 -394.843) (xy 404.981746 -394.841972)
			(xy 404.923082 -394.833326) (xy 404.866025 -394.817177) (xy 404.811531 -394.793797) (xy 404.760512 -394.763576)
			(xy 404.713822 -394.727021) (xy 404.672242 -394.684743) (xy 404.63647 -394.63745) (xy 404.607103 -394.585935)
			(xy 404.584633 -394.531059) (xy 404.569437 -394.473741) (xy 404.561769 -394.414941) (xy 404.561294 -394.385292)
			(xy 404.561814 -394.354229) (xy 404.57023 -394.292675) (xy 404.578058 -394.26261) (xy 404.580852 -394.25245)
			(xy 404.578312 -394.232638) (xy 404.530814 -394.150342) (xy 404.514812 -394.13815) (xy 404.504652 -394.13561)
			(xy 404.475536 -394.127633) (xy 404.419568 -394.104998) (xy 404.367061 -394.075201) (xy 404.318927 -394.038761)
			(xy 404.276001 -393.99631) (xy 404.239027 -393.948585) (xy 404.208648 -393.896413) (xy 404.185391 -393.840701)
			(xy 404.169659 -393.782414) (xy 404.161725 -393.722566) (xy 404.161244 -393.69238) (xy 404.161764 -393.661492)
			(xy 404.17007 -393.600276) (xy 404.186528 -393.540732) (xy 404.21084 -393.48394) (xy 404.226268 -393.457176)
			(xy 404.23211 -393.44727) (xy 404.234396 -393.424918) (xy 404.201122 -393.329668) (xy 404.185374 -393.313666)
			(xy 404.174706 -393.309602) (xy 404.151327 -393.300413) (xy 404.107429 -393.275995) (xy 404.067732 -393.245216)
			(xy 404.033151 -393.208783) (xy 404.004481 -393.167537) (xy 403.982383 -393.122427) (xy 403.967366 -393.074493)
			(xy 403.959776 -393.024838) (xy 403.959314 -392.999722) (xy 403.420834 -392.999722) (xy 403.420305 -393.026824)
			(xy 403.411495 -393.080307) (xy 403.403308 -393.106148) (xy 403.399498 -393.11707) (xy 403.402038 -393.139422)
			(xy 403.454616 -393.225274) (xy 403.473666 -393.23772) (xy 403.484842 -393.239498) (xy 403.514162 -393.244197)
			(xy 403.571332 -393.260247) (xy 403.625946 -393.283558) (xy 403.677086 -393.313738) (xy 403.723891 -393.35028)
			(xy 403.765576 -393.39257) (xy 403.80144 -393.439897) (xy 403.83088 -393.491466) (xy 403.853401 -393.54641)
			(xy 403.868625 -393.603806) (xy 403.876297 -393.66269) (xy 403.876764 -393.69238) (xy 403.876237 -393.723443)
			(xy 403.867825 -393.784996) (xy 403.86 -393.815062) (xy 403.857206 -393.825222) (xy 403.859746 -393.845034)
			(xy 403.907244 -393.92733) (xy 403.923246 -393.939522) (xy 403.933406 -393.942062) (xy 403.962507 -393.950092)
			(xy 404.018473 -393.972721) (xy 404.07098 -394.002511) (xy 404.119114 -394.038944) (xy 404.162042 -394.081389)
			(xy 404.199017 -394.129109) (xy 404.229398 -394.181275) (xy 404.252658 -394.236982) (xy 404.268393 -394.295264)
			(xy 404.27633 -394.355108) (xy 404.276814 -394.385292) (xy 404.276689 -394.399427) (xy 404.274907 -394.427641)
			(xy 404.273258 -394.44168) (xy 404.272497 -394.450287) (xy 404.276137 -394.467167) (xy 404.28037 -394.4747)
			(xy 404.296118 -394.5001) (xy 404.300839 -394.507154) (xy 404.31393 -394.517938) (xy 404.321772 -394.521182)
			(xy 404.34513 -394.530387) (xy 404.388972 -394.554847) (xy 404.428614 -394.585651) (xy 404.463147 -394.622092)
			(xy 404.491777 -394.663332) (xy 404.513847 -394.708424) (xy 404.52885 -394.756334) (xy 404.536442 -394.80596)
			(xy 404.53691 -394.831062) (xy 404.536483 -394.855264) (xy 404.52941 -394.903149) (xy 404.515424 -394.949488)
			(xy 404.494825 -394.99329) (xy 404.481792 -395.013688) (xy 404.477005 -395.021646) (xy 404.47297 -395.039756)
			(xy 404.473918 -395.048994) (xy 404.478236 -395.079982) (xy 404.479907 -395.089281) (xy 404.489195 -395.105722)
			(xy 404.49627 -395.111986) (xy 404.51836 -395.130666) (xy 404.558131 -395.172679) (xy 404.592293 -395.219367)
			(xy 404.6203 -395.269987) (xy 404.641707 -395.323732) (xy 404.656172 -395.379746) (xy 404.663465 -395.437136)
			(xy 404.66391 -395.466062) (xy 404.663323 -395.499384) (xy 404.65366 -395.565322) (xy 404.634532 -395.629161)
			(xy 404.620984 -395.65961) (xy 404.616734 -395.670074) (xy 404.616848 -395.692634) (xy 404.626583 -395.712986)
			(xy 404.634954 -395.72057) (xy 404.657175 -395.739274) (xy 404.697241 -395.781323) (xy 404.731665 -395.828103)
			(xy 404.759894 -395.878863) (xy 404.781474 -395.932787) (xy 404.796058 -395.989007) (xy 404.803411 -396.046621)
			(xy 404.803864 -396.075662) (xy 404.803383 -396.104667) (xy 404.796072 -396.162214) (xy 404.781551 -396.218376)
			(xy 404.760051 -396.272254) (xy 404.731917 -396.322984) (xy 404.697601 -396.369755) (xy 404.657651 -396.411815)
			(xy 404.635462 -396.4305) (xy 404.62835 -396.436088) (xy 404.619206 -396.451328) (xy 404.603966 -396.534132)
			(xy 404.60676 -396.551404) (xy 404.611332 -396.559532) (xy 404.623906 -396.582719) (xy 404.641781 -396.63234)
			(xy 404.650882 -396.684291) (xy 404.651464 -396.710662) (xy 404.651395 -396.720021) (xy 404.650252 -396.738703)
			(xy 404.649178 -396.748) (xy 404.648162 -396.75689) (xy 404.651972 -396.773654) (xy 404.695914 -396.843504)
			(xy 404.70963 -396.853918) (xy 404.718012 -396.856712) (xy 404.742035 -396.865195) (xy 404.787208 -396.888744)
			(xy 404.828014 -396.91924) (xy 404.863394 -396.955892) (xy 404.892431 -396.997749) (xy 404.91437 -397.043725)
			(xy 404.921974 -397.06804) (xy 404.923498 -397.073882) (xy 405.243792 -397.627602) (xy 405.247856 -397.63192)
			(xy 405.264057 -397.64963) (xy 405.29148 -397.689021) (xy 405.312622 -397.732111) (xy 405.326997 -397.777904)
			(xy 405.334272 -397.825346) (xy 405.334724 -397.849344) (xy 405.334346 -397.874152) (xy 405.326574 -397.923155)
			(xy 405.311228 -397.970337) (xy 405.288686 -398.014536) (xy 405.259504 -398.054662) (xy 405.224402 -398.089727)
			(xy 405.184244 -398.118865) (xy 405.140021 -398.141359) (xy 405.092821 -398.156654) (xy 405.04381 -398.164373)
			(xy 405.019002 -398.164812) (xy 404.993608 -398.16431) (xy 404.943474 -398.156179) (xy 404.895289 -398.140128)
			(xy 404.850294 -398.11657) (xy 404.809651 -398.086113) (xy 404.774409 -398.049542) (xy 404.745475 -398.007801)
			(xy 404.723597 -397.961966) (xy 404.71598 -397.937736) (xy 404.714456 -397.931894) (xy 404.394162 -397.378174)
			(xy 404.390098 -397.373856) (xy 404.373946 -397.356115) (xy 404.346575 -397.316716) (xy 404.325482 -397.273628)
			(xy 404.311153 -397.227844) (xy 404.303918 -397.180419) (xy 404.303484 -397.156432) (xy 404.303564 -397.144384)
			(xy 404.305347 -397.120355) (xy 404.30704 -397.108426) (xy 404.30831 -397.099536) (xy 404.305262 -397.082518)
			(xy 404.263098 -397.011652) (xy 404.24989 -397.000476) (xy 404.241508 -396.997428) (xy 404.219768 -396.989012)
			(xy 404.178909 -396.966576) (xy 404.141937 -396.938187) (xy 404.109713 -396.904505) (xy 404.082986 -396.866313)
			(xy 404.062378 -396.824502) (xy 404.04837 -396.780042) (xy 404.041286 -396.733969) (xy 404.040848 -396.710662)
			(xy 404.041408 -396.684289) (xy 404.050492 -396.63233) (xy 404.068383 -396.58271) (xy 404.08098 -396.559532)
			(xy 404.085552 -396.551404) (xy 404.088346 -396.534132) (xy 404.073106 -396.451328) (xy 404.063962 -396.436088)
			(xy 404.05685 -396.4305) (xy 404.034669 -396.411806) (xy 403.994724 -396.369741) (xy 403.960409 -396.322971)
			(xy 403.932273 -396.272242) (xy 403.910764 -396.218368) (xy 403.896229 -396.16221) (xy 403.888898 -396.104666)
			(xy 403.888448 -396.075662) (xy 403.889047 -396.042341) (xy 403.898706 -395.976403) (xy 403.917828 -395.912563)
			(xy 403.931374 -395.882114) (xy 403.935615 -395.871646) (xy 403.93551 -395.849087) (xy 403.925776 -395.828736)
			(xy 403.917404 -395.821154) (xy 403.895138 -395.802502) (xy 403.855075 -395.760443) (xy 403.820657 -395.713653)
			(xy 403.792434 -395.662884) (xy 403.770862 -395.608952) (xy 403.756286 -395.552725) (xy 403.748942 -395.495105)
			(xy 403.748494 -395.466062) (xy 403.74893 -395.437135) (xy 403.756215 -395.379741) (xy 403.770675 -395.323724)
			(xy 403.792081 -395.269976) (xy 403.82009 -395.219354) (xy 403.854257 -395.172667) (xy 403.894036 -395.130659)
			(xy 403.916134 -395.111986) (xy 403.923101 -395.105634) (xy 403.932362 -395.089234) (xy 403.934168 -395.079982)
			(xy 403.938486 -395.048994) (xy 403.939384 -395.039757) (xy 403.935363 -395.021658) (xy 403.930612 -395.013688)
			(xy 403.914305 -394.987842) (xy 403.890401 -394.931607) (xy 403.883114 -394.901928) (xy 403.881051 -394.893767)
			(xy 403.872353 -394.879365) (xy 403.866096 -394.873734) (xy 403.842982 -394.854684) (xy 403.83616 -394.849466)
			(xy 403.820061 -394.843503) (xy 403.811486 -394.843) (xy 403.78185 -394.841969) (xy 403.723186 -394.833323)
			(xy 403.666129 -394.817174) (xy 403.611635 -394.793794) (xy 403.560616 -394.763574) (xy 403.513926 -394.727019)
			(xy 403.472347 -394.684742) (xy 403.436574 -394.637449) (xy 403.407207 -394.585934) (xy 403.384737 -394.531058)
			(xy 403.369541 -394.473741) (xy 403.361873 -394.414941) (xy 403.361398 -394.385292) (xy 403.361918 -394.354229)
			(xy 403.370334 -394.292675) (xy 403.378162 -394.26261) (xy 403.380956 -394.25245) (xy 403.378416 -394.232638)
			(xy 403.330918 -394.150342) (xy 403.314916 -394.13815) (xy 403.304756 -394.13561) (xy 403.293034 -394.132467)
			(xy 403.269908 -394.125094) (xy 403.258528 -394.120878) (xy 403.246082 -394.116306) (xy 403.220174 -394.120116)
			(xy 403.130766 -394.188696) (xy 403.120352 -394.212826) (xy 403.121622 -394.22578) (xy 403.123146 -394.25753)
			(xy 403.122763 -394.281206) (xy 403.11603 -394.328077) (xy 403.102665 -394.373504) (xy 403.093174 -394.395198)
			(xy 403.088856 -394.404596) (xy 403.088094 -394.424662) (xy 403.120352 -394.511022) (xy 403.134068 -394.525754)
			(xy 403.143466 -394.530072) (xy 403.167838 -394.541755) (xy 403.212708 -394.571884) (xy 403.252085 -394.608904)
			(xy 403.284922 -394.65183) (xy 403.310348 -394.699522) (xy 403.327686 -394.750712) (xy 403.336475 -394.804039)
			(xy 403.337014 -394.831062) (xy 403.336586 -394.855264) (xy 403.329513 -394.903148) (xy 403.315528 -394.949488)
			(xy 403.294929 -394.99329) (xy 403.281896 -395.013688) (xy 403.27711 -395.021646) (xy 403.273074 -395.039756)
			(xy 403.274022 -395.048994) (xy 403.27834 -395.079982) (xy 403.28001 -395.089281) (xy 403.289299 -395.105722)
			(xy 403.296374 -395.111986) (xy 403.318464 -395.130665) (xy 403.358236 -395.172678) (xy 403.392397 -395.219366)
			(xy 403.420404 -395.269987) (xy 403.441811 -395.323732) (xy 403.456276 -395.379746) (xy 403.463569 -395.437136)
			(xy 403.464014 -395.466062) (xy 403.463427 -395.499384) (xy 403.453764 -395.565322) (xy 403.434636 -395.629161)
			(xy 403.421088 -395.65961) (xy 403.416837 -395.670074) (xy 403.416951 -395.692634) (xy 403.426687 -395.712986)
			(xy 403.435058 -395.72057) (xy 403.45728 -395.739273) (xy 403.497346 -395.781322) (xy 403.53177 -395.828103)
			(xy 403.559999 -395.878863) (xy 403.581578 -395.932787) (xy 403.596162 -395.989007) (xy 403.603515 -396.046621)
			(xy 403.603968 -396.075662) (xy 403.603485 -396.104667) (xy 403.596175 -396.162213) (xy 403.581653 -396.218376)
			(xy 403.560154 -396.272254) (xy 403.532021 -396.322984) (xy 403.497704 -396.369754) (xy 403.457755 -396.411815)
			(xy 403.435566 -396.4305) (xy 403.428454 -396.436088) (xy 403.41931 -396.451328) (xy 403.40407 -396.534132)
			(xy 403.406864 -396.551404) (xy 403.411436 -396.559532) (xy 403.424011 -396.582719) (xy 403.441885 -396.63234)
			(xy 403.450986 -396.684291) (xy 403.451568 -396.710662) (xy 403.451499 -396.720021) (xy 403.450356 -396.738703)
			(xy 403.449282 -396.748) (xy 403.448266 -396.75689) (xy 403.452076 -396.773654) (xy 403.496018 -396.843504)
			(xy 403.509734 -396.853918) (xy 403.518116 -396.856712) (xy 403.54214 -396.865193) (xy 403.587312 -396.888742)
			(xy 403.628118 -396.919239) (xy 403.663498 -396.955891) (xy 403.692535 -396.997749) (xy 403.714474 -397.043725)
			(xy 403.722078 -397.06804) (xy 403.723602 -397.073882) (xy 404.043896 -397.627602) (xy 404.04796 -397.63192)
			(xy 404.064162 -397.64963) (xy 404.091584 -397.689021) (xy 404.112726 -397.73211) (xy 404.127101 -397.777904)
			(xy 404.134376 -397.825346) (xy 404.134828 -397.849344) (xy 404.134446 -397.874151) (xy 404.126674 -397.923154)
			(xy 404.111328 -397.970336) (xy 404.088787 -398.014535) (xy 404.059606 -398.054661) (xy 404.024504 -398.089725)
			(xy 403.984346 -398.118864) (xy 403.940123 -398.141358) (xy 403.892925 -398.156653) (xy 403.843914 -398.164373)
			(xy 403.819106 -398.164812) (xy 403.793712 -398.164306) (xy 403.743578 -398.156177) (xy 403.695393 -398.140126)
			(xy 403.650399 -398.116568) (xy 403.609756 -398.086112) (xy 403.574513 -398.049541) (xy 403.545579 -398.007801)
			(xy 403.523701 -397.961966) (xy 403.516084 -397.937736) (xy 403.51456 -397.931894) (xy 403.194266 -397.378174)
			(xy 403.190202 -397.373856) (xy 403.174051 -397.356115) (xy 403.14668 -397.316716) (xy 403.125587 -397.273628)
			(xy 403.111257 -397.227844) (xy 403.104022 -397.180419) (xy 403.103588 -397.156432) (xy 403.103669 -397.144384)
			(xy 403.105452 -397.120355) (xy 403.107144 -397.108426) (xy 403.108414 -397.099536) (xy 403.105366 -397.082518)
			(xy 403.063202 -397.011652) (xy 403.049994 -397.000476) (xy 403.041612 -396.997428) (xy 403.019873 -396.98901)
			(xy 402.979014 -396.966574) (xy 402.942041 -396.938185) (xy 402.909817 -396.904504) (xy 402.88309 -396.866313)
			(xy 402.862483 -396.824501) (xy 402.848474 -396.780042) (xy 402.84139 -396.733969) (xy 402.840952 -396.710662)
			(xy 402.841524 -396.684289) (xy 402.850605 -396.632331) (xy 402.868491 -396.582711) (xy 402.881084 -396.559532)
			(xy 402.885656 -396.551404) (xy 402.88845 -396.534132) (xy 402.87321 -396.451328) (xy 402.864066 -396.436088)
			(xy 402.856954 -396.4305) (xy 402.834774 -396.411805) (xy 402.794829 -396.369741) (xy 402.760514 -396.32297)
			(xy 402.732377 -396.272242) (xy 402.710868 -396.218368) (xy 402.696333 -396.16221) (xy 402.689003 -396.104666)
			(xy 402.688552 -396.075662) (xy 402.689151 -396.042341) (xy 402.69881 -395.976403) (xy 402.717932 -395.912563)
			(xy 402.731478 -395.882114) (xy 402.735718 -395.871645) (xy 402.735613 -395.849087) (xy 402.725879 -395.828737)
			(xy 402.717508 -395.821154) (xy 402.695243 -395.802501) (xy 402.65518 -395.760442) (xy 402.620761 -395.713652)
			(xy 402.592538 -395.662884) (xy 402.570966 -395.608952) (xy 402.55639 -395.552725) (xy 402.549046 -395.495105)
			(xy 402.548598 -395.466062) (xy 402.549033 -395.437135) (xy 402.556317 -395.379741) (xy 402.570778 -395.323724)
			(xy 402.592184 -395.269975) (xy 402.620194 -395.219354) (xy 402.654361 -395.172667) (xy 402.69414 -395.130658)
			(xy 402.716238 -395.111986) (xy 402.723206 -395.105635) (xy 402.732467 -395.089234) (xy 402.734272 -395.079982)
			(xy 402.73859 -395.048994) (xy 402.739487 -395.039757) (xy 402.735466 -395.021658) (xy 402.730716 -395.013688)
			(xy 402.71773 -394.993264) (xy 402.697149 -394.949463) (xy 402.683161 -394.903132) (xy 402.676065 -394.855259)
			(xy 402.675598 -394.831062) (xy 402.675983 -394.807386) (xy 402.682716 -394.760515) (xy 402.69608 -394.715089)
			(xy 402.70557 -394.693394) (xy 402.709888 -394.683996) (xy 402.71065 -394.66393) (xy 402.678392 -394.57757)
			(xy 402.664676 -394.562838) (xy 402.655278 -394.55852) (xy 402.630912 -394.546823) (xy 402.586041 -394.516698)
			(xy 402.546662 -394.479682) (xy 402.513822 -394.436758) (xy 402.488395 -394.389068) (xy 402.471057 -394.337879)
			(xy 402.462269 -394.284553) (xy 402.46173 -394.25753) (xy 400.974691 -394.25753) (xy 400.945268 -394.29429)
			(xy 400.923252 -394.31595) (xy 400.914616 -394.324332) (xy 400.906488 -394.346684) (xy 400.918426 -394.451078)
			(xy 400.93138 -394.47089) (xy 400.941794 -394.47724) (xy 400.96714 -394.492737) (xy 401.013992 -394.529265)
			(xy 401.055722 -394.57155) (xy 401.091629 -394.61888) (xy 401.121109 -394.670458) (xy 401.143666 -394.725418)
			(xy 401.15892 -394.782835) (xy 401.166616 -394.841744) (xy 401.167092 -394.871448) (xy 401.166637 -394.902108)
			(xy 401.158444 -394.962877) (xy 401.142211 -395.022009) (xy 401.118229 -395.078444) (xy 401.086927 -395.131172)
			(xy 401.048866 -395.179249) (xy 401.027138 -395.200886) (xy 401.019402 -395.209201) (xy 401.011399 -395.23042)
			(xy 401.013307 -395.253018) (xy 401.018502 -395.263116) (xy 401.032641 -395.288584) (xy 401.05271 -395.343264)
			(xy 401.062872 -395.400616) (xy 401.06346 -395.42974) (xy 401.06295 -395.455727) (xy 401.05482 -395.507062)
			(xy 401.038759 -395.556492) (xy 401.015163 -395.602802) (xy 400.984613 -395.64485) (xy 400.947862 -395.681601)
			(xy 400.905814 -395.712151) (xy 400.859504 -395.735747) (xy 400.810074 -395.751808) (xy 400.758739 -395.759938)
			(xy 400.706765 -395.759938) (xy 400.65543 -395.751808) (xy 400.606 -395.735747) (xy 400.55969 -395.712151)
			(xy 400.517642 -395.681601) (xy 400.480891 -395.64485) (xy 400.450341 -395.602802) (xy 400.426745 -395.556492)
			(xy 400.410684 -395.507062) (xy 400.402554 -395.455727) (xy 400.402044 -395.42974) (xy 400.40247 -395.405227)
			(xy 400.409653 -395.356731) (xy 400.423926 -395.30983) (xy 400.434048 -395.2875) (xy 400.438443 -395.277037)
			(xy 400.43849 -395.254369) (xy 400.428751 -395.233899) (xy 400.420332 -395.226286) (xy 400.398107 -395.207626)
			(xy 400.358099 -395.165588) (xy 400.323729 -395.118828) (xy 400.295547 -395.068098) (xy 400.274007 -395.014211)
			(xy 400.259454 -394.958032) (xy 400.252122 -394.900464) (xy 400.251676 -394.871448) (xy 400.252184 -394.840568)
			(xy 400.260501 -394.779371) (xy 400.276976 -394.71985) (xy 400.30131 -394.663087) (xy 400.33306 -394.610114)
			(xy 400.371649 -394.561894) (xy 400.393662 -394.540232) (xy 400.402298 -394.53185) (xy 400.410426 -394.509498)
			(xy 400.398488 -394.405104) (xy 400.385534 -394.385292) (xy 400.37512 -394.378942) (xy 400.351738 -394.364715)
			(xy 400.308227 -394.331511) (xy 400.268992 -394.293348) (xy 400.234597 -394.250773) (xy 400.205532 -394.204394)
			(xy 400.19351 -394.179806) (xy 400.187414 -394.167106) (xy 400.164554 -394.151612) (xy 400.047714 -394.144246)
			(xy 400.02333 -394.156692) (xy 400.01571 -394.16863) (xy 400.000661 -394.191537) (xy 399.964964 -394.23313)
			(xy 399.923681 -394.269185) (xy 399.877664 -394.29896) (xy 399.827859 -394.321843) (xy 399.775291 -394.337362)
			(xy 399.721043 -394.345198) (xy 399.693638 -394.345668) (xy 399.66638 -394.345288) (xy 399.61242 -394.337534)
			(xy 399.560112 -394.32218) (xy 399.510522 -394.299537) (xy 399.464659 -394.270067) (xy 399.423457 -394.23437)
			(xy 399.387756 -394.193172) (xy 399.358281 -394.147312) (xy 399.335633 -394.097724) (xy 399.320274 -394.045417)
			(xy 399.312515 -393.991457) (xy 392.882058 -393.991457) (xy 392.891772 -394.010642) (xy 392.90117 -394.017754)
			(xy 392.92749 -394.038435) (xy 392.975028 -394.085559) (xy 393.015969 -394.138515) (xy 393.049606 -394.196386)
			(xy 393.075355 -394.258172) (xy 393.092771 -394.322804) (xy 393.101553 -394.389162) (xy 393.102084 -394.42263)
			(xy 393.101672 -394.453363) (xy 393.09426 -394.514379) (xy 393.079547 -394.574057) (xy 393.057748 -394.631527)
			(xy 393.02918 -394.68595) (xy 392.994261 -394.736533) (xy 392.9535 -394.782538) (xy 392.907491 -394.823295)
			(xy 392.856904 -394.858208) (xy 392.802478 -394.88677) (xy 392.745006 -394.908563) (xy 392.685326 -394.923269)
			(xy 392.624309 -394.930675) (xy 392.593576 -394.931138) (xy 392.56414 -394.930737) (xy 392.505662 -394.92393)
			(xy 392.448363 -394.910409) (xy 392.393011 -394.890355) (xy 392.340348 -394.864038) (xy 392.291079 -394.831811)
			(xy 392.268202 -394.813282) (xy 392.252962 -394.800836) (xy 392.213592 -394.802614) (xy 392.149584 -394.866622)
			(xy 392.142218 -394.881862) (xy 392.140948 -394.890244) (xy 392.136716 -394.920592) (xy 392.121826 -394.980032)
			(xy 392.099899 -395.037252) (xy 392.071253 -395.091421) (xy 392.036302 -395.141753) (xy 391.995554 -395.187519)
			(xy 391.9496 -395.228055) (xy 391.899107 -395.262772) (xy 391.844806 -395.291168) (xy 391.787486 -395.31283)
			(xy 391.727977 -395.327444) (xy 391.667143 -395.334799) (xy 391.636504 -395.335252) (xy 391.6051 -395.334723)
			(xy 391.542771 -395.326988) (xy 391.481869 -395.311636) (xy 391.423322 -395.288899) (xy 391.36802 -395.259125)
			(xy 391.316806 -395.222767) (xy 391.27046 -395.180378) (xy 391.229688 -395.132604) (xy 391.19511 -395.080172)
			(xy 391.167253 -395.023881) (xy 391.14654 -394.964587) (xy 391.133288 -394.903193) (xy 391.130028 -394.871956)
			(xy 391.129012 -394.861796) (xy 391.120376 -394.844778) (xy 391.052304 -394.785342) (xy 391.034016 -394.778992)
			(xy 391.023856 -394.7795) (xy 390.999726 -394.780008) (xy 390.968994 -394.779538) (xy 390.907979 -394.772132)
			(xy 390.848301 -394.757426) (xy 390.790832 -394.735633) (xy 390.736408 -394.707072) (xy 390.685823 -394.672158)
			(xy 390.639817 -394.631402) (xy 390.599058 -394.585397) (xy 390.564142 -394.534815) (xy 390.535578 -394.480392)
			(xy 390.513782 -394.422923) (xy 390.499072 -394.363246) (xy 390.491664 -394.302232) (xy 390.491218 -394.2715)
			(xy 390.491625 -394.240718) (xy 390.499043 -394.179603) (xy 390.513782 -394.11983) (xy 390.535626 -394.062273)
			(xy 390.564257 -394.007772) (xy 390.581388 -393.982194) (xy 390.586465 -393.974199) (xy 390.590915 -393.955807)
			(xy 390.590024 -393.94638) (xy 390.585706 -393.915646) (xy 390.584045 -393.906382) (xy 390.57492 -393.889938)
			(xy 390.567926 -393.883642) (xy 390.5461 -393.864954) (xy 390.506795 -393.82304) (xy 390.473047 -393.776535)
			(xy 390.445387 -393.72617) (xy 390.42425 -393.672739) (xy 390.40997 -393.617081) (xy 390.40277 -393.560074)
			(xy 390.402318 -393.531344) (xy 389.319442 -393.531344) (xy 389.325617 -393.546409) (xy 389.340842 -393.603805)
			(xy 389.348513 -393.662689) (xy 389.34898 -393.69238) (xy 389.348453 -393.723443) (xy 389.340041 -393.784996)
			(xy 389.332216 -393.815062) (xy 389.329422 -393.825222) (xy 389.331962 -393.845034) (xy 389.37946 -393.92733)
			(xy 389.395462 -393.939522) (xy 389.405622 -393.942062) (xy 389.434726 -393.950082) (xy 389.490692 -393.972713)
			(xy 389.543198 -394.002504) (xy 389.591332 -394.038939) (xy 389.634259 -394.081385) (xy 389.671234 -394.129105)
			(xy 389.701615 -394.181272) (xy 389.724875 -394.236981) (xy 389.740609 -394.295263) (xy 389.748546 -394.355108)
			(xy 389.74903 -394.385292) (xy 389.748928 -394.399042) (xy 389.747276 -394.426493) (xy 389.745728 -394.440156)
			(xy 389.74501 -394.448844) (xy 389.748783 -394.465853) (xy 389.753094 -394.47343) (xy 389.769096 -394.49883)
			(xy 389.773866 -394.505866) (xy 389.787108 -394.516508) (xy 389.795004 -394.519658) (xy 389.818778 -394.528584)
			(xy 389.863427 -394.552776) (xy 389.903853 -394.58351) (xy 389.939104 -394.620064) (xy 389.968352 -394.661577)
			(xy 389.99091 -394.707074) (xy 390.006246 -394.755485) (xy 390.014001 -394.805671) (xy 390.01446 -394.831062)
			(xy 390.01399 -394.857053) (xy 390.005863 -394.908395) (xy 389.989803 -394.957833) (xy 389.966205 -395.004149)
			(xy 389.935652 -395.046203) (xy 389.898895 -395.082959) (xy 389.85684 -395.113511) (xy 389.810523 -395.137106)
			(xy 389.761085 -395.153165) (xy 389.709743 -395.16129) (xy 389.683752 -395.16177) (xy 389.658845 -395.161272)
			(xy 389.60959 -395.153821) (xy 389.562012 -395.139065) (xy 389.517185 -395.117338) (xy 389.476125 -395.089132)
			(xy 389.439762 -395.055085) (xy 389.408918 -395.015968) (xy 389.384292 -394.972666) (xy 389.366441 -394.92616)
			(xy 389.360664 -394.901928) (xy 389.358501 -394.893708) (xy 389.34969 -394.879187) (xy 389.343392 -394.87348)
			(xy 389.320024 -394.85443) (xy 389.313135 -394.849225) (xy 389.2969 -394.843381) (xy 389.288274 -394.843)
			(xy 389.258437 -394.842297) (xy 389.199315 -394.834148) (xy 389.141753 -394.818384) (xy 389.086729 -394.795272)
			(xy 389.035176 -394.765204) (xy 388.987969 -394.728689) (xy 388.945908 -394.686349) (xy 388.909707 -394.6389)
			(xy 388.879981 -394.587149) (xy 388.857234 -394.531972) (xy 388.841852 -394.474308) (xy 388.834095 -394.415133)
			(xy 388.833614 -394.385292) (xy 388.834136 -394.354229) (xy 388.842551 -394.292675) (xy 388.850378 -394.26261)
			(xy 388.853172 -394.25245) (xy 388.850632 -394.232638) (xy 388.803134 -394.150342) (xy 388.787132 -394.13815)
			(xy 388.776972 -394.13561) (xy 388.747859 -394.12762) (xy 388.691891 -394.104986) (xy 388.639385 -394.075192)
			(xy 388.59125 -394.038754) (xy 388.548323 -393.996305) (xy 388.511349 -393.94858) (xy 388.480969 -393.89641)
			(xy 388.457712 -393.840699) (xy 388.44198 -393.782413) (xy 388.434046 -393.722566) (xy 388.433564 -393.69238)
			(xy 388.434081 -393.661492) (xy 388.442387 -393.600276) (xy 388.458846 -393.540731) (xy 388.48316 -393.48394)
			(xy 388.498588 -393.457176) (xy 388.50443 -393.44727) (xy 388.506716 -393.424918) (xy 388.473442 -393.329668)
			(xy 388.457694 -393.313666) (xy 388.447026 -393.309602) (xy 388.423629 -393.300456) (xy 388.379734 -393.276028)
			(xy 388.340041 -393.24524) (xy 388.305462 -393.208801) (xy 388.276795 -393.167549) (xy 388.2547 -393.122435)
			(xy 388.239685 -393.074497) (xy 388.232096 -393.024839) (xy 388.231634 -392.999722) (xy 387.693154 -392.999722)
			(xy 387.692624 -393.026824) (xy 387.683814 -393.080307) (xy 387.675628 -393.106148) (xy 387.671818 -393.11707)
			(xy 387.674358 -393.139422) (xy 387.726936 -393.225274) (xy 387.745986 -393.23772) (xy 387.757162 -393.239498)
			(xy 387.786484 -393.244181) (xy 387.843655 -393.260233) (xy 387.898269 -393.283547) (xy 387.949408 -393.313729)
			(xy 387.996213 -393.350273) (xy 388.037897 -393.392564) (xy 388.073761 -393.439893) (xy 388.1032 -393.491463)
			(xy 388.125722 -393.546408) (xy 388.140946 -393.603805) (xy 388.148617 -393.662689) (xy 388.149084 -393.69238)
			(xy 388.14856 -393.723506) (xy 388.140155 -393.785188) (xy 388.13232 -393.815316) (xy 388.129526 -393.825476)
			(xy 388.132066 -393.845542) (xy 388.17931 -393.92733) (xy 388.195312 -393.939522) (xy 388.205472 -393.942062)
			(xy 388.234585 -393.950048) (xy 388.290551 -393.972685) (xy 388.343056 -394.002482) (xy 388.391189 -394.038921)
			(xy 388.434115 -394.081371) (xy 388.471088 -394.129095) (xy 388.501468 -394.181265) (xy 388.524726 -394.236976)
			(xy 388.54046 -394.29526) (xy 388.548397 -394.355107) (xy 388.54888 -394.385292) (xy 388.548755 -394.399427)
			(xy 388.546973 -394.427641) (xy 388.545324 -394.44168) (xy 388.544568 -394.450287) (xy 388.548205 -394.467166)
			(xy 388.552436 -394.4747) (xy 388.568184 -394.5001) (xy 388.572896 -394.507158) (xy 388.586 -394.517928)
			(xy 388.593838 -394.521182) (xy 388.617221 -394.530361) (xy 388.661117 -394.554783) (xy 388.700812 -394.585565)
			(xy 388.735392 -394.621999) (xy 388.764061 -394.663246) (xy 388.786158 -394.708357) (xy 388.801176 -394.756291)
			(xy 388.808767 -394.805946) (xy 388.80923 -394.831062) (xy 388.808816 -394.855265) (xy 388.801741 -394.90315)
			(xy 388.787752 -394.94949) (xy 388.767148 -394.993291) (xy 388.754112 -395.013688) (xy 388.74932 -395.021642)
			(xy 388.74529 -395.039755) (xy 388.746238 -395.048994) (xy 388.750556 -395.079982) (xy 388.752251 -395.089275)
			(xy 388.761524 -395.105717) (xy 388.76859 -395.111986) (xy 388.790684 -395.130661) (xy 388.830454 -395.172675)
			(xy 388.864615 -395.219365) (xy 388.892621 -395.269985) (xy 388.914028 -395.323731) (xy 388.928492 -395.379746)
			(xy 388.935785 -395.437136) (xy 388.93623 -395.466062) (xy 392.983718 -395.466062) (xy 392.987789 -395.41044)
			(xy 392.999915 -395.356003) (xy 393.019838 -395.303912) (xy 393.047134 -395.255277) (xy 393.08122 -395.211134)
			(xy 393.121369 -395.172425) (xy 393.166727 -395.139974) (xy 393.216327 -395.114473) (xy 393.269111 -395.096466)
			(xy 393.323954 -395.086336) (xy 393.379688 -395.084299) (xy 393.435125 -395.090399) (xy 393.489082 -395.104505)
			(xy 393.540411 -395.126317) (xy 393.588017 -395.155371) (xy 393.630885 -395.191046) (xy 393.668102 -395.232583)
			(xy 393.698875 -395.279096) (xy 393.722547 -395.329593) (xy 393.738615 -395.383) (xy 393.746735 -395.438176)
			(xy 393.747244 -395.466062) (xy 393.746735 -395.493948) (xy 393.738615 -395.549124) (xy 393.722547 -395.602531)
			(xy 393.698875 -395.653028) (xy 393.668102 -395.699541) (xy 393.630885 -395.741078) (xy 393.588017 -395.776753)
			(xy 393.540411 -395.805807) (xy 393.489082 -395.827619) (xy 393.435125 -395.841725) (xy 393.379688 -395.847825)
			(xy 393.323954 -395.845788) (xy 393.269111 -395.835658) (xy 393.216327 -395.817651) (xy 393.166727 -395.79215)
			(xy 393.121369 -395.759699) (xy 393.08122 -395.72099) (xy 393.047134 -395.676847) (xy 393.019838 -395.628212)
			(xy 392.999915 -395.576121) (xy 392.987789 -395.521684) (xy 392.983718 -395.466062) (xy 388.93623 -395.466062)
			(xy 388.935641 -395.499383) (xy 388.925978 -395.565322) (xy 388.906852 -395.629161) (xy 388.893304 -395.65961)
			(xy 388.889047 -395.670072) (xy 388.889161 -395.692635) (xy 388.8989 -395.712987) (xy 388.907274 -395.72057)
			(xy 388.929499 -395.739269) (xy 388.969564 -395.78132) (xy 389.003988 -395.828101) (xy 389.032216 -395.878862)
			(xy 389.053795 -395.932786) (xy 389.068378 -395.989007) (xy 389.075731 -396.046621) (xy 389.076184 -396.075662)
			(xy 389.075695 -396.104666) (xy 389.068385 -396.162213) (xy 389.064691 -396.1765) (xy 395.05712 -396.1765)
			(xy 395.061191 -396.120878) (xy 395.073317 -396.066441) (xy 395.09324 -396.01435) (xy 395.120536 -395.965715)
			(xy 395.154622 -395.921572) (xy 395.194771 -395.882863) (xy 395.240129 -395.850412) (xy 395.289729 -395.824911)
			(xy 395.342513 -395.806904) (xy 395.397356 -395.796774) (xy 395.45309 -395.794737) (xy 395.508527 -395.800837)
			(xy 395.562484 -395.814943) (xy 395.613813 -395.836755) (xy 395.661419 -395.865809) (xy 395.704287 -395.901484)
			(xy 395.741504 -395.943021) (xy 395.772277 -395.989534) (xy 395.795949 -396.040031) (xy 395.812017 -396.093438)
			(xy 395.820137 -396.148614) (xy 395.820558 -396.171674) (xy 396.402052 -396.171674) (xy 396.40263 -396.136719)
			(xy 396.412194 -396.067466) (xy 396.431153 -396.000175) (xy 396.459148 -395.936115) (xy 396.495653 -395.876492)
			(xy 396.517368 -395.849094) (xy 396.522673 -395.842101) (xy 396.528642 -395.825605) (xy 396.529052 -395.816836)
			(xy 396.529052 -395.662912) (xy 396.528675 -395.654137) (xy 396.522699 -395.637634) (xy 396.517368 -395.630654)
			(xy 396.495675 -395.60324) (xy 396.459175 -395.543618) (xy 396.431179 -395.479561) (xy 396.412214 -395.412276)
			(xy 396.402636 -395.343028) (xy 396.402052 -395.308074) (xy 396.402532 -395.277344) (xy 396.409942 -395.216332)
			(xy 396.424652 -395.156659) (xy 396.446448 -395.099193) (xy 396.47501 -395.044773) (xy 396.509924 -394.994193)
			(xy 396.550679 -394.948189) (xy 396.596682 -394.907432) (xy 396.647261 -394.872517) (xy 396.70168 -394.843953)
			(xy 396.759145 -394.822157) (xy 396.818819 -394.807445) (xy 396.87983 -394.800032) (xy 396.91056 -394.799566)
			(xy 396.931485 -394.799774) (xy 396.973195 -394.803206) (xy 396.993872 -394.806424) (xy 397.003016 -394.807948)
			(xy 397.020796 -394.804646) (xy 397.092932 -394.760958) (xy 397.104108 -394.746988) (xy 397.107156 -394.738352)
			(xy 397.115916 -394.713329) (xy 397.139404 -394.6658) (xy 397.16925 -394.621983) (xy 397.204879 -394.582723)
			(xy 397.245602 -394.548777) (xy 397.290636 -394.5208) (xy 397.339111 -394.499331) (xy 397.390093 -394.484785)
			(xy 397.442598 -394.477441) (xy 397.469106 -394.476986) (xy 397.496357 -394.477472) (xy 397.550305 -394.485229)
			(xy 397.602599 -394.500585) (xy 397.652176 -394.523226) (xy 397.698026 -394.552693) (xy 397.739216 -394.588384)
			(xy 397.774907 -394.629574) (xy 397.804374 -394.675424) (xy 397.827015 -394.725001) (xy 397.842371 -394.777295)
			(xy 397.850128 -394.831243) (xy 397.850614 -394.858494) (xy 397.850101 -394.886466) (xy 397.841958 -394.941815)
			(xy 397.825817 -394.99538) (xy 397.802023 -395.046012) (xy 397.771087 -395.092625) (xy 397.733674 -395.134218)
			(xy 397.690586 -395.1699) (xy 397.642747 -395.198903) (xy 397.591184 -395.220607) (xy 397.537004 -395.234545)
			(xy 397.509238 -395.23797) (xy 397.500094 -395.238732) (xy 397.483838 -395.24686) (xy 397.425926 -395.308074)
			(xy 397.418814 -395.324584) (xy 397.418306 -395.333728) (xy 397.416208 -395.366046) (xy 397.404797 -395.429798)
			(xy 397.385377 -395.491583) (xy 397.358262 -395.550399) (xy 397.323892 -395.605291) (xy 397.303752 -395.630654)
			(xy 397.29847 -395.637663) (xy 397.292487 -395.654147) (xy 397.292068 -395.662912) (xy 397.292068 -395.816836)
			(xy 397.292418 -395.825614) (xy 397.298412 -395.842116) (xy 397.303752 -395.849094) (xy 397.325455 -395.876501)
			(xy 397.361956 -395.936124) (xy 397.389951 -396.000182) (xy 397.408914 -396.06747) (xy 397.418487 -396.13672)
			(xy 397.419068 -396.171674) (xy 397.418367 -396.210189) (xy 397.406762 -396.286338) (xy 397.395954 -396.323312)
			(xy 397.392652 -396.333726) (xy 397.395192 -396.355062) (xy 397.445738 -396.439136) (xy 397.463264 -396.451328)
			(xy 397.474186 -396.45336) (xy 397.50006 -396.458733) (xy 397.550145 -396.475583) (xy 397.597424 -396.499185)
			(xy 397.640993 -396.529087) (xy 397.680019 -396.564715) (xy 397.713753 -396.605389) (xy 397.741551 -396.65033)
			(xy 397.754497 -396.679674) (xy 399.436588 -396.679674) (xy 399.440659 -396.624052) (xy 399.452785 -396.569615)
			(xy 399.472708 -396.517524) (xy 399.500004 -396.468889) (xy 399.53409 -396.424746) (xy 399.574239 -396.386037)
			(xy 399.619597 -396.353586) (xy 399.669197 -396.328085) (xy 399.721981 -396.310078) (xy 399.776824 -396.299948)
			(xy 399.832558 -396.297911) (xy 399.887995 -396.304011) (xy 399.941952 -396.318117) (xy 399.993281 -396.339929)
			(xy 400.040887 -396.368983) (xy 400.083755 -396.404658) (xy 400.120972 -396.446195) (xy 400.151745 -396.492708)
			(xy 400.175417 -396.543205) (xy 400.191485 -396.596612) (xy 400.199605 -396.651788) (xy 400.200114 -396.679674)
			(xy 400.199667 -396.704137) (xy 400.402554 -396.704137) (xy 400.402554 -396.652163) (xy 400.410684 -396.600828)
			(xy 400.426745 -396.551398) (xy 400.450341 -396.505088) (xy 400.480891 -396.46304) (xy 400.517642 -396.426289)
			(xy 400.55969 -396.395739) (xy 400.606 -396.372143) (xy 400.65543 -396.356082) (xy 400.706765 -396.347952)
			(xy 400.758739 -396.347952) (xy 400.810074 -396.356082) (xy 400.859504 -396.372143) (xy 400.905814 -396.395739)
			(xy 400.947862 -396.426289) (xy 400.984613 -396.46304) (xy 401.015163 -396.505088) (xy 401.038759 -396.551398)
			(xy 401.05482 -396.600828) (xy 401.06295 -396.652163) (xy 401.06346 -396.67815) (xy 401.06295 -396.704137)
			(xy 401.05482 -396.755472) (xy 401.038759 -396.804902) (xy 401.015163 -396.851212) (xy 400.984613 -396.89326)
			(xy 400.947862 -396.930011) (xy 400.905814 -396.960561) (xy 400.859504 -396.984157) (xy 400.810074 -397.000218)
			(xy 400.758739 -397.008348) (xy 400.706765 -397.008348) (xy 400.65543 -397.000218) (xy 400.606 -396.984157)
			(xy 400.55969 -396.960561) (xy 400.517642 -396.930011) (xy 400.480891 -396.89326) (xy 400.450341 -396.851212)
			(xy 400.426745 -396.804902) (xy 400.410684 -396.755472) (xy 400.402554 -396.704137) (xy 400.199667 -396.704137)
			(xy 400.199605 -396.70756) (xy 400.191485 -396.762736) (xy 400.175417 -396.816143) (xy 400.151745 -396.86664)
			(xy 400.120972 -396.913153) (xy 400.083755 -396.95469) (xy 400.040887 -396.990365) (xy 399.993281 -397.019419)
			(xy 399.941952 -397.041231) (xy 399.887995 -397.055337) (xy 399.832558 -397.061437) (xy 399.776824 -397.0594)
			(xy 399.721981 -397.04927) (xy 399.669197 -397.031263) (xy 399.619597 -397.005762) (xy 399.574239 -396.973311)
			(xy 399.53409 -396.934602) (xy 399.500004 -396.890459) (xy 399.472708 -396.841824) (xy 399.452785 -396.789733)
			(xy 399.440659 -396.735296) (xy 399.436588 -396.679674) (xy 397.754497 -396.679674) (xy 397.76288 -396.698677)
			(xy 397.777332 -396.749506) (xy 397.784631 -396.801843) (xy 397.785082 -396.828264) (xy 397.784611 -396.855517)
			(xy 397.776858 -396.909469) (xy 397.761506 -396.961768) (xy 397.738865 -397.01135) (xy 397.709399 -397.057205)
			(xy 397.673706 -397.098399) (xy 397.632513 -397.134093) (xy 397.586659 -397.163561) (xy 397.537078 -397.186202)
			(xy 397.484779 -397.201556) (xy 397.430827 -397.20931) (xy 397.403574 -397.209772) (xy 397.370554 -397.208248)
			(xy 397.3576 -397.207232) (xy 397.334232 -397.217392) (xy 397.265652 -397.304514) (xy 397.261334 -397.32966)
			(xy 397.265398 -397.341852) (xy 397.274661 -397.371345) (xy 397.284613 -397.432356) (xy 397.28521 -397.463264)
			(xy 397.284784 -397.49052) (xy 397.277031 -397.544478) (xy 397.261677 -397.596783) (xy 397.239037 -397.646371)
			(xy 397.209569 -397.692232) (xy 397.173874 -397.733432) (xy 397.13268 -397.769133) (xy 397.086823 -397.798608)
			(xy 397.037239 -397.821257) (xy 396.984936 -397.836618) (xy 396.930979 -397.844379) (xy 396.876467 -397.844383)
			(xy 396.82251 -397.836628) (xy 396.770205 -397.821273) (xy 396.720618 -397.79863) (xy 396.674758 -397.769161)
			(xy 396.633559 -397.733465) (xy 396.597859 -397.692269) (xy 396.568386 -397.646412) (xy 396.545739 -397.596827)
			(xy 396.530379 -397.544524) (xy 396.52262 -397.490567) (xy 396.522618 -397.436055) (xy 396.530375 -397.382097)
			(xy 396.545731 -397.329793) (xy 396.568376 -397.280207) (xy 396.597846 -397.234348) (xy 396.633544 -397.19315)
			(xy 396.674741 -397.157452) (xy 396.720599 -397.12798) (xy 396.770185 -397.105334) (xy 396.822489 -397.089977)
			(xy 396.876446 -397.082219) (xy 396.903702 -397.081756) (xy 396.936722 -397.08328) (xy 396.949676 -397.084296)
			(xy 396.973044 -397.074136) (xy 397.041624 -396.987014) (xy 397.045942 -396.961868) (xy 397.041878 -396.949676)
			(xy 397.03262 -396.920181) (xy 397.022665 -396.859172) (xy 397.022066 -396.828264) (xy 397.023844 -396.791434)
			(xy 397.02486 -396.780512) (xy 397.018002 -396.760192) (xy 396.951454 -396.68831) (xy 396.931896 -396.679928)
			(xy 396.92072 -396.680182) (xy 396.91056 -396.680182) (xy 396.879827 -396.679782) (xy 396.81881 -396.672368)
			(xy 396.759131 -396.657654) (xy 396.701661 -396.635854) (xy 396.647238 -396.607286) (xy 396.596655 -396.572366)
			(xy 396.55065 -396.531603) (xy 396.509894 -396.485593) (xy 396.47498 -396.435005) (xy 396.446419 -396.380578)
			(xy 396.424626 -396.323106) (xy 396.40992 -396.263425) (xy 396.402514 -396.202407) (xy 396.402052 -396.171674)
			(xy 395.820558 -396.171674) (xy 395.820646 -396.1765) (xy 395.820137 -396.204386) (xy 395.812017 -396.259562)
			(xy 395.795949 -396.312969) (xy 395.772277 -396.363466) (xy 395.741504 -396.409979) (xy 395.704287 -396.451516)
			(xy 395.661419 -396.487191) (xy 395.613813 -396.516245) (xy 395.562484 -396.538057) (xy 395.508527 -396.552163)
			(xy 395.45309 -396.558263) (xy 395.397356 -396.556226) (xy 395.342513 -396.546096) (xy 395.289729 -396.528089)
			(xy 395.240129 -396.502588) (xy 395.194771 -396.470137) (xy 395.154622 -396.431428) (xy 395.120536 -396.387285)
			(xy 395.09324 -396.33865) (xy 395.073317 -396.286559) (xy 395.061191 -396.232122) (xy 395.05712 -396.1765)
			(xy 389.064691 -396.1765) (xy 389.053864 -396.218375) (xy 389.032366 -396.272252) (xy 389.004233 -396.322983)
			(xy 388.969918 -396.369753) (xy 388.92997 -396.411814) (xy 388.907782 -396.4305) (xy 388.90067 -396.436088)
			(xy 388.891526 -396.451328) (xy 388.876286 -396.534132) (xy 388.87908 -396.551404) (xy 388.883652 -396.559532)
			(xy 388.896228 -396.582718) (xy 388.914102 -396.63234) (xy 388.920925 -396.671292) (xy 390.46912 -396.671292)
			(xy 390.46961 -396.641324) (xy 390.477433 -396.581902) (xy 390.492946 -396.524009) (xy 390.515882 -396.468636)
			(xy 390.545849 -396.41673) (xy 390.582336 -396.36918) (xy 390.624716 -396.3268) (xy 390.672266 -396.290313)
			(xy 390.724172 -396.260346) (xy 390.779545 -396.23741) (xy 390.837438 -396.221897) (xy 390.89686 -396.214074)
			(xy 390.956796 -396.214074) (xy 391.016218 -396.221897) (xy 391.074111 -396.23741) (xy 391.129484 -396.260346)
			(xy 391.18139 -396.290313) (xy 391.22894 -396.3268) (xy 391.27132 -396.36918) (xy 391.307807 -396.41673)
			(xy 391.337774 -396.468636) (xy 391.36071 -396.524009) (xy 391.376223 -396.581902) (xy 391.384046 -396.641324)
			(xy 391.384536 -396.671292) (xy 391.383975 -396.703116) (xy 391.375158 -396.766151) (xy 391.357692 -396.827357)
			(xy 391.331915 -396.885552) (xy 391.298323 -396.939614) (xy 391.278364 -396.964408) (xy 391.272522 -396.97152)
			(xy 391.266426 -396.989046) (xy 391.268966 -397.075152) (xy 391.276078 -397.09217) (xy 391.282428 -397.099028)
			(xy 391.294914 -397.112556) (xy 391.317929 -397.141292) (xy 391.328402 -397.156432) (xy 391.33653 -397.168116)
			(xy 391.362184 -397.180054) (xy 391.479786 -397.166846) (xy 391.502138 -397.149574) (xy 391.507218 -397.136366)
			(xy 391.518068 -397.109864) (xy 391.546551 -397.060184) (xy 391.582139 -397.01532) (xy 391.624034 -396.976279)
			(xy 391.671293 -396.94394) (xy 391.722856 -396.919028) (xy 391.777563 -396.902103) (xy 391.834185 -396.893546)
			(xy 391.862818 -396.893034) (xy 391.890189 -396.893481) (xy 391.944369 -396.901302) (xy 391.996873 -396.916795)
			(xy 392.046619 -396.939641) (xy 392.092585 -396.969371) (xy 392.113516 -396.987014) (xy 392.120628 -396.99311)
			(xy 392.137646 -396.99946) (xy 392.22299 -396.99946) (xy 392.240008 -396.99311) (xy 392.24712 -396.987014)
			(xy 392.268053 -396.969373) (xy 392.314021 -396.939649) (xy 392.363767 -396.916803) (xy 392.416269 -396.901307)
			(xy 392.470447 -396.893478) (xy 392.525189 -396.893478) (xy 392.579367 -396.901307) (xy 392.631869 -396.916803)
			(xy 392.681615 -396.939649) (xy 392.727583 -396.969373) (xy 392.748516 -396.987014) (xy 392.755628 -396.99311)
			(xy 392.772646 -396.99946) (xy 392.85799 -396.99946) (xy 392.875008 -396.99311) (xy 392.88212 -396.987014)
			(xy 392.903073 -396.969401) (xy 392.94904 -396.939685) (xy 392.998782 -396.916844) (xy 393.051278 -396.901346)
			(xy 393.10545 -396.893512) (xy 393.132818 -396.893034) (xy 393.160071 -396.893437) (xy 393.214023 -396.901197)
			(xy 393.266321 -396.916555) (xy 393.315902 -396.9392) (xy 393.361755 -396.96867) (xy 393.402948 -397.004365)
			(xy 393.438641 -397.045559) (xy 393.468109 -397.091414) (xy 393.490751 -397.140995) (xy 393.502307 -397.180352)
			(xy 394.841185 -397.180352) (xy 394.841185 -397.125848) (xy 394.848942 -397.0719) (xy 394.864298 -397.019604)
			(xy 394.886941 -396.970026) (xy 394.916408 -396.924176) (xy 394.952101 -396.882986) (xy 394.993294 -396.847295)
			(xy 395.039146 -396.81783) (xy 395.088725 -396.79519) (xy 395.141021 -396.779838) (xy 395.19497 -396.772084)
			(xy 395.222222 -396.771622) (xy 395.249593 -396.77207) (xy 395.303773 -396.779891) (xy 395.356277 -396.795384)
			(xy 395.406023 -396.81823) (xy 395.451989 -396.847959) (xy 395.47292 -396.865602) (xy 395.480032 -396.871698)
			(xy 395.49705 -396.878048) (xy 395.582394 -396.878048) (xy 395.599412 -396.871698) (xy 395.606524 -396.865602)
			(xy 395.627474 -396.847985) (xy 395.673442 -396.81827) (xy 395.723185 -396.79543) (xy 395.775682 -396.779933)
			(xy 395.829854 -396.772099) (xy 395.857222 -396.771622) (xy 395.884474 -396.772049) (xy 395.938424 -396.779809)
			(xy 395.99072 -396.795167) (xy 396.040299 -396.817811) (xy 396.08615 -396.847281) (xy 396.127341 -396.882975)
			(xy 396.163033 -396.924168) (xy 396.192499 -396.970021) (xy 396.21514 -397.0196) (xy 396.230496 -397.071898)
			(xy 396.238252 -397.125848) (xy 396.238252 -397.180352) (xy 396.230496 -397.234302) (xy 396.21514 -397.2866)
			(xy 396.192499 -397.336179) (xy 396.163033 -397.382032) (xy 396.127341 -397.423225) (xy 396.08615 -397.458919)
			(xy 396.040299 -397.488389) (xy 395.99072 -397.511033) (xy 395.938424 -397.526391) (xy 395.884474 -397.534151)
			(xy 395.857222 -397.534638) (xy 395.829852 -397.534174) (xy 395.775672 -397.526358) (xy 395.723168 -397.510869)
			(xy 395.673421 -397.488027) (xy 395.627455 -397.4583) (xy 395.606524 -397.440658) (xy 395.599412 -397.434562)
			(xy 395.582394 -397.428212) (xy 395.49705 -397.428212) (xy 395.480032 -397.434562) (xy 395.47292 -397.440658)
			(xy 395.451986 -397.458295) (xy 395.406014 -397.488008) (xy 395.356267 -397.510845) (xy 395.303767 -397.526337)
			(xy 395.249591 -397.534165) (xy 395.222222 -397.534638) (xy 395.19497 -397.534116) (xy 395.141021 -397.526362)
			(xy 395.088725 -397.511009) (xy 395.039146 -397.48837) (xy 394.993294 -397.458905) (xy 394.952101 -397.423214)
			(xy 394.916408 -397.382024) (xy 394.886941 -397.336174) (xy 394.864298 -397.286596) (xy 394.848942 -397.2343)
			(xy 394.841185 -397.180352) (xy 393.502307 -397.180352) (xy 393.506107 -397.193294) (xy 393.513864 -397.247247)
			(xy 393.513864 -397.301753) (xy 393.506107 -397.355706) (xy 393.490751 -397.408005) (xy 393.468109 -397.457586)
			(xy 393.438641 -397.503441) (xy 393.402948 -397.544635) (xy 393.361755 -397.58033) (xy 393.315902 -397.6098)
			(xy 393.266321 -397.632445) (xy 393.214023 -397.647803) (xy 393.160071 -397.655563) (xy 393.132818 -397.65605)
			(xy 393.105448 -397.655586) (xy 393.051268 -397.647769) (xy 392.998764 -397.63228) (xy 392.949017 -397.609438)
			(xy 392.903051 -397.579712) (xy 392.88212 -397.56207) (xy 392.875008 -397.555974) (xy 392.85799 -397.549624)
			(xy 392.772646 -397.549624) (xy 392.755628 -397.555974) (xy 392.748516 -397.56207) (xy 392.727583 -397.579711)
			(xy 392.681615 -397.609435) (xy 392.631869 -397.632281) (xy 392.579367 -397.647777) (xy 392.525189 -397.655606)
			(xy 392.470447 -397.655606) (xy 392.416269 -397.647777) (xy 392.363767 -397.632281) (xy 392.314021 -397.609435)
			(xy 392.268053 -397.579711) (xy 392.24712 -397.56207) (xy 392.240008 -397.555974) (xy 392.22299 -397.549624)
			(xy 392.137646 -397.549624) (xy 392.120628 -397.555974) (xy 392.113516 -397.56207) (xy 392.092585 -397.57971)
			(xy 392.046612 -397.609423) (xy 391.996865 -397.632259) (xy 391.944364 -397.64775) (xy 391.890187 -397.655577)
			(xy 391.862818 -397.65605) (xy 391.834217 -397.655537) (xy 391.777654 -397.647005) (xy 391.722997 -397.630129)
			(xy 391.67147 -397.605286) (xy 391.624227 -397.573033) (xy 391.582324 -397.534093) (xy 391.564114 -397.512032)
			(xy 391.555478 -397.500856) (xy 391.528808 -397.49095) (xy 391.412476 -397.513302) (xy 391.391648 -397.532098)
			(xy 391.387584 -397.545814) (xy 391.377488 -397.577161) (xy 391.349516 -397.63678) (xy 391.313275 -397.691766)
			(xy 391.291826 -397.716756) (xy 391.285476 -397.723868) (xy 391.278872 -397.74114) (xy 391.278872 -397.827246)
			(xy 391.285476 -397.844518) (xy 391.291826 -397.85163) (xy 391.313403 -397.876866) (xy 391.349777 -397.932414)
			(xy 391.377744 -397.992633) (xy 391.396718 -398.05626) (xy 391.406301 -398.121962) (xy 391.406888 -398.15516)
			(xy 391.40637 -398.186762) (xy 391.397666 -398.249363) (xy 391.380418 -398.310168) (xy 391.354956 -398.368016)
			(xy 391.338816 -398.39519) (xy 391.334294 -398.403422) (xy 391.330854 -398.421866) (xy 391.334269 -398.440314)
			(xy 391.338816 -398.44853) (xy 391.354941 -398.47571) (xy 391.380369 -398.533567) (xy 391.397609 -398.594368)
			(xy 391.406336 -398.656961) (xy 391.406888 -398.68856) (xy 391.40635 -398.720174) (xy 391.402609 -398.74705)
			(xy 393.22198 -398.74705) (xy 393.22198 -398.69255) (xy 393.229735 -398.638605) (xy 393.245089 -398.586313)
			(xy 393.267728 -398.536738) (xy 393.297192 -398.490889) (xy 393.33288 -398.4497) (xy 393.374067 -398.414008)
			(xy 393.419913 -398.384541) (xy 393.469487 -398.361899) (xy 393.521778 -398.346541) (xy 393.575722 -398.338782)
			(xy 393.602972 -398.338294) (xy 393.630342 -398.338778) (xy 393.68452 -398.346592) (xy 393.737023 -398.362077)
			(xy 393.78677 -398.384914) (xy 393.832738 -398.414635) (xy 393.85367 -398.432274) (xy 393.860782 -398.43837)
			(xy 393.8778 -398.44472) (xy 393.963144 -398.44472) (xy 393.980162 -398.43837) (xy 393.987274 -398.432274)
			(xy 394.008202 -398.41463) (xy 394.054176 -398.384919) (xy 394.103925 -398.362085) (xy 394.156426 -398.346595)
			(xy 394.210603 -398.338768) (xy 394.237972 -398.338294) (xy 394.265226 -398.338751) (xy 394.319181 -398.346505)
			(xy 394.371482 -398.361859) (xy 394.421066 -398.3845) (xy 394.466923 -398.413967) (xy 394.508119 -398.449661)
			(xy 394.543816 -398.490855) (xy 394.573287 -398.536709) (xy 394.595931 -398.586292) (xy 394.611289 -398.638592)
			(xy 394.619047 -398.692546) (xy 394.619047 -398.747054) (xy 394.611289 -398.801008) (xy 394.595931 -398.853308)
			(xy 394.573287 -398.902891) (xy 394.543816 -398.948745) (xy 394.508119 -398.989939) (xy 394.466923 -399.025633)
			(xy 394.421066 -399.0551) (xy 394.371482 -399.077741) (xy 394.319181 -399.093095) (xy 394.265226 -399.100849)
			(xy 394.237972 -399.10131) (xy 394.210601 -399.100858) (xy 394.156422 -399.093036) (xy 394.103919 -399.077544)
			(xy 394.054172 -399.054699) (xy 394.008206 -399.024972) (xy 393.987274 -399.00733) (xy 393.980162 -399.001234)
			(xy 393.963144 -398.994884) (xy 393.8778 -398.994884) (xy 393.860782 -399.001234) (xy 393.85367 -399.00733)
			(xy 393.832726 -399.024954) (xy 393.786756 -399.054667) (xy 393.737012 -399.077506) (xy 393.684514 -399.093)
			(xy 393.63034 -399.100833) (xy 393.602972 -399.10131) (xy 393.575722 -399.100818) (xy 393.521778 -399.093059)
			(xy 393.469487 -399.077701) (xy 393.419913 -399.055059) (xy 393.374067 -399.025592) (xy 393.33288 -398.9899)
			(xy 393.297192 -398.948711) (xy 393.267728 -398.902862) (xy 393.245089 -398.853287) (xy 393.229735 -398.800995)
			(xy 393.22198 -398.74705) (xy 391.402609 -398.74705) (xy 391.397632 -398.782799) (xy 391.380384 -398.843629)
			(xy 391.354935 -398.90151) (xy 391.321767 -398.95534) (xy 391.28151 -399.004098) (xy 391.234931 -399.046855)
			(xy 391.182914 -399.082801) (xy 391.15492 -399.0975) (xy 391.14561 -399.102769) (xy 391.132096 -399.119326)
			(xy 391.126442 -399.139937) (xy 391.127488 -399.150586) (xy 391.129293 -399.163144) (xy 391.131199 -399.188445)
			(xy 391.131298 -399.201132) (xy 391.130788 -399.227119) (xy 391.122658 -399.278454) (xy 391.106597 -399.327884)
			(xy 391.083001 -399.374194) (xy 391.052451 -399.416242) (xy 391.0157 -399.452993) (xy 390.973652 -399.483543)
			(xy 390.927342 -399.507139) (xy 390.877912 -399.5232) (xy 390.826577 -399.53133) (xy 390.774603 -399.53133)
			(xy 390.723268 -399.5232) (xy 390.673838 -399.507139) (xy 390.627528 -399.483543) (xy 390.58548 -399.452993)
			(xy 390.548729 -399.416242) (xy 390.518179 -399.374194) (xy 390.494583 -399.327884) (xy 390.478522 -399.278454)
			(xy 390.470392 -399.227119) (xy 390.469882 -399.201132) (xy 390.470289 -399.177394) (xy 390.477085 -399.130408)
			(xy 390.490528 -399.084875) (xy 390.510341 -399.041732) (xy 390.536119 -399.001864) (xy 390.551416 -398.983708)
			(xy 390.558127 -398.97531) (xy 390.564463 -398.954789) (xy 390.561872 -398.933468) (xy 390.55675 -398.924018)
			(xy 390.541241 -398.897251) (xy 390.516826 -398.840409) (xy 390.500303 -398.780792) (xy 390.491975 -398.719492)
			(xy 390.491472 -398.68856) (xy 390.49199 -398.656958) (xy 390.500693 -398.594356) (xy 390.51794 -398.533552)
			(xy 390.543403 -398.475704) (xy 390.559544 -398.44853) (xy 390.564126 -398.440328) (xy 390.56754 -398.421866)
			(xy 390.564101 -398.403408) (xy 390.559544 -398.39519) (xy 390.543423 -398.368007) (xy 390.517995 -398.310151)
			(xy 390.500754 -398.249351) (xy 390.492026 -398.186758) (xy 390.491472 -398.15516) (xy 390.492035 -398.121925)
			(xy 390.501644 -398.056155) (xy 390.520668 -397.992467) (xy 390.548708 -397.932201) (xy 390.585172 -397.876627)
			(xy 390.606788 -397.851376) (xy 390.613138 -397.844264) (xy 390.619742 -397.826992) (xy 390.619742 -397.740886)
			(xy 390.613138 -397.723614) (xy 390.606788 -397.716502) (xy 390.585228 -397.691251) (xy 390.548852 -397.635708)
			(xy 390.520881 -397.575493) (xy 390.501903 -397.511868) (xy 390.492316 -397.446169) (xy 390.491726 -397.412972)
			(xy 390.492252 -397.381146) (xy 390.501076 -397.318109) (xy 390.518549 -397.256903) (xy 390.544334 -397.198708)
			(xy 390.577935 -397.144648) (xy 390.597898 -397.119856) (xy 390.60374 -397.112744) (xy 390.609836 -397.095218)
			(xy 390.607296 -397.009112) (xy 390.600184 -396.992094) (xy 390.593834 -396.985236) (xy 390.574343 -396.96397)
			(xy 390.540351 -396.91736) (xy 390.512487 -396.866847) (xy 390.491194 -396.813233) (xy 390.476808 -396.757367)
			(xy 390.469558 -396.700136) (xy 390.46912 -396.671292) (xy 388.920925 -396.671292) (xy 388.923202 -396.684291)
			(xy 388.923784 -396.710662) (xy 388.923716 -396.720021) (xy 388.922572 -396.738703) (xy 388.921498 -396.748)
			(xy 388.920482 -396.75689) (xy 388.924292 -396.773654) (xy 388.968234 -396.843504) (xy 388.98195 -396.853918)
			(xy 388.990332 -396.856712) (xy 389.014359 -396.865184) (xy 389.059531 -396.888736) (xy 389.100337 -396.919234)
			(xy 389.135716 -396.955888) (xy 389.164752 -396.997747) (xy 389.186691 -397.043725) (xy 389.194294 -397.06804)
			(xy 389.195818 -397.073882) (xy 389.516112 -397.627602) (xy 389.520176 -397.63192) (xy 389.536364 -397.649642)
			(xy 389.563791 -397.689029) (xy 389.584937 -397.732115) (xy 389.599315 -397.777906) (xy 389.606592 -397.825346)
			(xy 389.607044 -397.849344) (xy 389.606647 -397.874151) (xy 389.598875 -397.923152) (xy 389.58353 -397.970332)
			(xy 389.56099 -398.01453) (xy 389.53181 -398.054656) (xy 389.49671 -398.08972) (xy 389.456555 -398.118858)
			(xy 389.412334 -398.141353) (xy 389.365138 -398.15665) (xy 389.316129 -398.164372) (xy 389.291322 -398.164812)
			(xy 389.265928 -398.164292) (xy 389.215796 -398.156165) (xy 389.16761 -398.140117) (xy 389.122616 -398.116561)
			(xy 389.081973 -398.086107) (xy 389.04673 -398.049538) (xy 389.017796 -398.007799) (xy 388.995917 -397.961966)
			(xy 388.9883 -397.937736) (xy 388.986776 -397.931894) (xy 388.666482 -397.378174) (xy 388.662418 -397.373856)
			(xy 388.646253 -397.356127) (xy 388.618887 -397.316723) (xy 388.597798 -397.273632) (xy 388.583472 -397.227846)
			(xy 388.576238 -397.18042) (xy 388.575804 -397.156432) (xy 388.575885 -397.144384) (xy 388.577668 -397.120355)
			(xy 388.57936 -397.108426) (xy 388.58063 -397.099536) (xy 388.577582 -397.082518) (xy 388.535418 -397.011652)
			(xy 388.52221 -397.000476) (xy 388.513828 -396.997428) (xy 388.492071 -396.989056) (xy 388.451214 -396.966609)
			(xy 388.414245 -396.938212) (xy 388.382024 -396.904523) (xy 388.3553 -396.866326) (xy 388.334695 -396.824509)
			(xy 388.320689 -396.780046) (xy 388.313606 -396.733971) (xy 388.313168 -396.710662) (xy 388.313738 -396.684289)
			(xy 388.32282 -396.632331) (xy 388.340706 -396.582711) (xy 388.3533 -396.559532) (xy 388.357872 -396.551404)
			(xy 388.360666 -396.534132) (xy 388.345426 -396.451328) (xy 388.336282 -396.436088) (xy 388.32917 -396.4305)
			(xy 388.306993 -396.411801) (xy 388.267048 -396.369738) (xy 388.232731 -396.322968) (xy 388.204594 -396.272241)
			(xy 388.183085 -396.218367) (xy 388.168549 -396.16221) (xy 388.161219 -396.104666) (xy 388.160768 -396.075662)
			(xy 388.161365 -396.042341) (xy 388.171025 -395.976403) (xy 388.190148 -395.912563) (xy 388.203694 -395.882114)
			(xy 388.207928 -395.871644) (xy 388.207823 -395.849088) (xy 388.198093 -395.828738) (xy 388.189724 -395.821154)
			(xy 388.167462 -395.802497) (xy 388.127399 -395.760439) (xy 388.092979 -395.71365) (xy 388.064755 -395.662882)
			(xy 388.043183 -395.608951) (xy 388.028607 -395.552724) (xy 388.021262 -395.495105) (xy 388.020814 -395.466062)
			(xy 388.021279 -395.437136) (xy 388.028562 -395.379745) (xy 388.04302 -395.323729) (xy 388.064422 -395.269982)
			(xy 388.092426 -395.21936) (xy 388.126587 -395.172672) (xy 388.16636 -395.130661) (xy 388.188454 -395.111986)
			(xy 388.195425 -395.105637) (xy 388.204683 -395.089235) (xy 388.206488 -395.079982) (xy 388.210806 -395.048994)
			(xy 388.211717 -395.039758) (xy 388.207689 -395.021657) (xy 388.202932 -395.013688) (xy 388.186627 -394.987841)
			(xy 388.162722 -394.931607) (xy 388.155434 -394.901928) (xy 388.153366 -394.893769) (xy 388.144671 -394.879367)
			(xy 388.138416 -394.873734) (xy 388.115302 -394.854684) (xy 388.108416 -394.849447) (xy 388.09219 -394.843476)
			(xy 388.083552 -394.843) (xy 388.053915 -394.842) (xy 387.99525 -394.83335) (xy 387.938193 -394.817197)
			(xy 387.883698 -394.793814) (xy 387.832679 -394.76359) (xy 387.78599 -394.727032) (xy 387.744411 -394.684752)
			(xy 387.708638 -394.637457) (xy 387.679272 -394.58594) (xy 387.656803 -394.531062) (xy 387.641607 -394.473743)
			(xy 387.633939 -394.414942) (xy 387.633464 -394.385292) (xy 387.633985 -394.354229) (xy 387.642401 -394.292675)
			(xy 387.650228 -394.26261) (xy 387.653022 -394.25245) (xy 387.650482 -394.232638) (xy 387.602984 -394.150342)
			(xy 387.586982 -394.13815) (xy 387.576822 -394.13561) (xy 387.547732 -394.127585) (xy 387.491805 -394.104918)
			(xy 387.43934 -394.0751) (xy 387.391246 -394.03865) (xy 387.348356 -393.996199) (xy 387.311413 -393.948482)
			(xy 387.281058 -393.896327) (xy 387.257817 -393.840636) (xy 387.242091 -393.782375) (xy 387.234155 -393.722553)
			(xy 387.233668 -393.69238) (xy 387.234198 -393.661492) (xy 387.242503 -393.600277) (xy 387.258958 -393.540733)
			(xy 387.283267 -393.483941) (xy 387.298692 -393.457176) (xy 387.304534 -393.44727) (xy 387.30682 -393.424918)
			(xy 387.273546 -393.329668) (xy 387.257798 -393.313666) (xy 387.24713 -393.309602) (xy 387.223734 -393.300454)
			(xy 387.179839 -393.276027) (xy 387.140145 -393.245239) (xy 387.105566 -393.2088) (xy 387.076899 -393.167549)
			(xy 387.054804 -393.122435) (xy 387.039789 -393.074497) (xy 387.0322 -393.024839) (xy 387.031738 -392.999722)
			(xy 386.493004 -392.999722) (xy 386.492471 -393.026824) (xy 386.483663 -393.080306) (xy 386.475478 -393.106148)
			(xy 386.471668 -393.11707) (xy 386.474208 -393.139422) (xy 386.526786 -393.225274) (xy 386.545836 -393.23772)
			(xy 386.557012 -393.239498) (xy 386.586328 -393.24422) (xy 386.643498 -393.260266) (xy 386.698112 -393.283574)
			(xy 386.749252 -393.313751) (xy 386.796058 -393.350291) (xy 386.837743 -393.392578) (xy 386.873608 -393.439904)
			(xy 386.903049 -393.491471) (xy 386.925571 -393.546414) (xy 386.940795 -393.603808) (xy 386.948467 -393.66269)
			(xy 386.948934 -393.69238) (xy 386.948408 -393.723443) (xy 386.939995 -393.784996) (xy 386.93217 -393.815062)
			(xy 386.929376 -393.825222) (xy 386.931916 -393.845034) (xy 386.979414 -393.92733) (xy 386.995416 -393.939522)
			(xy 387.005576 -393.942062) (xy 387.03469 -393.950046) (xy 387.090656 -393.972683) (xy 387.143161 -394.00248)
			(xy 387.191294 -394.03892) (xy 387.234219 -394.08137) (xy 387.271193 -394.129094) (xy 387.301572 -394.181265)
			(xy 387.324831 -394.236975) (xy 387.340564 -394.29526) (xy 387.348501 -394.355107) (xy 387.348984 -394.385292)
			(xy 387.348859 -394.399427) (xy 387.347077 -394.427641) (xy 387.345428 -394.44168) (xy 387.344672 -394.450287)
			(xy 387.348309 -394.467166) (xy 387.35254 -394.4747) (xy 387.368288 -394.5001) (xy 387.372999 -394.507159)
			(xy 387.386104 -394.517929) (xy 387.393942 -394.521182) (xy 387.417326 -394.530359) (xy 387.461221 -394.554781)
			(xy 387.500916 -394.585564) (xy 387.535496 -394.621998) (xy 387.564165 -394.663246) (xy 387.586262 -394.708356)
			(xy 387.60128 -394.756291) (xy 387.608871 -394.805946) (xy 387.609334 -394.831062) (xy 387.60892 -394.855265)
			(xy 387.601845 -394.90315) (xy 387.587855 -394.94949) (xy 387.567251 -394.993291) (xy 387.554216 -395.013688)
			(xy 387.549424 -395.021642) (xy 387.545394 -395.039755) (xy 387.546342 -395.048994) (xy 387.55066 -395.079982)
			(xy 387.552354 -395.089275) (xy 387.561628 -395.105717) (xy 387.568694 -395.111986) (xy 387.590768 -395.130685)
			(xy 387.630543 -395.172692) (xy 387.664708 -395.219376) (xy 387.692718 -395.269993) (xy 387.714128 -395.323736)
			(xy 387.728595 -395.379748) (xy 387.735889 -395.437137) (xy 387.736334 -395.466062) (xy 387.735745 -395.499383)
			(xy 387.726082 -395.565322) (xy 387.706956 -395.629161) (xy 387.693408 -395.65961) (xy 387.68915 -395.670072)
			(xy 387.689264 -395.692635) (xy 387.699004 -395.712987) (xy 387.707378 -395.72057) (xy 387.729604 -395.739268)
			(xy 387.769669 -395.781319) (xy 387.804092 -395.828101) (xy 387.83232 -395.878861) (xy 387.853899 -395.932786)
			(xy 387.868482 -395.989007) (xy 387.875835 -396.046621) (xy 387.876288 -396.075662) (xy 387.875798 -396.104666)
			(xy 387.868488 -396.162213) (xy 387.853967 -396.218374) (xy 387.832469 -396.272252) (xy 387.804337 -396.322982)
			(xy 387.770022 -396.369753) (xy 387.730074 -396.411814) (xy 387.707886 -396.4305) (xy 387.700774 -396.436088)
			(xy 387.69163 -396.451328) (xy 387.67639 -396.534132) (xy 387.679184 -396.551404) (xy 387.683756 -396.559532)
			(xy 387.696332 -396.582718) (xy 387.714206 -396.63234) (xy 387.723306 -396.684291) (xy 387.723888 -396.710662)
			(xy 387.72382 -396.720021) (xy 387.722676 -396.738703) (xy 387.721602 -396.748) (xy 387.720586 -396.75689)
			(xy 387.724396 -396.773654) (xy 387.768338 -396.843504) (xy 387.782054 -396.853918) (xy 387.790436 -396.856712)
			(xy 387.814541 -396.865173) (xy 387.859831 -396.888803) (xy 387.900725 -396.919418) (xy 387.936155 -396.956219)
			(xy 387.965196 -396.998246) (xy 387.987091 -397.0444) (xy 387.994652 -397.068802) (xy 387.996176 -397.074644)
			(xy 388.315962 -397.627602) (xy 388.320026 -397.63192) (xy 388.336218 -397.649625) (xy 388.363583 -397.689035)
			(xy 388.384667 -397.732132) (xy 388.398987 -397.777923) (xy 388.406211 -397.825355) (xy 388.40664 -397.849344)
			(xy 388.406222 -397.874136) (xy 388.398459 -397.923109) (xy 388.383131 -397.970265) (xy 388.360614 -398.014442)
			(xy 388.331464 -398.054554) (xy 388.296399 -398.089611) (xy 388.256281 -398.118752) (xy 388.212098 -398.141258)
			(xy 388.164939 -398.156576) (xy 388.115964 -398.164328) (xy 388.091172 -398.164812) (xy 388.065777 -398.164336)
			(xy 388.015642 -398.156201) (xy 387.967456 -398.140146) (xy 387.922461 -398.116584) (xy 387.881819 -398.086123)
			(xy 387.846577 -398.049549) (xy 387.817644 -398.007805) (xy 387.795766 -397.961968) (xy 387.78815 -397.937736)
			(xy 387.786626 -397.931894) (xy 387.466078 -397.377412) (xy 387.462014 -397.373094) (xy 387.445909 -397.355439)
			(xy 387.418723 -397.316138) (xy 387.397773 -397.273187) (xy 387.383537 -397.227569) (xy 387.376343 -397.180326)
			(xy 387.375908 -397.156432) (xy 387.375989 -397.144384) (xy 387.377772 -397.120355) (xy 387.379464 -397.108426)
			(xy 387.380734 -397.099536) (xy 387.377686 -397.082518) (xy 387.335522 -397.011652) (xy 387.322314 -397.000476)
			(xy 387.313932 -396.997428) (xy 387.292176 -396.989054) (xy 387.251319 -396.966608) (xy 387.214349 -396.93821)
			(xy 387.182128 -396.904522) (xy 387.155404 -396.866325) (xy 387.1348 -396.824509) (xy 387.120793 -396.780046)
			(xy 387.11371 -396.733971) (xy 387.113272 -396.710662) (xy 387.113841 -396.684289) (xy 387.122923 -396.632331)
			(xy 387.14081 -396.582711) (xy 387.153404 -396.559532) (xy 387.157976 -396.551404) (xy 387.16077 -396.534132)
			(xy 387.14553 -396.451328) (xy 387.136386 -396.436088) (xy 387.129274 -396.4305) (xy 387.107098 -396.4118)
			(xy 387.067152 -396.369737) (xy 387.032836 -396.322968) (xy 387.004698 -396.272241) (xy 386.983189 -396.218367)
			(xy 386.968653 -396.16221) (xy 386.961323 -396.104666) (xy 386.960872 -396.075662) (xy 386.961469 -396.042341)
			(xy 386.971128 -395.976403) (xy 386.990252 -395.912563) (xy 387.003798 -395.882114) (xy 387.008031 -395.871644)
			(xy 387.007926 -395.849088) (xy 386.998197 -395.828738) (xy 386.989828 -395.821154) (xy 386.967567 -395.802496)
			(xy 386.927503 -395.760439) (xy 386.893083 -395.71365) (xy 386.86486 -395.662882) (xy 386.843287 -395.608951)
			(xy 386.828711 -395.552724) (xy 386.821366 -395.495105) (xy 386.820918 -395.466062) (xy 386.821382 -395.437136)
			(xy 386.828665 -395.379745) (xy 386.843123 -395.323729) (xy 386.864525 -395.269982) (xy 386.89253 -395.21936)
			(xy 386.926691 -395.172672) (xy 386.966464 -395.130661) (xy 386.988558 -395.111986) (xy 386.99553 -395.105638)
			(xy 387.004788 -395.089235) (xy 387.006592 -395.079982) (xy 387.01091 -395.048994) (xy 387.01182 -395.039758)
			(xy 387.007793 -395.021657) (xy 387.003036 -395.013688) (xy 386.986731 -394.987841) (xy 386.962826 -394.931606)
			(xy 386.955538 -394.901928) (xy 386.953469 -394.893769) (xy 386.944774 -394.879367) (xy 386.93852 -394.873734)
			(xy 386.915406 -394.854684) (xy 386.908519 -394.849448) (xy 386.892294 -394.843476) (xy 386.883656 -394.843)
			(xy 386.854019 -394.841996) (xy 386.795354 -394.833346) (xy 386.738297 -394.817195) (xy 386.683803 -394.793811)
			(xy 386.632784 -394.763588) (xy 386.586094 -394.727031) (xy 386.544515 -394.684751) (xy 386.508743 -394.637456)
			(xy 386.479376 -394.585939) (xy 386.456907 -394.531062) (xy 386.441711 -394.473743) (xy 386.434043 -394.414942)
			(xy 386.433568 -394.385292) (xy 386.434089 -394.354229) (xy 386.442505 -394.292675) (xy 386.450332 -394.26261)
			(xy 386.453126 -394.25245) (xy 386.450586 -394.232638) (xy 386.403088 -394.150342) (xy 386.387086 -394.13815)
			(xy 386.376926 -394.13561) (xy 386.347805 -394.12765) (xy 386.291837 -394.105012) (xy 386.239331 -394.075213)
			(xy 386.191198 -394.03877) (xy 386.148272 -393.996317) (xy 386.111299 -393.94859) (xy 386.080921 -393.896417)
			(xy 386.057664 -393.840703) (xy 386.041933 -393.782416) (xy 386.033999 -393.722566) (xy 386.033518 -393.69238)
			(xy 386.034041 -393.661492) (xy 386.042347 -393.600276) (xy 386.058804 -393.540732) (xy 386.083115 -393.483941)
			(xy 386.098542 -393.457176) (xy 386.104384 -393.44727) (xy 386.10667 -393.424918) (xy 386.073396 -393.329668)
			(xy 386.057648 -393.313666) (xy 386.04698 -393.309602) (xy 386.023595 -393.300427) (xy 385.979698 -393.276006)
			(xy 385.940003 -393.245224) (xy 385.905422 -393.208789) (xy 385.876753 -393.167541) (xy 385.854656 -393.12243)
			(xy 385.839639 -393.074494) (xy 385.83205 -393.024838) (xy 385.831588 -392.999722) (xy 385.293108 -392.999722)
			(xy 385.292575 -393.026824) (xy 385.283767 -393.080306) (xy 385.275582 -393.106148) (xy 385.271772 -393.11707)
			(xy 385.274312 -393.139422) (xy 385.32689 -393.225274) (xy 385.34594 -393.23772) (xy 385.357116 -393.239498)
			(xy 385.386432 -393.244217) (xy 385.443603 -393.260264) (xy 385.498217 -393.283572) (xy 385.549356 -393.313749)
			(xy 385.596162 -393.350289) (xy 385.637848 -393.392577) (xy 385.673712 -393.439903) (xy 385.703153 -393.49147)
			(xy 385.725675 -393.546413) (xy 385.740899 -393.603808) (xy 385.748571 -393.66269) (xy 385.749038 -393.69238)
			(xy 385.748515 -393.723506) (xy 385.740109 -393.785188) (xy 385.732274 -393.815316) (xy 385.72948 -393.825476)
			(xy 385.73202 -393.845542) (xy 385.779264 -393.92733) (xy 385.795266 -393.939522) (xy 385.805426 -393.942062)
			(xy 385.83453 -393.950079) (xy 385.890497 -393.97271) (xy 385.943003 -394.002502) (xy 385.991137 -394.038937)
			(xy 386.034064 -394.081384) (xy 386.071039 -394.129105) (xy 386.101419 -394.181272) (xy 386.124679 -394.23698)
			(xy 386.140414 -394.295263) (xy 386.14835 -394.355108) (xy 386.148834 -394.385292) (xy 386.148709 -394.399427)
			(xy 386.146927 -394.427641) (xy 386.145278 -394.44168) (xy 386.144514 -394.450287) (xy 386.148156 -394.467167)
			(xy 386.15239 -394.4747) (xy 386.168138 -394.5001) (xy 386.172832 -394.507172) (xy 386.185949 -394.517934)
			(xy 386.193792 -394.521182) (xy 386.217165 -394.530386) (xy 386.261062 -394.554802) (xy 386.300759 -394.585579)
			(xy 386.335341 -394.622009) (xy 386.364011 -394.663253) (xy 386.38611 -394.708361) (xy 386.401129 -394.756294)
			(xy 386.408721 -394.805947) (xy 386.409184 -394.831062) (xy 386.408761 -394.855264) (xy 386.401688 -394.903149)
			(xy 386.3877 -394.949489) (xy 386.3671 -394.993291) (xy 386.354066 -395.013688) (xy 386.349277 -395.021644)
			(xy 386.345244 -395.039756) (xy 386.346192 -395.048994) (xy 386.35051 -395.079982) (xy 386.352189 -395.089279)
			(xy 386.361472 -395.10572) (xy 386.368544 -395.111986) (xy 386.390628 -395.130672) (xy 386.430401 -395.172683)
			(xy 386.464564 -395.21937) (xy 386.492572 -395.269989) (xy 386.51398 -395.323733) (xy 386.528446 -395.379747)
			(xy 386.535739 -395.437136) (xy 386.536184 -395.466062) (xy 386.53559 -395.499383) (xy 386.525929 -395.565321)
			(xy 386.506804 -395.629161) (xy 386.493258 -395.65961) (xy 386.488984 -395.670068) (xy 386.489097 -395.692636)
			(xy 386.498847 -395.71299) (xy 386.507228 -395.72057) (xy 386.529464 -395.739256) (xy 386.569527 -395.78131)
			(xy 386.603948 -395.828095) (xy 386.632174 -395.878858) (xy 386.653751 -395.932783) (xy 386.668333 -395.989006)
			(xy 386.675685 -396.046621) (xy 386.676138 -396.075662) (xy 386.675666 -396.104667) (xy 386.668355 -396.162215)
			(xy 386.653833 -396.218378) (xy 386.632332 -396.272256) (xy 386.604196 -396.322986) (xy 386.569878 -396.369756)
			(xy 386.529926 -396.411816) (xy 386.507736 -396.4305) (xy 386.500624 -396.436088) (xy 386.49148 -396.451328)
			(xy 386.47624 -396.534132) (xy 386.479034 -396.551404) (xy 386.483606 -396.559532) (xy 386.496178 -396.58272)
			(xy 386.514054 -396.632341) (xy 386.523156 -396.684292) (xy 386.523738 -396.710662) (xy 386.523669 -396.720021)
			(xy 386.522526 -396.738703) (xy 386.521452 -396.748) (xy 386.520436 -396.75689) (xy 386.524246 -396.773654)
			(xy 386.568188 -396.843504) (xy 386.581904 -396.853918) (xy 386.590286 -396.856712) (xy 386.614304 -396.865209)
			(xy 386.659477 -396.888754) (xy 386.700284 -396.919247) (xy 386.735666 -396.955897) (xy 386.764703 -396.997752)
			(xy 386.786644 -397.043726) (xy 386.794248 -397.06804) (xy 386.795772 -397.073882) (xy 387.116066 -397.627602)
			(xy 387.12013 -397.63192) (xy 387.136323 -397.649625) (xy 387.163687 -397.689034) (xy 387.184772 -397.732132)
			(xy 387.199091 -397.777923) (xy 387.206315 -397.825354) (xy 387.206744 -397.849344) (xy 387.206322 -397.874136)
			(xy 387.198559 -397.923109) (xy 387.183231 -397.970264) (xy 387.160715 -398.014441) (xy 387.131566 -398.054552)
			(xy 387.0965 -398.08961) (xy 387.056383 -398.118751) (xy 387.012201 -398.141257) (xy 386.965042 -398.156575)
			(xy 386.916068 -398.164328) (xy 386.891276 -398.164812) (xy 386.865881 -398.164333) (xy 386.815746 -398.156198)
			(xy 386.76756 -398.140143) (xy 386.722566 -398.116582) (xy 386.681923 -398.086121) (xy 386.646681 -398.049548)
			(xy 386.617748 -398.007804) (xy 386.59587 -397.961967) (xy 386.588254 -397.937736) (xy 386.58673 -397.931894)
			(xy 386.266436 -397.378174) (xy 386.262372 -397.373856) (xy 386.246164 -397.356152) (xy 386.218742 -397.316759)
			(xy 386.1976 -397.273669) (xy 386.183227 -397.227874) (xy 386.175954 -397.180431) (xy 386.175504 -397.156432)
			(xy 386.175646 -397.14438) (xy 386.177552 -397.12035) (xy 386.179314 -397.108426) (xy 386.180584 -397.099536)
			(xy 386.177536 -397.082518) (xy 386.135372 -397.011652) (xy 386.122164 -397.000476) (xy 386.113782 -396.997428)
			(xy 386.092037 -396.989026) (xy 386.051178 -396.966587) (xy 386.014207 -396.938195) (xy 385.981984 -396.90451)
			(xy 385.955258 -396.866317) (xy 385.934651 -396.824504) (xy 385.920644 -396.780043) (xy 385.91356 -396.73397)
			(xy 385.913122 -396.710662) (xy 385.913685 -396.684289) (xy 385.922769 -396.63233) (xy 385.940658 -396.58271)
			(xy 385.953254 -396.559532) (xy 385.957826 -396.551404) (xy 385.96062 -396.534132) (xy 385.94538 -396.451328)
			(xy 385.936236 -396.436088) (xy 385.929124 -396.4305) (xy 385.906958 -396.411788) (xy 385.86701 -396.369728)
			(xy 385.832691 -396.322962) (xy 385.804552 -396.272237) (xy 385.783041 -396.218365) (xy 385.768504 -396.162208)
			(xy 385.761173 -396.104666) (xy 385.760722 -396.075662) (xy 385.761324 -396.042341) (xy 385.770982 -395.976403)
			(xy 385.790103 -395.912563) (xy 385.803648 -395.882114) (xy 385.807897 -395.871648) (xy 385.807793 -395.849086)
			(xy 385.798053 -395.828735) (xy 385.789678 -395.821154) (xy 385.767406 -395.802509) (xy 385.727345 -395.760447)
			(xy 385.692928 -395.713656) (xy 385.664706 -395.662886) (xy 385.643135 -395.608954) (xy 385.62856 -395.552725)
			(xy 385.621216 -395.495105) (xy 385.620768 -395.466062) (xy 385.621214 -395.437135) (xy 385.628498 -395.379743)
			(xy 385.642957 -395.323726) (xy 385.664362 -395.269978) (xy 385.69237 -395.219356) (xy 385.726535 -395.172669)
			(xy 385.766312 -395.130659) (xy 385.788408 -395.111986) (xy 385.795387 -395.105646) (xy 385.80464 -395.089237)
			(xy 385.806442 -395.079982) (xy 385.81076 -395.048994) (xy 385.811662 -395.039757) (xy 385.807638 -395.021658)
			(xy 385.802886 -395.013688) (xy 385.786577 -394.987843) (xy 385.762674 -394.931607) (xy 385.755388 -394.901928)
			(xy 385.753332 -394.893765) (xy 385.744629 -394.879364) (xy 385.73837 -394.873734) (xy 385.715256 -394.854684)
			(xy 385.708356 -394.849468) (xy 385.692141 -394.843484) (xy 385.683506 -394.843) (xy 385.653871 -394.84195)
			(xy 385.595207 -394.833307) (xy 385.538151 -394.817161) (xy 385.483657 -394.793783) (xy 385.432638 -394.763564)
			(xy 385.385947 -394.727011) (xy 385.344368 -394.684735) (xy 385.308595 -394.637445) (xy 385.279227 -394.585931)
			(xy 385.256758 -394.531056) (xy 385.241561 -394.473739) (xy 385.233893 -394.41494) (xy 385.233418 -394.385292)
			(xy 385.23394 -394.354229) (xy 385.242355 -394.292675) (xy 385.250182 -394.26261) (xy 385.252976 -394.25245)
			(xy 385.250436 -394.232638) (xy 385.202938 -394.150342) (xy 385.186936 -394.13815) (xy 385.176776 -394.13561)
			(xy 385.147696 -394.12755) (xy 385.091768 -394.104888) (xy 385.039302 -394.075077) (xy 384.991207 -394.038632)
			(xy 384.948315 -393.996185) (xy 384.911371 -393.948472) (xy 384.881015 -393.896319) (xy 384.857772 -393.840631)
			(xy 384.842046 -393.782372) (xy 384.834109 -393.722552) (xy 384.833622 -393.69238) (xy 384.834145 -393.661492)
			(xy 384.84245 -393.600276) (xy 384.858908 -393.540732) (xy 384.883219 -393.483941) (xy 384.898646 -393.457176)
			(xy 384.904488 -393.44727) (xy 384.906774 -393.424918) (xy 384.8735 -393.329668) (xy 384.857752 -393.313666)
			(xy 384.847084 -393.309602) (xy 384.8237 -393.300425) (xy 384.779803 -393.276004) (xy 384.740107 -393.245222)
			(xy 384.705526 -393.208788) (xy 384.676857 -393.16754) (xy 384.65476 -393.122429) (xy 384.639744 -393.074494)
			(xy 384.632154 -393.024838) (xy 384.631692 -392.999722) (xy 384.092958 -392.999722) (xy 384.092428 -393.026824)
			(xy 384.083618 -393.080307) (xy 384.075432 -393.106148) (xy 384.071622 -393.11707) (xy 384.074162 -393.139422)
			(xy 384.12674 -393.225274) (xy 384.14579 -393.23772) (xy 384.156966 -393.239498) (xy 384.186289 -393.244178)
			(xy 384.24346 -393.260231) (xy 384.298073 -393.283544) (xy 384.349212 -393.313727) (xy 384.396017 -393.350271)
			(xy 384.437702 -393.392563) (xy 384.473565 -393.439892) (xy 384.503005 -393.491462) (xy 384.525526 -393.546408)
			(xy 384.54075 -393.603805) (xy 384.548421 -393.662689) (xy 384.548888 -393.69238) (xy 384.54836 -393.723443)
			(xy 384.539949 -393.784996) (xy 384.532124 -393.815062) (xy 384.52933 -393.825222) (xy 384.53187 -393.845034)
			(xy 384.579368 -393.92733) (xy 384.59537 -393.939522) (xy 384.60553 -393.942062) (xy 384.634635 -393.950077)
			(xy 384.690602 -393.972708) (xy 384.743108 -394.0025) (xy 384.791242 -394.038936) (xy 384.834168 -394.081383)
			(xy 384.871143 -394.129104) (xy 384.901523 -394.181271) (xy 384.924783 -394.23698) (xy 384.940518 -394.295262)
			(xy 384.948454 -394.355107) (xy 384.948938 -394.385292) (xy 384.948813 -394.399427) (xy 384.947031 -394.427641)
			(xy 384.945382 -394.44168) (xy 384.944618 -394.450287) (xy 384.948259 -394.467168) (xy 384.952494 -394.4747)
			(xy 384.968242 -394.5001) (xy 384.972935 -394.507173) (xy 384.986052 -394.517935) (xy 384.993896 -394.521182)
			(xy 385.01727 -394.530384) (xy 385.061167 -394.5548) (xy 385.100863 -394.585578) (xy 385.135445 -394.622009)
			(xy 385.164116 -394.663253) (xy 385.186215 -394.708361) (xy 385.201233 -394.756293) (xy 385.208825 -394.805947)
			(xy 385.209288 -394.831062) (xy 385.208865 -394.855264) (xy 385.201791 -394.903149) (xy 385.187804 -394.949489)
			(xy 385.167204 -394.993291) (xy 385.15417 -395.013688) (xy 385.149382 -395.021645) (xy 385.145348 -395.039756)
			(xy 385.146296 -395.048994) (xy 385.150614 -395.079982) (xy 385.152292 -395.089279) (xy 385.161575 -395.105721)
			(xy 385.168648 -395.111986) (xy 385.190733 -395.130672) (xy 385.230506 -395.172682) (xy 385.264668 -395.21937)
			(xy 385.292676 -395.269989) (xy 385.314084 -395.323733) (xy 385.32855 -395.379747) (xy 385.335843 -395.437136)
			(xy 385.336288 -395.466062) (xy 385.335694 -395.499383) (xy 385.326032 -395.565321) (xy 385.306908 -395.629161)
			(xy 385.293362 -395.65961) (xy 385.289086 -395.670068) (xy 385.289199 -395.692637) (xy 385.29895 -395.712991)
			(xy 385.307332 -395.72057) (xy 385.329569 -395.739255) (xy 385.369632 -395.781309) (xy 385.404052 -395.828094)
			(xy 385.432278 -395.878857) (xy 385.453855 -395.932783) (xy 385.468437 -395.989005) (xy 385.475789 -396.046621)
			(xy 385.476242 -396.075662) (xy 385.475769 -396.104667) (xy 385.468458 -396.162215) (xy 385.453936 -396.218377)
			(xy 385.432435 -396.272256) (xy 385.4043 -396.322986) (xy 385.369981 -396.369756) (xy 385.33003 -396.411816)
			(xy 385.30784 -396.4305) (xy 385.300728 -396.436088) (xy 385.291584 -396.451328) (xy 385.276344 -396.534132)
			(xy 385.279138 -396.551404) (xy 385.28371 -396.559532) (xy 385.296283 -396.58272) (xy 385.314158 -396.632341)
			(xy 385.32326 -396.684292) (xy 385.323842 -396.710662) (xy 385.323773 -396.720021) (xy 385.32263 -396.738703)
			(xy 385.321556 -396.748) (xy 385.32054 -396.75689) (xy 385.32435 -396.773654) (xy 385.368292 -396.843504)
			(xy 385.382008 -396.853918) (xy 385.39039 -396.856712) (xy 385.414486 -396.865197) (xy 385.459777 -396.888821)
			(xy 385.500672 -396.919431) (xy 385.536104 -396.956228) (xy 385.565147 -396.99825) (xy 385.587044 -397.044401)
			(xy 385.594606 -397.068802) (xy 385.59613 -397.074644) (xy 385.915916 -397.627602) (xy 385.91998 -397.63192)
			(xy 385.936168 -397.649642) (xy 385.963596 -397.689028) (xy 385.984742 -397.732114) (xy 385.999119 -397.777906)
			(xy 386.006396 -397.825346) (xy 386.006848 -397.849344) (xy 386.006447 -397.87415) (xy 385.998675 -397.923151)
			(xy 385.98333 -397.970332) (xy 385.960791 -398.014529) (xy 385.931611 -398.054654) (xy 385.896512 -398.089718)
			(xy 385.856357 -398.118857) (xy 385.812137 -398.141352) (xy 385.764941 -398.156649) (xy 385.715933 -398.164371)
			(xy 385.691126 -398.164812) (xy 385.665732 -398.164289) (xy 385.6156 -398.156162) (xy 385.567415 -398.140114)
			(xy 385.52242 -398.11656) (xy 385.481777 -398.086105) (xy 385.446534 -398.049537) (xy 385.4176 -398.007798)
			(xy 385.395721 -397.961966) (xy 385.388104 -397.937736) (xy 385.38658 -397.931894) (xy 385.066032 -397.377412)
			(xy 385.061968 -397.373094) (xy 385.045868 -397.355422) (xy 385.018618 -397.316144) (xy 384.997607 -397.273204)
			(xy 384.983314 -397.227586) (xy 384.976067 -397.180334) (xy 384.975608 -397.156432) (xy 384.97575 -397.14438)
			(xy 384.977656 -397.12035) (xy 384.979418 -397.108426) (xy 384.980688 -397.099536) (xy 384.97764 -397.082518)
			(xy 384.935476 -397.011652) (xy 384.922268 -397.000476) (xy 384.913886 -396.997428) (xy 384.892142 -396.989024)
			(xy 384.851283 -396.966585) (xy 384.814311 -396.938194) (xy 384.782088 -396.904509) (xy 384.755362 -396.866317)
			(xy 384.734756 -396.824504) (xy 384.720748 -396.780043) (xy 384.713664 -396.73397) (xy 384.713226 -396.710662)
			(xy 384.713788 -396.684289) (xy 384.722872 -396.63233) (xy 384.740762 -396.58271) (xy 384.753358 -396.559532)
			(xy 384.75793 -396.551404) (xy 384.760724 -396.534132) (xy 384.745484 -396.451328) (xy 384.73634 -396.436088)
			(xy 384.729228 -396.4305) (xy 384.707063 -396.411787) (xy 384.667115 -396.369728) (xy 384.632796 -396.322961)
			(xy 384.604656 -396.272236) (xy 384.583145 -396.218365) (xy 384.568608 -396.162208) (xy 384.561277 -396.104666)
			(xy 384.560826 -396.075662) (xy 384.561427 -396.042341) (xy 384.571086 -395.976403) (xy 384.590207 -395.912563)
			(xy 384.603752 -395.882114) (xy 384.608 -395.871648) (xy 384.607896 -395.849086) (xy 384.598157 -395.828735)
			(xy 384.589782 -395.821154) (xy 384.567511 -395.802508) (xy 384.52745 -395.760447) (xy 384.493032 -395.713655)
			(xy 384.464811 -395.662886) (xy 384.443239 -395.608953) (xy 384.428664 -395.552725) (xy 384.42132 -395.495105)
			(xy 384.420872 -395.466062) (xy 384.421316 -395.437135) (xy 384.4286 -395.379742) (xy 384.44306 -395.323725)
			(xy 384.464465 -395.269977) (xy 384.492473 -395.219356) (xy 384.526638 -395.172668) (xy 384.566415 -395.130659)
			(xy 384.588512 -395.111986) (xy 384.595476 -395.105631) (xy 384.60474 -395.089233) (xy 384.606546 -395.079982)
			(xy 384.610864 -395.048994) (xy 384.611765 -395.039757) (xy 384.607742 -395.021658) (xy 384.60299 -395.013688)
			(xy 384.586681 -394.987843) (xy 384.562778 -394.931607) (xy 384.555492 -394.901928) (xy 384.553435 -394.893765)
			(xy 384.544733 -394.879364) (xy 384.538474 -394.873734) (xy 384.51536 -394.854684) (xy 384.508485 -394.84943)
			(xy 384.492251 -394.843469) (xy 384.48361 -394.843) (xy 384.453975 -394.841946) (xy 384.395312 -394.833303)
			(xy 384.338255 -394.817158) (xy 384.283761 -394.793781) (xy 384.232742 -394.763563) (xy 384.186052 -394.72701)
			(xy 384.144472 -394.684734) (xy 384.108699 -394.637444) (xy 384.079332 -394.58593) (xy 384.056862 -394.531055)
			(xy 384.041665 -394.473739) (xy 384.033997 -394.41494) (xy 384.033522 -394.385292) (xy 384.034044 -394.354229)
			(xy 384.042459 -394.292675) (xy 384.050286 -394.26261) (xy 384.05308 -394.25245) (xy 384.05054 -394.232638)
			(xy 384.003042 -394.150342) (xy 383.98704 -394.13815) (xy 383.97688 -394.13561) (xy 383.947769 -394.127614)
			(xy 383.891801 -394.104982) (xy 383.839294 -394.075189) (xy 383.791159 -394.038751) (xy 383.748232 -393.996302)
			(xy 383.711257 -393.948579) (xy 383.680878 -393.896409) (xy 383.65762 -393.840698) (xy 383.641888 -393.782413)
			(xy 383.633954 -393.722565) (xy 383.633472 -393.69238) (xy 383.634002 -393.661492) (xy 383.642306 -393.600277)
			(xy 383.658762 -393.540733) (xy 383.68307 -393.483941) (xy 383.698496 -393.457176) (xy 383.704338 -393.44727)
			(xy 383.706624 -393.424918) (xy 383.67335 -393.329668) (xy 383.657602 -393.313666) (xy 383.646934 -393.309602)
			(xy 383.623539 -393.300452) (xy 383.579644 -393.276025) (xy 383.53995 -393.245238) (xy 383.505371 -393.208799)
			(xy 383.476704 -393.167548) (xy 383.454608 -393.122434) (xy 383.439593 -393.074497) (xy 383.432004 -393.024839)
			(xy 383.431542 -392.999722) (xy 382.893062 -392.999722) (xy 382.892531 -393.026824) (xy 382.883722 -393.080307)
			(xy 382.875536 -393.106148) (xy 382.871726 -393.11707) (xy 382.874266 -393.139422) (xy 382.926844 -393.225274)
			(xy 382.945894 -393.23772) (xy 382.95707 -393.239498) (xy 382.986393 -393.244175) (xy 383.043564 -393.260228)
			(xy 383.098178 -393.283542) (xy 383.149317 -393.313725) (xy 383.196122 -393.35027) (xy 383.237806 -393.392562)
			(xy 383.273669 -393.439891) (xy 383.303109 -393.491462) (xy 383.32563 -393.546407) (xy 383.340854 -393.603805)
			(xy 383.348525 -393.662689) (xy 383.348992 -393.69238) (xy 383.348464 -393.723443) (xy 383.340053 -393.784996)
			(xy 383.332228 -393.815062) (xy 383.329434 -393.825222) (xy 383.331974 -393.845034) (xy 383.379472 -393.92733)
			(xy 383.395474 -393.939522) (xy 383.405634 -393.942062) (xy 383.43474 -393.950074) (xy 383.490706 -393.972706)
			(xy 383.543212 -394.002499) (xy 383.591346 -394.038934) (xy 383.634273 -394.081382) (xy 383.671247 -394.129103)
			(xy 383.701628 -394.181271) (xy 383.724887 -394.236979) (xy 383.740622 -394.295262) (xy 383.748558 -394.355107)
			(xy 383.749042 -394.385292) (xy 383.748917 -394.399427) (xy 383.747135 -394.427641) (xy 383.745486 -394.44168)
			(xy 383.744721 -394.450287) (xy 383.748363 -394.467168) (xy 383.752598 -394.4747) (xy 383.768346 -394.5001)
			(xy 383.773058 -394.507161) (xy 383.786155 -394.517941) (xy 383.794 -394.521182) (xy 383.817342 -394.530426)
			(xy 383.861186 -394.554877) (xy 383.900831 -394.585674) (xy 383.935367 -394.622108) (xy 383.964 -394.663343)
			(xy 383.986072 -394.708431) (xy 384.001077 -394.756338) (xy 384.008669 -394.805961) (xy 384.009138 -394.831062)
			(xy 384.008723 -394.855265) (xy 384.001648 -394.90315) (xy 383.987659 -394.94949) (xy 383.967055 -394.993291)
			(xy 383.95402 -395.013688) (xy 383.949229 -395.021643) (xy 383.945198 -395.039755) (xy 383.946146 -395.048994)
			(xy 383.950464 -395.079982) (xy 383.952157 -395.089275) (xy 383.961431 -395.105717) (xy 383.968498 -395.111986)
			(xy 383.990572 -395.130684) (xy 384.030347 -395.172691) (xy 384.064512 -395.219376) (xy 384.092523 -395.269993)
			(xy 384.113932 -395.323736) (xy 384.128399 -395.379748) (xy 384.135693 -395.437137) (xy 384.136138 -395.466062)
			(xy 384.135548 -395.499383) (xy 384.125886 -395.565322) (xy 384.10676 -395.629161) (xy 384.093212 -395.65961)
			(xy 384.088953 -395.670072) (xy 384.089066 -395.692635) (xy 384.098807 -395.712988) (xy 384.107182 -395.72057)
			(xy 384.129409 -395.739267) (xy 384.169474 -395.781318) (xy 384.203897 -395.8281) (xy 384.232124 -395.878861)
			(xy 384.253703 -395.932786) (xy 384.268286 -395.989007) (xy 384.275639 -396.046621) (xy 384.276092 -396.075662)
			(xy 384.275601 -396.104666) (xy 384.26829 -396.162212) (xy 384.25377 -396.218374) (xy 384.232272 -396.272252)
			(xy 384.20414 -396.322982) (xy 384.169825 -396.369753) (xy 384.129878 -396.411814) (xy 384.10769 -396.4305)
			(xy 384.100578 -396.436088) (xy 384.091434 -396.451328) (xy 384.076194 -396.534132) (xy 384.078988 -396.551404)
			(xy 384.08356 -396.559532) (xy 384.096137 -396.582718) (xy 384.11401 -396.63234) (xy 384.12311 -396.684291)
			(xy 384.123692 -396.710662) (xy 384.123624 -396.720021) (xy 384.12248 -396.738703) (xy 384.121406 -396.748)
			(xy 384.12039 -396.75689) (xy 384.1242 -396.773654) (xy 384.168142 -396.843504) (xy 384.181858 -396.853918)
			(xy 384.19024 -396.856712) (xy 384.214268 -396.86518) (xy 384.259441 -396.888733) (xy 384.300246 -396.919232)
			(xy 384.335625 -396.955887) (xy 384.36466 -396.997746) (xy 384.386599 -397.043724) (xy 384.394202 -397.06804)
			(xy 384.395726 -397.073882) (xy 384.71602 -397.627602) (xy 384.720084 -397.63192) (xy 384.736273 -397.649641)
			(xy 384.7637 -397.689028) (xy 384.784846 -397.732114) (xy 384.799223 -397.777906) (xy 384.8065 -397.825346)
			(xy 384.806952 -397.849344) (xy 384.806547 -397.87415) (xy 384.798775 -397.92315) (xy 384.783431 -397.970331)
			(xy 384.760891 -398.014528) (xy 384.731713 -398.054653) (xy 384.696614 -398.089717) (xy 384.65646 -398.118856)
			(xy 384.61224 -398.141351) (xy 384.565045 -398.156648) (xy 384.516037 -398.164371) (xy 384.49123 -398.164812)
			(xy 384.465837 -398.164285) (xy 384.415704 -398.156159) (xy 384.367519 -398.140112) (xy 384.322525 -398.116558)
			(xy 384.281882 -398.086104) (xy 384.246638 -398.049536) (xy 384.217704 -398.007798) (xy 384.195825 -397.961965)
			(xy 384.188208 -397.937736) (xy 384.186684 -397.931894) (xy 383.86639 -397.378174) (xy 383.862326 -397.373856)
			(xy 383.846162 -397.356126) (xy 383.818796 -397.316723) (xy 383.797706 -397.273632) (xy 383.78338 -397.227846)
			(xy 383.776146 -397.18042) (xy 383.775712 -397.156432) (xy 383.775793 -397.144384) (xy 383.777576 -397.120355)
			(xy 383.779268 -397.108426) (xy 383.780538 -397.099536) (xy 383.77749 -397.082518) (xy 383.735326 -397.011652)
			(xy 383.722118 -397.000476) (xy 383.713736 -396.997428) (xy 383.691981 -396.989051) (xy 383.651123 -396.966606)
			(xy 383.614154 -396.938209) (xy 383.581933 -396.904521) (xy 383.555209 -396.866324) (xy 383.534604 -396.824509)
			(xy 383.520597 -396.780046) (xy 383.513514 -396.73397) (xy 383.513076 -396.710662) (xy 383.513645 -396.684289)
			(xy 383.522727 -396.632331) (xy 383.540614 -396.58271) (xy 383.553208 -396.559532) (xy 383.55778 -396.551404)
			(xy 383.560574 -396.534132) (xy 383.545334 -396.451328) (xy 383.53619 -396.436088) (xy 383.529078 -396.4305)
			(xy 383.506903 -396.411799) (xy 383.466957 -396.369736) (xy 383.43264 -396.322967) (xy 383.404502 -396.27224)
			(xy 383.382993 -396.218367) (xy 383.368457 -396.162209) (xy 383.361127 -396.104666) (xy 383.360676 -396.075662)
			(xy 383.361273 -396.042341) (xy 383.370932 -395.976402) (xy 383.390056 -395.912563) (xy 383.403602 -395.882114)
			(xy 383.407834 -395.871643) (xy 383.407728 -395.849088) (xy 383.398 -395.828738) (xy 383.389632 -395.821154)
			(xy 383.367372 -395.802495) (xy 383.327308 -395.760438) (xy 383.292888 -395.713649) (xy 383.264664 -395.662882)
			(xy 383.243091 -395.608951) (xy 383.228515 -395.552724) (xy 383.22117 -395.495105) (xy 383.220722 -395.466062)
			(xy 383.221184 -395.437136) (xy 383.228467 -395.379745) (xy 383.242925 -395.323729) (xy 383.264328 -395.269981)
			(xy 383.292333 -395.21936) (xy 383.326494 -395.172671) (xy 383.366268 -395.13066) (xy 383.388362 -395.111986)
			(xy 383.395334 -395.105639) (xy 383.404592 -395.089235) (xy 383.406396 -395.079982) (xy 383.410714 -395.048994)
			(xy 383.411623 -395.039758) (xy 383.407596 -395.021657) (xy 383.40284 -395.013688) (xy 383.386535 -394.98784)
			(xy 383.36263 -394.931606) (xy 383.355342 -394.901928) (xy 383.353272 -394.89377) (xy 383.344578 -394.879367)
			(xy 383.338324 -394.873734) (xy 383.31521 -394.854684) (xy 383.30838 -394.849477) (xy 383.292287 -394.843507)
			(xy 383.283714 -394.843) (xy 383.254079 -394.841943) (xy 383.195416 -394.8333) (xy 383.13836 -394.817155)
			(xy 383.083866 -394.793778) (xy 383.032846 -394.763561) (xy 382.986156 -394.727008) (xy 382.944576 -394.684733)
			(xy 382.908803 -394.637443) (xy 382.879436 -394.585929) (xy 382.856966 -394.531055) (xy 382.841769 -394.473739)
			(xy 382.834101 -394.41494) (xy 382.833626 -394.385292) (xy 382.834148 -394.354229) (xy 382.842563 -394.292675)
			(xy 382.85039 -394.26261) (xy 382.853184 -394.25245) (xy 382.850644 -394.232638) (xy 382.803146 -394.150342)
			(xy 382.787144 -394.13815) (xy 382.776984 -394.13561) (xy 382.747874 -394.127612) (xy 382.691906 -394.10498)
			(xy 382.639398 -394.075187) (xy 382.591263 -394.03875) (xy 382.548336 -393.996301) (xy 382.511362 -393.948578)
			(xy 382.480982 -393.896408) (xy 382.457724 -393.840697) (xy 382.441992 -393.782413) (xy 382.434058 -393.722565)
			(xy 382.433576 -393.69238) (xy 382.434105 -393.661492) (xy 382.44241 -393.600277) (xy 382.458866 -393.540733)
			(xy 382.483174 -393.483941) (xy 382.4986 -393.457176) (xy 382.504442 -393.44727) (xy 382.506728 -393.424918)
			(xy 382.473454 -393.329668) (xy 382.457706 -393.313666) (xy 382.447038 -393.309602) (xy 382.423644 -393.300449)
			(xy 382.379749 -393.276023) (xy 382.340054 -393.245237) (xy 382.305475 -393.208798) (xy 382.276808 -393.167547)
			(xy 382.254712 -393.122434) (xy 382.239697 -393.074497) (xy 382.232108 -393.024839) (xy 382.231646 -392.999722)
			(xy 381.693166 -392.999722) (xy 381.692635 -393.026824) (xy 381.683826 -393.080307) (xy 381.67564 -393.106148)
			(xy 381.67183 -393.11707) (xy 381.67437 -393.139422) (xy 381.726948 -393.225528) (xy 381.745744 -393.23772)
			(xy 381.757174 -393.239498) (xy 381.786467 -393.244282) (xy 381.843601 -393.260359) (xy 381.898178 -393.283687)
			(xy 381.94928 -393.313876) (xy 381.996051 -393.350418) (xy 382.037705 -393.3927) (xy 382.073543 -393.440012)
			(xy 382.102964 -393.491561) (xy 382.125473 -393.54648) (xy 382.140694 -393.603849) (xy 382.14837 -393.662703)
			(xy 382.148842 -393.69238) (xy 382.148315 -393.723443) (xy 382.139903 -393.784996) (xy 382.132078 -393.815062)
			(xy 382.129284 -393.825222) (xy 382.131824 -393.845034) (xy 382.179322 -393.92733) (xy 382.195324 -393.939522)
			(xy 382.205484 -393.942062) (xy 382.2346 -393.95004) (xy 382.290565 -393.972678) (xy 382.34307 -394.002476)
			(xy 382.391203 -394.038917) (xy 382.434128 -394.081368) (xy 382.471101 -394.129093) (xy 382.50148 -394.181263)
			(xy 382.524739 -394.236975) (xy 382.540473 -394.295259) (xy 382.548409 -394.355106) (xy 382.548892 -394.385292)
			(xy 382.548767 -394.399427) (xy 382.546985 -394.427641) (xy 382.545336 -394.44168) (xy 382.544578 -394.450287)
			(xy 382.548217 -394.467167) (xy 382.552448 -394.4747) (xy 382.568196 -394.5001) (xy 382.572904 -394.507161)
			(xy 382.586011 -394.51793) (xy 382.59385 -394.521182) (xy 382.617236 -394.530354) (xy 382.661131 -394.554778)
			(xy 382.700825 -394.585561) (xy 382.735405 -394.621997) (xy 382.764073 -394.663245) (xy 382.786171 -394.708355)
			(xy 382.801188 -394.75629) (xy 382.808779 -394.805946) (xy 382.809242 -394.831062) (xy 382.808826 -394.855265)
			(xy 382.801752 -394.90315) (xy 382.787763 -394.94949) (xy 382.767159 -394.993291) (xy 382.754124 -395.013688)
			(xy 382.749333 -395.021643) (xy 382.745302 -395.039755) (xy 382.74625 -395.048994) (xy 382.750568 -395.079982)
			(xy 382.75226 -395.089275) (xy 382.761535 -395.105717) (xy 382.768602 -395.111986) (xy 382.790677 -395.130683)
			(xy 382.830452 -395.172691) (xy 382.864617 -395.219375) (xy 382.892627 -395.269993) (xy 382.914036 -395.323736)
			(xy 382.928503 -395.379748) (xy 382.935797 -395.437137) (xy 382.936242 -395.466062) (xy 382.935652 -395.499383)
			(xy 382.92599 -395.565322) (xy 382.906864 -395.629161) (xy 382.893316 -395.65961) (xy 382.889055 -395.670071)
			(xy 382.889169 -395.692635) (xy 382.898911 -395.712988) (xy 382.907286 -395.72057) (xy 382.929513 -395.739266)
			(xy 382.969578 -395.781317) (xy 383.004001 -395.8281) (xy 383.032229 -395.878861) (xy 383.053807 -395.932785)
			(xy 383.06839 -395.989007) (xy 383.075743 -396.046621) (xy 383.076196 -396.075662) (xy 383.075703 -396.104666)
			(xy 383.068393 -396.162212) (xy 383.053873 -396.218374) (xy 383.032374 -396.272251) (xy 383.004243 -396.322982)
			(xy 382.969929 -396.369753) (xy 382.929981 -396.411814) (xy 382.907794 -396.4305) (xy 382.900682 -396.436088)
			(xy 382.891538 -396.451328) (xy 382.876298 -396.534132) (xy 382.879092 -396.551404) (xy 382.883664 -396.559532)
			(xy 382.896241 -396.582718) (xy 382.914114 -396.63234) (xy 382.923214 -396.684291) (xy 382.923796 -396.710662)
			(xy 382.923728 -396.720021) (xy 382.922584 -396.738703) (xy 382.92151 -396.748) (xy 382.920494 -396.75689)
			(xy 382.924304 -396.773654) (xy 382.968246 -396.843504) (xy 382.981962 -396.853918) (xy 382.990344 -396.856712)
			(xy 383.014373 -396.865178) (xy 383.059545 -396.888731) (xy 383.10035 -396.919231) (xy 383.135729 -396.955886)
			(xy 383.164765 -396.997746) (xy 383.186703 -397.043724) (xy 383.194306 -397.06804) (xy 383.19583 -397.073882)
			(xy 383.516124 -397.627602) (xy 383.520188 -397.63192) (xy 383.536378 -397.64964) (xy 383.563804 -397.689028)
			(xy 383.58495 -397.732114) (xy 383.599327 -397.777906) (xy 383.606604 -397.825346) (xy 383.607056 -397.849344)
			(xy 383.606647 -397.87415) (xy 383.598875 -397.92315) (xy 383.583531 -397.97033) (xy 383.560992 -398.014527)
			(xy 383.531814 -398.054651) (xy 383.496715 -398.089715) (xy 383.456562 -398.118854) (xy 383.412343 -398.14135)
			(xy 383.365148 -398.156648) (xy 383.316141 -398.164371) (xy 383.291334 -398.164812) (xy 383.265941 -398.164282)
			(xy 383.215808 -398.156156) (xy 383.167624 -398.14011) (xy 383.122629 -398.116556) (xy 383.081986 -398.086103)
			(xy 383.046743 -398.049535) (xy 383.017808 -398.007797) (xy 382.995929 -397.961965) (xy 382.988312 -397.937736)
			(xy 382.986788 -397.931894) (xy 382.666494 -397.378174) (xy 382.66243 -397.373856) (xy 382.646267 -397.356126)
			(xy 382.6189 -397.316722) (xy 382.59781 -397.273631) (xy 382.583484 -397.227846) (xy 382.57625 -397.18042)
			(xy 382.575816 -397.156432) (xy 382.575897 -397.144384) (xy 382.577679 -397.120355) (xy 382.579372 -397.108426)
			(xy 382.580642 -397.099536) (xy 382.577594 -397.082518) (xy 382.53543 -397.011652) (xy 382.522222 -397.000476)
			(xy 382.51384 -396.997428) (xy 382.492086 -396.989049) (xy 382.451228 -396.966604) (xy 382.414259 -396.938208)
			(xy 382.382037 -396.90452) (xy 382.355313 -396.866324) (xy 382.334708 -396.824508) (xy 382.320701 -396.780046)
			(xy 382.313618 -396.73397) (xy 382.31318 -396.710662) (xy 382.313748 -396.684289) (xy 382.322831 -396.632331)
			(xy 382.340718 -396.58271) (xy 382.353312 -396.559532) (xy 382.357884 -396.551404) (xy 382.360678 -396.534132)
			(xy 382.345438 -396.451328) (xy 382.336294 -396.436088) (xy 382.329182 -396.4305) (xy 382.307008 -396.411798)
			(xy 382.267061 -396.369736) (xy 382.232745 -396.322967) (xy 382.204607 -396.27224) (xy 382.183098 -396.218367)
			(xy 382.168561 -396.162209) (xy 382.161231 -396.104666) (xy 382.16078 -396.075662) (xy 382.161376 -396.042341)
			(xy 382.171036 -395.976402) (xy 382.190159 -395.912563) (xy 382.203706 -395.882114) (xy 382.207936 -395.871643)
			(xy 382.207831 -395.849088) (xy 382.198103 -395.828738) (xy 382.189736 -395.821154) (xy 382.167476 -395.802494)
			(xy 382.127413 -395.760437) (xy 382.092992 -395.713649) (xy 382.064768 -395.662881) (xy 382.043195 -395.608951)
			(xy 382.028619 -395.552724) (xy 382.021274 -395.495105) (xy 382.020826 -395.466062) (xy 382.021287 -395.437136)
			(xy 382.02857 -395.379744) (xy 382.043028 -395.323728) (xy 382.064431 -395.269981) (xy 382.092436 -395.21936)
			(xy 382.126598 -395.172671) (xy 382.166371 -395.13066) (xy 382.188466 -395.111986) (xy 382.195439 -395.10564)
			(xy 382.204696 -395.089235) (xy 382.2065 -395.079982) (xy 382.210818 -395.048994) (xy 382.211727 -395.039757)
			(xy 382.2077 -395.021657) (xy 382.202944 -395.013688) (xy 382.18664 -394.98784) (xy 382.162734 -394.931606)
			(xy 382.155446 -394.901928) (xy 382.153375 -394.89377) (xy 382.144682 -394.879367) (xy 382.138428 -394.873734)
			(xy 382.115314 -394.854684) (xy 382.108425 -394.849451) (xy 382.092201 -394.843478) (xy 382.083564 -394.843)
			(xy 382.053927 -394.841989) (xy 381.995263 -394.83334) (xy 381.938206 -394.817189) (xy 381.883711 -394.793807)
			(xy 381.832692 -394.763584) (xy 381.786002 -394.727027) (xy 381.744423 -394.684748) (xy 381.708651 -394.637455)
			(xy 381.679284 -394.585938) (xy 381.656815 -394.531061) (xy 381.641619 -394.473742) (xy 381.633951 -394.414941)
			(xy 381.633476 -394.385292) (xy 381.633996 -394.354229) (xy 381.642413 -394.292675) (xy 381.65024 -394.26261)
			(xy 381.653034 -394.25245) (xy 381.650494 -394.232638) (xy 381.602996 -394.150342) (xy 381.586994 -394.13815)
			(xy 381.576834 -394.13561) (xy 381.547714 -394.127645) (xy 381.491747 -394.105007) (xy 381.43924 -394.075209)
			(xy 381.391107 -394.038767) (xy 381.348181 -393.996315) (xy 381.311208 -393.948588) (xy 381.280829 -393.896415)
			(xy 381.257572 -393.840702) (xy 381.241841 -393.782415) (xy 381.233907 -393.722566) (xy 381.233426 -393.69238)
			(xy 381.233901 -393.661458) (xy 381.242183 -393.600171) (xy 381.258648 -393.540559) (xy 381.282995 -393.48371)
			(xy 381.29845 -393.456922) (xy 381.304546 -393.44727) (xy 381.306832 -393.424918) (xy 381.273304 -393.329668)
			(xy 381.257556 -393.313666) (xy 381.246888 -393.309602) (xy 381.223538 -393.300378) (xy 381.179694 -393.275924)
			(xy 381.140049 -393.245124) (xy 381.105513 -393.208687) (xy 381.076882 -393.167449) (xy 381.054811 -393.122358)
			(xy 381.039808 -393.074449) (xy 381.032218 -393.024823) (xy 381.03175 -392.999722) (xy 380.493016 -392.999722)
			(xy 380.492483 -393.026824) (xy 380.483675 -393.080306) (xy 380.47549 -393.106148) (xy 380.47168 -393.11707)
			(xy 380.47422 -393.139422) (xy 380.526798 -393.225274) (xy 380.545848 -393.23772) (xy 380.557024 -393.239498)
			(xy 380.586341 -393.244211) (xy 380.643512 -393.260258) (xy 380.698126 -393.283567) (xy 380.749265 -393.313746)
			(xy 380.796071 -393.350286) (xy 380.837756 -393.392575) (xy 380.873621 -393.439901) (xy 380.903061 -393.491469)
			(xy 380.925583 -393.546412) (xy 380.940807 -393.603807) (xy 380.948479 -393.66269) (xy 380.948946 -393.69238)
			(xy 380.948419 -393.723443) (xy 380.940007 -393.784996) (xy 380.932182 -393.815062) (xy 380.929388 -393.825222)
			(xy 380.931928 -393.845034) (xy 380.979426 -393.92733) (xy 380.995428 -393.939522) (xy 381.005588 -393.942062)
			(xy 381.034704 -393.950038) (xy 381.09067 -393.972676) (xy 381.143175 -394.002475) (xy 381.191307 -394.038916)
			(xy 381.234233 -394.081367) (xy 381.271206 -394.129092) (xy 381.301585 -394.181263) (xy 381.324843 -394.236974)
			(xy 381.340577 -394.295259) (xy 381.348513 -394.355106) (xy 381.348996 -394.385292) (xy 381.348871 -394.399427)
			(xy 381.347089 -394.427641) (xy 381.34544 -394.44168) (xy 381.344682 -394.450287) (xy 381.34832 -394.467167)
			(xy 381.352552 -394.4747) (xy 381.3683 -394.5001) (xy 381.372994 -394.507175) (xy 381.386104 -394.517948)
			(xy 381.393954 -394.521182) (xy 381.417308 -394.530397) (xy 381.46115 -394.554855) (xy 381.500793 -394.585657)
			(xy 381.535327 -394.622096) (xy 381.563957 -394.663335) (xy 381.586028 -394.708426) (xy 381.601031 -394.756335)
			(xy 381.608623 -394.805961) (xy 381.609092 -394.831062) (xy 381.608668 -394.855264) (xy 381.601594 -394.903149)
			(xy 381.587608 -394.949489) (xy 381.567007 -394.993291) (xy 381.553974 -395.013688) (xy 381.549186 -395.021645)
			(xy 381.545152 -395.039756) (xy 381.5461 -395.048994) (xy 381.550418 -395.079982) (xy 381.552094 -395.08928)
			(xy 381.561379 -395.105721) (xy 381.568452 -395.111986) (xy 381.590538 -395.130671) (xy 381.63031 -395.172682)
			(xy 381.664473 -395.219369) (xy 381.692481 -395.269988) (xy 381.713888 -395.323733) (xy 381.728354 -395.379747)
			(xy 381.735647 -395.437136) (xy 381.736092 -395.466062) (xy 381.735497 -395.499383) (xy 381.725836 -395.565321)
			(xy 381.706712 -395.629161) (xy 381.693166 -395.65961) (xy 381.688922 -395.670076) (xy 381.689036 -395.692633)
			(xy 381.698768 -395.712984) (xy 381.707136 -395.72057) (xy 381.729374 -395.739254) (xy 381.769436 -395.781309)
			(xy 381.803857 -395.828094) (xy 381.832082 -395.878857) (xy 381.853659 -395.932783) (xy 381.868241 -395.989005)
			(xy 381.875593 -396.046621) (xy 381.876046 -396.075662) (xy 381.875571 -396.104667) (xy 381.86826 -396.162214)
			(xy 381.853738 -396.218377) (xy 381.832238 -396.272255) (xy 381.804103 -396.322986) (xy 381.769785 -396.369756)
			(xy 381.729834 -396.411815) (xy 381.707644 -396.4305) (xy 381.700532 -396.436088) (xy 381.691388 -396.451328)
			(xy 381.676148 -396.534132) (xy 381.678942 -396.551404) (xy 381.683514 -396.559532) (xy 381.696087 -396.58272)
			(xy 381.713962 -396.63234) (xy 381.723064 -396.684291) (xy 381.723646 -396.710662) (xy 381.723577 -396.720021)
			(xy 381.722434 -396.738703) (xy 381.72136 -396.748) (xy 381.720344 -396.75689) (xy 381.724154 -396.773654)
			(xy 381.768096 -396.843504) (xy 381.781812 -396.853918) (xy 381.790194 -396.856712) (xy 381.814213 -396.865204)
			(xy 381.859387 -396.888751) (xy 381.900193 -396.919245) (xy 381.935574 -396.955895) (xy 381.964612 -396.997751)
			(xy 381.986552 -397.043726) (xy 381.994156 -397.06804) (xy 381.99568 -397.073882) (xy 382.315974 -397.627602)
			(xy 382.320038 -397.63192) (xy 382.336232 -397.649624) (xy 382.363596 -397.689034) (xy 382.38468 -397.732131)
			(xy 382.398999 -397.777923) (xy 382.406223 -397.825354) (xy 382.406652 -397.849344) (xy 382.406223 -397.874136)
			(xy 382.39846 -397.923108) (xy 382.383132 -397.970262) (xy 382.360616 -398.014439) (xy 382.331468 -398.054549)
			(xy 382.296404 -398.089607) (xy 382.256288 -398.118748) (xy 382.212107 -398.141255) (xy 382.164949 -398.156574)
			(xy 382.115976 -398.164327) (xy 382.091184 -398.164812) (xy 382.065789 -398.164326) (xy 382.015655 -398.156193)
			(xy 381.967469 -398.140139) (xy 381.922475 -398.116578) (xy 381.881832 -398.086119) (xy 381.84659 -398.049546)
			(xy 381.817656 -398.007803) (xy 381.795778 -397.961967) (xy 381.788162 -397.937736) (xy 381.786638 -397.931894)
			(xy 381.466344 -397.378174) (xy 381.46228 -397.373856) (xy 381.446073 -397.35615) (xy 381.41865 -397.316759)
			(xy 381.397508 -397.273668) (xy 381.383135 -397.227874) (xy 381.375862 -397.180431) (xy 381.375412 -397.156432)
			(xy 381.375554 -397.14438) (xy 381.37746 -397.12035) (xy 381.379222 -397.108426) (xy 381.380492 -397.099536)
			(xy 381.377444 -397.082518) (xy 381.33528 -397.011652) (xy 381.322072 -397.000476) (xy 381.31369 -396.997428)
			(xy 381.291947 -396.989022) (xy 381.251087 -396.966584) (xy 381.214116 -396.938192) (xy 381.181893 -396.904509)
			(xy 381.155167 -396.866316) (xy 381.13456 -396.824503) (xy 381.120552 -396.780043) (xy 381.113468 -396.733969)
			(xy 381.11303 -396.710662) (xy 381.113592 -396.684289) (xy 381.122676 -396.63233) (xy 381.140566 -396.58271)
			(xy 381.153162 -396.559532) (xy 381.157734 -396.551404) (xy 381.160528 -396.534132) (xy 381.145288 -396.451328)
			(xy 381.136144 -396.436088) (xy 381.129032 -396.4305) (xy 381.106868 -396.411786) (xy 381.066919 -396.369727)
			(xy 381.0326 -396.322961) (xy 381.00446 -396.272236) (xy 380.982949 -396.218364) (xy 380.968412 -396.162208)
			(xy 380.961081 -396.104666) (xy 380.96063 -396.075662) (xy 380.961231 -396.042341) (xy 380.970889 -395.976403)
			(xy 380.990011 -395.912563) (xy 381.003556 -395.882114) (xy 381.007803 -395.871647) (xy 381.007698 -395.849086)
			(xy 380.997961 -395.828735) (xy 380.989586 -395.821154) (xy 380.967316 -395.802507) (xy 380.927255 -395.760446)
			(xy 380.892837 -395.713655) (xy 380.864615 -395.662885) (xy 380.843043 -395.608953) (xy 380.828468 -395.552725)
			(xy 380.821124 -395.495105) (xy 380.820676 -395.466062) (xy 380.821119 -395.437135) (xy 380.828403 -395.379742)
			(xy 380.842863 -395.323725) (xy 380.864267 -395.269977) (xy 380.892276 -395.219356) (xy 380.926442 -395.172668)
			(xy 380.966219 -395.130659) (xy 380.988316 -395.111986) (xy 380.995281 -395.105631) (xy 381.004544 -395.089233)
			(xy 381.00635 -395.079982) (xy 381.010668 -395.048994) (xy 381.011569 -395.039757) (xy 381.007546 -395.021658)
			(xy 381.002794 -395.013688) (xy 380.986485 -394.987843) (xy 380.962582 -394.931607) (xy 380.955296 -394.901928)
			(xy 380.953238 -394.893766) (xy 380.944536 -394.879365) (xy 380.938278 -394.873734) (xy 380.915164 -394.854684)
			(xy 380.908346 -394.849459) (xy 380.892244 -394.8435) (xy 380.883668 -394.843) (xy 380.854032 -394.841985)
			(xy 380.795367 -394.833337) (xy 380.73831 -394.817187) (xy 380.683816 -394.793805) (xy 380.632797 -394.763582)
			(xy 380.586107 -394.727026) (xy 380.544527 -394.684747) (xy 380.508755 -394.637454) (xy 380.479388 -394.585937)
			(xy 380.456919 -394.531061) (xy 380.441723 -394.473742) (xy 380.434055 -394.414941) (xy 380.43358 -394.385292)
			(xy 380.4341 -394.354229) (xy 380.442517 -394.292675) (xy 380.450344 -394.26261) (xy 380.453138 -394.25245)
			(xy 380.450598 -394.232638) (xy 380.4031 -394.150342) (xy 380.387098 -394.13815) (xy 380.376938 -394.13561)
			(xy 380.347819 -394.127643) (xy 380.291851 -394.105005) (xy 380.239345 -394.075207) (xy 380.191211 -394.038766)
			(xy 380.148285 -393.996314) (xy 380.111312 -393.948587) (xy 380.080933 -393.896415) (xy 380.057676 -393.840702)
			(xy 380.041945 -393.782415) (xy 380.034011 -393.722566) (xy 380.03353 -393.69238) (xy 380.034052 -393.661492)
			(xy 380.042357 -393.600276) (xy 380.058815 -393.540732) (xy 380.083127 -393.48394) (xy 380.098554 -393.457176)
			(xy 380.104396 -393.44727) (xy 380.106682 -393.424918) (xy 380.073408 -393.329668) (xy 380.05766 -393.313666)
			(xy 380.046992 -393.309602) (xy 380.02361 -393.30042) (xy 379.979713 -393.276001) (xy 379.940016 -393.24522)
			(xy 379.905435 -393.208786) (xy 379.876766 -393.167539) (xy 379.854668 -393.122429) (xy 379.839652 -393.074494)
			(xy 379.832062 -393.024838) (xy 379.8316 -392.999722) (xy 379.29312 -392.999722) (xy 379.292587 -393.026824)
			(xy 379.283779 -393.080306) (xy 379.275594 -393.106148) (xy 379.271784 -393.11707) (xy 379.274324 -393.139422)
			(xy 379.326902 -393.225274) (xy 379.345952 -393.23772) (xy 379.357128 -393.239498) (xy 379.386446 -393.244208)
			(xy 379.443616 -393.260256) (xy 379.49823 -393.283565) (xy 379.54937 -393.313744) (xy 379.596176 -393.350285)
			(xy 379.637861 -393.392574) (xy 379.673725 -393.4399) (xy 379.703165 -393.491468) (xy 379.725687 -393.546412)
			(xy 379.740911 -393.603807) (xy 379.748583 -393.66269) (xy 379.74905 -393.69238) (xy 379.748527 -393.723506)
			(xy 379.740121 -393.785188) (xy 379.732286 -393.815316) (xy 379.729492 -393.825476) (xy 379.732032 -393.845542)
			(xy 379.779276 -393.92733) (xy 379.795278 -393.939522) (xy 379.805438 -393.942062) (xy 379.834545 -393.950071)
			(xy 379.890511 -393.972704) (xy 379.943017 -394.002497) (xy 379.991151 -394.038933) (xy 380.034077 -394.08138)
			(xy 380.071051 -394.129102) (xy 380.101432 -394.18127) (xy 380.124691 -394.236979) (xy 380.140426 -394.295262)
			(xy 380.148362 -394.355107) (xy 380.148846 -394.385292) (xy 380.148721 -394.399427) (xy 380.146939 -394.427641)
			(xy 380.14529 -394.44168) (xy 380.144524 -394.450287) (xy 380.148167 -394.467168) (xy 380.152402 -394.4747)
			(xy 380.16815 -394.5001) (xy 380.172872 -394.50715) (xy 380.185969 -394.517925) (xy 380.193804 -394.521182)
			(xy 380.21718 -394.530379) (xy 380.261076 -394.554797) (xy 380.300772 -394.585575) (xy 380.335354 -394.622007)
			(xy 380.364024 -394.663252) (xy 380.386123 -394.70836) (xy 380.401141 -394.756293) (xy 380.408733 -394.805947)
			(xy 380.409196 -394.831062) (xy 380.408771 -394.855264) (xy 380.401698 -394.903149) (xy 380.387711 -394.949488)
			(xy 380.367111 -394.99329) (xy 380.354078 -395.013688) (xy 380.349291 -395.021645) (xy 380.345256 -395.039756)
			(xy 380.346204 -395.048994) (xy 380.350522 -395.079982) (xy 380.352197 -395.08928) (xy 380.361482 -395.105721)
			(xy 380.368556 -395.111986) (xy 380.390643 -395.13067) (xy 380.430415 -395.172681) (xy 380.464577 -395.219369)
			(xy 380.492585 -395.269988) (xy 380.513992 -395.323733) (xy 380.528458 -395.379747) (xy 380.535751 -395.437136)
			(xy 380.536196 -395.466062) (xy 380.535601 -395.499383) (xy 380.52594 -395.565321) (xy 380.506816 -395.629161)
			(xy 380.49327 -395.65961) (xy 380.489025 -395.670075) (xy 380.489139 -395.692634) (xy 380.498871 -395.712985)
			(xy 380.50724 -395.72057) (xy 380.529458 -395.739278) (xy 380.569525 -395.781326) (xy 380.60395 -395.828105)
			(xy 380.632179 -395.878864) (xy 380.65376 -395.932788) (xy 380.668344 -395.989008) (xy 380.675697 -396.046622)
			(xy 380.67615 -396.075662) (xy 380.675674 -396.104667) (xy 380.668363 -396.162214) (xy 380.653841 -396.218377)
			(xy 380.632341 -396.272255) (xy 380.604206 -396.322985) (xy 380.569888 -396.369755) (xy 380.529937 -396.411815)
			(xy 380.507748 -396.4305) (xy 380.500636 -396.436088) (xy 380.491492 -396.451328) (xy 380.476252 -396.534132)
			(xy 380.479046 -396.551404) (xy 380.483618 -396.559532) (xy 380.496191 -396.58272) (xy 380.514066 -396.63234)
			(xy 380.523168 -396.684291) (xy 380.52375 -396.710662) (xy 380.523681 -396.720021) (xy 380.522538 -396.738703)
			(xy 380.521464 -396.748) (xy 380.520448 -396.75689) (xy 380.524258 -396.773654) (xy 380.5682 -396.843504)
			(xy 380.581916 -396.853918) (xy 380.590298 -396.856712) (xy 380.614318 -396.865202) (xy 380.659491 -396.888749)
			(xy 380.700298 -396.919244) (xy 380.735679 -396.955894) (xy 380.764716 -396.99775) (xy 380.786656 -397.043726)
			(xy 380.79426 -397.06804) (xy 380.795784 -397.073882) (xy 381.116078 -397.627602) (xy 381.120142 -397.63192)
			(xy 381.136337 -397.649623) (xy 381.1637 -397.689033) (xy 381.184784 -397.732131) (xy 381.199103 -397.777923)
			(xy 381.206328 -397.825354) (xy 381.206756 -397.849344) (xy 381.206323 -397.874135) (xy 381.19856 -397.923107)
			(xy 381.183232 -397.970261) (xy 381.160717 -398.014438) (xy 381.131569 -398.054548) (xy 381.096505 -398.089605)
			(xy 381.05639 -398.118746) (xy 381.012209 -398.141254) (xy 380.965052 -398.156573) (xy 380.916079 -398.164327)
			(xy 380.891288 -398.164812) (xy 380.865893 -398.164322) (xy 380.815759 -398.15619) (xy 380.767573 -398.140136)
			(xy 380.722579 -398.116576) (xy 380.681936 -398.086118) (xy 380.646694 -398.049545) (xy 380.61776 -398.007803)
			(xy 380.595882 -397.961967) (xy 380.588266 -397.937736) (xy 380.586742 -397.931894) (xy 380.266448 -397.378174)
			(xy 380.262384 -397.373856) (xy 380.246178 -397.35615) (xy 380.218755 -397.316758) (xy 380.197613 -397.273668)
			(xy 380.183239 -397.227874) (xy 380.175966 -397.180431) (xy 380.175516 -397.156432) (xy 380.175658 -397.14438)
			(xy 380.177564 -397.12035) (xy 380.179326 -397.108426) (xy 380.180596 -397.099536) (xy 380.177548 -397.082518)
			(xy 380.135384 -397.011652) (xy 380.122176 -397.000476) (xy 380.113794 -396.997428) (xy 380.092051 -396.98902)
			(xy 380.051192 -396.966582) (xy 380.014221 -396.938191) (xy 379.981997 -396.904508) (xy 379.955271 -396.866315)
			(xy 379.934664 -396.824503) (xy 379.920656 -396.780043) (xy 379.913572 -396.733969) (xy 379.913134 -396.710662)
			(xy 379.913695 -396.684289) (xy 379.922779 -396.63233) (xy 379.94067 -396.58271) (xy 379.953266 -396.559532)
			(xy 379.957838 -396.551404) (xy 379.960632 -396.534132) (xy 379.945392 -396.451328) (xy 379.936248 -396.436088)
			(xy 379.929136 -396.4305) (xy 379.906973 -396.411785) (xy 379.867024 -396.369726) (xy 379.832705 -396.32296)
			(xy 379.804564 -396.272236) (xy 379.783053 -396.218364) (xy 379.768516 -396.162208) (xy 379.761185 -396.104666)
			(xy 379.760734 -396.075662) (xy 379.761335 -396.042341) (xy 379.770993 -395.976403) (xy 379.790115 -395.912563)
			(xy 379.80366 -395.882114) (xy 379.807906 -395.871647) (xy 379.807801 -395.849087) (xy 379.798064 -395.828735)
			(xy 379.78969 -395.821154) (xy 379.767421 -395.802506) (xy 379.727359 -395.760445) (xy 379.692941 -395.713654)
			(xy 379.664719 -395.662885) (xy 379.643147 -395.608953) (xy 379.628572 -395.552725) (xy 379.621228 -395.495105)
			(xy 379.62078 -395.466062) (xy 379.621221 -395.437135) (xy 379.628505 -395.379742) (xy 379.642965 -395.323725)
			(xy 379.66437 -395.269977) (xy 379.692379 -395.219355) (xy 379.726545 -395.172668) (xy 379.766323 -395.130659)
			(xy 379.78842 -395.111986) (xy 379.795385 -395.105632) (xy 379.804648 -395.089234) (xy 379.806454 -395.079982)
			(xy 379.810772 -395.048994) (xy 379.811672 -395.039757) (xy 379.80765 -395.021658) (xy 379.802898 -395.013688)
			(xy 379.786589 -394.987843) (xy 379.762686 -394.931607) (xy 379.7554 -394.901928) (xy 379.753341 -394.893766)
			(xy 379.74464 -394.879365) (xy 379.738382 -394.873734) (xy 379.715268 -394.854684) (xy 379.708391 -394.849433)
			(xy 379.692158 -394.84347) (xy 379.683518 -394.843) (xy 379.653883 -394.841939) (xy 379.59522 -394.833297)
			(xy 379.538164 -394.817153) (xy 379.48367 -394.793776) (xy 379.432651 -394.763559) (xy 379.38596 -394.727007)
			(xy 379.34438 -394.684732) (xy 379.308607 -394.637442) (xy 379.27924 -394.585929) (xy 379.25677 -394.531055)
			(xy 379.241573 -394.473739) (xy 379.233905 -394.41494) (xy 379.23343 -394.385292) (xy 379.233951 -394.354229)
			(xy 379.242367 -394.292675) (xy 379.250194 -394.26261) (xy 379.252988 -394.25245) (xy 379.250448 -394.232638)
			(xy 379.20295 -394.150342) (xy 379.186948 -394.13815) (xy 379.176788 -394.13561) (xy 379.14771 -394.127542)
			(xy 379.091783 -394.104882) (xy 379.039316 -394.075072) (xy 378.99122 -394.038628) (xy 378.948329 -393.996182)
			(xy 378.911384 -393.948469) (xy 378.881027 -393.896317) (xy 378.857784 -393.84063) (xy 378.842058 -393.782371)
			(xy 378.834121 -393.722552) (xy 378.833634 -393.69238) (xy 378.834155 -393.661492) (xy 378.842461 -393.600276)
			(xy 378.858919 -393.540732) (xy 378.88323 -393.48394) (xy 378.898658 -393.457176) (xy 378.9045 -393.44727)
			(xy 378.906786 -393.424918) (xy 378.873512 -393.329668) (xy 378.857764 -393.313666) (xy 378.847096 -393.309602)
			(xy 378.823715 -393.300418) (xy 378.779817 -393.275999) (xy 378.740121 -393.245219) (xy 378.70554 -393.208785)
			(xy 378.67687 -393.167539) (xy 378.654772 -393.122428) (xy 378.639756 -393.074493) (xy 378.632166 -393.024838)
			(xy 378.631704 -392.999722) (xy 378.09297 -392.999722) (xy 378.092439 -393.026824) (xy 378.08363 -393.080307)
			(xy 378.075444 -393.106148) (xy 378.071634 -393.11707) (xy 378.074174 -393.139422) (xy 378.126752 -393.225274)
			(xy 378.145802 -393.23772) (xy 378.156978 -393.239498) (xy 378.186302 -393.244168) (xy 378.243473 -393.260223)
			(xy 378.298087 -393.283538) (xy 378.349226 -393.313722) (xy 378.396031 -393.350267) (xy 378.437715 -393.39256)
			(xy 378.473578 -393.439889) (xy 378.503017 -393.491461) (xy 378.525538 -393.546407) (xy 378.540762 -393.603804)
			(xy 378.548433 -393.662689) (xy 378.5489 -393.69238) (xy 378.548375 -393.723443) (xy 378.539962 -393.784997)
			(xy 378.532136 -393.815062) (xy 378.529342 -393.825222) (xy 378.531882 -393.845034) (xy 378.57938 -393.92733)
			(xy 378.595382 -393.939522) (xy 378.605542 -393.942062) (xy 378.634649 -393.950069) (xy 378.690616 -393.972702)
			(xy 378.743121 -394.002495) (xy 378.791255 -394.038932) (xy 378.834182 -394.081379) (xy 378.871156 -394.129101)
			(xy 378.901536 -394.18127) (xy 378.924795 -394.236979) (xy 378.94053 -394.295262) (xy 378.948466 -394.355107)
			(xy 378.94895 -394.385292) (xy 378.948825 -394.399427) (xy 378.947043 -394.427641) (xy 378.945394 -394.44168)
			(xy 378.944628 -394.450287) (xy 378.94827 -394.467168) (xy 378.952506 -394.4747) (xy 378.968254 -394.5001)
			(xy 378.972975 -394.507151) (xy 378.986073 -394.517925) (xy 378.993908 -394.521182) (xy 379.017285 -394.530377)
			(xy 379.061181 -394.554795) (xy 379.100877 -394.585574) (xy 379.135458 -394.622006) (xy 379.164128 -394.663251)
			(xy 379.186227 -394.70836) (xy 379.201245 -394.756293) (xy 379.208837 -394.805947) (xy 379.2093 -394.831062)
			(xy 379.208875 -394.855264) (xy 379.201801 -394.903149) (xy 379.187815 -394.949488) (xy 379.167215 -394.99329)
			(xy 379.154182 -395.013688) (xy 379.149395 -395.021645) (xy 379.14536 -395.039756) (xy 379.146308 -395.048994)
			(xy 379.150626 -395.079982) (xy 379.1523 -395.08928) (xy 379.161586 -395.105721) (xy 379.16866 -395.111986)
			(xy 379.190748 -395.130669) (xy 379.230519 -395.17268) (xy 379.264681 -395.219368) (xy 379.292689 -395.269988)
			(xy 379.314097 -395.323733) (xy 379.328562 -395.379746) (xy 379.335855 -395.437136) (xy 379.3363 -395.466062)
			(xy 379.335714 -395.499384) (xy 379.326051 -395.565322) (xy 379.306923 -395.629161) (xy 379.293374 -395.65961)
			(xy 379.289127 -395.670075) (xy 379.289241 -395.692634) (xy 379.298975 -395.712985) (xy 379.307344 -395.72057)
			(xy 379.329563 -395.739277) (xy 379.36963 -395.781325) (xy 379.404054 -395.828105) (xy 379.432284 -395.878864)
			(xy 379.453864 -395.932787) (xy 379.468448 -395.989008) (xy 379.475801 -396.046621) (xy 379.476254 -396.075662)
			(xy 379.475776 -396.104667) (xy 379.468466 -396.162214) (xy 379.453944 -396.218377) (xy 379.432444 -396.272255)
			(xy 379.404309 -396.322985) (xy 379.369992 -396.369755) (xy 379.330041 -396.411815) (xy 379.307852 -396.4305)
			(xy 379.30074 -396.436088) (xy 379.291596 -396.451328) (xy 379.276356 -396.534132) (xy 379.27915 -396.551404)
			(xy 379.283722 -396.559532) (xy 379.296296 -396.582719) (xy 379.314171 -396.63234) (xy 379.323272 -396.684291)
			(xy 379.323854 -396.710662) (xy 379.323785 -396.720021) (xy 379.322642 -396.738703) (xy 379.321568 -396.748)
			(xy 379.320552 -396.75689) (xy 379.324362 -396.773654) (xy 379.368304 -396.843504) (xy 379.38202 -396.853918)
			(xy 379.390402 -396.856712) (xy 379.4145 -396.865191) (xy 379.459791 -396.888817) (xy 379.500686 -396.919428)
			(xy 379.536117 -396.956225) (xy 379.56516 -396.998249) (xy 379.587056 -397.044401) (xy 379.594618 -397.068802)
			(xy 379.596142 -397.074644) (xy 379.915928 -397.627602) (xy 379.919992 -397.63192) (xy 379.936182 -397.64964)
			(xy 379.963609 -397.689027) (xy 379.984754 -397.732114) (xy 379.999131 -397.777906) (xy 380.006408 -397.825346)
			(xy 380.00686 -397.849344) (xy 380.006447 -397.87415) (xy 379.998675 -397.923149) (xy 379.983331 -397.970329)
			(xy 379.960793 -398.014525) (xy 379.931615 -398.05465) (xy 379.896517 -398.089714) (xy 379.856364 -398.118853)
			(xy 379.812146 -398.141349) (xy 379.764951 -398.156647) (xy 379.715944 -398.164371) (xy 379.691138 -398.164812)
			(xy 379.665745 -398.164278) (xy 379.615613 -398.156153) (xy 379.567428 -398.140107) (xy 379.522434 -398.116554)
			(xy 379.48179 -398.086101) (xy 379.446547 -398.049534) (xy 379.417612 -398.007797) (xy 379.395733 -397.961965)
			(xy 379.388116 -397.937736) (xy 379.386592 -397.931894) (xy 379.066044 -397.377412) (xy 379.06198 -397.373094)
			(xy 379.045882 -397.35542) (xy 379.018632 -397.316143) (xy 378.997619 -397.273204) (xy 378.983326 -397.227586)
			(xy 378.976079 -397.180334) (xy 378.97562 -397.156432) (xy 378.975762 -397.14438) (xy 378.977668 -397.12035)
			(xy 378.97943 -397.108426) (xy 378.9807 -397.099536) (xy 378.977652 -397.082518) (xy 378.935488 -397.011652)
			(xy 378.92228 -397.000476) (xy 378.913898 -396.997428) (xy 378.892156 -396.989017) (xy 378.851297 -396.96658)
			(xy 378.814325 -396.93819) (xy 378.782101 -396.904507) (xy 378.755375 -396.866315) (xy 378.734768 -396.824503)
			(xy 378.72076 -396.780043) (xy 378.713676 -396.733969) (xy 378.713238 -396.710662) (xy 378.713799 -396.684289)
			(xy 378.722883 -396.63233) (xy 378.740774 -396.58271) (xy 378.75337 -396.559532) (xy 378.757942 -396.551404)
			(xy 378.760736 -396.534132) (xy 378.745496 -396.451328) (xy 378.736352 -396.436088) (xy 378.72924 -396.4305)
			(xy 378.707078 -396.411784) (xy 378.667129 -396.369726) (xy 378.632809 -396.32296) (xy 378.604669 -396.272235)
			(xy 378.583158 -396.218364) (xy 378.56862 -396.162208) (xy 378.561289 -396.104666) (xy 378.560838 -396.075662)
			(xy 378.561438 -396.042341) (xy 378.571097 -395.976403) (xy 378.590219 -395.912563) (xy 378.603764 -395.882114)
			(xy 378.608008 -395.871647) (xy 378.607904 -395.849087) (xy 378.598167 -395.828736) (xy 378.589794 -395.821154)
			(xy 378.567526 -395.802505) (xy 378.527464 -395.760445) (xy 378.493045 -395.713654) (xy 378.464823 -395.662885)
			(xy 378.443251 -395.608953) (xy 378.428676 -395.552725) (xy 378.421332 -395.495105) (xy 378.420884 -395.466062)
			(xy 378.421324 -395.437135) (xy 378.428608 -395.379742) (xy 378.443068 -395.323725) (xy 378.464473 -395.269976)
			(xy 378.492482 -395.219355) (xy 378.526649 -395.172668) (xy 378.566427 -395.130659) (xy 378.588524 -395.111986)
			(xy 378.59549 -395.105633) (xy 378.604752 -395.089234) (xy 378.606558 -395.079982) (xy 378.610876 -395.048994)
			(xy 378.611776 -395.039757) (xy 378.607754 -395.021658) (xy 378.603002 -395.013688) (xy 378.586694 -394.987843)
			(xy 378.56279 -394.931607) (xy 378.555504 -394.901928) (xy 378.553444 -394.893766) (xy 378.544744 -394.879365)
			(xy 378.538486 -394.873734) (xy 378.515372 -394.854684) (xy 378.508494 -394.849435) (xy 378.492262 -394.843471)
			(xy 378.483622 -394.843) (xy 378.453984 -394.842027) (xy 378.395318 -394.833373) (xy 378.33826 -394.817218)
			(xy 378.283766 -394.793831) (xy 378.232747 -394.763604) (xy 378.186057 -394.727044) (xy 378.144479 -394.684761)
			(xy 378.108707 -394.637465) (xy 378.079341 -394.585945) (xy 378.056872 -394.531066) (xy 378.041677 -394.473745)
			(xy 378.034009 -394.414942) (xy 378.033534 -394.385292) (xy 378.034055 -394.354229) (xy 378.042471 -394.292675)
			(xy 378.050298 -394.26261) (xy 378.053092 -394.25245) (xy 378.050552 -394.232638) (xy 378.003054 -394.150342)
			(xy 377.987052 -394.13815) (xy 377.976892 -394.13561) (xy 377.947783 -394.127606) (xy 377.891815 -394.104975)
			(xy 377.839308 -394.075183) (xy 377.791172 -394.038747) (xy 377.748245 -393.996299) (xy 377.71127 -393.948576)
			(xy 377.68089 -393.896407) (xy 377.657632 -393.840697) (xy 377.6419 -393.782412) (xy 377.633966 -393.722565)
			(xy 377.633484 -393.69238) (xy 377.634012 -393.661492) (xy 377.642317 -393.600277) (xy 377.658773 -393.540733)
			(xy 377.683082 -393.483941) (xy 377.698508 -393.457176) (xy 377.70435 -393.44727) (xy 377.706636 -393.424918)
			(xy 377.673362 -393.329668) (xy 377.657614 -393.313666) (xy 377.646946 -393.309602) (xy 377.623554 -393.300445)
			(xy 377.579658 -393.27602) (xy 377.539964 -393.245234) (xy 377.505384 -393.208797) (xy 377.476717 -393.167546)
			(xy 377.454621 -393.122433) (xy 377.439605 -393.074496) (xy 377.432016 -393.024839) (xy 377.431554 -392.999722)
			(xy 376.893074 -392.999722) (xy 376.892543 -393.026824) (xy 376.883734 -393.080307) (xy 376.875548 -393.106148)
			(xy 376.871738 -393.11707) (xy 376.874278 -393.139422) (xy 376.926856 -393.225274) (xy 376.945906 -393.23772)
			(xy 376.957082 -393.239498) (xy 376.986407 -393.244165) (xy 377.043578 -393.26022) (xy 377.098192 -393.283536)
			(xy 377.14933 -393.31372) (xy 377.196135 -393.350266) (xy 377.237819 -393.392559) (xy 377.273682 -393.439889)
			(xy 377.303121 -393.49146) (xy 377.325642 -393.546406) (xy 377.340866 -393.603804) (xy 377.348537 -393.662689)
			(xy 377.349004 -393.69238) (xy 377.348479 -393.723443) (xy 377.340066 -393.784997) (xy 377.33224 -393.815062)
			(xy 377.329446 -393.825222) (xy 377.331986 -393.845034) (xy 377.379484 -393.92733) (xy 377.395486 -393.939522)
			(xy 377.405646 -393.942062) (xy 377.434754 -393.950066) (xy 377.490721 -393.972699) (xy 377.543226 -394.002493)
			(xy 377.59136 -394.03893) (xy 377.634286 -394.081378) (xy 377.67126 -394.1291) (xy 377.701641 -394.181269)
			(xy 377.7249 -394.236978) (xy 377.740634 -394.295261) (xy 377.748571 -394.355107) (xy 377.749054 -394.385292)
			(xy 377.748929 -394.399427) (xy 377.747147 -394.427641) (xy 377.745498 -394.44168) (xy 377.744732 -394.450287)
			(xy 377.748374 -394.467168) (xy 377.75261 -394.4747) (xy 377.768358 -394.5001) (xy 377.773066 -394.507164)
			(xy 377.786166 -394.517943) (xy 377.794012 -394.521182) (xy 377.817356 -394.53042) (xy 377.8612 -394.554872)
			(xy 377.900845 -394.58567) (xy 377.93538 -394.622105) (xy 377.964013 -394.663341) (xy 377.986084 -394.70843)
			(xy 378.001089 -394.756337) (xy 378.008681 -394.805961) (xy 378.00915 -394.831062) (xy 378.008733 -394.855264)
			(xy 378.001658 -394.90315) (xy 377.98767 -394.94949) (xy 377.967067 -394.993291) (xy 377.954032 -395.013688)
			(xy 377.949241 -395.021643) (xy 377.94521 -395.039756) (xy 377.946158 -395.048994) (xy 377.950476 -395.079982)
			(xy 377.952165 -395.089276) (xy 377.961442 -395.105718) (xy 377.96851 -395.111986) (xy 377.990587 -395.130681)
			(xy 378.030361 -395.172689) (xy 378.064526 -395.219374) (xy 378.092535 -395.269992) (xy 378.113944 -395.323735)
			(xy 378.128411 -395.379748) (xy 378.135705 -395.437137) (xy 378.13615 -395.466062) (xy 378.135559 -395.499383)
			(xy 378.125897 -395.565322) (xy 378.106771 -395.629161) (xy 378.093224 -395.65961) (xy 378.088961 -395.670071)
			(xy 378.089075 -395.692635) (xy 378.098818 -395.712988) (xy 378.107194 -395.72057) (xy 378.129423 -395.739264)
			(xy 378.169487 -395.781316) (xy 378.20391 -395.828099) (xy 378.232137 -395.87886) (xy 378.253716 -395.932785)
			(xy 378.268298 -395.989006) (xy 378.275651 -396.046621) (xy 378.276104 -396.075662) (xy 378.275645 -396.104668)
			(xy 378.268333 -396.162216) (xy 378.253809 -396.21838) (xy 378.232307 -396.272259) (xy 378.204169 -396.322989)
			(xy 378.169848 -396.369758) (xy 378.129893 -396.411817) (xy 378.107702 -396.4305) (xy 378.10059 -396.436088)
			(xy 378.091446 -396.451328) (xy 378.076206 -396.534132) (xy 378.079 -396.551404) (xy 378.083572 -396.559532)
			(xy 378.096142 -396.582722) (xy 378.114019 -396.632341) (xy 378.123122 -396.684292) (xy 378.123704 -396.710662)
			(xy 378.123635 -396.720021) (xy 378.122492 -396.738703) (xy 378.121418 -396.748) (xy 378.120402 -396.75689)
			(xy 378.124212 -396.773654) (xy 378.168154 -396.843504) (xy 378.18187 -396.853918) (xy 378.190252 -396.856712)
			(xy 378.214283 -396.865173) (xy 378.259455 -396.888728) (xy 378.300259 -396.919229) (xy 378.335638 -396.955885)
			(xy 378.364673 -396.997745) (xy 378.386611 -397.043724) (xy 378.394214 -397.06804) (xy 378.395738 -397.073882)
			(xy 378.716032 -397.627602) (xy 378.720096 -397.63192) (xy 378.736287 -397.649639) (xy 378.763713 -397.689027)
			(xy 378.784859 -397.732114) (xy 378.799235 -397.777905) (xy 378.806512 -397.825346) (xy 378.806964 -397.849344)
			(xy 378.806547 -397.87415) (xy 378.798776 -397.923149) (xy 378.783432 -397.970328) (xy 378.760893 -398.014524)
			(xy 378.731716 -398.054649) (xy 378.696619 -398.089713) (xy 378.656466 -398.118851) (xy 378.612248 -398.141347)
			(xy 378.565055 -398.156646) (xy 378.516048 -398.16437) (xy 378.491242 -398.164812) (xy 378.465849 -398.164275)
			(xy 378.415717 -398.15615) (xy 378.367532 -398.140105) (xy 378.322538 -398.116552) (xy 378.281895 -398.0861)
			(xy 378.246651 -398.049534) (xy 378.217717 -398.007796) (xy 378.195837 -397.961965) (xy 378.18822 -397.937736)
			(xy 378.186696 -397.931894) (xy 377.866402 -397.378174) (xy 377.862338 -397.373856) (xy 377.846176 -397.356124)
			(xy 377.818809 -397.316721) (xy 377.797719 -397.273631) (xy 377.783392 -397.227846) (xy 377.776158 -397.18042)
			(xy 377.775724 -397.156432) (xy 377.775805 -397.144384) (xy 377.777587 -397.120355) (xy 377.77928 -397.108426)
			(xy 377.78055 -397.099536) (xy 377.777502 -397.082518) (xy 377.735338 -397.011652) (xy 377.72213 -397.000476)
			(xy 377.713748 -396.997428) (xy 377.691995 -396.989045) (xy 377.651138 -396.966601) (xy 377.614168 -396.938205)
			(xy 377.581946 -396.904518) (xy 377.555222 -396.866323) (xy 377.534616 -396.824508) (xy 377.520609 -396.780045)
			(xy 377.513526 -396.73397) (xy 377.513088 -396.710662) (xy 377.513655 -396.684289) (xy 377.522738 -396.632331)
			(xy 377.540626 -396.58271) (xy 377.55322 -396.559532) (xy 377.557792 -396.551404) (xy 377.560586 -396.534132)
			(xy 377.545346 -396.451328) (xy 377.536202 -396.436088) (xy 377.52909 -396.4305) (xy 377.506917 -396.411796)
			(xy 377.466971 -396.369734) (xy 377.432654 -396.322966) (xy 377.404515 -396.272239) (xy 377.383006 -396.218366)
			(xy 377.368469 -396.162209) (xy 377.361139 -396.104666) (xy 377.360688 -396.075662) (xy 377.361284 -396.042341)
			(xy 377.370943 -395.976402) (xy 377.390067 -395.912563) (xy 377.403614 -395.882114) (xy 377.407842 -395.871642)
			(xy 377.407737 -395.849088) (xy 377.398011 -395.828739) (xy 377.389644 -395.821154) (xy 377.367386 -395.802492)
			(xy 377.327322 -395.760436) (xy 377.292901 -395.713648) (xy 377.264677 -395.662881) (xy 377.243103 -395.60895)
			(xy 377.228527 -395.552724) (xy 377.221182 -395.495105) (xy 377.220734 -395.466062) (xy 377.221192 -395.437136)
			(xy 377.228475 -395.379744) (xy 377.242934 -395.323728) (xy 377.264336 -395.26998) (xy 377.292342 -395.219359)
			(xy 377.326505 -395.172671) (xy 377.366279 -395.13066) (xy 377.388374 -395.111986) (xy 377.395348 -395.105641)
			(xy 377.404604 -395.089235) (xy 377.406408 -395.079982) (xy 377.410726 -395.048994) (xy 377.411633 -395.039757)
			(xy 377.407607 -395.021657) (xy 377.402852 -395.013688) (xy 377.38654 -394.987845) (xy 377.362639 -394.931608)
			(xy 377.355354 -394.901928) (xy 377.353281 -394.893771) (xy 377.344589 -394.879368) (xy 377.338336 -394.873734)
			(xy 377.315222 -394.854684) (xy 377.308389 -394.849482) (xy 377.292299 -394.843509) (xy 377.283726 -394.843)
			(xy 377.254088 -394.842024) (xy 377.195422 -394.83337) (xy 377.138365 -394.817215) (xy 377.08387 -394.793829)
			(xy 377.032851 -394.763602) (xy 376.986162 -394.727042) (xy 376.944583 -394.68476) (xy 376.908811 -394.637464)
			(xy 376.879445 -394.585945) (xy 376.856976 -394.531066) (xy 376.841781 -394.473745) (xy 376.834113 -394.414942)
			(xy 376.833638 -394.385292) (xy 376.834159 -394.354229) (xy 376.842575 -394.292675) (xy 376.850402 -394.26261)
			(xy 376.853196 -394.25245) (xy 376.850656 -394.232638) (xy 376.803158 -394.150342) (xy 376.787156 -394.13815)
			(xy 376.776996 -394.13561) (xy 376.747888 -394.127604) (xy 376.69192 -394.104973) (xy 376.639412 -394.075182)
			(xy 376.591277 -394.038746) (xy 376.548349 -393.996298) (xy 376.511375 -393.948576) (xy 376.480995 -393.896406)
			(xy 376.457736 -393.840696) (xy 376.442004 -393.782412) (xy 376.43407 -393.722565) (xy 376.433588 -393.69238)
			(xy 376.434115 -393.661492) (xy 376.44242 -393.600277) (xy 376.458877 -393.540733) (xy 376.483186 -393.483941)
			(xy 376.498612 -393.457176) (xy 376.504454 -393.44727) (xy 376.50674 -393.424918) (xy 376.473466 -393.329668)
			(xy 376.457718 -393.313666) (xy 376.44705 -393.309602) (xy 376.423659 -393.300443) (xy 376.379763 -393.276018)
			(xy 376.340068 -393.245233) (xy 376.305489 -393.208796) (xy 376.276821 -393.167546) (xy 376.254725 -393.122433)
			(xy 376.239709 -393.074496) (xy 376.23212 -393.024839) (xy 376.231658 -392.999722) (xy 375.693178 -392.999722)
			(xy 375.692647 -393.026824) (xy 375.683838 -393.080307) (xy 375.675652 -393.106148) (xy 375.671842 -393.11707)
			(xy 375.674382 -393.139422) (xy 375.72696 -393.225528) (xy 375.745756 -393.23772) (xy 375.757186 -393.239498)
			(xy 375.786481 -393.244272) (xy 375.843615 -393.260351) (xy 375.898192 -393.283681) (xy 375.949294 -393.313871)
			(xy 375.996064 -393.350414) (xy 376.037718 -393.392697) (xy 376.073556 -393.44001) (xy 376.102976 -393.491559)
			(xy 376.125485 -393.546479) (xy 376.140706 -393.603848) (xy 376.148382 -393.662703) (xy 376.148854 -393.69238)
			(xy 376.148327 -393.723443) (xy 376.139915 -393.784996) (xy 376.13209 -393.815062) (xy 376.129296 -393.825222)
			(xy 376.131836 -393.845034) (xy 376.179334 -393.92733) (xy 376.195336 -393.939522) (xy 376.205496 -393.942062)
			(xy 376.234614 -393.950032) (xy 376.29058 -393.972672) (xy 376.343084 -394.002471) (xy 376.391217 -394.038913)
			(xy 376.434141 -394.081365) (xy 376.471114 -394.129091) (xy 376.501493 -394.181262) (xy 376.524751 -394.236973)
			(xy 376.540485 -394.295259) (xy 376.548421 -394.355106) (xy 376.548904 -394.385292) (xy 376.548779 -394.399427)
			(xy 376.546997 -394.427641) (xy 376.545348 -394.44168) (xy 376.544589 -394.450287) (xy 376.548228 -394.467167)
			(xy 376.55246 -394.4747) (xy 376.568208 -394.5001) (xy 376.572912 -394.507164) (xy 376.586022 -394.517931)
			(xy 376.593862 -394.521182) (xy 376.61725 -394.530348) (xy 376.661145 -394.554773) (xy 376.700839 -394.585557)
			(xy 376.735418 -394.621994) (xy 376.764086 -394.663243) (xy 376.786183 -394.708354) (xy 376.8012 -394.75629)
			(xy 376.808791 -394.805946) (xy 376.809254 -394.831062) (xy 376.808836 -394.855264) (xy 376.801762 -394.90315)
			(xy 376.787773 -394.949489) (xy 376.767171 -394.993291) (xy 376.754136 -395.013688) (xy 376.749346 -395.021643)
			(xy 376.745314 -395.039756) (xy 376.746262 -395.048994) (xy 376.75058 -395.079982) (xy 376.752268 -395.089276)
			(xy 376.761545 -395.105718) (xy 376.768614 -395.111986) (xy 376.790692 -395.13068) (xy 376.830466 -395.172689)
			(xy 376.86463 -395.219374) (xy 376.89264 -395.269992) (xy 376.914048 -395.323735) (xy 376.928515 -395.379748)
			(xy 376.935809 -395.437137) (xy 376.936254 -395.466062) (xy 376.935663 -395.499383) (xy 376.926001 -395.565322)
			(xy 376.906875 -395.629161) (xy 376.893328 -395.65961) (xy 376.889064 -395.670071) (xy 376.889177 -395.692635)
			(xy 376.898921 -395.712988) (xy 376.907298 -395.72057) (xy 376.929528 -395.739263) (xy 376.969592 -395.781315)
			(xy 377.004014 -395.828098) (xy 377.032241 -395.87886) (xy 377.05382 -395.932785) (xy 377.068402 -395.989006)
			(xy 377.075755 -396.046621) (xy 377.076208 -396.075662) (xy 377.075747 -396.104668) (xy 377.068436 -396.162216)
			(xy 377.053912 -396.21838) (xy 377.03241 -396.272258) (xy 377.004272 -396.322989) (xy 376.969952 -396.369758)
			(xy 376.929997 -396.411816) (xy 376.907806 -396.4305) (xy 376.900694 -396.436088) (xy 376.89155 -396.451328)
			(xy 376.87631 -396.534132) (xy 376.879104 -396.551404) (xy 376.883676 -396.559532) (xy 376.896246 -396.582721)
			(xy 376.914123 -396.632341) (xy 376.923226 -396.684292) (xy 376.923808 -396.710662) (xy 376.923739 -396.720021)
			(xy 376.922596 -396.738703) (xy 376.921522 -396.748) (xy 376.920506 -396.75689) (xy 376.924316 -396.773654)
			(xy 376.968258 -396.843504) (xy 376.981974 -396.853918) (xy 376.990356 -396.856712) (xy 377.014387 -396.865171)
			(xy 377.059559 -396.888726) (xy 377.100364 -396.919228) (xy 377.135742 -396.955884) (xy 377.164777 -396.997745)
			(xy 377.186715 -397.043724) (xy 377.194318 -397.06804) (xy 377.195842 -397.073882) (xy 377.516136 -397.627602)
			(xy 377.5202 -397.63192) (xy 377.536392 -397.649639) (xy 377.563818 -397.689027) (xy 377.584963 -397.732113)
			(xy 377.599339 -397.777905) (xy 377.606616 -397.825346) (xy 377.607068 -397.849344) (xy 377.606647 -397.874149)
			(xy 377.598876 -397.923148) (xy 377.583532 -397.970327) (xy 377.560994 -398.014523) (xy 377.531817 -398.054647)
			(xy 377.49672 -398.089711) (xy 377.456568 -398.11885) (xy 377.412351 -398.141346) (xy 377.365158 -398.156645)
			(xy 377.316152 -398.16437) (xy 377.291346 -398.164812) (xy 377.265953 -398.164271) (xy 377.215821 -398.156148)
			(xy 377.167637 -398.140103) (xy 377.122642 -398.116551) (xy 377.081999 -398.086099) (xy 377.046756 -398.049533)
			(xy 377.017821 -398.007796) (xy 376.995941 -397.961965) (xy 376.988324 -397.937736) (xy 376.9868 -397.931894)
			(xy 376.666506 -397.378174) (xy 376.662442 -397.373856) (xy 376.646281 -397.356124) (xy 376.618913 -397.316721)
			(xy 376.597823 -397.273631) (xy 376.583496 -397.227846) (xy 376.576262 -397.18042) (xy 376.575828 -397.156432)
			(xy 376.575909 -397.144384) (xy 376.577691 -397.120355) (xy 376.579384 -397.108426) (xy 376.580654 -397.099536)
			(xy 376.577606 -397.082518) (xy 376.535442 -397.011652) (xy 376.522234 -397.000476) (xy 376.513852 -396.997428)
			(xy 376.4921 -396.989043) (xy 376.451242 -396.966599) (xy 376.414272 -396.938204) (xy 376.38205 -396.904517)
			(xy 376.355326 -396.866322) (xy 376.33472 -396.824507) (xy 376.320713 -396.780045) (xy 376.31363 -396.73397)
			(xy 376.313192 -396.710662) (xy 376.313759 -396.684289) (xy 376.322842 -396.632331) (xy 376.34073 -396.58271)
			(xy 376.353324 -396.559532) (xy 376.357896 -396.551404) (xy 376.36069 -396.534132) (xy 376.34545 -396.451328)
			(xy 376.336306 -396.436088) (xy 376.329194 -396.4305) (xy 376.307022 -396.411795) (xy 376.267075 -396.369734)
			(xy 376.232758 -396.322965) (xy 376.20462 -396.272239) (xy 376.18311 -396.218366) (xy 376.168573 -396.162209)
			(xy 376.161243 -396.104666) (xy 376.160792 -396.075662) (xy 376.161387 -396.042341) (xy 376.171047 -395.976402)
			(xy 376.190171 -395.912563) (xy 376.203718 -395.882114) (xy 376.207945 -395.871642) (xy 376.207839 -395.849088)
			(xy 376.198114 -395.828739) (xy 376.189748 -395.821154) (xy 376.167491 -395.802491) (xy 376.127426 -395.760435)
			(xy 376.093005 -395.713647) (xy 376.064781 -395.66288) (xy 376.043207 -395.60895) (xy 376.028631 -395.552724)
			(xy 376.021286 -395.495105) (xy 376.020838 -395.466062) (xy 376.021295 -395.437136) (xy 376.028578 -395.379744)
			(xy 376.043036 -395.323728) (xy 376.064439 -395.26998) (xy 376.092446 -395.219359) (xy 376.126608 -395.17267)
			(xy 376.166383 -395.13066) (xy 376.188478 -395.111986) (xy 376.195453 -395.105641) (xy 376.204708 -395.089236)
			(xy 376.206512 -395.079982) (xy 376.21083 -395.048994) (xy 376.211737 -395.039757) (xy 376.207711 -395.021657)
			(xy 376.202956 -395.013688) (xy 376.186644 -394.987845) (xy 376.162743 -394.931607) (xy 376.155458 -394.901928)
			(xy 376.15341 -394.893762) (xy 376.144702 -394.879362) (xy 376.13844 -394.873734) (xy 376.115326 -394.854684)
			(xy 376.108434 -394.849456) (xy 376.092213 -394.84348) (xy 376.083576 -394.843) (xy 376.05394 -394.841978)
			(xy 375.995275 -394.83333) (xy 375.938219 -394.817181) (xy 375.883724 -394.7938) (xy 375.832705 -394.763579)
			(xy 375.786015 -394.727023) (xy 375.744436 -394.684745) (xy 375.708663 -394.637452) (xy 375.679297 -394.585936)
			(xy 375.656827 -394.53106) (xy 375.641631 -394.473741) (xy 375.633963 -394.414941) (xy 375.633488 -394.385292)
			(xy 375.634008 -394.354229) (xy 375.642424 -394.292675) (xy 375.650252 -394.26261) (xy 375.653046 -394.25245)
			(xy 375.650506 -394.232638) (xy 375.603008 -394.150342) (xy 375.587006 -394.13815) (xy 375.576846 -394.13561)
			(xy 375.547728 -394.127637) (xy 375.491761 -394.105001) (xy 375.439254 -394.075204) (xy 375.39112 -394.038763)
			(xy 375.348194 -393.996312) (xy 375.311221 -393.948586) (xy 375.280842 -393.896414) (xy 375.257585 -393.840701)
			(xy 375.241853 -393.782415) (xy 375.233919 -393.722566) (xy 375.233438 -393.69238) (xy 375.233911 -393.661458)
			(xy 375.242194 -393.600171) (xy 375.258659 -393.540559) (xy 375.283007 -393.48371) (xy 375.298462 -393.456922)
			(xy 375.304558 -393.44727) (xy 375.306844 -393.424918) (xy 375.273316 -393.329668) (xy 375.257568 -393.313666)
			(xy 375.2469 -393.309602) (xy 375.223552 -393.300371) (xy 375.179708 -393.275919) (xy 375.140062 -393.24512)
			(xy 375.105527 -393.208684) (xy 375.076895 -393.167447) (xy 375.054823 -393.122357) (xy 375.03982 -393.074449)
			(xy 375.03223 -393.024823) (xy 375.031762 -392.999722) (xy 374.493028 -392.999722) (xy 374.492499 -393.026824)
			(xy 374.483689 -393.080307) (xy 374.475502 -393.106148) (xy 374.471692 -393.11707) (xy 374.474232 -393.139422)
			(xy 374.52681 -393.225274) (xy 374.54586 -393.23772) (xy 374.557036 -393.239498) (xy 374.586355 -393.244201)
			(xy 374.643525 -393.260251) (xy 374.698139 -393.283561) (xy 374.749279 -393.31374) (xy 374.796084 -393.350282)
			(xy 374.837769 -393.392572) (xy 374.873633 -393.439898) (xy 374.903073 -393.491467) (xy 374.925595 -393.546411)
			(xy 374.940819 -393.603807) (xy 374.948491 -393.66269) (xy 374.948958 -393.69238) (xy 374.948431 -393.723443)
			(xy 374.940019 -393.784996) (xy 374.932194 -393.815062) (xy 374.9294 -393.825222) (xy 374.93194 -393.845034)
			(xy 374.979438 -393.92733) (xy 374.99544 -393.939522) (xy 375.0056 -393.942062) (xy 375.034719 -393.95003)
			(xy 375.090684 -393.97267) (xy 375.143189 -394.002469) (xy 375.191321 -394.038911) (xy 375.234246 -394.081364)
			(xy 375.271218 -394.12909) (xy 375.301597 -394.181261) (xy 375.324855 -394.236973) (xy 375.340589 -394.295258)
			(xy 375.348525 -394.355106) (xy 375.349008 -394.385292) (xy 375.348883 -394.399427) (xy 375.347101 -394.427641)
			(xy 375.345452 -394.44168) (xy 375.344692 -394.450287) (xy 375.348331 -394.467167) (xy 375.352564 -394.4747)
			(xy 375.368312 -394.5001) (xy 375.373035 -394.507153) (xy 375.386125 -394.517937) (xy 375.393966 -394.521182)
			(xy 375.417322 -394.53039) (xy 375.461165 -394.55485) (xy 375.500807 -394.585653) (xy 375.53534 -394.622093)
			(xy 375.563971 -394.663332) (xy 375.586041 -394.708425) (xy 375.601044 -394.756334) (xy 375.608636 -394.80596)
			(xy 375.609104 -394.831062) (xy 375.608678 -394.855264) (xy 375.601605 -394.903149) (xy 375.587618 -394.949488)
			(xy 375.567019 -394.99329) (xy 375.553986 -395.013688) (xy 375.549199 -395.021645) (xy 375.545164 -395.039756)
			(xy 375.546112 -395.048994) (xy 375.55043 -395.079982) (xy 375.552103 -395.089281) (xy 375.561389 -395.105722)
			(xy 375.568464 -395.111986) (xy 375.590552 -395.130668) (xy 375.630324 -395.17268) (xy 375.664486 -395.219368)
			(xy 375.692494 -395.269987) (xy 375.713901 -395.323733) (xy 375.728366 -395.379746) (xy 375.735659 -395.437136)
			(xy 375.736104 -395.466062) (xy 375.735518 -395.499384) (xy 375.725854 -395.565322) (xy 375.706727 -395.629161)
			(xy 375.693178 -395.65961) (xy 375.68893 -395.670075) (xy 375.689044 -395.692634) (xy 375.698778 -395.712985)
			(xy 375.707148 -395.72057) (xy 375.729367 -395.739276) (xy 375.769434 -395.781324) (xy 375.803859 -395.828104)
			(xy 375.832088 -395.878864) (xy 375.853668 -395.932787) (xy 375.868252 -395.989008) (xy 375.875605 -396.046621)
			(xy 375.876058 -396.075662) (xy 375.875579 -396.104667) (xy 375.868268 -396.162214) (xy 375.853747 -396.218376)
			(xy 375.832246 -396.272254) (xy 375.804113 -396.322985) (xy 375.769795 -396.369755) (xy 375.729845 -396.411815)
			(xy 375.707656 -396.4305) (xy 375.700544 -396.436088) (xy 375.6914 -396.451328) (xy 375.67616 -396.534132)
			(xy 375.678954 -396.551404) (xy 375.683526 -396.559532) (xy 375.6961 -396.582719) (xy 375.713975 -396.63234)
			(xy 375.723076 -396.684291) (xy 375.723658 -396.710662) (xy 375.723589 -396.720021) (xy 375.722446 -396.738703)
			(xy 375.721372 -396.748) (xy 375.720356 -396.75689) (xy 375.724166 -396.773654) (xy 375.768108 -396.843504)
			(xy 375.781824 -396.853918) (xy 375.790206 -396.856712) (xy 375.814228 -396.865198) (xy 375.859401 -396.888746)
			(xy 375.900207 -396.919242) (xy 375.935587 -396.955893) (xy 375.964624 -396.99775) (xy 375.986564 -397.043725)
			(xy 375.994168 -397.06804) (xy 375.995692 -397.073882) (xy 376.315986 -397.627602) (xy 376.32005 -397.63192)
			(xy 376.336246 -397.649622) (xy 376.363609 -397.689033) (xy 376.384693 -397.732131) (xy 376.399011 -397.777923)
			(xy 376.406236 -397.825354) (xy 376.406664 -397.849344) (xy 376.406223 -397.874135) (xy 376.39846 -397.923106)
			(xy 376.383133 -397.970259) (xy 376.360619 -398.014435) (xy 376.331471 -398.054545) (xy 376.296409 -398.089603)
			(xy 376.256294 -398.118744) (xy 376.212115 -398.141251) (xy 376.164959 -398.156571) (xy 376.115987 -398.164326)
			(xy 376.091196 -398.164812) (xy 376.065802 -398.164315) (xy 376.015668 -398.156184) (xy 375.967482 -398.140132)
			(xy 375.922488 -398.116573) (xy 375.881845 -398.086115) (xy 375.846602 -398.049543) (xy 375.817669 -398.007802)
			(xy 375.795791 -397.961967) (xy 375.788174 -397.937736) (xy 375.78665 -397.931894) (xy 375.466356 -397.378174)
			(xy 375.462292 -397.373856) (xy 375.446088 -397.356149) (xy 375.418664 -397.316757) (xy 375.397521 -397.273668)
			(xy 375.383148 -397.227873) (xy 375.375874 -397.180431) (xy 375.375424 -397.156432) (xy 375.375566 -397.14438)
			(xy 375.377472 -397.12035) (xy 375.379234 -397.108426) (xy 375.380504 -397.099536) (xy 375.377456 -397.082518)
			(xy 375.335292 -397.011652) (xy 375.322084 -397.000476) (xy 375.313702 -396.997428) (xy 375.291961 -396.989015)
			(xy 375.251102 -396.966578) (xy 375.21413 -396.938189) (xy 375.181906 -396.904506) (xy 375.155179 -396.866314)
			(xy 375.134572 -396.824502) (xy 375.120564 -396.780042) (xy 375.11348 -396.733969) (xy 375.113042 -396.710662)
			(xy 375.113602 -396.684289) (xy 375.122687 -396.63233) (xy 375.140578 -396.58271) (xy 375.153174 -396.559532)
			(xy 375.157746 -396.551404) (xy 375.16054 -396.534132) (xy 375.1453 -396.451328) (xy 375.136156 -396.436088)
			(xy 375.129044 -396.4305) (xy 375.106883 -396.411783) (xy 375.066933 -396.369725) (xy 375.032614 -396.322959)
			(xy 375.004473 -396.272235) (xy 374.982962 -396.218364) (xy 374.968424 -396.162208) (xy 374.961093 -396.104666)
			(xy 374.960642 -396.075662) (xy 374.961242 -396.042341) (xy 374.9709 -395.976403) (xy 374.990022 -395.912563)
			(xy 375.003568 -395.882114) (xy 375.007811 -395.871646) (xy 375.007706 -395.849087) (xy 374.997971 -395.828736)
			(xy 374.989598 -395.821154) (xy 374.967331 -395.802504) (xy 374.927269 -395.760444) (xy 374.89285 -395.713654)
			(xy 374.864628 -395.662884) (xy 374.843056 -395.608953) (xy 374.82848 -395.552725) (xy 374.821136 -395.495105)
			(xy 374.820688 -395.466062) (xy 374.821126 -395.437135) (xy 374.828411 -395.379742) (xy 374.842871 -395.323724)
			(xy 374.864276 -395.269976) (xy 374.892286 -395.219355) (xy 374.926452 -395.172667) (xy 374.966231 -395.130659)
			(xy 374.988328 -395.111986) (xy 374.995294 -395.105633) (xy 375.004556 -395.089234) (xy 375.006362 -395.079982)
			(xy 375.01068 -395.048994) (xy 375.011579 -395.039757) (xy 375.007557 -395.021658) (xy 375.002806 -395.013688)
			(xy 374.986498 -394.987842) (xy 374.962595 -394.931607) (xy 374.955308 -394.901928) (xy 374.953247 -394.893767)
			(xy 374.944547 -394.879365) (xy 374.93829 -394.873734) (xy 374.915176 -394.854684) (xy 374.908355 -394.849463)
			(xy 374.892255 -394.843502) (xy 374.88368 -394.843) (xy 374.854044 -394.841974) (xy 374.79538 -394.833327)
			(xy 374.738323 -394.817178) (xy 374.683829 -394.793798) (xy 374.63281 -394.763577) (xy 374.58612 -394.727021)
			(xy 374.54454 -394.684743) (xy 374.508768 -394.637451) (xy 374.479401 -394.585935) (xy 374.456931 -394.531059)
			(xy 374.441735 -394.473741) (xy 374.434067 -394.414941) (xy 374.433592 -394.385292) (xy 374.434112 -394.354229)
			(xy 374.442528 -394.292675) (xy 374.450356 -394.26261) (xy 374.45315 -394.25245) (xy 374.45061 -394.232638)
			(xy 374.403112 -394.150342) (xy 374.38711 -394.13815) (xy 374.37695 -394.13561) (xy 374.347833 -394.127635)
			(xy 374.291865 -394.104999) (xy 374.239359 -394.075202) (xy 374.191225 -394.038762) (xy 374.148298 -393.996311)
			(xy 374.111325 -393.948585) (xy 374.080946 -393.896413) (xy 374.057689 -393.840701) (xy 374.041957 -393.782414)
			(xy 374.034023 -393.722566) (xy 374.033542 -393.69238) (xy 374.034062 -393.661492) (xy 374.042368 -393.600276)
			(xy 374.058826 -393.540732) (xy 374.083138 -393.48394) (xy 374.098566 -393.457176) (xy 374.104408 -393.44727)
			(xy 374.106694 -393.424918) (xy 374.07342 -393.329668) (xy 374.057672 -393.313666) (xy 374.047004 -393.309602)
			(xy 374.023624 -393.300414) (xy 373.979727 -393.275996) (xy 373.94003 -393.245216) (xy 373.905449 -393.208784)
			(xy 373.876779 -393.167537) (xy 373.854681 -393.122427) (xy 373.839664 -393.074493) (xy 373.832074 -393.024838)
			(xy 373.831612 -392.999722) (xy 373.293132 -392.999722) (xy 373.292603 -393.026824) (xy 373.283793 -393.080307)
			(xy 373.275606 -393.106148) (xy 373.271796 -393.11707) (xy 373.274336 -393.139422) (xy 373.326914 -393.225274)
			(xy 373.345964 -393.23772) (xy 373.35714 -393.239498) (xy 373.386459 -393.244198) (xy 373.44363 -393.260248)
			(xy 373.498244 -393.283559) (xy 373.549383 -393.313739) (xy 373.596189 -393.350281) (xy 373.637874 -393.39257)
			(xy 373.673738 -393.439898) (xy 373.703178 -393.491466) (xy 373.725699 -393.546411) (xy 373.740923 -393.603806)
			(xy 373.748595 -393.66269) (xy 373.749062 -393.69238) (xy 373.748538 -393.723506) (xy 373.740133 -393.785188)
			(xy 373.732298 -393.815316) (xy 373.729504 -393.825476) (xy 373.732044 -393.845542) (xy 373.779288 -393.92733)
			(xy 373.79529 -393.939522) (xy 373.80545 -393.942062) (xy 373.834559 -393.950063) (xy 373.890525 -393.972697)
			(xy 373.943031 -394.002491) (xy 373.991164 -394.038929) (xy 374.034091 -394.081377) (xy 374.071065 -394.1291)
			(xy 374.101445 -394.181268) (xy 374.124704 -394.236978) (xy 374.140438 -394.295261) (xy 374.148375 -394.355107)
			(xy 374.148858 -394.385292) (xy 374.148733 -394.399427) (xy 374.146951 -394.427641) (xy 374.145302 -394.44168)
			(xy 374.144535 -394.450287) (xy 374.148178 -394.467168) (xy 374.152414 -394.4747) (xy 374.168162 -394.5001)
			(xy 374.172881 -394.507153) (xy 374.18598 -394.517926) (xy 374.193816 -394.521182) (xy 374.217194 -394.530373)
			(xy 374.261091 -394.554792) (xy 374.300786 -394.585572) (xy 374.335367 -394.622004) (xy 374.364037 -394.66325)
			(xy 374.386135 -394.708359) (xy 374.401153 -394.756292) (xy 374.408745 -394.805946) (xy 374.409208 -394.831062)
			(xy 374.408781 -394.855264) (xy 374.401708 -394.903149) (xy 374.387722 -394.949488) (xy 374.367123 -394.99329)
			(xy 374.35409 -395.013688) (xy 374.349303 -395.021646) (xy 374.345268 -395.039756) (xy 374.346216 -395.048994)
			(xy 374.350534 -395.079982) (xy 374.352206 -395.089281) (xy 374.361493 -395.105722) (xy 374.368568 -395.111986)
			(xy 374.390657 -395.130667) (xy 374.430429 -395.172679) (xy 374.46459 -395.219367) (xy 374.492598 -395.269987)
			(xy 374.514005 -395.323732) (xy 374.52847 -395.379746) (xy 374.535763 -395.437136) (xy 374.536208 -395.466062)
			(xy 374.535621 -395.499384) (xy 374.525958 -395.565322) (xy 374.506831 -395.629161) (xy 374.493282 -395.65961)
			(xy 374.489033 -395.670074) (xy 374.489147 -395.692634) (xy 374.498881 -395.712985) (xy 374.507252 -395.72057)
			(xy 374.529472 -395.739275) (xy 374.569539 -395.781323) (xy 374.603963 -395.828104) (xy 374.632192 -395.878863)
			(xy 374.653772 -395.932787) (xy 374.668356 -395.989008) (xy 374.675709 -396.046621) (xy 374.676162 -396.075662)
			(xy 374.675681 -396.104667) (xy 374.668371 -396.162214) (xy 374.653849 -396.218376) (xy 374.632349 -396.272254)
			(xy 374.604216 -396.322985) (xy 374.569899 -396.369755) (xy 374.529949 -396.411815) (xy 374.50776 -396.4305)
			(xy 374.500648 -396.436088) (xy 374.491504 -396.451328) (xy 374.476264 -396.534132) (xy 374.479058 -396.551404)
			(xy 374.48363 -396.559532) (xy 374.496204 -396.582719) (xy 374.514079 -396.63234) (xy 374.52318 -396.684291)
			(xy 374.523762 -396.710662) (xy 374.523693 -396.720021) (xy 374.52255 -396.738703) (xy 374.521476 -396.748)
			(xy 374.52046 -396.75689) (xy 374.52427 -396.773654) (xy 374.568212 -396.843504) (xy 374.581928 -396.853918)
			(xy 374.59031 -396.856712) (xy 374.614332 -396.865196) (xy 374.659505 -396.888744) (xy 374.700311 -396.91924)
			(xy 374.735692 -396.955892) (xy 374.764729 -396.997749) (xy 374.786668 -397.043725) (xy 374.794272 -397.06804)
			(xy 374.795796 -397.073882) (xy 375.11609 -397.627602) (xy 375.120154 -397.63192) (xy 375.136351 -397.649621)
			(xy 375.163714 -397.689032) (xy 375.184797 -397.73213) (xy 375.199116 -397.777923) (xy 375.20634 -397.825354)
			(xy 375.206768 -397.849344) (xy 375.206323 -397.874135) (xy 375.19856 -397.923105) (xy 375.183233 -397.970259)
			(xy 375.160719 -398.014434) (xy 375.131573 -398.054544) (xy 375.096511 -398.089601) (xy 375.056396 -398.118742)
			(xy 375.012218 -398.14125) (xy 374.965062 -398.15657) (xy 374.916091 -398.164326) (xy 374.8913 -398.164812)
			(xy 374.865906 -398.164312) (xy 374.815772 -398.156181) (xy 374.767586 -398.140129) (xy 374.722592 -398.116571)
			(xy 374.681949 -398.086114) (xy 374.646707 -398.049543) (xy 374.617773 -398.007801) (xy 374.595895 -397.961967)
			(xy 374.588278 -397.937736) (xy 374.586754 -397.931894) (xy 374.26646 -397.378174) (xy 374.262396 -397.373856)
			(xy 374.246192 -397.356148) (xy 374.218768 -397.316757) (xy 374.197625 -397.273668) (xy 374.183252 -397.227873)
			(xy 374.175978 -397.18043) (xy 374.175528 -397.156432) (xy 374.17567 -397.14438) (xy 374.177576 -397.12035)
			(xy 374.179338 -397.108426) (xy 374.180608 -397.099536) (xy 374.17756 -397.082518) (xy 374.135396 -397.011652)
			(xy 374.122188 -397.000476) (xy 374.113806 -396.997428) (xy 374.092066 -396.989013) (xy 374.051206 -396.966577)
			(xy 374.014234 -396.938187) (xy 373.98201 -396.904505) (xy 373.955284 -396.866314) (xy 373.934676 -396.824502)
			(xy 373.920668 -396.780042) (xy 373.913584 -396.733969) (xy 373.913146 -396.710662) (xy 373.913706 -396.684289)
			(xy 373.92279 -396.63233) (xy 373.940681 -396.58271) (xy 373.953278 -396.559532) (xy 373.95785 -396.551404)
			(xy 373.960644 -396.534132) (xy 373.945404 -396.451328) (xy 373.93626 -396.436088) (xy 373.929148 -396.4305)
			(xy 373.906967 -396.411807) (xy 373.867022 -396.369742) (xy 373.832707 -396.322971) (xy 373.80457 -396.272243)
			(xy 373.783062 -396.218368) (xy 373.768527 -396.16221) (xy 373.761196 -396.104666) (xy 373.760746 -396.075662)
			(xy 373.761345 -396.042341) (xy 373.771004 -395.976403) (xy 373.790126 -395.912563) (xy 373.803672 -395.882114)
			(xy 373.807914 -395.871646) (xy 373.807809 -395.849087) (xy 373.798074 -395.828736) (xy 373.789702 -395.821154)
			(xy 373.767435 -395.802503) (xy 373.727373 -395.760443) (xy 373.692954 -395.713653) (xy 373.664732 -395.662884)
			(xy 373.64316 -395.608952) (xy 373.628584 -395.552725) (xy 373.62124 -395.495105) (xy 373.620792 -395.466062)
			(xy 373.621229 -395.437135) (xy 373.628513 -395.379742) (xy 373.642974 -395.323724) (xy 373.664379 -395.269976)
			(xy 373.692389 -395.219354) (xy 373.726556 -395.172667) (xy 373.766335 -395.130659) (xy 373.788432 -395.111986)
			(xy 373.795399 -395.105634) (xy 373.80466 -395.089234) (xy 373.806466 -395.079982) (xy 373.810784 -395.048994)
			(xy 373.811682 -395.039757) (xy 373.807661 -395.021658) (xy 373.80291 -395.013688) (xy 373.786602 -394.987842)
			(xy 373.762699 -394.931607) (xy 373.755412 -394.901928) (xy 373.75335 -394.893767) (xy 373.744651 -394.879366)
			(xy 373.738394 -394.873734) (xy 373.71528 -394.854684) (xy 373.7084 -394.849438) (xy 373.69217 -394.843472)
			(xy 373.68353 -394.843) (xy 373.653892 -394.84202) (xy 373.595226 -394.833367) (xy 373.538169 -394.817212)
			(xy 373.483675 -394.793826) (xy 373.432656 -394.7636) (xy 373.385966 -394.727041) (xy 373.344387 -394.684759)
			(xy 373.308616 -394.637463) (xy 373.279249 -394.585944) (xy 373.256781 -394.531065) (xy 373.241585 -394.473745)
			(xy 373.233917 -394.414942) (xy 373.233442 -394.385292) (xy 373.233963 -394.354229) (xy 373.242379 -394.292675)
			(xy 373.250206 -394.26261) (xy 373.253 -394.25245) (xy 373.25046 -394.232638) (xy 373.202962 -394.150342)
			(xy 373.18696 -394.13815) (xy 373.1768 -394.13561) (xy 373.147706 -394.1276) (xy 373.091779 -394.104929)
			(xy 373.039314 -394.07511) (xy 372.991221 -394.038658) (xy 372.948332 -393.996205) (xy 372.91139 -393.948487)
			(xy 372.881035 -393.89633) (xy 372.857794 -393.840638) (xy 372.842069 -393.782376) (xy 372.834133 -393.722553)
			(xy 372.833646 -393.69238) (xy 372.834165 -393.661492) (xy 372.842471 -393.600276) (xy 372.85893 -393.540732)
			(xy 372.883242 -393.48394) (xy 372.89867 -393.457176) (xy 372.904512 -393.44727) (xy 372.906798 -393.424918)
			(xy 372.873524 -393.329668) (xy 372.857776 -393.313666) (xy 372.847108 -393.309602) (xy 372.823729 -393.300412)
			(xy 372.779832 -393.275994) (xy 372.740135 -393.245215) (xy 372.705553 -393.208783) (xy 372.676883 -393.167537)
			(xy 372.654785 -393.122427) (xy 372.639768 -393.074493) (xy 372.632178 -393.024838) (xy 372.631716 -392.999722)
			(xy 372.092982 -392.999722) (xy 372.09245 -393.026824) (xy 372.083642 -393.080307) (xy 372.075456 -393.106148)
			(xy 372.071646 -393.11707) (xy 372.074186 -393.139422) (xy 372.126764 -393.225274) (xy 372.145814 -393.23772)
			(xy 372.15699 -393.239498) (xy 372.186303 -393.244237) (xy 372.243473 -393.260281) (xy 372.298087 -393.283586)
			(xy 372.349227 -393.313761) (xy 372.396034 -393.350298) (xy 372.43772 -393.392584) (xy 372.473585 -393.439908)
			(xy 372.503026 -393.491474) (xy 372.525548 -393.546416) (xy 372.540773 -393.60381) (xy 372.548445 -393.662691)
			(xy 372.548912 -393.69238) (xy 372.548386 -393.723443) (xy 372.539974 -393.784997) (xy 372.532148 -393.815062)
			(xy 372.529354 -393.825222) (xy 372.531894 -393.845034) (xy 372.579392 -393.92733) (xy 372.595394 -393.939522)
			(xy 372.605554 -393.942062) (xy 372.634664 -393.95006) (xy 372.69063 -393.972695) (xy 372.743136 -394.002489)
			(xy 372.791269 -394.038927) (xy 372.834195 -394.081376) (xy 372.871169 -394.129099) (xy 372.901549 -394.181268)
			(xy 372.924808 -394.236977) (xy 372.940542 -394.295261) (xy 372.948479 -394.355107) (xy 372.948962 -394.385292)
			(xy 372.948837 -394.399427) (xy 372.947055 -394.427641) (xy 372.945406 -394.44168) (xy 372.944639 -394.450287)
			(xy 372.948282 -394.467168) (xy 372.952518 -394.4747) (xy 372.968266 -394.5001) (xy 372.972984 -394.507154)
			(xy 372.986084 -394.517926) (xy 372.99392 -394.521182) (xy 373.017299 -394.530371) (xy 373.061195 -394.55479)
			(xy 373.100891 -394.58557) (xy 373.135472 -394.622003) (xy 373.164141 -394.663249) (xy 373.186239 -394.708358)
			(xy 373.201257 -394.756292) (xy 373.208849 -394.805946) (xy 373.209312 -394.831062) (xy 373.208885 -394.855264)
			(xy 373.201812 -394.903148) (xy 373.187826 -394.949488) (xy 373.167227 -394.99329) (xy 373.154194 -395.013688)
			(xy 373.149408 -395.021646) (xy 373.145372 -395.039756) (xy 373.14632 -395.048994) (xy 373.150638 -395.079982)
			(xy 373.152309 -395.089281) (xy 373.161597 -395.105722) (xy 373.168672 -395.111986) (xy 373.190762 -395.130666)
			(xy 373.230533 -395.172678) (xy 373.264695 -395.219367) (xy 373.292702 -395.269987) (xy 373.314109 -395.323732)
			(xy 373.328574 -395.379746) (xy 373.335867 -395.437136) (xy 373.336312 -395.466062) (xy 373.335725 -395.499384)
			(xy 373.326062 -395.565322) (xy 373.306934 -395.629161) (xy 373.293386 -395.65961) (xy 373.289135 -395.670074)
			(xy 373.289249 -395.692634) (xy 373.298985 -395.712986) (xy 373.307356 -395.72057) (xy 373.329577 -395.739274)
			(xy 373.369643 -395.781323) (xy 373.404068 -395.828103) (xy 373.432296 -395.878863) (xy 373.453876 -395.932787)
			(xy 373.46846 -395.989007) (xy 373.475813 -396.046621) (xy 373.476266 -396.075662) (xy 373.475784 -396.104667)
			(xy 373.468473 -396.162214) (xy 373.453952 -396.218376) (xy 373.432452 -396.272254) (xy 373.404319 -396.322984)
			(xy 373.370002 -396.369754) (xy 373.330053 -396.411815) (xy 373.307864 -396.4305) (xy 373.300752 -396.436088)
			(xy 373.291608 -396.451328) (xy 373.276368 -396.534132) (xy 373.279162 -396.551404) (xy 373.283734 -396.559532)
			(xy 373.296309 -396.582719) (xy 373.314183 -396.63234) (xy 373.323284 -396.684291) (xy 373.323866 -396.710662)
			(xy 373.323797 -396.720021) (xy 373.322654 -396.738703) (xy 373.32158 -396.748) (xy 373.320564 -396.75689)
			(xy 373.324374 -396.773654) (xy 373.368316 -396.843504) (xy 373.382032 -396.853918) (xy 373.390414 -396.856712)
			(xy 373.414514 -396.865184) (xy 373.459805 -396.888812) (xy 373.500699 -396.919425) (xy 373.53613 -396.956223)
			(xy 373.565173 -396.998248) (xy 373.587068 -397.0444) (xy 373.59463 -397.068802) (xy 373.596154 -397.074644)
			(xy 373.91594 -397.627602) (xy 373.920004 -397.63192) (xy 373.936196 -397.649638) (xy 373.963622 -397.689026)
			(xy 373.984767 -397.732113) (xy 373.999143 -397.777905) (xy 374.00642 -397.825346) (xy 374.006872 -397.849344)
			(xy 374.006447 -397.874149) (xy 373.998676 -397.923148) (xy 373.983333 -397.970326) (xy 373.960795 -398.014522)
			(xy 373.931618 -398.054646) (xy 373.896522 -398.08971) (xy 373.856371 -398.118849) (xy 373.812154 -398.141345)
			(xy 373.764961 -398.156644) (xy 373.715956 -398.16437) (xy 373.69115 -398.164812) (xy 373.665757 -398.164268)
			(xy 373.615626 -398.156145) (xy 373.567441 -398.1401) (xy 373.522447 -398.116549) (xy 373.481803 -398.086097)
			(xy 373.44656 -398.049532) (xy 373.417625 -398.007795) (xy 373.395745 -397.961965) (xy 373.388128 -397.937736)
			(xy 373.386604 -397.931894) (xy 373.066056 -397.377412) (xy 373.061992 -397.373094) (xy 373.045896 -397.355418)
			(xy 373.018645 -397.316142) (xy 372.997632 -397.273203) (xy 372.983338 -397.227586) (xy 372.976091 -397.180334)
			(xy 372.975632 -397.156432) (xy 372.975774 -397.14438) (xy 372.97768 -397.12035) (xy 372.979442 -397.108426)
			(xy 372.980712 -397.099536) (xy 372.977664 -397.082518) (xy 372.9355 -397.011652) (xy 372.922292 -397.000476)
			(xy 372.91391 -396.997428) (xy 372.892171 -396.989011) (xy 372.851311 -396.966575) (xy 372.814339 -396.938186)
			(xy 372.782115 -396.904504) (xy 372.755388 -396.866313) (xy 372.734781 -396.824501) (xy 372.720772 -396.780042)
			(xy 372.713688 -396.733969) (xy 372.71325 -396.710662) (xy 372.713822 -396.684289) (xy 372.722904 -396.632331)
			(xy 372.740789 -396.582711) (xy 372.753382 -396.559532) (xy 372.757954 -396.551404) (xy 372.760748 -396.534132)
			(xy 372.745508 -396.451328) (xy 372.736364 -396.436088) (xy 372.729252 -396.4305) (xy 372.707071 -396.411806)
			(xy 372.667127 -396.369741) (xy 372.632811 -396.32297) (xy 372.604675 -396.272242) (xy 372.583166 -396.218368)
			(xy 372.568631 -396.16221) (xy 372.5613 -396.104666) (xy 372.56085 -396.075662) (xy 372.561449 -396.042341)
			(xy 372.571108 -395.976403) (xy 372.59023 -395.912563) (xy 372.603776 -395.882114) (xy 372.608016 -395.871646)
			(xy 372.607911 -395.849087) (xy 372.598178 -395.828736) (xy 372.589806 -395.821154) (xy 372.56754 -395.802502)
			(xy 372.527478 -395.760443) (xy 372.493059 -395.713653) (xy 372.464836 -395.662884) (xy 372.443264 -395.608952)
			(xy 372.428688 -395.552725) (xy 372.421344 -395.495105) (xy 372.420896 -395.466062) (xy 372.421331 -395.437135)
			(xy 372.428616 -395.379741) (xy 372.443076 -395.323724) (xy 372.464482 -395.269975) (xy 372.492492 -395.219354)
			(xy 372.526659 -395.172667) (xy 372.566438 -395.130659) (xy 372.588536 -395.111986) (xy 372.595504 -395.105634)
			(xy 372.604765 -395.089234) (xy 372.60657 -395.079982) (xy 372.610888 -395.048994) (xy 372.611786 -395.039757)
			(xy 372.607765 -395.021658) (xy 372.603014 -395.013688) (xy 372.586707 -394.987842) (xy 372.562803 -394.931607)
			(xy 372.555516 -394.901928) (xy 372.553453 -394.893767) (xy 372.544755 -394.879366) (xy 372.538498 -394.873734)
			(xy 372.515384 -394.854684) (xy 372.508503 -394.849439) (xy 372.492273 -394.843473) (xy 372.483634 -394.843)
			(xy 372.453996 -394.842016) (xy 372.395331 -394.833364) (xy 372.338273 -394.81721) (xy 372.283779 -394.793824)
			(xy 372.23276 -394.763599) (xy 372.18607 -394.727039) (xy 372.144492 -394.684757) (xy 372.10872 -394.637462)
			(xy 372.079354 -394.585943) (xy 372.056885 -394.531065) (xy 372.041689 -394.473744) (xy 372.034021 -394.414942)
			(xy 372.033546 -394.385292) (xy 372.034067 -394.354229) (xy 372.042483 -394.292675) (xy 372.05031 -394.26261)
			(xy 372.053104 -394.25245) (xy 372.050564 -394.232638) (xy 372.003066 -394.150342) (xy 371.987064 -394.13815)
			(xy 371.976904 -394.13561) (xy 371.947779 -394.127665) (xy 371.891811 -394.105024) (xy 371.839306 -394.075222)
			(xy 371.791173 -394.038778) (xy 371.748248 -393.996323) (xy 371.711276 -393.948594) (xy 371.680898 -393.89642)
			(xy 371.657642 -393.840705) (xy 371.64191 -393.782417) (xy 371.633977 -393.722567) (xy 371.633496 -393.69238)
			(xy 371.634022 -393.661492) (xy 371.642327 -393.600277) (xy 371.658784 -393.540733) (xy 371.683094 -393.483941)
			(xy 371.69852 -393.457176) (xy 371.704362 -393.44727) (xy 371.706648 -393.424918) (xy 371.673374 -393.329668)
			(xy 371.657626 -393.313666) (xy 371.646958 -393.309602) (xy 371.623568 -393.300439) (xy 371.579672 -393.276015)
			(xy 371.539977 -393.24523) (xy 371.505398 -393.208794) (xy 371.476729 -393.167544) (xy 371.454633 -393.122432)
			(xy 371.439617 -393.074495) (xy 371.432028 -393.024839) (xy 371.431566 -392.999722) (xy 370.893086 -392.999722)
			(xy 370.892554 -393.026824) (xy 370.883746 -393.080307) (xy 370.87556 -393.106148) (xy 370.87175 -393.11707)
			(xy 370.87429 -393.139422) (xy 370.926868 -393.225274) (xy 370.945918 -393.23772) (xy 370.957094 -393.239498)
			(xy 370.986407 -393.244234) (xy 371.043578 -393.260278) (xy 371.098192 -393.283584) (xy 371.149332 -393.313759)
			(xy 371.196138 -393.350297) (xy 371.237824 -393.392583) (xy 371.273689 -393.439907) (xy 371.30313 -393.491474)
			(xy 371.325652 -393.546415) (xy 371.340877 -393.603809) (xy 371.348549 -393.66269) (xy 371.349016 -393.69238)
			(xy 371.34849 -393.723443) (xy 371.340078 -393.784996) (xy 371.332252 -393.815062) (xy 371.329458 -393.825222)
			(xy 371.331998 -393.845034) (xy 371.379496 -393.92733) (xy 371.395498 -393.939522) (xy 371.405658 -393.942062)
			(xy 371.434769 -393.950058) (xy 371.490735 -393.972693) (xy 371.54324 -394.002488) (xy 371.591374 -394.038926)
			(xy 371.6343 -394.081375) (xy 371.671273 -394.129098) (xy 371.701653 -394.181267) (xy 371.724912 -394.236977)
			(xy 371.740646 -394.295261) (xy 371.748583 -394.355107) (xy 371.749066 -394.385292) (xy 371.748941 -394.399427)
			(xy 371.747159 -394.427641) (xy 371.74551 -394.44168) (xy 371.744756 -394.450287) (xy 371.748392 -394.467166)
			(xy 371.752622 -394.4747) (xy 371.76837 -394.5001) (xy 371.773074 -394.507167) (xy 371.786177 -394.517944)
			(xy 371.794024 -394.521182) (xy 371.817371 -394.530413) (xy 371.861214 -394.554867) (xy 371.900859 -394.585666)
			(xy 371.935393 -394.622103) (xy 371.964025 -394.663339) (xy 371.986097 -394.708429) (xy 372.001101 -394.756336)
			(xy 372.008693 -394.805961) (xy 372.009162 -394.831062) (xy 372.008743 -394.855264) (xy 372.001669 -394.90315)
			(xy 371.987681 -394.949489) (xy 371.967078 -394.993291) (xy 371.954044 -395.013688) (xy 371.949254 -395.021644)
			(xy 371.945222 -395.039756) (xy 371.94617 -395.048994) (xy 371.950488 -395.079982) (xy 371.952174 -395.089277)
			(xy 371.961452 -395.105719) (xy 371.968522 -395.111986) (xy 371.990601 -395.130678) (xy 372.030375 -395.172687)
			(xy 372.064539 -395.219373) (xy 372.092548 -395.269991) (xy 372.113957 -395.323735) (xy 372.128423 -395.379748)
			(xy 372.135717 -395.437137) (xy 372.136162 -395.466062) (xy 372.13557 -395.499383) (xy 372.125908 -395.565322)
			(xy 372.106783 -395.629161) (xy 372.093236 -395.65961) (xy 372.088969 -395.67007) (xy 372.089082 -395.692636)
			(xy 372.098828 -395.712989) (xy 372.107206 -395.72057) (xy 372.129438 -395.739261) (xy 372.169501 -395.781314)
			(xy 372.203923 -395.828097) (xy 372.23215 -395.878859) (xy 372.253728 -395.932784) (xy 372.268311 -395.989006)
			(xy 372.275663 -396.046621) (xy 372.276116 -396.075662) (xy 372.275652 -396.104668) (xy 372.268341 -396.162216)
			(xy 372.253818 -396.218379) (xy 372.232316 -396.272258) (xy 372.204179 -396.322988) (xy 372.169859 -396.369757)
			(xy 372.129905 -396.411816) (xy 372.107714 -396.4305) (xy 372.100602 -396.436088) (xy 372.091458 -396.451328)
			(xy 372.076218 -396.534132) (xy 372.079012 -396.551404) (xy 372.083584 -396.559532) (xy 372.096155 -396.582721)
			(xy 372.114031 -396.632341) (xy 372.123134 -396.684292) (xy 372.123716 -396.710662) (xy 372.123647 -396.720021)
			(xy 372.122504 -396.738703) (xy 372.12143 -396.748) (xy 372.120414 -396.75689) (xy 372.124224 -396.773654)
			(xy 372.168166 -396.843504) (xy 372.181882 -396.853918) (xy 372.190264 -396.856712) (xy 372.214297 -396.865167)
			(xy 372.259469 -396.888723) (xy 372.300273 -396.919226) (xy 372.335651 -396.955883) (xy 372.364686 -396.997744)
			(xy 372.386623 -397.043724) (xy 372.394226 -397.06804) (xy 372.39575 -397.073882) (xy 372.716044 -397.627602)
			(xy 372.720108 -397.63192) (xy 372.736301 -397.649637) (xy 372.763727 -397.689026) (xy 372.784871 -397.732113)
			(xy 372.799247 -397.777905) (xy 372.806524 -397.825346) (xy 372.806976 -397.849344) (xy 372.806547 -397.874149)
			(xy 372.798776 -397.923147) (xy 372.783433 -397.970325) (xy 372.760896 -398.014521) (xy 372.73172 -398.054645)
			(xy 372.696624 -398.089708) (xy 372.656473 -398.118847) (xy 372.612257 -398.141344) (xy 372.565064 -398.156644)
			(xy 372.516059 -398.164369) (xy 372.491254 -398.164812) (xy 372.465858 -398.164352) (xy 372.415723 -398.156214)
			(xy 372.367536 -398.140156) (xy 372.322542 -398.116592) (xy 372.2819 -398.086129) (xy 372.246658 -398.049553)
			(xy 372.217725 -398.007807) (xy 372.195848 -397.961968) (xy 372.188232 -397.937736) (xy 372.186708 -397.931894)
			(xy 371.866414 -397.378174) (xy 371.86235 -397.373856) (xy 371.84619 -397.356123) (xy 371.818822 -397.31672)
			(xy 371.797732 -397.27363) (xy 371.783404 -397.227845) (xy 371.77617 -397.180419) (xy 371.775736 -397.156432)
			(xy 371.775817 -397.144384) (xy 371.777599 -397.120355) (xy 371.779292 -397.108426) (xy 371.780562 -397.099536)
			(xy 371.777514 -397.082518) (xy 371.73535 -397.011652) (xy 371.722142 -397.000476) (xy 371.71376 -396.997428)
			(xy 371.69201 -396.989038) (xy 371.651152 -396.966596) (xy 371.614182 -396.938202) (xy 371.581959 -396.904515)
			(xy 371.555234 -396.866321) (xy 371.534629 -396.824506) (xy 371.520621 -396.780045) (xy 371.513538 -396.73397)
			(xy 371.5131 -396.710662) (xy 371.513666 -396.684289) (xy 371.522749 -396.632331) (xy 371.540637 -396.58271)
			(xy 371.553232 -396.559532) (xy 371.557804 -396.551404) (xy 371.560598 -396.534132) (xy 371.545358 -396.451328)
			(xy 371.536214 -396.436088) (xy 371.529102 -396.4305) (xy 371.506932 -396.411793) (xy 371.466985 -396.369732)
			(xy 371.432667 -396.322964) (xy 371.404528 -396.272238) (xy 371.383018 -396.218366) (xy 371.368482 -396.162209)
			(xy 371.361151 -396.104666) (xy 371.3607 -396.075662) (xy 371.361295 -396.042341) (xy 371.370954 -395.976402)
			(xy 371.390079 -395.912563) (xy 371.403626 -395.882114) (xy 371.40785 -395.871641) (xy 371.407745 -395.849089)
			(xy 371.398021 -395.828739) (xy 371.389656 -395.821154) (xy 371.367401 -395.80249) (xy 371.327336 -395.760434)
			(xy 371.292914 -395.713647) (xy 371.26469 -395.66288) (xy 371.243116 -395.60895) (xy 371.228539 -395.552723)
			(xy 371.221194 -395.495105) (xy 371.220746 -395.466062) (xy 371.2212 -395.437136) (xy 371.228483 -395.379744)
			(xy 371.242942 -395.323727) (xy 371.264345 -395.269979) (xy 371.292352 -395.219358) (xy 371.326515 -395.17267)
			(xy 371.366291 -395.13066) (xy 371.388386 -395.111986) (xy 371.395362 -395.105643) (xy 371.404617 -395.089236)
			(xy 371.40642 -395.079982) (xy 371.410738 -395.048994) (xy 371.411643 -395.039757) (xy 371.407618 -395.021657)
			(xy 371.402864 -395.013688) (xy 371.386553 -394.987844) (xy 371.362652 -394.931607) (xy 371.355366 -394.901928)
			(xy 371.353316 -394.893763) (xy 371.344609 -394.879363) (xy 371.338348 -394.873734) (xy 371.315234 -394.854684)
			(xy 371.308398 -394.849487) (xy 371.29231 -394.843511) (xy 371.283738 -394.843) (xy 371.2541 -394.842013)
			(xy 371.195435 -394.833361) (xy 371.138378 -394.817207) (xy 371.083883 -394.793822) (xy 371.032864 -394.763597)
			(xy 370.986175 -394.727037) (xy 370.944596 -394.684756) (xy 370.908824 -394.637461) (xy 370.879458 -394.585943)
			(xy 370.856989 -394.531064) (xy 370.841793 -394.473744) (xy 370.834125 -394.414942) (xy 370.83365 -394.385292)
			(xy 370.834171 -394.354229) (xy 370.842587 -394.292675) (xy 370.850414 -394.26261) (xy 370.853208 -394.25245)
			(xy 370.850668 -394.232638) (xy 370.80317 -394.150342) (xy 370.787168 -394.13815) (xy 370.777008 -394.13561)
			(xy 370.765287 -394.132463) (xy 370.742161 -394.125093) (xy 370.73078 -394.120878) (xy 370.718334 -394.116306)
			(xy 370.692426 -394.120116) (xy 370.603018 -394.188696) (xy 370.592604 -394.212826) (xy 370.593874 -394.22578)
			(xy 370.595398 -394.25753) (xy 370.59501 -394.281206) (xy 370.588279 -394.328077) (xy 370.574915 -394.373503)
			(xy 370.565426 -394.395198) (xy 370.561108 -394.404596) (xy 370.560346 -394.424662) (xy 370.592604 -394.511022)
			(xy 370.60632 -394.525754) (xy 370.615718 -394.530072) (xy 370.640079 -394.541777) (xy 370.684951 -394.5719)
			(xy 370.72433 -394.608915) (xy 370.75717 -394.651838) (xy 370.782598 -394.699527) (xy 370.799937 -394.750715)
			(xy 370.808726 -394.80404) (xy 370.809266 -394.831062) (xy 370.808846 -394.855264) (xy 370.801772 -394.903149)
			(xy 370.787784 -394.949489) (xy 370.767182 -394.993291) (xy 370.754148 -395.013688) (xy 370.749358 -395.021644)
			(xy 370.745326 -395.039756) (xy 370.746274 -395.048994) (xy 370.750592 -395.079982) (xy 370.752276 -395.089277)
			(xy 370.761556 -395.105719) (xy 370.768626 -395.111986) (xy 370.790706 -395.130677) (xy 370.83048 -395.172687)
			(xy 370.864643 -395.219372) (xy 370.892652 -395.269991) (xy 370.914061 -395.323735) (xy 370.928527 -395.379747)
			(xy 370.935821 -395.437137) (xy 370.936266 -395.466062) (xy 370.935674 -395.499383) (xy 370.926012 -395.565322)
			(xy 370.906887 -395.629161) (xy 370.89334 -395.65961) (xy 370.889072 -395.67007) (xy 370.889185 -395.692636)
			(xy 370.898932 -395.712989) (xy 370.90731 -395.72057) (xy 370.929542 -395.73926) (xy 370.969606 -395.781313)
			(xy 371.004028 -395.828097) (xy 371.032254 -395.878859) (xy 371.053832 -395.932784) (xy 371.068415 -395.989006)
			(xy 371.075767 -396.046621) (xy 371.07622 -396.075662) (xy 371.075755 -396.104667) (xy 371.068443 -396.162216)
			(xy 371.05392 -396.218379) (xy 371.032418 -396.272257) (xy 371.004282 -396.322988) (xy 370.969962 -396.369757)
			(xy 370.930009 -396.411816) (xy 370.907818 -396.4305) (xy 370.900706 -396.436088) (xy 370.891562 -396.451328)
			(xy 370.876322 -396.534132) (xy 370.879116 -396.551404) (xy 370.883688 -396.559532) (xy 370.896259 -396.582721)
			(xy 370.914136 -396.632341) (xy 370.923238 -396.684292) (xy 370.92382 -396.710662) (xy 370.923751 -396.720021)
			(xy 370.922608 -396.738703) (xy 370.921534 -396.748) (xy 370.920518 -396.75689) (xy 370.924328 -396.773654)
			(xy 370.96827 -396.843504) (xy 370.981986 -396.853918) (xy 370.990368 -396.856712) (xy 371.014382 -396.865218)
			(xy 371.059556 -396.888761) (xy 371.100364 -396.919252) (xy 371.135746 -396.9559) (xy 371.164784 -396.997753)
			(xy 371.186726 -397.043726) (xy 371.19433 -397.06804) (xy 371.195854 -397.073882) (xy 371.516148 -397.627602)
			(xy 371.520212 -397.63192) (xy 371.536406 -397.649637) (xy 371.563831 -397.689025) (xy 371.584975 -397.732113)
			(xy 371.599352 -397.777905) (xy 371.606628 -397.825346) (xy 371.60708 -397.849344) (xy 371.606647 -397.874149)
			(xy 371.598876 -397.923146) (xy 371.583533 -397.970324) (xy 371.560996 -398.014519) (xy 371.531821 -398.054643)
			(xy 371.496725 -398.089707) (xy 371.456575 -398.118846) (xy 371.412359 -398.141343) (xy 371.365168 -398.156643)
			(xy 371.316163 -398.164369) (xy 371.291358 -398.164812) (xy 371.265962 -398.164348) (xy 371.215827 -398.156211)
			(xy 371.167641 -398.140154) (xy 371.122646 -398.11659) (xy 371.082004 -398.086127) (xy 371.046762 -398.049552)
			(xy 371.017829 -398.007806) (xy 370.995952 -397.961968) (xy 370.988336 -397.937736) (xy 370.986812 -397.931894)
			(xy 370.666518 -397.378174) (xy 370.662454 -397.373856) (xy 370.646295 -397.356122) (xy 370.618926 -397.31672)
			(xy 370.597836 -397.27363) (xy 370.583508 -397.227845) (xy 370.576274 -397.180419) (xy 370.57584 -397.156432)
			(xy 370.575921 -397.144384) (xy 370.577703 -397.120355) (xy 370.579396 -397.108426) (xy 370.580666 -397.099536)
			(xy 370.577618 -397.082518) (xy 370.535454 -397.011652) (xy 370.522246 -397.000476) (xy 370.513864 -396.997428)
			(xy 370.492115 -396.989036) (xy 370.451257 -396.966594) (xy 370.414286 -396.9382) (xy 370.382064 -396.904514)
			(xy 370.355339 -396.86632) (xy 370.334733 -396.824506) (xy 370.320725 -396.780044) (xy 370.313642 -396.73397)
			(xy 370.313204 -396.710662) (xy 370.313769 -396.684289) (xy 370.322852 -396.63233) (xy 370.340741 -396.58271)
			(xy 370.353336 -396.559532) (xy 370.357908 -396.551404) (xy 370.360702 -396.534132) (xy 370.345462 -396.451328)
			(xy 370.336318 -396.436088) (xy 370.329206 -396.4305) (xy 370.307037 -396.411792) (xy 370.267089 -396.369731)
			(xy 370.232771 -396.322964) (xy 370.204632 -396.272238) (xy 370.183122 -396.218366) (xy 370.168586 -396.162209)
			(xy 370.161255 -396.104666) (xy 370.160804 -396.075662) (xy 370.161407 -396.042341) (xy 370.171065 -395.976403)
			(xy 370.190186 -395.912564) (xy 370.20373 -395.882114) (xy 370.207953 -395.871641) (xy 370.207847 -395.849089)
			(xy 370.198124 -395.82874) (xy 370.18976 -395.821154) (xy 370.167505 -395.802489) (xy 370.12744 -395.760433)
			(xy 370.093019 -395.713646) (xy 370.064794 -395.66288) (xy 370.04322 -395.60895) (xy 370.028643 -395.552723)
			(xy 370.021298 -395.495105) (xy 370.02085 -395.466062) (xy 370.021302 -395.437136) (xy 370.028586 -395.379743)
			(xy 370.043045 -395.323727) (xy 370.064448 -395.269979) (xy 370.092455 -395.219358) (xy 370.126619 -395.17267)
			(xy 370.166394 -395.13066) (xy 370.18849 -395.111986) (xy 370.195467 -395.105643) (xy 370.204721 -395.089236)
			(xy 370.206524 -395.079982) (xy 370.210842 -395.048994) (xy 370.211747 -395.039757) (xy 370.207722 -395.021657)
			(xy 370.202968 -395.013688) (xy 370.189988 -394.993261) (xy 370.169404 -394.949461) (xy 370.155414 -394.903132)
			(xy 370.148318 -394.855259) (xy 370.14785 -394.831062) (xy 370.148231 -394.807386) (xy 370.154964 -394.760515)
			(xy 370.168331 -394.715088) (xy 370.177822 -394.693394) (xy 370.18214 -394.683996) (xy 370.182902 -394.66393)
			(xy 370.150644 -394.57757) (xy 370.136928 -394.562838) (xy 370.12753 -394.55852) (xy 370.103154 -394.546845)
			(xy 370.058284 -394.516715) (xy 370.018907 -394.479694) (xy 369.98607 -394.436766) (xy 369.960645 -394.389072)
			(xy 369.943308 -394.337881) (xy 369.934521 -394.284553) (xy 369.933982 -394.25753) (xy 368.446935 -394.25753)
			(xy 368.417517 -394.294288) (xy 368.395504 -394.31595) (xy 368.386868 -394.324332) (xy 368.37874 -394.346684)
			(xy 368.390678 -394.451078) (xy 368.403632 -394.47089) (xy 368.414046 -394.47724) (xy 368.439381 -394.492755)
			(xy 368.486235 -394.529279) (xy 368.527968 -394.57156) (xy 368.563877 -394.618887) (xy 368.593358 -394.670463)
			(xy 368.615916 -394.725421) (xy 368.631172 -394.782837) (xy 368.638867 -394.841744) (xy 368.639344 -394.871448)
			(xy 368.638873 -394.902107) (xy 368.630681 -394.962875) (xy 368.61445 -395.022006) (xy 368.590471 -395.078441)
			(xy 368.559173 -395.13117) (xy 368.521116 -395.179248) (xy 368.49939 -395.200886) (xy 368.491653 -395.209199)
			(xy 368.483656 -395.23042) (xy 368.485563 -395.253017) (xy 368.490754 -395.263116) (xy 368.504888 -395.288587)
			(xy 368.52496 -395.343265) (xy 368.535123 -395.400617) (xy 368.535712 -395.42974) (xy 368.535202 -395.455727)
			(xy 368.527072 -395.507062) (xy 368.511011 -395.556492) (xy 368.487415 -395.602802) (xy 368.456865 -395.64485)
			(xy 368.420114 -395.681601) (xy 368.378066 -395.712151) (xy 368.331756 -395.735747) (xy 368.282326 -395.751808)
			(xy 368.230991 -395.759938) (xy 368.179017 -395.759938) (xy 368.127682 -395.751808) (xy 368.078252 -395.735747)
			(xy 368.031942 -395.712151) (xy 367.989894 -395.681601) (xy 367.953143 -395.64485) (xy 367.922593 -395.602802)
			(xy 367.898997 -395.556492) (xy 367.882936 -395.507062) (xy 367.874806 -395.455727) (xy 367.874296 -395.42974)
			(xy 367.874717 -395.405227) (xy 367.881901 -395.35673) (xy 367.896177 -395.309829) (xy 367.9063 -395.2875)
			(xy 367.910678 -395.277033) (xy 367.910724 -395.25437) (xy 367.900996 -395.233902) (xy 367.892584 -395.226286)
			(xy 367.87037 -395.207613) (xy 367.83036 -395.165579) (xy 367.795987 -395.118822) (xy 367.767803 -395.068094)
			(xy 367.746261 -395.014208) (xy 367.731707 -394.958031) (xy 367.724374 -394.900464) (xy 367.723928 -394.871448)
			(xy 367.72442 -394.840568) (xy 367.732738 -394.779369) (xy 367.749215 -394.719847) (xy 367.773552 -394.663083)
			(xy 367.805306 -394.610111) (xy 367.843899 -394.561893) (xy 367.865914 -394.540232) (xy 367.87455 -394.53185)
			(xy 367.882678 -394.509498) (xy 367.87074 -394.405104) (xy 367.857786 -394.385292) (xy 367.847372 -394.378942)
			(xy 367.823982 -394.364729) (xy 367.780472 -394.331521) (xy 367.74124 -394.293355) (xy 367.706846 -394.250776)
			(xy 367.677783 -394.204395) (xy 367.665762 -394.179806) (xy 367.659666 -394.167106) (xy 367.636806 -394.151612)
			(xy 367.519966 -394.144246) (xy 367.495582 -394.156692) (xy 367.487962 -394.16863) (xy 367.472878 -394.191514)
			(xy 367.437187 -394.233106) (xy 367.395911 -394.269163) (xy 367.349899 -394.298941) (xy 367.300099 -394.321828)
			(xy 367.247537 -394.337352) (xy 367.193294 -394.345194) (xy 367.16589 -394.345668) (xy 367.138636 -394.345261)
			(xy 367.084684 -394.337503) (xy 367.032385 -394.322145) (xy 366.982804 -394.299501) (xy 366.93695 -394.270032)
			(xy 366.895757 -394.234336) (xy 366.860062 -394.193142) (xy 366.830594 -394.147287) (xy 366.807951 -394.097706)
			(xy 366.792595 -394.045406) (xy 366.784838 -393.991454) (xy 358.291976 -393.991454) (xy 358.299766 -393.99718)
			(xy 358.325855 -394.01485) (xy 358.373881 -394.055641) (xy 358.416505 -394.102049) (xy 358.453073 -394.153364)
			(xy 358.483028 -394.208801) (xy 358.505909 -394.267511) (xy 358.521368 -394.328597) (xy 358.529167 -394.391124)
			(xy 358.529636 -394.42263) (xy 358.52917 -394.45336) (xy 358.521759 -394.514373) (xy 358.507048 -394.574047)
			(xy 358.486736 -394.6276) (xy 362.130076 -394.6276) (xy 362.13409 -394.563802) (xy 362.146068 -394.501011)
			(xy 362.165822 -394.440216) (xy 362.19304 -394.382375) (xy 362.227292 -394.328403) (xy 362.268038 -394.279149)
			(xy 362.314637 -394.23539) (xy 362.366353 -394.197817) (xy 362.42237 -394.167021) (xy 362.481805 -394.143489)
			(xy 362.54372 -394.127592) (xy 362.60714 -394.119581) (xy 362.639102 -394.1191) (xy 362.669798 -394.119591)
			(xy 362.730742 -394.126989) (xy 362.79035 -394.141677) (xy 362.847755 -394.163441) (xy 362.902118 -394.191964)
			(xy 362.927646 -394.209016) (xy 362.936398 -394.214487) (xy 362.956602 -394.218615) (xy 362.976806 -394.214487)
			(xy 362.985558 -394.209016) (xy 363.011082 -394.19196) (xy 363.065454 -394.163454) (xy 363.12286 -394.141695)
			(xy 363.182466 -394.126998) (xy 363.243407 -394.119579) (xy 363.274102 -394.1191) (xy 363.306063 -394.119586)
			(xy 363.369482 -394.127598) (xy 363.431397 -394.143495) (xy 363.490831 -394.167027) (xy 363.546847 -394.197822)
			(xy 363.598561 -394.235395) (xy 363.645159 -394.279154) (xy 363.685905 -394.328407) (xy 363.720157 -394.382379)
			(xy 363.747374 -394.440218) (xy 363.767127 -394.501013) (xy 363.779105 -394.563803) (xy 363.783119 -394.6276)
			(xy 363.779105 -394.691397) (xy 363.767127 -394.754187) (xy 363.747374 -394.814982) (xy 363.720157 -394.872821)
			(xy 363.685905 -394.926793) (xy 363.645159 -394.976046) (xy 363.598561 -395.019805) (xy 363.546847 -395.057378)
			(xy 363.490831 -395.088173) (xy 363.431397 -395.111705) (xy 363.369482 -395.127602) (xy 363.306063 -395.135614)
			(xy 363.274102 -395.136116) (xy 363.243405 -395.135671) (xy 363.182459 -395.128261) (xy 363.12285 -395.113562)
			(xy 363.065447 -395.091788) (xy 363.011085 -395.063256) (xy 362.985558 -395.0462) (xy 362.976806 -395.040729)
			(xy 362.956602 -395.036601) (xy 362.936398 -395.040729) (xy 362.927646 -395.0462) (xy 362.902122 -395.063257)
			(xy 362.84775 -395.091762) (xy 362.790344 -395.113521) (xy 362.730738 -395.128217) (xy 362.669797 -395.135637)
			(xy 362.639102 -395.136116) (xy 362.60714 -395.135619) (xy 362.54372 -395.127608) (xy 362.481805 -395.111711)
			(xy 362.42237 -395.088179) (xy 362.366353 -395.057383) (xy 362.314637 -395.01981) (xy 362.268038 -394.976051)
			(xy 362.227292 -394.926797) (xy 362.19304 -394.872825) (xy 362.165822 -394.814984) (xy 362.146068 -394.754189)
			(xy 362.13409 -394.691398) (xy 362.130076 -394.6276) (xy 358.486736 -394.6276) (xy 358.485252 -394.631513)
			(xy 358.456688 -394.685934) (xy 358.421773 -394.736515) (xy 358.381017 -394.782518) (xy 358.335013 -394.823275)
			(xy 358.284432 -394.858189) (xy 358.230012 -394.886752) (xy 358.172545 -394.908548) (xy 358.112871 -394.923259)
			(xy 358.051858 -394.93067) (xy 358.021128 -394.931138) (xy 357.979218 -394.92936) (xy 357.968296 -394.928598)
			(xy 357.948484 -394.935202) (xy 357.885492 -394.993368) (xy 357.878113 -395.000889) (xy 357.869702 -395.020181)
			(xy 357.869236 -395.030706) (xy 357.869236 -395.170152) (xy 357.868775 -395.194742) (xy 357.861072 -395.243314)
			(xy 357.845864 -395.290083) (xy 357.823525 -395.333897) (xy 357.794606 -395.373675) (xy 357.777542 -395.391386)
			(xy 357.702866 -395.466062) (xy 358.41127 -395.466062) (xy 358.415341 -395.41044) (xy 358.427467 -395.356003)
			(xy 358.44739 -395.303912) (xy 358.474686 -395.255277) (xy 358.508772 -395.211134) (xy 358.548921 -395.172425)
			(xy 358.594279 -395.139974) (xy 358.643879 -395.114473) (xy 358.696663 -395.096466) (xy 358.751506 -395.086336)
			(xy 358.80724 -395.084299) (xy 358.862677 -395.090399) (xy 358.916634 -395.104505) (xy 358.967963 -395.126317)
			(xy 359.015569 -395.155371) (xy 359.058437 -395.191046) (xy 359.095654 -395.232583) (xy 359.126427 -395.279096)
			(xy 359.150099 -395.329593) (xy 359.166167 -395.383) (xy 359.174287 -395.438176) (xy 359.174796 -395.466062)
			(xy 359.174287 -395.493948) (xy 359.166167 -395.549124) (xy 359.150099 -395.602531) (xy 359.126427 -395.653028)
			(xy 359.095654 -395.699541) (xy 359.058437 -395.741078) (xy 359.015569 -395.776753) (xy 358.967963 -395.805807)
			(xy 358.916634 -395.827619) (xy 358.862677 -395.841725) (xy 358.80724 -395.847825) (xy 358.751506 -395.845788)
			(xy 358.696663 -395.835658) (xy 358.643879 -395.817651) (xy 358.594279 -395.79215) (xy 358.548921 -395.759699)
			(xy 358.508772 -395.72099) (xy 358.474686 -395.676847) (xy 358.44739 -395.628212) (xy 358.427467 -395.576121)
			(xy 358.415341 -395.521684) (xy 358.41127 -395.466062) (xy 357.702866 -395.466062) (xy 357.525066 -395.643862)
			(xy 357.518258 -395.651207) (xy 357.510537 -395.669671) (xy 357.51008 -395.679676) (xy 357.51008 -396.1765)
			(xy 360.484672 -396.1765) (xy 360.488743 -396.120878) (xy 360.500869 -396.066441) (xy 360.520792 -396.01435)
			(xy 360.548088 -395.965715) (xy 360.582174 -395.921572) (xy 360.622323 -395.882863) (xy 360.667681 -395.850412)
			(xy 360.717281 -395.824911) (xy 360.770065 -395.806904) (xy 360.824908 -395.796774) (xy 360.880642 -395.794737)
			(xy 360.936079 -395.800837) (xy 360.990036 -395.814943) (xy 361.041365 -395.836755) (xy 361.088971 -395.865809)
			(xy 361.131839 -395.901484) (xy 361.169056 -395.943021) (xy 361.199829 -395.989534) (xy 361.223501 -396.040031)
			(xy 361.239569 -396.093438) (xy 361.247689 -396.148614) (xy 361.24811 -396.171674) (xy 363.874304 -396.171674)
			(xy 363.87487 -396.136718) (xy 363.884435 -396.067464) (xy 363.903396 -396.000173) (xy 363.931395 -395.936113)
			(xy 363.967903 -395.876491) (xy 363.98962 -395.849094) (xy 363.994919 -395.842097) (xy 364.000893 -395.825604)
			(xy 364.001304 -395.816836) (xy 364.001304 -395.662912) (xy 364.000937 -395.654135) (xy 363.994955 -395.637633)
			(xy 363.98962 -395.630654) (xy 363.967935 -395.603234) (xy 363.931432 -395.543614) (xy 363.903434 -395.479559)
			(xy 363.884467 -395.412275) (xy 363.874888 -395.343027) (xy 363.874304 -395.308074) (xy 363.874732 -395.277342)
			(xy 363.882143 -395.216326) (xy 363.896855 -395.156649) (xy 363.918653 -395.09918) (xy 363.94722 -395.044758)
			(xy 363.982137 -394.994175) (xy 364.022897 -394.94817) (xy 364.068905 -394.907414) (xy 364.11949 -394.8725)
			(xy 364.173915 -394.843938) (xy 364.231385 -394.822144) (xy 364.291064 -394.807436) (xy 364.35208 -394.800029)
			(xy 364.382812 -394.799566) (xy 364.408585 -394.799879) (xy 364.459866 -394.805098) (xy 364.485174 -394.80998)
			(xy 364.495588 -394.812012) (xy 364.515654 -394.807948) (xy 364.593378 -394.754354) (xy 364.6043 -394.736828)
			(xy 364.606078 -394.726414) (xy 364.610754 -394.699854) (xy 364.626628 -394.648315) (xy 364.649605 -394.599526)
			(xy 364.679226 -394.554461) (xy 364.714901 -394.514018) (xy 364.755917 -394.479004) (xy 364.801458 -394.450119)
			(xy 364.850613 -394.427937) (xy 364.902404 -394.412901) (xy 364.955796 -394.405312) (xy 364.98276 -394.40485)
			(xy 365.010008 -394.405415) (xy 365.063951 -394.413165) (xy 365.116242 -394.428513) (xy 365.165816 -394.451147)
			(xy 365.211664 -394.480605) (xy 365.252854 -394.516288) (xy 365.288546 -394.55747) (xy 365.318014 -394.603312)
			(xy 365.340658 -394.652881) (xy 365.356017 -394.705169) (xy 365.363779 -394.75911) (xy 365.364268 -394.786358)
			(xy 365.363778 -394.813289) (xy 365.35622 -394.866619) (xy 365.341236 -394.918355) (xy 365.319122 -394.967468)
			(xy 365.290319 -395.012982) (xy 365.255399 -395.053991) (xy 365.215057 -395.08968) (xy 365.170096 -395.119339)
			(xy 365.12141 -395.142378) (xy 365.069967 -395.158338) (xy 365.01679 -395.166903) (xy 364.989872 -395.167866)
			(xy 364.979204 -395.16812) (xy 364.960408 -395.176502) (xy 364.8964 -395.245844) (xy 364.889542 -395.265402)
			(xy 364.890304 -395.275816) (xy 364.89132 -395.308074) (xy 364.890719 -395.343029) (xy 364.881161 -395.412281)
			(xy 364.862209 -395.479571) (xy 364.834218 -395.543632) (xy 364.797717 -395.603255) (xy 364.776004 -395.630654)
			(xy 364.770717 -395.637659) (xy 364.764738 -395.654146) (xy 364.76432 -395.662912) (xy 364.76432 -395.816836)
			(xy 364.76468 -395.825613) (xy 364.770668 -395.842115) (xy 364.776004 -395.849094) (xy 364.797715 -395.876495)
			(xy 364.834213 -395.93612) (xy 364.862206 -396.00018) (xy 364.881167 -396.067469) (xy 364.890739 -396.136719)
			(xy 364.89132 -396.171674) (xy 364.890871 -396.202891) (xy 364.883254 -396.26486) (xy 364.868109 -396.32543)
			(xy 364.845662 -396.383689) (xy 364.831376 -396.41145) (xy 364.826804 -396.419578) (xy 364.824518 -396.437612)
			(xy 364.843568 -396.520924) (xy 364.853474 -396.53591) (xy 364.861094 -396.541498) (xy 364.88164 -396.556926)
			(xy 364.918772 -396.592439) (xy 364.950802 -396.632614) (xy 364.977151 -396.676724) (xy 364.978412 -396.679674)
			(xy 366.90884 -396.679674) (xy 366.912911 -396.624052) (xy 366.925037 -396.569615) (xy 366.94496 -396.517524)
			(xy 366.972256 -396.468889) (xy 367.006342 -396.424746) (xy 367.046491 -396.386037) (xy 367.091849 -396.353586)
			(xy 367.141449 -396.328085) (xy 367.194233 -396.310078) (xy 367.249076 -396.299948) (xy 367.30481 -396.297911)
			(xy 367.360247 -396.304011) (xy 367.414204 -396.318117) (xy 367.465533 -396.339929) (xy 367.513139 -396.368983)
			(xy 367.556007 -396.404658) (xy 367.593224 -396.446195) (xy 367.623997 -396.492708) (xy 367.647669 -396.543205)
			(xy 367.663737 -396.596612) (xy 367.671857 -396.651788) (xy 367.672366 -396.679674) (xy 367.671919 -396.704137)
			(xy 367.874806 -396.704137) (xy 367.874806 -396.652163) (xy 367.882936 -396.600828) (xy 367.898997 -396.551398)
			(xy 367.922593 -396.505088) (xy 367.953143 -396.46304) (xy 367.989894 -396.426289) (xy 368.031942 -396.395739)
			(xy 368.078252 -396.372143) (xy 368.127682 -396.356082) (xy 368.179017 -396.347952) (xy 368.230991 -396.347952)
			(xy 368.282326 -396.356082) (xy 368.331756 -396.372143) (xy 368.378066 -396.395739) (xy 368.420114 -396.426289)
			(xy 368.456865 -396.46304) (xy 368.487415 -396.505088) (xy 368.511011 -396.551398) (xy 368.527072 -396.600828)
			(xy 368.535202 -396.652163) (xy 368.535712 -396.67815) (xy 368.535202 -396.704137) (xy 368.527072 -396.755472)
			(xy 368.511011 -396.804902) (xy 368.487415 -396.851212) (xy 368.456865 -396.89326) (xy 368.420114 -396.930011)
			(xy 368.378066 -396.960561) (xy 368.331756 -396.984157) (xy 368.282326 -397.000218) (xy 368.230991 -397.008348)
			(xy 368.179017 -397.008348) (xy 368.127682 -397.000218) (xy 368.078252 -396.984157) (xy 368.031942 -396.960561)
			(xy 367.989894 -396.930011) (xy 367.953143 -396.89326) (xy 367.922593 -396.851212) (xy 367.898997 -396.804902)
			(xy 367.882936 -396.755472) (xy 367.874806 -396.704137) (xy 367.671919 -396.704137) (xy 367.671857 -396.70756)
			(xy 367.663737 -396.762736) (xy 367.647669 -396.816143) (xy 367.623997 -396.86664) (xy 367.593224 -396.913153)
			(xy 367.556007 -396.95469) (xy 367.513139 -396.990365) (xy 367.465533 -397.019419) (xy 367.414204 -397.041231)
			(xy 367.360247 -397.055337) (xy 367.30481 -397.061437) (xy 367.249076 -397.0594) (xy 367.194233 -397.04927)
			(xy 367.141449 -397.031263) (xy 367.091849 -397.005762) (xy 367.046491 -396.973311) (xy 367.006342 -396.934602)
			(xy 366.972256 -396.890459) (xy 366.94496 -396.841824) (xy 366.925037 -396.789733) (xy 366.912911 -396.735296)
			(xy 366.90884 -396.679674) (xy 364.978412 -396.679674) (xy 364.99734 -396.723972) (xy 365.011006 -396.773502)
			(xy 365.017901 -396.824418) (xy 365.01832 -396.850108) (xy 365.017878 -396.877479) (xy 365.010057 -396.93166)
			(xy 364.994564 -396.984164) (xy 364.971716 -397.033911) (xy 364.941985 -397.079876) (xy 364.92434 -397.100806)
			(xy 364.918244 -397.107918) (xy 364.911894 -397.124936) (xy 364.911894 -397.21028) (xy 364.918244 -397.227298)
			(xy 364.92434 -397.23441) (xy 364.942004 -397.255322) (xy 364.971711 -397.301301) (xy 364.994541 -397.351054)
			(xy 365.010027 -397.403558) (xy 365.017849 -397.457738) (xy 365.01832 -397.485108) (xy 365.017834 -397.512359)
			(xy 365.010078 -397.566307) (xy 364.994723 -397.618602) (xy 364.972081 -397.668179) (xy 364.942615 -397.714029)
			(xy 364.906924 -397.75522) (xy 364.865733 -397.790911) (xy 364.819883 -397.820377) (xy 364.770306 -397.843019)
			(xy 364.718011 -397.858374) (xy 364.664063 -397.86613) (xy 364.609561 -397.86613) (xy 364.555613 -397.858374)
			(xy 364.503318 -397.843019) (xy 364.453741 -397.820377) (xy 364.407891 -397.790911) (xy 364.3667 -397.75522)
			(xy 364.331009 -397.714029) (xy 364.301543 -397.668179) (xy 364.278901 -397.618602) (xy 364.263546 -397.566307)
			(xy 364.25579 -397.512359) (xy 364.255304 -397.485108) (xy 364.255774 -397.457738) (xy 364.263591 -397.403559)
			(xy 364.279079 -397.351056) (xy 364.30192 -397.301309) (xy 364.331643 -397.255342) (xy 364.349284 -397.23441)
			(xy 364.35538 -397.227298) (xy 364.36173 -397.21028) (xy 364.36173 -397.124936) (xy 364.35538 -397.107918)
			(xy 364.349284 -397.100806) (xy 364.331632 -397.079885) (xy 364.301922 -397.033909) (xy 364.279089 -396.984158)
			(xy 364.263601 -396.931655) (xy 364.255776 -396.877478) (xy 364.255304 -396.850108) (xy 364.255591 -396.828584)
			(xy 364.260428 -396.785809) (xy 364.264956 -396.764764) (xy 364.266988 -396.75562) (xy 364.264702 -396.737586)
			(xy 364.224316 -396.662148) (xy 364.210854 -396.65021) (xy 364.201964 -396.646908) (xy 364.17344 -396.635542)
			(xy 364.119094 -396.60696) (xy 364.068587 -396.57204) (xy 364.022654 -396.531291) (xy 363.981963 -396.485307)
			(xy 363.947108 -396.434755) (xy 363.918594 -396.380374) (xy 363.896839 -396.322954) (xy 363.882158 -396.263332)
			(xy 363.874765 -396.202376) (xy 363.874304 -396.171674) (xy 361.24811 -396.171674) (xy 361.248198 -396.1765)
			(xy 361.247689 -396.204386) (xy 361.239569 -396.259562) (xy 361.223501 -396.312969) (xy 361.199829 -396.363466)
			(xy 361.169056 -396.409979) (xy 361.131839 -396.451516) (xy 361.088971 -396.487191) (xy 361.041365 -396.516245)
			(xy 360.990036 -396.538057) (xy 360.936079 -396.552163) (xy 360.880642 -396.558263) (xy 360.824908 -396.556226)
			(xy 360.770065 -396.546096) (xy 360.717281 -396.528089) (xy 360.667681 -396.502588) (xy 360.622323 -396.470137)
			(xy 360.582174 -396.431428) (xy 360.548088 -396.387285) (xy 360.520792 -396.33865) (xy 360.500869 -396.286559)
			(xy 360.488743 -396.232122) (xy 360.484672 -396.1765) (xy 357.51008 -396.1765) (xy 357.51008 -396.93723)
			(xy 357.510699 -396.948655) (xy 357.520578 -396.969257) (xy 357.52913 -396.976854) (xy 357.541068 -396.987014)
			(xy 357.54818 -396.99311) (xy 357.565198 -396.99946) (xy 357.650542 -396.99946) (xy 357.66756 -396.99311)
			(xy 357.674672 -396.987014) (xy 357.695605 -396.969373) (xy 357.741573 -396.939649) (xy 357.791319 -396.916803)
			(xy 357.843821 -396.901307) (xy 357.897999 -396.893478) (xy 357.952741 -396.893478) (xy 358.006919 -396.901307)
			(xy 358.059421 -396.916803) (xy 358.109167 -396.939649) (xy 358.155135 -396.969373) (xy 358.176068 -396.987014)
			(xy 358.18318 -396.99311) (xy 358.200198 -396.99946) (xy 358.285542 -396.99946) (xy 358.30256 -396.99311)
			(xy 358.309672 -396.987014) (xy 358.330603 -396.96937) (xy 358.376568 -396.939639) (xy 358.426314 -396.916792)
			(xy 358.478818 -396.901297) (xy 358.532999 -396.893474) (xy 358.56037 -396.893034) (xy 358.587621 -396.893495)
			(xy 358.641569 -396.901248) (xy 358.693865 -396.9166) (xy 358.743444 -396.939238) (xy 358.789295 -396.968702)
			(xy 358.830487 -397.004392) (xy 358.86618 -397.04558) (xy 358.895648 -397.09143) (xy 358.91829 -397.141007)
			(xy 358.933646 -397.193301) (xy 358.941403 -397.247249) (xy 358.941403 -397.301751) (xy 358.933646 -397.355699)
			(xy 358.91829 -397.407993) (xy 358.895648 -397.45757) (xy 358.86618 -397.50342) (xy 358.830487 -397.544608)
			(xy 358.789295 -397.580298) (xy 358.743444 -397.609762) (xy 358.693865 -397.6324) (xy 358.641569 -397.647752)
			(xy 358.587621 -397.655505) (xy 358.56037 -397.65605) (xy 358.533001 -397.655576) (xy 358.478826 -397.647748)
			(xy 358.426326 -397.632256) (xy 358.376579 -397.609418) (xy 358.330608 -397.579705) (xy 358.309672 -397.56207)
			(xy 358.30256 -397.555974) (xy 358.285542 -397.549624) (xy 358.200198 -397.549624) (xy 358.18318 -397.555974)
			(xy 358.176068 -397.56207) (xy 358.155135 -397.579711) (xy 358.109167 -397.609435) (xy 358.059421 -397.632281)
			(xy 358.006919 -397.647777) (xy 357.952741 -397.655606) (xy 357.897999 -397.655606) (xy 357.843821 -397.647777)
			(xy 357.791319 -397.632281) (xy 357.741573 -397.609435) (xy 357.695605 -397.579711) (xy 357.674672 -397.56207)
			(xy 357.66756 -397.555974) (xy 357.650542 -397.549624) (xy 357.565198 -397.549624) (xy 357.54818 -397.555974)
			(xy 357.541068 -397.56207) (xy 357.52913 -397.57223) (xy 357.520624 -397.579865) (xy 357.510749 -397.600442)
			(xy 357.51008 -397.611854) (xy 357.51008 -397.684498) (xy 357.510502 -397.694569) (xy 357.518214 -397.713176)
			(xy 357.525066 -397.720566) (xy 358.125014 -398.320514) (xy 358.131868 -398.327909) (xy 358.13961 -398.346508)
			(xy 358.14 -398.356582) (xy 358.14 -402.081195) (xy 359.374942 -402.081195) (xy 359.374942 -402.017273)
			(xy 359.382953 -401.953855) (xy 359.39885 -401.891941) (xy 359.422382 -401.832508) (xy 359.453176 -401.776493)
			(xy 359.490749 -401.724778) (xy 359.534506 -401.678181) (xy 359.583759 -401.637436) (xy 359.63773 -401.603185)
			(xy 359.695569 -401.575968) (xy 359.756362 -401.556215) (xy 359.819152 -401.544237) (xy 359.882948 -401.540224)
			(xy 359.946744 -401.544237) (xy 360.009534 -401.556215) (xy 360.070327 -401.575968) (xy 360.128166 -401.603185)
			(xy 360.182137 -401.637436) (xy 360.23139 -401.678181) (xy 360.275147 -401.724778) (xy 360.31272 -401.776493)
			(xy 360.343514 -401.832508) (xy 360.367046 -401.891941) (xy 360.369868 -401.90293) (xy 361.068366 -401.90293)
			(xy 361.068829 -401.872233) (xy 361.076234 -401.811288) (xy 361.090929 -401.75168) (xy 361.1127 -401.694276)
			(xy 361.141228 -401.639913) (xy 361.158282 -401.614386) (xy 361.16373 -401.605621) (xy 361.167869 -401.585425)
			(xy 361.16375 -401.565225) (xy 361.158282 -401.556474) (xy 361.141247 -401.530936) (xy 361.112736 -401.476569)
			(xy 361.090972 -401.419167) (xy 361.076271 -401.359563) (xy 361.068847 -401.298624) (xy 361.068366 -401.26793)
			(xy 361.068829 -401.237233) (xy 361.076234 -401.176288) (xy 361.090929 -401.11668) (xy 361.1127 -401.059276)
			(xy 361.141228 -401.004913) (xy 361.158282 -400.979386) (xy 361.16373 -400.970621) (xy 361.167869 -400.950425)
			(xy 361.16375 -400.930225) (xy 361.158282 -400.921474) (xy 361.141247 -400.895936) (xy 361.112736 -400.841569)
			(xy 361.090972 -400.784167) (xy 361.076271 -400.724563) (xy 361.068847 -400.663624) (xy 361.068366 -400.63293)
			(xy 361.068829 -400.602233) (xy 361.076234 -400.541288) (xy 361.090929 -400.48168) (xy 361.1127 -400.424276)
			(xy 361.141228 -400.369913) (xy 361.158282 -400.344386) (xy 361.16373 -400.335621) (xy 361.167869 -400.315425)
			(xy 361.16375 -400.295225) (xy 361.158282 -400.286474) (xy 361.141247 -400.260936) (xy 361.112736 -400.206569)
			(xy 361.090972 -400.149167) (xy 361.076271 -400.089563) (xy 361.068847 -400.028624) (xy 361.068366 -399.99793)
			(xy 361.06881 -399.966878) (xy 361.076392 -399.905238) (xy 361.091422 -399.844979) (xy 361.113677 -399.786999)
			(xy 361.142825 -399.732159) (xy 361.178433 -399.681277) (xy 361.219972 -399.635108) (xy 361.266822 -399.59434)
			(xy 361.318288 -399.55958) (xy 361.345734 -399.545048) (xy 361.353906 -399.540356) (xy 361.36641 -399.526279)
			(xy 361.370118 -399.517616) (xy 361.38104 -399.488914) (xy 361.383963 -399.47999) (xy 361.383818 -399.461226)
			(xy 361.380786 -399.452338) (xy 361.36953 -399.422471) (xy 361.353707 -399.360635) (xy 361.345727 -399.297308)
			(xy 361.345226 -399.265394) (xy 361.345711 -399.234698) (xy 361.35311 -399.173753) (xy 361.367799 -399.114145)
			(xy 361.389564 -399.05674) (xy 361.418089 -399.002378) (xy 361.435142 -398.97685) (xy 361.440616 -398.9681)
			(xy 361.444739 -398.947895) (xy 361.440612 -398.927691) (xy 361.435142 -398.918938) (xy 361.418087 -398.893413)
			(xy 361.38958 -398.839042) (xy 361.367821 -398.781636) (xy 361.353124 -398.72203) (xy 361.345704 -398.661089)
			(xy 361.345226 -398.630394) (xy 361.345733 -398.599314) (xy 361.35331 -398.537617) (xy 361.368351 -398.477304)
			(xy 361.390632 -398.419274) (xy 361.41982 -398.364392) (xy 361.45548 -398.313478) (xy 361.49708 -398.267289)
			(xy 361.543999 -398.226516) (xy 361.569508 -398.208754) (xy 361.576789 -398.203375) (xy 361.587333 -398.188676)
			(xy 361.590082 -398.180052) (xy 361.59821 -398.150842) (xy 361.600158 -398.142188) (xy 361.598741 -398.124521)
			(xy 361.595416 -398.116298) (xy 361.584547 -398.091352) (xy 361.569261 -398.03913) (xy 361.561564 -397.985263)
			(xy 361.561126 -397.958056) (xy 361.561619 -397.930687) (xy 361.569429 -397.876508) (xy 361.584912 -397.824005)
			(xy 361.607748 -397.774258) (xy 361.637467 -397.72829) (xy 361.655106 -397.707358) (xy 361.661202 -397.700246)
			(xy 361.667552 -397.683228) (xy 361.667552 -397.597884) (xy 361.661202 -397.580866) (xy 361.655106 -397.573754)
			(xy 361.63748 -397.552812) (xy 361.607766 -397.506842) (xy 361.584927 -397.457097) (xy 361.569433 -397.404598)
			(xy 361.561602 -397.350424) (xy 361.561126 -397.323056) (xy 361.561537 -397.295802) (xy 361.5693 -397.24185)
			(xy 361.584663 -397.189552) (xy 361.607312 -397.139972) (xy 361.636786 -397.09412) (xy 361.672485 -397.05293)
			(xy 361.713683 -397.017239) (xy 361.759541 -396.987774) (xy 361.809125 -396.965136) (xy 361.861426 -396.949784)
			(xy 361.91538 -396.942031) (xy 361.942634 -396.941548) (xy 361.969394 -396.941998) (xy 362.02239 -396.949466)
			(xy 362.073823 -396.964265) (xy 362.122684 -396.986104) (xy 362.168014 -397.014556) (xy 362.18876 -397.031464)
			(xy 362.197904 -397.039338) (xy 362.221018 -397.044926) (xy 362.323634 -397.021812) (xy 362.341922 -397.006826)
			(xy 362.347002 -396.995904) (xy 362.358671 -396.971183) (xy 362.388071 -396.925097) (xy 362.423751 -396.88368)
			(xy 362.464978 -396.847782) (xy 362.510908 -396.818138) (xy 362.5606 -396.795356) (xy 362.613036 -396.779902)
			(xy 362.667141 -396.772093) (xy 362.694474 -396.771622) (xy 362.721844 -396.772098) (xy 362.776023 -396.779913)
			(xy 362.828526 -396.795399) (xy 362.878273 -396.818239) (xy 362.92424 -396.847962) (xy 362.945172 -396.865602)
			(xy 362.952284 -396.871698) (xy 362.969302 -396.878048) (xy 363.054646 -396.878048) (xy 363.071664 -396.871698)
			(xy 363.078776 -396.865602) (xy 363.099707 -396.847961) (xy 363.14568 -396.818249) (xy 363.195428 -396.795414)
			(xy 363.247929 -396.779923) (xy 363.302105 -396.772096) (xy 363.329474 -396.771622) (xy 363.35673 -396.772023)
			(xy 363.410688 -396.779778) (xy 363.462993 -396.795133) (xy 363.512581 -396.817776) (xy 363.558441 -396.847245)
			(xy 363.59964 -396.882942) (xy 363.635339 -396.924138) (xy 363.664812 -396.969996) (xy 363.687458 -397.019582)
			(xy 363.702817 -397.071886) (xy 363.710575 -397.125844) (xy 363.710575 -397.180356) (xy 363.702817 -397.234314)
			(xy 363.687458 -397.286618) (xy 363.664812 -397.336204) (xy 363.635339 -397.382062) (xy 363.59964 -397.423258)
			(xy 363.558441 -397.458955) (xy 363.512581 -397.488424) (xy 363.462993 -397.511067) (xy 363.410688 -397.526422)
			(xy 363.35673 -397.534177) (xy 363.329474 -397.534638) (xy 363.302102 -397.534202) (xy 363.247922 -397.526379)
			(xy 363.195417 -397.510884) (xy 363.145671 -397.488035) (xy 363.099706 -397.458303) (xy 363.078776 -397.440658)
			(xy 363.071664 -397.434562) (xy 363.054646 -397.428212) (xy 362.969302 -397.428212) (xy 362.952284 -397.434562)
			(xy 362.945172 -397.440658) (xy 362.924218 -397.45827) (xy 362.878252 -397.487988) (xy 362.82851 -397.510829)
			(xy 362.776014 -397.526327) (xy 362.721842 -397.534161) (xy 362.694474 -397.534638) (xy 362.667714 -397.534187)
			(xy 362.614718 -397.52672) (xy 362.563285 -397.511921) (xy 362.514424 -397.490082) (xy 362.469094 -397.46163)
			(xy 362.448348 -397.444722) (xy 362.439204 -397.436848) (xy 362.41609 -397.43126) (xy 362.313474 -397.454374)
			(xy 362.295186 -397.46936) (xy 362.290106 -397.480282) (xy 362.278162 -397.50547) (xy 362.248074 -397.552394)
			(xy 362.230162 -397.573754) (xy 362.224066 -397.580866) (xy 362.217716 -397.597884) (xy 362.217716 -397.683228)
			(xy 362.224066 -397.700246) (xy 362.230162 -397.707358) (xy 362.247789 -397.7283) (xy 362.277504 -397.774269)
			(xy 362.300343 -397.824014) (xy 362.315837 -397.876513) (xy 362.323667 -397.930687) (xy 362.324142 -397.958056)
			(xy 362.32371 -397.984418) (xy 362.316459 -398.036642) (xy 362.302087 -398.08737) (xy 362.28087 -398.135638)
			(xy 362.253211 -398.180525) (xy 362.236766 -398.201134) (xy 362.231422 -398.208178) (xy 362.225456 -398.224811)
			(xy 362.225082 -398.233646) (xy 362.225336 -398.264126) (xy 362.225772 -398.273161) (xy 362.232139 -398.290078)
			(xy 362.237782 -398.297146) (xy 362.262944 -398.327262) (xy 362.304666 -398.393725) (xy 362.32084 -398.42948)
			(xy 362.325158 -398.439132) (xy 362.340398 -398.45361) (xy 362.430314 -398.485868) (xy 362.451396 -398.484344)
			(xy 362.460794 -398.479518) (xy 362.487962 -398.465959) (xy 362.544828 -398.444668) (xy 362.603825 -398.430302)
			(xy 362.664114 -398.423066) (xy 362.694474 -398.422622) (xy 362.725171 -398.423073) (xy 362.786117 -398.43048)
			(xy 362.845726 -398.445177) (xy 362.90313 -398.46695) (xy 362.957491 -398.495482) (xy 362.983018 -398.512538)
			(xy 362.99177 -398.518009) (xy 363.011974 -398.522137) (xy 363.032178 -398.518009) (xy 363.04093 -398.512538)
			(xy 363.066464 -398.495496) (xy 363.120833 -398.466987) (xy 363.178236 -398.445225) (xy 363.23784 -398.430526)
			(xy 363.298779 -398.423102) (xy 363.329474 -398.422622) (xy 363.360207 -398.423062) (xy 363.421224 -398.430468)
			(xy 363.480904 -398.445176) (xy 363.538376 -398.46697) (xy 363.592801 -398.495534) (xy 363.643387 -398.53045)
			(xy 363.689394 -398.571209) (xy 363.730153 -398.617217) (xy 363.765068 -398.667802) (xy 363.793631 -398.722228)
			(xy 363.815425 -398.7797) (xy 363.830132 -398.83938) (xy 363.837538 -398.900397) (xy 363.837982 -398.93113)
			(xy 363.837418 -398.965316) (xy 363.82828 -399.033074) (xy 363.810146 -399.098997) (xy 363.783343 -399.161896)
			(xy 363.748355 -399.220637) (xy 363.705812 -399.274161) (xy 363.656481 -399.321501) (xy 363.629194 -399.342102)
			(xy 363.61751 -399.350484) (xy 363.606842 -399.376138) (xy 363.623352 -399.493232) (xy 363.641132 -399.514822)
			(xy 363.654594 -399.519648) (xy 363.686132 -399.531663) (xy 363.746002 -399.562811) (xy 363.801231 -399.601597)
			(xy 363.85085 -399.647342) (xy 363.893989 -399.699243) (xy 363.929891 -399.756389) (xy 363.944408 -399.786856)
			(xy 363.950758 -399.800572) (xy 363.97565 -399.81632) (xy 364.098078 -399.81632) (xy 364.12297 -399.800572)
			(xy 364.12932 -399.786856) (xy 364.142936 -399.758116) (xy 364.176307 -399.703978) (xy 364.21617 -399.654425)
			(xy 364.261904 -399.610233) (xy 364.287054 -399.590768) (xy 364.294161 -399.585011) (xy 364.304059 -399.569648)
			(xy 364.306358 -399.560796) (xy 364.312708 -399.531078) (xy 364.314234 -399.52219) (xy 364.311633 -399.504359)
			(xy 364.307628 -399.49628) (xy 364.293229 -399.468244) (xy 364.272843 -399.408609) (xy 364.262532 -399.346436)
			(xy 364.261908 -399.314924) (xy 364.262386 -399.287554) (xy 364.270201 -399.233376) (xy 364.285687 -399.180872)
			(xy 364.308526 -399.131125) (xy 364.338248 -399.085158) (xy 364.355888 -399.064226) (xy 364.361984 -399.057114)
			(xy 364.368334 -399.040096) (xy 364.368334 -398.954752) (xy 364.361984 -398.937734) (xy 364.355888 -398.930622)
			(xy 364.338244 -398.909694) (xy 364.308533 -398.86372) (xy 364.285698 -398.813971) (xy 364.270209 -398.76147)
			(xy 364.262381 -398.707293) (xy 364.261908 -398.679924) (xy 364.262394 -398.652673) (xy 364.27015 -398.598725)
			(xy 364.285505 -398.54643) (xy 364.308147 -398.496853) (xy 364.337613 -398.451003) (xy 364.373304 -398.409812)
			(xy 364.414495 -398.374121) (xy 364.460345 -398.344655) (xy 364.509922 -398.322013) (xy 364.562217 -398.306658)
			(xy 364.616165 -398.298902) (xy 364.670667 -398.298902) (xy 364.724615 -398.306658) (xy 364.77691 -398.322013)
			(xy 364.826487 -398.344655) (xy 364.872337 -398.374121) (xy 364.913528 -398.409812) (xy 364.949219 -398.451003)
			(xy 364.978685 -398.496853) (xy 365.001327 -398.54643) (xy 365.016682 -398.598725) (xy 365.024438 -398.652673)
			(xy 365.024924 -398.679924) (xy 365.024491 -398.707296) (xy 365.016668 -398.761477) (xy 365.001172 -398.813981)
			(xy 364.978323 -398.863727) (xy 364.94859 -398.909692) (xy 364.930944 -398.930622) (xy 364.924848 -398.937734)
			(xy 364.918498 -398.954752) (xy 364.918498 -399.008092) (xy 367.735612 -399.008092) (xy 367.736169 -398.9748)
			(xy 367.745789 -398.908915) (xy 367.764868 -398.845123) (xy 367.793002 -398.784776) (xy 367.810796 -398.756632)
			(xy 367.815859 -398.748116) (xy 367.819677 -398.728693) (xy 367.815854 -398.709272) (xy 367.810796 -398.700752)
			(xy 367.79302 -398.672601) (xy 367.764925 -398.612243) (xy 367.745857 -398.548455) (xy 367.736214 -398.48258)
			(xy 367.735612 -398.449292) (xy 367.736102 -398.419324) (xy 367.743925 -398.359902) (xy 367.759438 -398.302009)
			(xy 367.782374 -398.246636) (xy 367.812341 -398.19473) (xy 367.848828 -398.14718) (xy 367.891208 -398.1048)
			(xy 367.938758 -398.068313) (xy 367.990664 -398.038346) (xy 368.046037 -398.01541) (xy 368.10393 -397.999897)
			(xy 368.163352 -397.992074) (xy 368.223288 -397.992074) (xy 368.28271 -397.999897) (xy 368.340603 -398.01541)
			(xy 368.395976 -398.038346) (xy 368.447882 -398.068313) (xy 368.495432 -398.1048) (xy 368.537812 -398.14718)
			(xy 368.574299 -398.19473) (xy 368.604266 -398.246636) (xy 368.627202 -398.302009) (xy 368.642715 -398.359902)
			(xy 368.650538 -398.419324) (xy 368.651028 -398.449292) (xy 368.650458 -398.482584) (xy 368.641785 -398.542002)
			(xy 370.1852 -398.542002) (xy 370.18916 -398.492948) (xy 370.200937 -398.445164) (xy 370.220228 -398.399888)
			(xy 370.246531 -398.358292) (xy 370.279166 -398.321455) (xy 370.317287 -398.29033) (xy 370.359908 -398.265723)
			(xy 370.405924 -398.248271) (xy 370.454143 -398.238427) (xy 370.503318 -398.236446) (xy 370.552173 -398.242378)
			(xy 370.599444 -398.25607) (xy 370.643906 -398.277168) (xy 370.684409 -398.305124) (xy 370.719902 -398.339216)
			(xy 370.749467 -398.37856) (xy 370.772338 -398.422137) (xy 370.787922 -398.468818) (xy 370.795817 -398.517395)
			(xy 370.796312 -398.542002) (xy 371.38535 -398.542002) (xy 371.38931 -398.492948) (xy 371.401087 -398.445164)
			(xy 371.420378 -398.399888) (xy 371.446681 -398.358292) (xy 371.479316 -398.321455) (xy 371.517437 -398.29033)
			(xy 371.560058 -398.265723) (xy 371.606074 -398.248271) (xy 371.654293 -398.238427) (xy 371.703468 -398.236446)
			(xy 371.752323 -398.242378) (xy 371.799594 -398.25607) (xy 371.844056 -398.277168) (xy 371.884559 -398.305124)
			(xy 371.920052 -398.339216) (xy 371.949617 -398.37856) (xy 371.972488 -398.422137) (xy 371.988072 -398.468818)
			(xy 371.995967 -398.517395) (xy 371.996462 -398.542002) (xy 372.5855 -398.542002) (xy 372.58946 -398.492948)
			(xy 372.601237 -398.445164) (xy 372.620528 -398.399888) (xy 372.646831 -398.358292) (xy 372.679466 -398.321455)
			(xy 372.717587 -398.29033) (xy 372.760208 -398.265723) (xy 372.806224 -398.248271) (xy 372.854443 -398.238427)
			(xy 372.903618 -398.236446) (xy 372.952473 -398.242378) (xy 372.999744 -398.25607) (xy 373.044206 -398.277168)
			(xy 373.084709 -398.305124) (xy 373.120202 -398.339216) (xy 373.149767 -398.37856) (xy 373.172638 -398.422137)
			(xy 373.188222 -398.468818) (xy 373.196117 -398.517395) (xy 373.196612 -398.542002) (xy 373.785396 -398.542002)
			(xy 373.789356 -398.492948) (xy 373.801133 -398.445164) (xy 373.820424 -398.399888) (xy 373.846727 -398.358292)
			(xy 373.879362 -398.321455) (xy 373.917483 -398.29033) (xy 373.960104 -398.265723) (xy 374.00612 -398.248271)
			(xy 374.054339 -398.238427) (xy 374.103514 -398.236446) (xy 374.152369 -398.242378) (xy 374.19964 -398.25607)
			(xy 374.244102 -398.277168) (xy 374.284605 -398.305124) (xy 374.320098 -398.339216) (xy 374.349663 -398.37856)
			(xy 374.372534 -398.422137) (xy 374.388118 -398.468818) (xy 374.396013 -398.517395) (xy 374.396508 -398.542002)
			(xy 374.985546 -398.542002) (xy 374.989506 -398.492948) (xy 375.001283 -398.445164) (xy 375.020574 -398.399888)
			(xy 375.046877 -398.358292) (xy 375.079512 -398.321455) (xy 375.117633 -398.29033) (xy 375.160254 -398.265723)
			(xy 375.20627 -398.248271) (xy 375.254489 -398.238427) (xy 375.303664 -398.236446) (xy 375.352519 -398.242378)
			(xy 375.39979 -398.25607) (xy 375.444252 -398.277168) (xy 375.484755 -398.305124) (xy 375.520248 -398.339216)
			(xy 375.549813 -398.37856) (xy 375.572684 -398.422137) (xy 375.588268 -398.468818) (xy 375.596163 -398.517395)
			(xy 375.596658 -398.542002) (xy 376.185442 -398.542002) (xy 376.189402 -398.492948) (xy 376.201179 -398.445164)
			(xy 376.22047 -398.399888) (xy 376.246773 -398.358292) (xy 376.279408 -398.321455) (xy 376.317529 -398.29033)
			(xy 376.36015 -398.265723) (xy 376.406166 -398.248271) (xy 376.454385 -398.238427) (xy 376.50356 -398.236446)
			(xy 376.552415 -398.242378) (xy 376.599686 -398.25607) (xy 376.644148 -398.277168) (xy 376.684651 -398.305124)
			(xy 376.720144 -398.339216) (xy 376.749709 -398.37856) (xy 376.77258 -398.422137) (xy 376.788164 -398.468818)
			(xy 376.796059 -398.517395) (xy 376.796554 -398.542002) (xy 377.385338 -398.542002) (xy 377.389298 -398.492948)
			(xy 377.401075 -398.445164) (xy 377.420366 -398.399888) (xy 377.446669 -398.358292) (xy 377.479304 -398.321455)
			(xy 377.517425 -398.29033) (xy 377.560046 -398.265723) (xy 377.606062 -398.248271) (xy 377.654281 -398.238427)
			(xy 377.703456 -398.236446) (xy 377.752311 -398.242378) (xy 377.799582 -398.25607) (xy 377.844044 -398.277168)
			(xy 377.884547 -398.305124) (xy 377.92004 -398.339216) (xy 377.949605 -398.37856) (xy 377.972476 -398.422137)
			(xy 377.98806 -398.468818) (xy 377.995955 -398.517395) (xy 377.99645 -398.542002) (xy 378.585488 -398.542002)
			(xy 378.589448 -398.492948) (xy 378.601225 -398.445164) (xy 378.620516 -398.399888) (xy 378.646819 -398.358292)
			(xy 378.679454 -398.321455) (xy 378.717575 -398.29033) (xy 378.760196 -398.265723) (xy 378.806212 -398.248271)
			(xy 378.854431 -398.238427) (xy 378.903606 -398.236446) (xy 378.952461 -398.242378) (xy 378.999732 -398.25607)
			(xy 379.044194 -398.277168) (xy 379.084697 -398.305124) (xy 379.12019 -398.339216) (xy 379.149755 -398.37856)
			(xy 379.172626 -398.422137) (xy 379.18821 -398.468818) (xy 379.196105 -398.517395) (xy 379.1966 -398.542002)
			(xy 379.785384 -398.542002) (xy 379.789344 -398.492948) (xy 379.801121 -398.445164) (xy 379.820412 -398.399888)
			(xy 379.846715 -398.358292) (xy 379.87935 -398.321455) (xy 379.917471 -398.29033) (xy 379.960092 -398.265723)
			(xy 380.006108 -398.248271) (xy 380.054327 -398.238427) (xy 380.103502 -398.236446) (xy 380.152357 -398.242378)
			(xy 380.199628 -398.25607) (xy 380.24409 -398.277168) (xy 380.284593 -398.305124) (xy 380.320086 -398.339216)
			(xy 380.349651 -398.37856) (xy 380.372522 -398.422137) (xy 380.388106 -398.468818) (xy 380.396001 -398.517395)
			(xy 380.396496 -398.542002) (xy 380.985534 -398.542002) (xy 380.989494 -398.492948) (xy 381.001271 -398.445164)
			(xy 381.020562 -398.399888) (xy 381.046865 -398.358292) (xy 381.0795 -398.321455) (xy 381.117621 -398.29033)
			(xy 381.160242 -398.265723) (xy 381.206258 -398.248271) (xy 381.254477 -398.238427) (xy 381.303652 -398.236446)
			(xy 381.352507 -398.242378) (xy 381.399778 -398.25607) (xy 381.44424 -398.277168) (xy 381.484743 -398.305124)
			(xy 381.520236 -398.339216) (xy 381.549801 -398.37856) (xy 381.572672 -398.422137) (xy 381.588256 -398.468818)
			(xy 381.596151 -398.517395) (xy 381.596646 -398.542002) (xy 382.18543 -398.542002) (xy 382.18939 -398.492948)
			(xy 382.201167 -398.445164) (xy 382.220458 -398.399888) (xy 382.246761 -398.358292) (xy 382.279396 -398.321455)
			(xy 382.317517 -398.29033) (xy 382.360138 -398.265723) (xy 382.406154 -398.248271) (xy 382.454373 -398.238427)
			(xy 382.503548 -398.236446) (xy 382.552403 -398.242378) (xy 382.599674 -398.25607) (xy 382.644136 -398.277168)
			(xy 382.684639 -398.305124) (xy 382.720132 -398.339216) (xy 382.749697 -398.37856) (xy 382.772568 -398.422137)
			(xy 382.788152 -398.468818) (xy 382.796047 -398.517395) (xy 382.796542 -398.542002) (xy 383.385326 -398.542002)
			(xy 383.389286 -398.492948) (xy 383.401063 -398.445164) (xy 383.420354 -398.399888) (xy 383.446657 -398.358292)
			(xy 383.479292 -398.321455) (xy 383.517413 -398.29033) (xy 383.560034 -398.265723) (xy 383.60605 -398.248271)
			(xy 383.654269 -398.238427) (xy 383.703444 -398.236446) (xy 383.752299 -398.242378) (xy 383.79957 -398.25607)
			(xy 383.844032 -398.277168) (xy 383.884535 -398.305124) (xy 383.920028 -398.339216) (xy 383.949593 -398.37856)
			(xy 383.972464 -398.422137) (xy 383.988048 -398.468818) (xy 383.995943 -398.517395) (xy 383.996438 -398.542002)
			(xy 384.585476 -398.542002) (xy 384.589436 -398.492948) (xy 384.601213 -398.445164) (xy 384.620504 -398.399888)
			(xy 384.646807 -398.358292) (xy 384.679442 -398.321455) (xy 384.717563 -398.29033) (xy 384.760184 -398.265723)
			(xy 384.8062 -398.248271) (xy 384.854419 -398.238427) (xy 384.903594 -398.236446) (xy 384.952449 -398.242378)
			(xy 384.99972 -398.25607) (xy 385.044182 -398.277168) (xy 385.084685 -398.305124) (xy 385.120178 -398.339216)
			(xy 385.149743 -398.37856) (xy 385.172614 -398.422137) (xy 385.188198 -398.468818) (xy 385.196093 -398.517395)
			(xy 385.196588 -398.542002) (xy 385.785372 -398.542002) (xy 385.789332 -398.492948) (xy 385.801109 -398.445164)
			(xy 385.8204 -398.399888) (xy 385.846703 -398.358292) (xy 385.879338 -398.321455) (xy 385.917459 -398.29033)
			(xy 385.96008 -398.265723) (xy 386.006096 -398.248271) (xy 386.054315 -398.238427) (xy 386.10349 -398.236446)
			(xy 386.152345 -398.242378) (xy 386.199616 -398.25607) (xy 386.244078 -398.277168) (xy 386.284581 -398.305124)
			(xy 386.320074 -398.339216) (xy 386.349639 -398.37856) (xy 386.37251 -398.422137) (xy 386.388094 -398.468818)
			(xy 386.395989 -398.517395) (xy 386.396484 -398.542002) (xy 386.985522 -398.542002) (xy 386.989482 -398.492948)
			(xy 387.001259 -398.445164) (xy 387.02055 -398.399888) (xy 387.046853 -398.358292) (xy 387.079488 -398.321455)
			(xy 387.117609 -398.29033) (xy 387.16023 -398.265723) (xy 387.206246 -398.248271) (xy 387.254465 -398.238427)
			(xy 387.30364 -398.236446) (xy 387.352495 -398.242378) (xy 387.399766 -398.25607) (xy 387.444228 -398.277168)
			(xy 387.484731 -398.305124) (xy 387.520224 -398.339216) (xy 387.549789 -398.37856) (xy 387.57266 -398.422137)
			(xy 387.588244 -398.468818) (xy 387.596139 -398.517395) (xy 387.596634 -398.542002) (xy 388.185418 -398.542002)
			(xy 388.189378 -398.492948) (xy 388.201155 -398.445164) (xy 388.220446 -398.399888) (xy 388.246749 -398.358292)
			(xy 388.279384 -398.321455) (xy 388.317505 -398.29033) (xy 388.360126 -398.265723) (xy 388.406142 -398.248271)
			(xy 388.454361 -398.238427) (xy 388.503536 -398.236446) (xy 388.552391 -398.242378) (xy 388.599662 -398.25607)
			(xy 388.644124 -398.277168) (xy 388.684627 -398.305124) (xy 388.72012 -398.339216) (xy 388.749685 -398.37856)
			(xy 388.772556 -398.422137) (xy 388.78814 -398.468818) (xy 388.796035 -398.517395) (xy 388.79653 -398.542002)
			(xy 388.796035 -398.566609) (xy 388.795811 -398.567989) (xy 389.515098 -398.567989) (xy 389.515098 -398.516015)
			(xy 389.523228 -398.46468) (xy 389.539289 -398.41525) (xy 389.562885 -398.36894) (xy 389.593435 -398.326892)
			(xy 389.630186 -398.290141) (xy 389.672234 -398.259591) (xy 389.718544 -398.235995) (xy 389.767974 -398.219934)
			(xy 389.819309 -398.211804) (xy 389.871283 -398.211804) (xy 389.922618 -398.219934) (xy 389.972048 -398.235995)
			(xy 390.018358 -398.259591) (xy 390.060406 -398.290141) (xy 390.097157 -398.326892) (xy 390.127707 -398.36894)
			(xy 390.151303 -398.41525) (xy 390.167364 -398.46468) (xy 390.175494 -398.516015) (xy 390.176004 -398.542002)
			(xy 390.175494 -398.567989) (xy 390.167364 -398.619324) (xy 390.151303 -398.668754) (xy 390.127707 -398.715064)
			(xy 390.097157 -398.757112) (xy 390.060406 -398.793863) (xy 390.018358 -398.824413) (xy 389.972048 -398.848009)
			(xy 389.922618 -398.86407) (xy 389.871283 -398.8722) (xy 389.819309 -398.8722) (xy 389.767974 -398.86407)
			(xy 389.718544 -398.848009) (xy 389.672234 -398.824413) (xy 389.630186 -398.793863) (xy 389.593435 -398.757112)
			(xy 389.562885 -398.715064) (xy 389.539289 -398.668754) (xy 389.523228 -398.619324) (xy 389.515098 -398.567989)
			(xy 388.795811 -398.567989) (xy 388.78814 -398.615186) (xy 388.772556 -398.661867) (xy 388.749685 -398.705444)
			(xy 388.72012 -398.744788) (xy 388.684627 -398.77888) (xy 388.644124 -398.806836) (xy 388.599662 -398.827934)
			(xy 388.552391 -398.841626) (xy 388.503536 -398.847558) (xy 388.454361 -398.845577) (xy 388.406142 -398.835733)
			(xy 388.360126 -398.818281) (xy 388.317505 -398.793674) (xy 388.279384 -398.762549) (xy 388.246749 -398.725712)
			(xy 388.220446 -398.684116) (xy 388.201155 -398.63884) (xy 388.189378 -398.591056) (xy 388.185418 -398.542002)
			(xy 387.596634 -398.542002) (xy 387.596139 -398.566609) (xy 387.588244 -398.615186) (xy 387.57266 -398.661867)
			(xy 387.549789 -398.705444) (xy 387.520224 -398.744788) (xy 387.484731 -398.77888) (xy 387.444228 -398.806836)
			(xy 387.399766 -398.827934) (xy 387.352495 -398.841626) (xy 387.30364 -398.847558) (xy 387.254465 -398.845577)
			(xy 387.206246 -398.835733) (xy 387.16023 -398.818281) (xy 387.117609 -398.793674) (xy 387.079488 -398.762549)
			(xy 387.046853 -398.725712) (xy 387.02055 -398.684116) (xy 387.001259 -398.63884) (xy 386.989482 -398.591056)
			(xy 386.985522 -398.542002) (xy 386.396484 -398.542002) (xy 386.395989 -398.566609) (xy 386.388094 -398.615186)
			(xy 386.37251 -398.661867) (xy 386.349639 -398.705444) (xy 386.320074 -398.744788) (xy 386.284581 -398.77888)
			(xy 386.244078 -398.806836) (xy 386.199616 -398.827934) (xy 386.152345 -398.841626) (xy 386.10349 -398.847558)
			(xy 386.054315 -398.845577) (xy 386.006096 -398.835733) (xy 385.96008 -398.818281) (xy 385.917459 -398.793674)
			(xy 385.879338 -398.762549) (xy 385.846703 -398.725712) (xy 385.8204 -398.684116) (xy 385.801109 -398.63884)
			(xy 385.789332 -398.591056) (xy 385.785372 -398.542002) (xy 385.196588 -398.542002) (xy 385.196093 -398.566609)
			(xy 385.188198 -398.615186) (xy 385.172614 -398.661867) (xy 385.149743 -398.705444) (xy 385.120178 -398.744788)
			(xy 385.084685 -398.77888) (xy 385.044182 -398.806836) (xy 384.99972 -398.827934) (xy 384.952449 -398.841626)
			(xy 384.903594 -398.847558) (xy 384.854419 -398.845577) (xy 384.8062 -398.835733) (xy 384.760184 -398.818281)
			(xy 384.717563 -398.793674) (xy 384.679442 -398.762549) (xy 384.646807 -398.725712) (xy 384.620504 -398.684116)
			(xy 384.601213 -398.63884) (xy 384.589436 -398.591056) (xy 384.585476 -398.542002) (xy 383.996438 -398.542002)
			(xy 383.995943 -398.566609) (xy 383.988048 -398.615186) (xy 383.972464 -398.661867) (xy 383.949593 -398.705444)
			(xy 383.920028 -398.744788) (xy 383.884535 -398.77888) (xy 383.844032 -398.806836) (xy 383.79957 -398.827934)
			(xy 383.752299 -398.841626) (xy 383.703444 -398.847558) (xy 383.654269 -398.845577) (xy 383.60605 -398.835733)
			(xy 383.560034 -398.818281) (xy 383.517413 -398.793674) (xy 383.479292 -398.762549) (xy 383.446657 -398.725712)
			(xy 383.420354 -398.684116) (xy 383.401063 -398.63884) (xy 383.389286 -398.591056) (xy 383.385326 -398.542002)
			(xy 382.796542 -398.542002) (xy 382.796047 -398.566609) (xy 382.788152 -398.615186) (xy 382.772568 -398.661867)
			(xy 382.749697 -398.705444) (xy 382.720132 -398.744788) (xy 382.684639 -398.77888) (xy 382.644136 -398.806836)
			(xy 382.599674 -398.827934) (xy 382.552403 -398.841626) (xy 382.503548 -398.847558) (xy 382.454373 -398.845577)
			(xy 382.406154 -398.835733) (xy 382.360138 -398.818281) (xy 382.317517 -398.793674) (xy 382.279396 -398.762549)
			(xy 382.246761 -398.725712) (xy 382.220458 -398.684116) (xy 382.201167 -398.63884) (xy 382.18939 -398.591056)
			(xy 382.18543 -398.542002) (xy 381.596646 -398.542002) (xy 381.596151 -398.566609) (xy 381.588256 -398.615186)
			(xy 381.572672 -398.661867) (xy 381.549801 -398.705444) (xy 381.520236 -398.744788) (xy 381.484743 -398.77888)
			(xy 381.44424 -398.806836) (xy 381.399778 -398.827934) (xy 381.352507 -398.841626) (xy 381.303652 -398.847558)
			(xy 381.254477 -398.845577) (xy 381.206258 -398.835733) (xy 381.160242 -398.818281) (xy 381.117621 -398.793674)
			(xy 381.0795 -398.762549) (xy 381.046865 -398.725712) (xy 381.020562 -398.684116) (xy 381.001271 -398.63884)
			(xy 380.989494 -398.591056) (xy 380.985534 -398.542002) (xy 380.396496 -398.542002) (xy 380.396001 -398.566609)
			(xy 380.388106 -398.615186) (xy 380.372522 -398.661867) (xy 380.349651 -398.705444) (xy 380.320086 -398.744788)
			(xy 380.284593 -398.77888) (xy 380.24409 -398.806836) (xy 380.199628 -398.827934) (xy 380.152357 -398.841626)
			(xy 380.103502 -398.847558) (xy 380.054327 -398.845577) (xy 380.006108 -398.835733) (xy 379.960092 -398.818281)
			(xy 379.917471 -398.793674) (xy 379.87935 -398.762549) (xy 379.846715 -398.725712) (xy 379.820412 -398.684116)
			(xy 379.801121 -398.63884) (xy 379.789344 -398.591056) (xy 379.785384 -398.542002) (xy 379.1966 -398.542002)
			(xy 379.196105 -398.566609) (xy 379.18821 -398.615186) (xy 379.172626 -398.661867) (xy 379.149755 -398.705444)
			(xy 379.12019 -398.744788) (xy 379.084697 -398.77888) (xy 379.044194 -398.806836) (xy 378.999732 -398.827934)
			(xy 378.952461 -398.841626) (xy 378.903606 -398.847558) (xy 378.854431 -398.845577) (xy 378.806212 -398.835733)
			(xy 378.760196 -398.818281) (xy 378.717575 -398.793674) (xy 378.679454 -398.762549) (xy 378.646819 -398.725712)
			(xy 378.620516 -398.684116) (xy 378.601225 -398.63884) (xy 378.589448 -398.591056) (xy 378.585488 -398.542002)
			(xy 377.99645 -398.542002) (xy 377.995955 -398.566609) (xy 377.98806 -398.615186) (xy 377.972476 -398.661867)
			(xy 377.949605 -398.705444) (xy 377.92004 -398.744788) (xy 377.884547 -398.77888) (xy 377.844044 -398.806836)
			(xy 377.799582 -398.827934) (xy 377.752311 -398.841626) (xy 377.703456 -398.847558) (xy 377.654281 -398.845577)
			(xy 377.606062 -398.835733) (xy 377.560046 -398.818281) (xy 377.517425 -398.793674) (xy 377.479304 -398.762549)
			(xy 377.446669 -398.725712) (xy 377.420366 -398.684116) (xy 377.401075 -398.63884) (xy 377.389298 -398.591056)
			(xy 377.385338 -398.542002) (xy 376.796554 -398.542002) (xy 376.796059 -398.566609) (xy 376.788164 -398.615186)
			(xy 376.77258 -398.661867) (xy 376.749709 -398.705444) (xy 376.720144 -398.744788) (xy 376.684651 -398.77888)
			(xy 376.644148 -398.806836) (xy 376.599686 -398.827934) (xy 376.552415 -398.841626) (xy 376.50356 -398.847558)
			(xy 376.454385 -398.845577) (xy 376.406166 -398.835733) (xy 376.36015 -398.818281) (xy 376.317529 -398.793674)
			(xy 376.279408 -398.762549) (xy 376.246773 -398.725712) (xy 376.22047 -398.684116) (xy 376.201179 -398.63884)
			(xy 376.189402 -398.591056) (xy 376.185442 -398.542002) (xy 375.596658 -398.542002) (xy 375.596163 -398.566609)
			(xy 375.588268 -398.615186) (xy 375.572684 -398.661867) (xy 375.549813 -398.705444) (xy 375.520248 -398.744788)
			(xy 375.484755 -398.77888) (xy 375.444252 -398.806836) (xy 375.39979 -398.827934) (xy 375.352519 -398.841626)
			(xy 375.303664 -398.847558) (xy 375.254489 -398.845577) (xy 375.20627 -398.835733) (xy 375.160254 -398.818281)
			(xy 375.117633 -398.793674) (xy 375.079512 -398.762549) (xy 375.046877 -398.725712) (xy 375.020574 -398.684116)
			(xy 375.001283 -398.63884) (xy 374.989506 -398.591056) (xy 374.985546 -398.542002) (xy 374.396508 -398.542002)
			(xy 374.396013 -398.566609) (xy 374.388118 -398.615186) (xy 374.372534 -398.661867) (xy 374.349663 -398.705444)
			(xy 374.320098 -398.744788) (xy 374.284605 -398.77888) (xy 374.244102 -398.806836) (xy 374.19964 -398.827934)
			(xy 374.152369 -398.841626) (xy 374.103514 -398.847558) (xy 374.054339 -398.845577) (xy 374.00612 -398.835733)
			(xy 373.960104 -398.818281) (xy 373.917483 -398.793674) (xy 373.879362 -398.762549) (xy 373.846727 -398.725712)
			(xy 373.820424 -398.684116) (xy 373.801133 -398.63884) (xy 373.789356 -398.591056) (xy 373.785396 -398.542002)
			(xy 373.196612 -398.542002) (xy 373.196117 -398.566609) (xy 373.188222 -398.615186) (xy 373.172638 -398.661867)
			(xy 373.149767 -398.705444) (xy 373.120202 -398.744788) (xy 373.084709 -398.77888) (xy 373.044206 -398.806836)
			(xy 372.999744 -398.827934) (xy 372.952473 -398.841626) (xy 372.903618 -398.847558) (xy 372.854443 -398.845577)
			(xy 372.806224 -398.835733) (xy 372.760208 -398.818281) (xy 372.717587 -398.793674) (xy 372.679466 -398.762549)
			(xy 372.646831 -398.725712) (xy 372.620528 -398.684116) (xy 372.601237 -398.63884) (xy 372.58946 -398.591056)
			(xy 372.5855 -398.542002) (xy 371.996462 -398.542002) (xy 371.995967 -398.566609) (xy 371.988072 -398.615186)
			(xy 371.972488 -398.661867) (xy 371.949617 -398.705444) (xy 371.920052 -398.744788) (xy 371.884559 -398.77888)
			(xy 371.844056 -398.806836) (xy 371.799594 -398.827934) (xy 371.752323 -398.841626) (xy 371.703468 -398.847558)
			(xy 371.654293 -398.845577) (xy 371.606074 -398.835733) (xy 371.560058 -398.818281) (xy 371.517437 -398.793674)
			(xy 371.479316 -398.762549) (xy 371.446681 -398.725712) (xy 371.420378 -398.684116) (xy 371.401087 -398.63884)
			(xy 371.38931 -398.591056) (xy 371.38535 -398.542002) (xy 370.796312 -398.542002) (xy 370.795817 -398.566609)
			(xy 370.787922 -398.615186) (xy 370.772338 -398.661867) (xy 370.749467 -398.705444) (xy 370.719902 -398.744788)
			(xy 370.684409 -398.77888) (xy 370.643906 -398.806836) (xy 370.599444 -398.827934) (xy 370.552173 -398.841626)
			(xy 370.503318 -398.847558) (xy 370.454143 -398.845577) (xy 370.405924 -398.835733) (xy 370.359908 -398.818281)
			(xy 370.317287 -398.793674) (xy 370.279166 -398.762549) (xy 370.246531 -398.725712) (xy 370.220228 -398.684116)
			(xy 370.200937 -398.63884) (xy 370.18916 -398.591056) (xy 370.1852 -398.542002) (xy 368.641785 -398.542002)
			(xy 368.640841 -398.548468) (xy 368.621766 -398.612259) (xy 368.593636 -398.672608) (xy 368.575844 -398.700752)
			(xy 368.570799 -398.709277) (xy 368.566982 -398.728693) (xy 368.570794 -398.748111) (xy 368.575844 -398.756632)
			(xy 368.593618 -398.784784) (xy 368.621712 -398.845143) (xy 368.640781 -398.90893) (xy 368.650425 -398.974804)
			(xy 368.651028 -399.008092) (xy 368.650584 -399.037392) (xy 368.643137 -399.095515) (xy 368.628314 -399.152208)
			(xy 368.617754 -399.179542) (xy 368.61369 -399.189194) (xy 368.614198 -399.20926) (xy 368.652044 -399.295112)
			(xy 368.666522 -399.309082) (xy 368.676428 -399.312638) (xy 368.699796 -399.32182) (xy 368.743641 -399.34628)
			(xy 368.783286 -399.377086) (xy 368.81782 -399.413529) (xy 368.84645 -399.454773) (xy 368.868518 -399.49987)
			(xy 368.883516 -399.547784) (xy 368.891101 -399.597415) (xy 368.891566 -399.622518) (xy 368.891056 -399.648505)
			(xy 368.882926 -399.69984) (xy 368.866865 -399.74927) (xy 368.843269 -399.79558) (xy 368.812719 -399.837628)
			(xy 368.775968 -399.874379) (xy 368.73392 -399.904929) (xy 368.68761 -399.928525) (xy 368.63818 -399.944586)
			(xy 368.586845 -399.952716) (xy 368.534871 -399.952716) (xy 368.483536 -399.944586) (xy 368.434106 -399.928525)
			(xy 368.387796 -399.904929) (xy 368.345748 -399.874379) (xy 368.308997 -399.837628) (xy 368.278447 -399.79558)
			(xy 368.254851 -399.74927) (xy 368.23879 -399.69984) (xy 368.23066 -399.648505) (xy 368.23015 -399.622518)
			(xy 368.230252 -399.611307) (xy 368.231778 -399.588936) (xy 368.233198 -399.577814) (xy 368.234722 -399.5674)
			(xy 368.229388 -399.547842) (xy 368.17173 -399.473928) (xy 368.15395 -399.464276) (xy 368.143536 -399.463006)
			(xy 368.11335 -399.459187) (xy 368.054274 -399.444626) (xy 367.997649 -399.422365) (xy 367.944474 -399.392796)
			(xy 367.895686 -399.356441) (xy 367.852147 -399.31394) (xy 367.814624 -399.266045) (xy 367.783779 -399.213599)
			(xy 367.760156 -399.157528) (xy 367.744173 -399.098821) (xy 367.736111 -399.038514) (xy 367.735612 -399.008092)
			(xy 364.918498 -399.008092) (xy 364.918498 -399.040096) (xy 364.924848 -399.057114) (xy 364.930944 -399.064226)
			(xy 364.948569 -399.085169) (xy 364.978282 -399.13114) (xy 365.00112 -399.180884) (xy 365.016614 -399.233382)
			(xy 365.024447 -399.287556) (xy 365.024924 -399.314924) (xy 365.02475 -399.331262) (xy 365.02195 -399.363819)
			(xy 365.019336 -399.379948) (xy 365.017304 -399.392394) (xy 365.02467 -399.416016) (xy 365.101378 -399.492216)
			(xy 365.125 -399.499582) (xy 365.137192 -399.497296) (xy 365.159422 -399.493592) (xy 365.204319 -399.489645)
			(xy 365.226854 -399.489422) (xy 365.257551 -399.489883) (xy 365.318496 -399.497288) (xy 365.378105 -399.511982)
			(xy 365.435509 -399.533753) (xy 365.489871 -399.562283) (xy 365.515398 -399.579338) (xy 365.52415 -399.584809)
			(xy 365.544354 -399.588937) (xy 365.564558 -399.584809) (xy 365.57331 -399.579338) (xy 365.598849 -399.562305)
			(xy 365.653217 -399.533795) (xy 365.710618 -399.51203) (xy 365.770221 -399.497329) (xy 365.83116 -399.489903)
			(xy 365.861854 -399.489422) (xy 365.892551 -399.489883) (xy 365.953496 -399.497288) (xy 366.013105 -399.511982)
			(xy 366.070509 -399.533753) (xy 366.124871 -399.562283) (xy 366.150398 -399.579338) (xy 366.15915 -399.584809)
			(xy 366.179354 -399.588937) (xy 366.199558 -399.584809) (xy 366.20831 -399.579338) (xy 366.233849 -399.562305)
			(xy 366.288217 -399.533795) (xy 366.345618 -399.51203) (xy 366.405221 -399.497329) (xy 366.46616 -399.489903)
			(xy 366.496854 -399.489422) (xy 366.527586 -399.489881) (xy 366.588603 -399.497285) (xy 366.648283 -399.51199)
			(xy 366.705754 -399.533783) (xy 366.76018 -399.562344) (xy 366.810765 -399.597258) (xy 366.856773 -399.638016)
			(xy 366.897532 -399.684022) (xy 366.932448 -399.734607) (xy 366.961011 -399.789031) (xy 366.982805 -399.846502)
			(xy 366.997512 -399.906181) (xy 367.004918 -399.967198) (xy 367.005362 -399.99793) (xy 367.004891 -400.028626)
			(xy 366.99749 -400.089572) (xy 366.982797 -400.149181) (xy 366.961028 -400.206585) (xy 366.932501 -400.260947)
			(xy 366.915446 -400.286474) (xy 366.909953 -400.295213) (xy 366.905837 -400.315425) (xy 366.909972 -400.335632)
			(xy 366.915446 -400.344386) (xy 366.933734 -400.372834) (xy 366.940592 -400.384518) (xy 366.963706 -400.397472)
			(xy 367.07826 -400.397726) (xy 367.10112 -400.384518) (xy 367.108232 -400.372834) (xy 367.125506 -400.344949)
			(xy 367.166151 -400.293461) (xy 367.213078 -400.247627) (xy 367.26551 -400.208208) (xy 367.322574 -400.175857)
			(xy 367.383325 -400.151112) (xy 367.446753 -400.134384) (xy 367.511806 -400.12595) (xy 367.544604 -400.125438)
			(xy 367.575338 -400.125834) (xy 367.636358 -400.133244) (xy 367.696039 -400.147955) (xy 367.753512 -400.169754)
			(xy 367.807938 -400.198321) (xy 367.858524 -400.233241) (xy 367.904532 -400.274004) (xy 367.94529 -400.320015)
			(xy 367.980205 -400.370605) (xy 368.008767 -400.425034) (xy 368.030559 -400.482509) (xy 368.045265 -400.542192)
			(xy 368.052669 -400.603212) (xy 368.053112 -400.633946) (xy 368.052398 -400.671994) (xy 368.041042 -400.747239)
			(xy 368.030506 -400.783806) (xy 368.027712 -400.792696) (xy 368.028728 -400.81073) (xy 368.063018 -400.888708)
			(xy 368.075718 -400.901662) (xy 368.0841 -400.905472) (xy 368.108192 -400.917426) (xy 368.15303 -400.947125)
			(xy 368.193255 -400.982824) (xy 368.228071 -401.023816) (xy 368.256787 -401.06929) (xy 368.278835 -401.118345)
			(xy 368.293779 -401.170009) (xy 368.301322 -401.223259) (xy 368.301778 -401.25015) (xy 368.301292 -401.277401)
			(xy 368.293536 -401.331349) (xy 368.278181 -401.383644) (xy 368.255539 -401.433221) (xy 368.226073 -401.479071)
			(xy 368.190382 -401.520262) (xy 368.149191 -401.555953) (xy 368.103341 -401.585419) (xy 368.053764 -401.608061)
			(xy 368.001469 -401.623416) (xy 367.947521 -401.631172) (xy 367.893019 -401.631172) (xy 367.839071 -401.623416)
			(xy 367.786776 -401.608061) (xy 367.737199 -401.585419) (xy 367.691349 -401.555953) (xy 367.650158 -401.520262)
			(xy 367.614467 -401.479071) (xy 367.585001 -401.433221) (xy 367.562359 -401.383644) (xy 367.547004 -401.331349)
			(xy 367.539248 -401.277401) (xy 367.538762 -401.25015) (xy 367.539016 -401.237958) (xy 367.53927 -401.22856)
			(xy 367.533428 -401.211542) (xy 367.480088 -401.145248) (xy 367.46434 -401.136104) (xy 367.455196 -401.13458)
			(xy 367.424627 -401.128635) (xy 367.365128 -401.110242) (xy 367.308318 -401.084728) (xy 367.255043 -401.052474)
			(xy 367.206101 -401.013963) (xy 367.162223 -400.96977) (xy 367.124063 -400.920554) (xy 367.107724 -400.894042)
			(xy 367.100866 -400.882358) (xy 367.077752 -400.869404) (xy 366.963198 -400.86915) (xy 366.940338 -400.882358)
			(xy 366.933226 -400.894042) (xy 366.915446 -400.921474) (xy 366.909953 -400.930213) (xy 366.905837 -400.950425)
			(xy 366.909972 -400.970632) (xy 366.915446 -400.979386) (xy 366.932467 -401.004933) (xy 366.96098 -401.059298)
			(xy 366.982746 -401.116698) (xy 366.997451 -401.176299) (xy 367.004879 -401.237236) (xy 367.005362 -401.26793)
			(xy 367.004891 -401.298626) (xy 366.99749 -401.359572) (xy 366.982797 -401.419181) (xy 366.961028 -401.476585)
			(xy 366.932501 -401.530947) (xy 366.915446 -401.556474) (xy 366.909953 -401.565213) (xy 366.905837 -401.585425)
			(xy 366.909972 -401.605632) (xy 366.915446 -401.614386) (xy 366.932467 -401.639933) (xy 366.96098 -401.694298)
			(xy 366.982746 -401.751698) (xy 366.997451 -401.811299) (xy 367.004879 -401.872236) (xy 367.005362 -401.90293)
			(xy 367.00499 -401.933665) (xy 366.997577 -401.994685) (xy 366.982863 -402.054367) (xy 366.961062 -402.11184)
			(xy 366.932492 -402.166266) (xy 366.89757 -402.216852) (xy 366.856805 -402.262859) (xy 366.810792 -402.303617)
			(xy 366.760201 -402.338532) (xy 366.705771 -402.367093) (xy 366.648294 -402.388886) (xy 366.58861 -402.403591)
			(xy 366.527589 -402.410995) (xy 366.496854 -402.411438) (xy 366.466158 -402.410962) (xy 366.405213 -402.40356)
			(xy 366.345605 -402.388868) (xy 366.288201 -402.3671) (xy 366.233838 -402.338575) (xy 366.20831 -402.321522)
			(xy 366.199558 -402.316051) (xy 366.179354 -402.311923) (xy 366.15915 -402.316051) (xy 366.150398 -402.321522)
			(xy 366.124853 -402.338547) (xy 366.070488 -402.36706) (xy 366.013088 -402.388826) (xy 365.953486 -402.403529)
			(xy 365.892548 -402.410956) (xy 365.861854 -402.411438) (xy 365.831158 -402.410962) (xy 365.770213 -402.40356)
			(xy 365.710605 -402.388868) (xy 365.653201 -402.3671) (xy 365.598838 -402.338575) (xy 365.57331 -402.321522)
			(xy 365.564558 -402.316051) (xy 365.544354 -402.311923) (xy 365.52415 -402.316051) (xy 365.515398 -402.321522)
			(xy 365.489853 -402.338547) (xy 365.435488 -402.36706) (xy 365.378088 -402.388826) (xy 365.318486 -402.403529)
			(xy 365.257548 -402.410956) (xy 365.226854 -402.411438) (xy 365.196158 -402.410962) (xy 365.135213 -402.40356)
			(xy 365.075605 -402.388868) (xy 365.018201 -402.3671) (xy 364.963838 -402.338575) (xy 364.93831 -402.321522)
			(xy 364.929558 -402.316051) (xy 364.909354 -402.311923) (xy 364.88915 -402.316051) (xy 364.880398 -402.321522)
			(xy 364.865158 -402.331682) (xy 364.856008 -402.338276) (xy 364.844054 -402.357368) (xy 364.841353 -402.379732)
			(xy 364.84433 -402.39061) (xy 364.852471 -402.41645) (xy 364.863897 -402.469411) (xy 364.869633 -402.523286)
			(xy 364.869984 -402.550376) (xy 364.86954 -402.581109) (xy 364.862133 -402.642126) (xy 364.847426 -402.701805)
			(xy 364.825631 -402.759276) (xy 364.797068 -402.813702) (xy 364.762153 -402.864287) (xy 364.721394 -402.910294)
			(xy 364.675387 -402.951053) (xy 364.624802 -402.985968) (xy 364.570376 -403.014531) (xy 364.512905 -403.036326)
			(xy 364.453226 -403.051033) (xy 364.392209 -403.05844) (xy 364.361476 -403.058884) (xy 364.327889 -403.058373)
			(xy 364.261301 -403.049526) (xy 364.196458 -403.031989) (xy 364.134487 -403.006066) (xy 364.07647 -402.972211)
			(xy 364.023415 -402.931011) (xy 363.976246 -402.883185) (xy 363.955584 -402.8567) (xy 363.948632 -402.848368)
			(xy 363.929643 -402.837921) (xy 363.908036 -402.836223) (xy 363.897672 -402.839428) (xy 363.869935 -402.848993)
			(xy 363.812822 -402.862437) (xy 363.754543 -402.869222) (xy 363.725206 -402.869654) (xy 363.68536 -402.868922)
			(xy 363.606638 -402.856542) (xy 363.568488 -402.845016) (xy 363.558473 -402.84231) (xy 363.53784 -402.84426)
			(xy 363.519646 -402.854186) (xy 363.512862 -402.862034) (xy 363.49214 -402.887858) (xy 363.445112 -402.934464)
			(xy 363.392433 -402.974574) (xy 363.334995 -403.007508) (xy 363.273768 -403.03271) (xy 363.209789 -403.049753)
			(xy 363.144139 -403.05835) (xy 363.111034 -403.058884) (xy 363.080302 -403.05843) (xy 363.019285 -403.051025)
			(xy 362.959606 -403.036319) (xy 362.902134 -403.014525) (xy 362.847709 -402.985963) (xy 362.797124 -402.951048)
			(xy 362.751117 -402.91029) (xy 362.710358 -402.864284) (xy 362.675442 -402.813699) (xy 362.646879 -402.759275)
			(xy 362.625084 -402.701804) (xy 362.610377 -402.642125) (xy 362.60297 -402.581108) (xy 362.602526 -402.550376)
			(xy 362.603148 -402.513791) (xy 362.613603 -402.441371) (xy 362.623354 -402.406104) (xy 362.626127 -402.394907)
			(xy 362.622472 -402.372157) (xy 362.609269 -402.353273) (xy 362.599478 -402.347176) (xy 362.588923 -402.341202)
			(xy 362.568342 -402.328367) (xy 362.55833 -402.321522) (xy 362.549578 -402.316051) (xy 362.529374 -402.311923)
			(xy 362.50917 -402.316051) (xy 362.500418 -402.321522) (xy 362.474868 -402.338538) (xy 362.420504 -402.367052)
			(xy 362.363105 -402.38882) (xy 362.303504 -402.403526) (xy 362.242568 -402.410955) (xy 362.211874 -402.411438)
			(xy 362.181178 -402.410952) (xy 362.120234 -402.403552) (xy 362.060626 -402.388862) (xy 362.003221 -402.367097)
			(xy 361.948858 -402.338574) (xy 361.92333 -402.321522) (xy 361.914578 -402.316051) (xy 361.894374 -402.311923)
			(xy 361.87417 -402.316051) (xy 361.865418 -402.321522) (xy 361.839868 -402.338538) (xy 361.785504 -402.367052)
			(xy 361.728105 -402.38882) (xy 361.668504 -402.403526) (xy 361.607568 -402.410955) (xy 361.576874 -402.411438)
			(xy 361.546144 -402.410968) (xy 361.485131 -402.403558) (xy 361.425457 -402.388847) (xy 361.367991 -402.367051)
			(xy 361.31357 -402.338488) (xy 361.262989 -402.303574) (xy 361.216985 -402.262818) (xy 361.176229 -402.216814)
			(xy 361.141314 -402.166233) (xy 361.11275 -402.111813) (xy 361.090954 -402.054347) (xy 361.076243 -401.994673)
			(xy 361.068832 -401.93366) (xy 361.068366 -401.90293) (xy 360.369868 -401.90293) (xy 360.382943 -401.953855)
			(xy 360.390954 -402.017273) (xy 360.391456 -402.049234) (xy 360.390954 -402.081195) (xy 360.382943 -402.144613)
			(xy 360.367046 -402.206527) (xy 360.343514 -402.26596) (xy 360.31272 -402.321975) (xy 360.275147 -402.37369)
			(xy 360.23139 -402.420287) (xy 360.182137 -402.461032) (xy 360.128166 -402.495283) (xy 360.070327 -402.5225)
			(xy 360.009534 -402.542253) (xy 359.946744 -402.554231) (xy 359.882948 -402.558245) (xy 359.819152 -402.554231)
			(xy 359.756362 -402.542253) (xy 359.695569 -402.5225) (xy 359.63773 -402.495283) (xy 359.583759 -402.461032)
			(xy 359.534506 -402.420287) (xy 359.490749 -402.37369) (xy 359.453176 -402.321975) (xy 359.422382 -402.26596)
			(xy 359.39885 -402.206527) (xy 359.382953 -402.144613) (xy 359.374942 -402.081195) (xy 358.14 -402.081195)
			(xy 358.14 -403.115737) (xy 358.606338 -403.115737) (xy 358.606338 -403.051815) (xy 358.614349 -402.988397)
			(xy 358.630246 -402.926483) (xy 358.653778 -402.86705) (xy 358.684572 -402.811035) (xy 358.722145 -402.75932)
			(xy 358.765902 -402.712723) (xy 358.815155 -402.671978) (xy 358.869126 -402.637727) (xy 358.926965 -402.61051)
			(xy 358.987758 -402.590757) (xy 359.050548 -402.578779) (xy 359.114344 -402.574766) (xy 359.17814 -402.578779)
			(xy 359.24093 -402.590757) (xy 359.301723 -402.61051) (xy 359.359562 -402.637727) (xy 359.413533 -402.671978)
			(xy 359.462786 -402.712723) (xy 359.506543 -402.75932) (xy 359.544116 -402.811035) (xy 359.57491 -402.86705)
			(xy 359.598442 -402.926483) (xy 359.614339 -402.988397) (xy 359.62235 -403.051815) (xy 359.622852 -403.083776)
			(xy 359.62235 -403.115737) (xy 359.614339 -403.179155) (xy 359.598442 -403.241069) (xy 359.57491 -403.300502)
			(xy 359.544116 -403.356517) (xy 359.506543 -403.408232) (xy 359.462786 -403.454829) (xy 359.413533 -403.495574)
			(xy 359.359562 -403.529825) (xy 359.301723 -403.557042) (xy 359.24093 -403.576795) (xy 359.17814 -403.588773)
			(xy 359.114344 -403.592787) (xy 359.050548 -403.588773) (xy 358.987758 -403.576795) (xy 358.926965 -403.557042)
			(xy 358.869126 -403.529825) (xy 358.815155 -403.495574) (xy 358.765902 -403.454829) (xy 358.722145 -403.408232)
			(xy 358.684572 -403.356517) (xy 358.653778 -403.300502) (xy 358.630246 -403.241069) (xy 358.614349 -403.179155)
			(xy 358.606338 -403.115737) (xy 358.14 -403.115737) (xy 358.14 -404.607987) (xy 359.33608 -404.607987)
			(xy 359.33608 -404.544065) (xy 359.344091 -404.480647) (xy 359.359988 -404.418733) (xy 359.38352 -404.3593)
			(xy 359.414314 -404.303285) (xy 359.451887 -404.25157) (xy 359.495644 -404.204973) (xy 359.544897 -404.164228)
			(xy 359.598868 -404.129977) (xy 359.656707 -404.10276) (xy 359.7175 -404.083007) (xy 359.78029 -404.071029)
			(xy 359.844086 -404.067016) (xy 359.907882 -404.071029) (xy 359.970672 -404.083007) (xy 360.031465 -404.10276)
			(xy 360.089304 -404.129977) (xy 360.143275 -404.164228) (xy 360.192528 -404.204973) (xy 360.236285 -404.25157)
			(xy 360.273858 -404.303285) (xy 360.304652 -404.3593) (xy 360.328184 -404.418733) (xy 360.344081 -404.480647)
			(xy 360.352092 -404.544065) (xy 360.352594 -404.576026) (xy 360.352092 -404.607987) (xy 360.344081 -404.671405)
			(xy 360.328184 -404.733319) (xy 360.304652 -404.792752) (xy 360.273858 -404.848767) (xy 360.236285 -404.900482)
			(xy 360.192528 -404.947079) (xy 360.143275 -404.987824) (xy 360.089304 -405.022075) (xy 360.031465 -405.049292)
			(xy 359.970672 -405.069045) (xy 359.907882 -405.081023) (xy 359.844086 -405.085037) (xy 359.78029 -405.081023)
			(xy 359.7175 -405.069045) (xy 359.656707 -405.049292) (xy 359.598868 -405.022075) (xy 359.544897 -404.987824)
			(xy 359.495644 -404.947079) (xy 359.451887 -404.900482) (xy 359.414314 -404.848767) (xy 359.38352 -404.792752)
			(xy 359.359988 -404.733319) (xy 359.344091 -404.671405) (xy 359.33608 -404.607987) (xy 358.14 -404.607987)
			(xy 358.14 -404.806658) (xy 358.140434 -404.816723) (xy 358.148163 -404.835313) (xy 358.154986 -404.842726)
			(xy 358.732074 -405.419814) (xy 358.739472 -405.426658) (xy 358.758072 -405.434379) (xy 358.768142 -405.4348)
			(xy 364.245144 -405.4348) (xy 364.27156 -405.41575) (xy 364.276894 -405.400256) (xy 364.286308 -405.373932)
			(xy 364.311746 -405.324151) (xy 364.344177 -405.278615) (xy 364.382905 -405.238299) (xy 364.427102 -405.204066)
			(xy 364.475822 -405.176649) (xy 364.528021 -405.156635) (xy 364.582582 -405.144453) (xy 364.638336 -405.140363)
			(xy 364.69409 -405.144453) (xy 364.748651 -405.156635) (xy 364.80085 -405.176649) (xy 364.84957 -405.204066)
			(xy 364.893767 -405.238299) (xy 364.932495 -405.278615) (xy 364.964926 -405.324151) (xy 364.990364 -405.373932)
			(xy 364.999778 -405.400256) (xy 365.005112 -405.41575) (xy 365.031528 -405.4348) (xy 369.307618 -405.4348)
			(xy 369.317687 -405.434373) (xy 369.336286 -405.426654) (xy 369.343686 -405.419814) (xy 369.581176 -405.182324)
			(xy 369.587867 -405.174917) (xy 369.595461 -405.15648) (xy 369.595908 -405.14651) (xy 369.595908 -403.126194)
			(xy 369.577366 -403.099778) (xy 369.561872 -403.094444) (xy 369.535809 -403.08486) (xy 369.486551 -403.059226)
			(xy 369.441528 -403.026722) (xy 369.401693 -402.988036) (xy 369.367885 -402.943985) (xy 369.34082 -402.895498)
			(xy 369.321068 -402.843601) (xy 369.309047 -402.789388) (xy 369.305011 -402.734006) (xy 369.309045 -402.678623)
			(xy 369.321065 -402.624411) (xy 369.340815 -402.572512) (xy 369.367879 -402.524025) (xy 369.401685 -402.479972)
			(xy 369.441519 -402.441285) (xy 369.486541 -402.40878) (xy 369.535798 -402.383145) (xy 369.561872 -402.373592)
			(xy 369.577366 -402.368258) (xy 369.595908 -402.341842) (xy 369.595908 -401.394168) (xy 369.596487 -401.358096)
			(xy 369.605509 -401.286517) (xy 369.623358 -401.216614) (xy 369.63604 -401.18284) (xy 369.640358 -401.171664)
			(xy 369.638326 -401.14855) (xy 369.58524 -401.059142) (xy 369.565682 -401.046442) (xy 369.553998 -401.044918)
			(xy 369.52767 -401.041102) (xy 369.476617 -401.02616) (xy 369.428613 -401.003239) (xy 369.384896 -400.972931)
			(xy 369.346593 -400.936017) (xy 369.314693 -400.893449) (xy 369.290016 -400.846323) (xy 369.2732 -400.795856)
			(xy 369.264679 -400.743348) (xy 369.264184 -400.71675) (xy 369.264581 -400.693517) (xy 369.27109 -400.64751)
			(xy 369.283973 -400.602866) (xy 369.302976 -400.560465) (xy 369.327725 -400.521139) (xy 369.342416 -400.503136)
			(xy 369.348512 -400.496024) (xy 369.354608 -400.479514) (xy 369.354608 -400.395186) (xy 369.348512 -400.378676)
			(xy 369.342416 -400.371564) (xy 369.327709 -400.353573) (xy 369.302955 -400.314247) (xy 369.283952 -400.271843)
			(xy 369.271074 -400.227195) (xy 369.264574 -400.181184) (xy 369.264184 -400.15795) (xy 369.264694 -400.131963)
			(xy 369.272824 -400.080628) (xy 369.288885 -400.031198) (xy 369.312481 -399.984888) (xy 369.343031 -399.94284)
			(xy 369.379782 -399.906089) (xy 369.42183 -399.875539) (xy 369.46814 -399.851943) (xy 369.51757 -399.835882)
			(xy 369.568905 -399.827752) (xy 369.620879 -399.827752) (xy 369.672214 -399.835882) (xy 369.721644 -399.851943)
			(xy 369.767954 -399.875539) (xy 369.810002 -399.906089) (xy 369.846753 -399.94284) (xy 369.877303 -399.984888)
			(xy 369.900899 -400.031198) (xy 369.91696 -400.080628) (xy 369.92509 -400.131963) (xy 369.9256 -400.15795)
			(xy 369.925203 -400.181183) (xy 369.918694 -400.22719) (xy 369.905811 -400.271833) (xy 369.886807 -400.314234)
			(xy 369.862056 -400.353559) (xy 369.847368 -400.371564) (xy 369.841272 -400.378676) (xy 369.835176 -400.395186)
			(xy 369.835176 -400.479514) (xy 369.841272 -400.496024) (xy 369.847368 -400.503136) (xy 369.864697 -400.524446)
			(xy 369.892766 -400.571653) (xy 369.912647 -400.62285) (xy 369.923792 -400.676629) (xy 369.925346 -400.70405)
			(xy 369.925854 -400.713956) (xy 369.93322 -400.731228) (xy 369.940078 -400.738086) (xy 369.947444 -400.744926)
			(xy 369.965977 -400.752668) (xy 369.986061 -400.752668) (xy 370.004594 -400.744926) (xy 370.01196 -400.738086)
			(xy 370.07038 -400.67992) (xy 370.097031 -400.654041) (xy 370.155816 -400.608623) (xy 370.219928 -400.571095)
			(xy 370.288313 -400.542075) (xy 370.359847 -400.52204) (xy 370.396516 -400.51609) (xy 370.407097 -400.514048)
			(xy 370.425244 -400.502465) (xy 370.431568 -400.493738) (xy 370.453586 -400.461338) (xy 370.504977 -400.402216)
			(xy 370.563868 -400.350561) (xy 370.59616 -400.328384) (xy 370.604368 -400.322402) (xy 370.615604 -400.305504)
			(xy 370.619412 -400.285572) (xy 370.61775 -400.275552) (xy 370.614672 -400.26005) (xy 370.611367 -400.228617)
			(xy 370.611146 -400.212814) (xy 370.611668 -400.187559) (xy 370.619981 -400.137737) (xy 370.636382 -400.089963)
			(xy 370.660423 -400.04554) (xy 370.691447 -400.00568) (xy 370.728609 -399.97147) (xy 370.770895 -399.943844)
			(xy 370.817151 -399.923554) (xy 370.866116 -399.911154) (xy 370.916454 -399.906983) (xy 370.966792 -399.911154)
			(xy 371.015757 -399.923554) (xy 371.062013 -399.943844) (xy 371.104299 -399.97147) (xy 371.141461 -400.00568)
			(xy 371.172485 -400.04554) (xy 371.196526 -400.089963) (xy 371.212927 -400.137737) (xy 371.22124 -400.187559)
			(xy 371.221762 -400.212814) (xy 371.221762 -400.21764) (xy 371.222256 -400.227645) (xy 371.229922 -400.24613)
			(xy 371.244072 -400.260279) (xy 371.262557 -400.267944) (xy 371.272562 -400.26844) (xy 371.760496 -400.26844)
			(xy 371.770507 -400.267953) (xy 371.789007 -400.260296) (xy 371.803171 -400.246144) (xy 371.810845 -400.227651)
			(xy 371.811296 -400.21764) (xy 371.811296 -400.216878) (xy 371.811296 -400.212814) (xy 371.811818 -400.187559)
			(xy 371.820131 -400.137737) (xy 371.836532 -400.089963) (xy 371.860573 -400.04554) (xy 371.891597 -400.00568)
			(xy 371.928759 -399.97147) (xy 371.971045 -399.943844) (xy 372.017301 -399.923554) (xy 372.066266 -399.911154)
			(xy 372.116604 -399.906983) (xy 372.166942 -399.911154) (xy 372.215907 -399.923554) (xy 372.262163 -399.943844)
			(xy 372.304449 -399.97147) (xy 372.341611 -400.00568) (xy 372.372635 -400.04554) (xy 372.396676 -400.089963)
			(xy 372.413077 -400.137737) (xy 372.42139 -400.187559) (xy 372.421912 -400.212814) (xy 372.421912 -400.21764)
			(xy 372.422407 -400.227641) (xy 372.430074 -400.246117) (xy 372.444226 -400.260255) (xy 372.46271 -400.267903)
			(xy 372.472712 -400.26844) (xy 372.960392 -400.26844) (xy 372.970404 -400.267954) (xy 372.988905 -400.260297)
			(xy 373.00307 -400.246145) (xy 373.010744 -400.227651) (xy 373.011192 -400.21764) (xy 373.011192 -400.216878)
			(xy 373.011192 -400.212814) (xy 373.011714 -400.187559) (xy 373.020027 -400.137737) (xy 373.036428 -400.089963)
			(xy 373.060469 -400.04554) (xy 373.091493 -400.00568) (xy 373.128655 -399.97147) (xy 373.170941 -399.943844)
			(xy 373.217197 -399.923554) (xy 373.266162 -399.911154) (xy 373.3165 -399.906983) (xy 373.366838 -399.911154)
			(xy 373.415803 -399.923554) (xy 373.462059 -399.943844) (xy 373.504345 -399.97147) (xy 373.541507 -400.00568)
			(xy 373.572531 -400.04554) (xy 373.596572 -400.089963) (xy 373.612973 -400.137737) (xy 373.621286 -400.187559)
			(xy 373.621808 -400.212814) (xy 373.621808 -400.21764) (xy 373.622303 -400.227642) (xy 373.62997 -400.246118)
			(xy 373.644122 -400.260257) (xy 373.662606 -400.267906) (xy 373.672608 -400.26844) (xy 374.160288 -400.26844)
			(xy 374.1703 -400.267955) (xy 374.188803 -400.260299) (xy 374.202969 -400.246147) (xy 374.210644 -400.227652)
			(xy 374.211088 -400.21764) (xy 374.211088 -400.216878) (xy 374.211088 -400.212814) (xy 374.21161 -400.187559)
			(xy 374.219923 -400.137737) (xy 374.236324 -400.089963) (xy 374.260365 -400.04554) (xy 374.291389 -400.00568)
			(xy 374.328551 -399.97147) (xy 374.370837 -399.943844) (xy 374.417093 -399.923554) (xy 374.466058 -399.911154)
			(xy 374.516396 -399.906983) (xy 374.566734 -399.911154) (xy 374.615699 -399.923554) (xy 374.661955 -399.943844)
			(xy 374.704241 -399.97147) (xy 374.741403 -400.00568) (xy 374.772427 -400.04554) (xy 374.796468 -400.089963)
			(xy 374.812869 -400.137737) (xy 374.821182 -400.187559) (xy 374.821704 -400.212814) (xy 374.821704 -400.21764)
			(xy 374.822199 -400.227642) (xy 374.829866 -400.246119) (xy 374.844018 -400.260259) (xy 374.862502 -400.26791)
			(xy 374.872504 -400.26844) (xy 375.360438 -400.26844) (xy 375.370444 -400.267946) (xy 375.388929 -400.260281)
			(xy 375.40308 -400.246131) (xy 375.410746 -400.227646) (xy 375.411238 -400.21764) (xy 375.411238 -400.216878)
			(xy 375.411238 -400.212814) (xy 375.41176 -400.187559) (xy 375.420073 -400.137737) (xy 375.436474 -400.089963)
			(xy 375.460515 -400.04554) (xy 375.491539 -400.00568) (xy 375.528701 -399.97147) (xy 375.570987 -399.943844)
			(xy 375.617243 -399.923554) (xy 375.666208 -399.911154) (xy 375.716546 -399.906983) (xy 375.766884 -399.911154)
			(xy 375.815849 -399.923554) (xy 375.862105 -399.943844) (xy 375.904391 -399.97147) (xy 375.941553 -400.00568)
			(xy 375.972577 -400.04554) (xy 375.996618 -400.089963) (xy 376.013019 -400.137737) (xy 376.021332 -400.187559)
			(xy 376.021854 -400.212814) (xy 376.021854 -400.21764) (xy 376.022348 -400.227646) (xy 376.030013 -400.246132)
			(xy 376.044163 -400.260283) (xy 376.062648 -400.26795) (xy 376.072654 -400.26844) (xy 376.560334 -400.26844)
			(xy 376.57034 -400.267947) (xy 376.588827 -400.260282) (xy 376.602979 -400.246132) (xy 376.610645 -400.227646)
			(xy 376.611134 -400.21764) (xy 376.611134 -400.216878) (xy 376.611134 -400.212814) (xy 376.611656 -400.187559)
			(xy 376.619969 -400.137737) (xy 376.63637 -400.089963) (xy 376.660411 -400.04554) (xy 376.691435 -400.00568)
			(xy 376.728597 -399.97147) (xy 376.770883 -399.943844) (xy 376.817139 -399.923554) (xy 376.866104 -399.911154)
			(xy 376.916442 -399.906983) (xy 376.96678 -399.911154) (xy 377.015745 -399.923554) (xy 377.062001 -399.943844)
			(xy 377.104287 -399.97147) (xy 377.141449 -400.00568) (xy 377.172473 -400.04554) (xy 377.196514 -400.089963)
			(xy 377.212915 -400.137737) (xy 377.221228 -400.187559) (xy 377.22175 -400.212814) (xy 377.22175 -400.21764)
			(xy 377.222244 -400.227646) (xy 377.229909 -400.246133) (xy 377.244059 -400.260285) (xy 377.262544 -400.267954)
			(xy 377.27255 -400.26844) (xy 377.760484 -400.26844) (xy 377.770497 -400.267955) (xy 377.789001 -400.2603)
			(xy 377.803169 -400.246148) (xy 377.810844 -400.227652) (xy 377.811284 -400.21764) (xy 377.811284 -400.216878)
			(xy 377.811284 -400.212814) (xy 377.811806 -400.187559) (xy 377.820119 -400.137737) (xy 377.83652 -400.089963)
			(xy 377.860561 -400.04554) (xy 377.891585 -400.00568) (xy 377.928747 -399.97147) (xy 377.971033 -399.943844)
			(xy 378.017289 -399.923554) (xy 378.066254 -399.911154) (xy 378.116592 -399.906983) (xy 378.16693 -399.911154)
			(xy 378.215895 -399.923554) (xy 378.262151 -399.943844) (xy 378.304437 -399.97147) (xy 378.341599 -400.00568)
			(xy 378.372623 -400.04554) (xy 378.396664 -400.089963) (xy 378.413065 -400.137737) (xy 378.421378 -400.187559)
			(xy 378.4219 -400.212814) (xy 378.4219 -400.21764) (xy 378.422395 -400.227642) (xy 378.430062 -400.24612)
			(xy 378.444213 -400.260261) (xy 378.462697 -400.267913) (xy 378.4727 -400.26844) (xy 378.96038 -400.26844)
			(xy 378.970393 -400.267956) (xy 378.988899 -400.260301) (xy 379.003068 -400.246149) (xy 379.010744 -400.227653)
			(xy 379.01118 -400.21764) (xy 379.01118 -400.216878) (xy 379.01118 -400.212814) (xy 379.011702 -400.187559)
			(xy 379.020015 -400.137737) (xy 379.036416 -400.089963) (xy 379.060457 -400.04554) (xy 379.091481 -400.00568)
			(xy 379.128643 -399.97147) (xy 379.170929 -399.943844) (xy 379.217185 -399.923554) (xy 379.26615 -399.911154)
			(xy 379.316488 -399.906983) (xy 379.366826 -399.911154) (xy 379.415791 -399.923554) (xy 379.462047 -399.943844)
			(xy 379.504333 -399.97147) (xy 379.541495 -400.00568) (xy 379.572519 -400.04554) (xy 379.59656 -400.089963)
			(xy 379.612961 -400.137737) (xy 379.621274 -400.187559) (xy 379.621796 -400.212814) (xy 379.621796 -400.21764)
			(xy 379.622291 -400.227643) (xy 379.629958 -400.246121) (xy 379.644109 -400.260263) (xy 379.662593 -400.267916)
			(xy 379.672596 -400.26844) (xy 380.160276 -400.26844) (xy 380.17029 -400.267957) (xy 380.188797 -400.260303)
			(xy 380.202967 -400.24615) (xy 380.210644 -400.227653) (xy 380.211076 -400.21764) (xy 380.211076 -400.216878)
			(xy 380.211076 -400.212814) (xy 380.211598 -400.187559) (xy 380.219911 -400.137737) (xy 380.236312 -400.089963)
			(xy 380.260353 -400.04554) (xy 380.291377 -400.00568) (xy 380.328539 -399.97147) (xy 380.370825 -399.943844)
			(xy 380.417081 -399.923554) (xy 380.466046 -399.911154) (xy 380.516384 -399.906983) (xy 380.566722 -399.911154)
			(xy 380.615687 -399.923554) (xy 380.661943 -399.943844) (xy 380.704229 -399.97147) (xy 380.741391 -400.00568)
			(xy 380.772415 -400.04554) (xy 380.796456 -400.089963) (xy 380.812857 -400.137737) (xy 380.82117 -400.187559)
			(xy 380.821692 -400.212814) (xy 380.821692 -400.21764) (xy 380.822187 -400.227643) (xy 380.829853 -400.246122)
			(xy 380.844005 -400.260265) (xy 380.862489 -400.267919) (xy 380.872492 -400.26844) (xy 381.360426 -400.26844)
			(xy 381.370433 -400.267948) (xy 381.388923 -400.260285) (xy 381.403077 -400.246135) (xy 381.410745 -400.227647)
			(xy 381.411226 -400.21764) (xy 381.411226 -400.216878) (xy 381.411226 -400.212814) (xy 381.411748 -400.187559)
			(xy 381.420061 -400.137737) (xy 381.436462 -400.089963) (xy 381.460503 -400.04554) (xy 381.491527 -400.00568)
			(xy 381.528689 -399.97147) (xy 381.570975 -399.943844) (xy 381.617231 -399.923554) (xy 381.666196 -399.911154)
			(xy 381.716534 -399.906983) (xy 381.766872 -399.911154) (xy 381.815837 -399.923554) (xy 381.862093 -399.943844)
			(xy 381.904379 -399.97147) (xy 381.941541 -400.00568) (xy 381.972565 -400.04554) (xy 381.996606 -400.089963)
			(xy 382.013007 -400.137737) (xy 382.02132 -400.187559) (xy 382.021842 -400.212814) (xy 382.021842 -400.21764)
			(xy 382.022269 -400.227653) (xy 382.029948 -400.246149) (xy 382.04412 -400.260298) (xy 382.062628 -400.267947)
			(xy 382.072642 -400.26844) (xy 382.560322 -400.26844) (xy 382.57033 -400.267949) (xy 382.588821 -400.260287)
			(xy 382.602977 -400.246136) (xy 382.610645 -400.227647) (xy 382.611122 -400.21764) (xy 382.611122 -400.216878)
			(xy 382.611122 -400.212814) (xy 382.611644 -400.187559) (xy 382.619957 -400.137737) (xy 382.636358 -400.089963)
			(xy 382.660399 -400.04554) (xy 382.691423 -400.00568) (xy 382.728585 -399.97147) (xy 382.770871 -399.943844)
			(xy 382.817127 -399.923554) (xy 382.866092 -399.911154) (xy 382.91643 -399.906983) (xy 382.966768 -399.911154)
			(xy 383.015733 -399.923554) (xy 383.061989 -399.943844) (xy 383.104275 -399.97147) (xy 383.141437 -400.00568)
			(xy 383.172461 -400.04554) (xy 383.196502 -400.089963) (xy 383.212903 -400.137737) (xy 383.221216 -400.187559)
			(xy 383.221738 -400.212814) (xy 383.221738 -400.21764) (xy 383.222234 -400.227639) (xy 383.229902 -400.246111)
			(xy 383.244055 -400.260242) (xy 383.262538 -400.267882) (xy 383.272538 -400.26844) (xy 383.760472 -400.26844)
			(xy 383.770486 -400.267957) (xy 383.788995 -400.260304) (xy 383.803166 -400.246152) (xy 383.810844 -400.227654)
			(xy 383.811272 -400.21764) (xy 383.811272 -400.216878) (xy 383.811272 -400.212814) (xy 383.811794 -400.187559)
			(xy 383.820107 -400.137737) (xy 383.836508 -400.089963) (xy 383.860549 -400.04554) (xy 383.891573 -400.00568)
			(xy 383.928735 -399.97147) (xy 383.971021 -399.943844) (xy 384.017277 -399.923554) (xy 384.066242 -399.911154)
			(xy 384.11658 -399.906983) (xy 384.166918 -399.911154) (xy 384.215883 -399.923554) (xy 384.262139 -399.943844)
			(xy 384.304425 -399.97147) (xy 384.341587 -400.00568) (xy 384.372611 -400.04554) (xy 384.396652 -400.089963)
			(xy 384.413053 -400.137737) (xy 384.421366 -400.187559) (xy 384.421888 -400.212814) (xy 384.421888 -400.21764)
			(xy 384.422383 -400.227643) (xy 384.430049 -400.246123) (xy 384.4442 -400.260267) (xy 384.462685 -400.267923)
			(xy 384.472688 -400.26844) (xy 384.960368 -400.26844) (xy 384.970383 -400.267958) (xy 384.988892 -400.260306)
			(xy 385.003065 -400.246153) (xy 385.010744 -400.227654) (xy 385.011168 -400.21764) (xy 385.011168 -400.216878)
			(xy 385.011168 -400.212814) (xy 385.01169 -400.187559) (xy 385.020003 -400.137737) (xy 385.036404 -400.089963)
			(xy 385.060445 -400.04554) (xy 385.091469 -400.00568) (xy 385.128631 -399.97147) (xy 385.170917 -399.943844)
			(xy 385.217173 -399.923554) (xy 385.266138 -399.911154) (xy 385.316476 -399.906983) (xy 385.366814 -399.911154)
			(xy 385.415779 -399.923554) (xy 385.462035 -399.943844) (xy 385.504321 -399.97147) (xy 385.541483 -400.00568)
			(xy 385.572507 -400.04554) (xy 385.596548 -400.089963) (xy 385.612949 -400.137737) (xy 385.621262 -400.187559)
			(xy 385.621784 -400.212814) (xy 385.621784 -400.21764) (xy 385.622278 -400.227644) (xy 385.629945 -400.246124)
			(xy 385.644096 -400.260269) (xy 385.66258 -400.267926) (xy 385.672584 -400.26844) (xy 386.160264 -400.26844)
			(xy 386.170279 -400.267959) (xy 386.18879 -400.260307) (xy 386.202964 -400.246154) (xy 386.210644 -400.227655)
			(xy 386.211064 -400.21764) (xy 386.211064 -400.216878) (xy 386.211064 -400.212814) (xy 386.211586 -400.187559)
			(xy 386.219899 -400.137737) (xy 386.2363 -400.089963) (xy 386.260341 -400.04554) (xy 386.291365 -400.00568)
			(xy 386.328527 -399.97147) (xy 386.370813 -399.943844) (xy 386.417069 -399.923554) (xy 386.466034 -399.911154)
			(xy 386.516372 -399.906983) (xy 386.56671 -399.911154) (xy 386.615675 -399.923554) (xy 386.661931 -399.943844)
			(xy 386.704217 -399.97147) (xy 386.741379 -400.00568) (xy 386.772403 -400.04554) (xy 386.796444 -400.089963)
			(xy 386.812845 -400.137737) (xy 386.821158 -400.187559) (xy 386.82168 -400.212814) (xy 386.82168 -400.21764)
			(xy 386.822174 -400.227644) (xy 386.82984 -400.246125) (xy 386.843991 -400.260271) (xy 386.862476 -400.267929)
			(xy 386.87248 -400.26844) (xy 387.360414 -400.26844) (xy 387.370423 -400.26795) (xy 387.388917 -400.260289)
			(xy 387.403075 -400.246138) (xy 387.410745 -400.227648) (xy 387.411214 -400.21764) (xy 387.411214 -400.216878)
			(xy 387.411214 -400.212814) (xy 387.411736 -400.187559) (xy 387.420049 -400.137737) (xy 387.43645 -400.089963)
			(xy 387.460491 -400.04554) (xy 387.491515 -400.00568) (xy 387.528677 -399.97147) (xy 387.570963 -399.943844)
			(xy 387.617219 -399.923554) (xy 387.666184 -399.911154) (xy 387.716522 -399.906983) (xy 387.76686 -399.911154)
			(xy 387.815825 -399.923554) (xy 387.862081 -399.943844) (xy 387.904367 -399.97147) (xy 387.941529 -400.00568)
			(xy 387.972553 -400.04554) (xy 387.996594 -400.089963) (xy 388.012995 -400.137737) (xy 388.021308 -400.187559)
			(xy 388.02183 -400.212814) (xy 388.02183 -400.21764) (xy 388.022325 -400.22764) (xy 388.029993 -400.246113)
			(xy 388.044146 -400.260246) (xy 388.062629 -400.267889) (xy 388.07263 -400.26844) (xy 388.56031 -400.26844)
			(xy 388.570319 -400.267951) (xy 388.588815 -400.260291) (xy 388.602974 -400.24614) (xy 388.610645 -400.227649)
			(xy 388.61111 -400.21764) (xy 388.61111 -400.216878) (xy 388.61111 -400.212814) (xy 388.611632 -400.187559)
			(xy 388.619945 -400.137737) (xy 388.636346 -400.089963) (xy 388.660387 -400.04554) (xy 388.691411 -400.00568)
			(xy 388.728573 -399.97147) (xy 388.770859 -399.943844) (xy 388.817115 -399.923554) (xy 388.86608 -399.911154)
			(xy 388.916418 -399.906983) (xy 388.966756 -399.911154) (xy 389.015721 -399.923554) (xy 389.061977 -399.943844)
			(xy 389.104263 -399.97147) (xy 389.141425 -400.00568) (xy 389.172449 -400.04554) (xy 389.19649 -400.089963)
			(xy 389.212891 -400.137737) (xy 389.221204 -400.187559) (xy 389.221726 -400.212814) (xy 389.221726 -400.21764)
			(xy 389.222221 -400.22764) (xy 389.229889 -400.246114) (xy 389.244041 -400.260248) (xy 389.262525 -400.267892)
			(xy 389.272526 -400.26844) (xy 394.15339 -400.26844) (xy 394.165239 -400.267825) (xy 394.186439 -400.257237)
			(xy 394.19403 -400.24812) (xy 394.250164 -400.173698) (xy 394.254228 -400.15033) (xy 394.250926 -400.138646)
			(xy 394.241656 -400.104209) (xy 394.231714 -400.033588) (xy 394.231114 -399.99793) (xy 394.231652 -399.964702)
			(xy 394.240306 -399.898812) (xy 394.25747 -399.83461) (xy 394.282851 -399.773192) (xy 394.316018 -399.715604)
			(xy 394.356404 -399.662827) (xy 394.403322 -399.615761) (xy 394.455971 -399.575209) (xy 394.513454 -399.541861)
			(xy 394.574792 -399.516287) (xy 394.638939 -399.498921) (xy 394.671804 -399.493994) (xy 394.683234 -399.49247)
			(xy 394.701776 -399.480532) (xy 394.755624 -399.395188) (xy 394.758418 -399.373344) (xy 394.754862 -399.362422)
			(xy 394.74357 -399.324622) (xy 394.731444 -399.246672) (xy 394.730732 -399.207228) (xy 394.731176 -399.176496)
			(xy 394.738582 -399.115479) (xy 394.753289 -399.0558) (xy 394.775084 -398.998329) (xy 394.803647 -398.943904)
			(xy 394.838563 -398.89332) (xy 394.879322 -398.847313) (xy 394.925329 -398.806555) (xy 394.975915 -398.771641)
			(xy 395.03034 -398.743079) (xy 395.087811 -398.721286) (xy 395.147491 -398.70658) (xy 395.208508 -398.699175)
			(xy 395.23924 -398.69872) (xy 395.269934 -398.699201) (xy 395.330873 -398.706626) (xy 395.390476 -398.721327)
			(xy 395.447879 -398.74309) (xy 395.502246 -398.7716) (xy 395.527784 -398.788636) (xy 395.536536 -398.794107)
			(xy 395.55674 -398.798235) (xy 395.576944 -398.794107) (xy 395.585696 -398.788636) (xy 395.611223 -398.77158)
			(xy 395.665585 -398.74305) (xy 395.722989 -398.721279) (xy 395.782598 -398.706584) (xy 395.843543 -398.699178)
			(xy 395.87424 -398.69872) (xy 395.904969 -398.699186) (xy 395.965978 -398.706599) (xy 396.025649 -398.721311)
			(xy 396.083111 -398.743109) (xy 396.137527 -398.771673) (xy 396.188103 -398.806589) (xy 396.234102 -398.847346)
			(xy 396.274853 -398.89335) (xy 396.309762 -398.943931) (xy 396.338319 -398.998351) (xy 396.360109 -399.055816)
			(xy 396.374813 -399.115489) (xy 396.382218 -399.176499) (xy 396.382748 -399.207228) (xy 396.382174 -399.242074)
			(xy 396.372657 -399.311112) (xy 396.353806 -399.378206) (xy 396.325973 -399.442098) (xy 396.308326 -399.47215)
			(xy 396.3035 -399.480024) (xy 396.299944 -399.497804) (xy 396.314422 -399.582132) (xy 396.323566 -399.59788)
			(xy 396.330932 -399.603722) (xy 396.353275 -399.622482) (xy 396.393958 -399.664302) (xy 396.429591 -399.710501)
			(xy 396.459705 -399.760472) (xy 396.472156 -399.786856) (xy 396.478506 -399.800572) (xy 396.503398 -399.81632)
			(xy 396.625826 -399.81632) (xy 396.650718 -399.800572) (xy 396.657068 -399.786856) (xy 396.671678 -399.756209)
			(xy 396.707835 -399.698747) (xy 396.751312 -399.646602) (xy 396.801336 -399.600701) (xy 396.85702 -399.561859)
			(xy 396.886938 -399.54581) (xy 396.894811 -399.541381) (xy 396.907051 -399.528113) (xy 396.910814 -399.519902)
			(xy 396.922244 -399.491962) (xy 396.925296 -399.48372) (xy 396.926215 -399.466182) (xy 396.924022 -399.457672)
			(xy 396.91606 -399.430226) (xy 396.907515 -399.373723) (xy 396.907004 -399.34515) (xy 396.907591 -399.31525)
			(xy 396.916911 -399.25618) (xy 396.925546 -399.227548) (xy 396.929102 -399.21688) (xy 396.926308 -399.195036)
			(xy 396.874492 -399.109946) (xy 396.856204 -399.097754) (xy 396.845028 -399.095976) (xy 396.818516 -399.091235)
			(xy 396.767079 -399.075274) (xy 396.718398 -399.052237) (xy 396.673442 -399.022581) (xy 396.633104 -398.986895)
			(xy 396.598187 -398.945891) (xy 396.569385 -398.900383) (xy 396.547271 -398.851276) (xy 396.532285 -398.799546)
			(xy 396.524724 -398.746223) (xy 396.524226 -398.719294) (xy 396.524712 -398.692043) (xy 396.532468 -398.638095)
			(xy 396.547823 -398.5858) (xy 396.570465 -398.536223) (xy 396.599931 -398.490373) (xy 396.635622 -398.449182)
			(xy 396.676813 -398.413491) (xy 396.722663 -398.384025) (xy 396.77224 -398.361383) (xy 396.824535 -398.346028)
			(xy 396.878483 -398.338272) (xy 396.932985 -398.338272) (xy 396.986933 -398.346028) (xy 397.039228 -398.361383)
			(xy 397.088805 -398.384025) (xy 397.134655 -398.413491) (xy 397.175846 -398.449182) (xy 397.211537 -398.490373)
			(xy 397.241003 -398.536223) (xy 397.263645 -398.5858) (xy 397.279 -398.638095) (xy 397.286756 -398.692043)
			(xy 397.287242 -398.719294) (xy 397.286659 -398.749195) (xy 397.277346 -398.808267) (xy 397.2687 -398.836896)
			(xy 397.265144 -398.847564) (xy 397.267938 -398.869408) (xy 397.319754 -398.954498) (xy 397.338042 -398.96669)
			(xy 397.349218 -398.968468) (xy 397.375729 -398.973211) (xy 397.427165 -398.989176) (xy 397.467133 -399.008092)
			(xy 400.26336 -399.008092) (xy 400.263925 -398.9748) (xy 400.273544 -398.908916) (xy 400.29262 -398.845125)
			(xy 400.320751 -398.784776) (xy 400.338544 -398.756632) (xy 400.343603 -398.748114) (xy 400.347417 -398.728693)
			(xy 400.343598 -398.709273) (xy 400.338544 -398.700752) (xy 400.320762 -398.672605) (xy 400.29267 -398.612245)
			(xy 400.273603 -398.548456) (xy 400.263961 -398.482581) (xy 400.26336 -398.449292) (xy 400.26385 -398.419324)
			(xy 400.271673 -398.359902) (xy 400.287186 -398.302009) (xy 400.310122 -398.246636) (xy 400.340089 -398.19473)
			(xy 400.376576 -398.14718) (xy 400.418956 -398.1048) (xy 400.466506 -398.068313) (xy 400.518412 -398.038346)
			(xy 400.573785 -398.01541) (xy 400.631678 -397.999897) (xy 400.6911 -397.992074) (xy 400.751036 -397.992074)
			(xy 400.810458 -397.999897) (xy 400.868351 -398.01541) (xy 400.923724 -398.038346) (xy 400.97563 -398.068313)
			(xy 401.02318 -398.1048) (xy 401.06556 -398.14718) (xy 401.102047 -398.19473) (xy 401.132014 -398.246636)
			(xy 401.15495 -398.302009) (xy 401.170463 -398.359902) (xy 401.178286 -398.419324) (xy 401.178776 -398.449292)
			(xy 401.178214 -398.482584) (xy 401.16954 -398.542002) (xy 402.712948 -398.542002) (xy 402.716908 -398.492948)
			(xy 402.728685 -398.445164) (xy 402.747976 -398.399888) (xy 402.774279 -398.358292) (xy 402.806914 -398.321455)
			(xy 402.845035 -398.29033) (xy 402.887656 -398.265723) (xy 402.933672 -398.248271) (xy 402.981891 -398.238427)
			(xy 403.031066 -398.236446) (xy 403.079921 -398.242378) (xy 403.127192 -398.25607) (xy 403.171654 -398.277168)
			(xy 403.212157 -398.305124) (xy 403.24765 -398.339216) (xy 403.277215 -398.37856) (xy 403.300086 -398.422137)
			(xy 403.31567 -398.468818) (xy 403.323565 -398.517395) (xy 403.32406 -398.542002) (xy 403.913098 -398.542002)
			(xy 403.917058 -398.492948) (xy 403.928835 -398.445164) (xy 403.948126 -398.399888) (xy 403.974429 -398.358292)
			(xy 404.007064 -398.321455) (xy 404.045185 -398.29033) (xy 404.087806 -398.265723) (xy 404.133822 -398.248271)
			(xy 404.182041 -398.238427) (xy 404.231216 -398.236446) (xy 404.280071 -398.242378) (xy 404.327342 -398.25607)
			(xy 404.371804 -398.277168) (xy 404.412307 -398.305124) (xy 404.4478 -398.339216) (xy 404.477365 -398.37856)
			(xy 404.500236 -398.422137) (xy 404.51582 -398.468818) (xy 404.523715 -398.517395) (xy 404.52421 -398.542002)
			(xy 405.113248 -398.542002) (xy 405.117208 -398.492948) (xy 405.128985 -398.445164) (xy 405.148276 -398.399888)
			(xy 405.174579 -398.358292) (xy 405.207214 -398.321455) (xy 405.245335 -398.29033) (xy 405.287956 -398.265723)
			(xy 405.333972 -398.248271) (xy 405.382191 -398.238427) (xy 405.431366 -398.236446) (xy 405.480221 -398.242378)
			(xy 405.527492 -398.25607) (xy 405.571954 -398.277168) (xy 405.612457 -398.305124) (xy 405.64795 -398.339216)
			(xy 405.677515 -398.37856) (xy 405.700386 -398.422137) (xy 405.71597 -398.468818) (xy 405.723865 -398.517395)
			(xy 405.72436 -398.542002) (xy 406.313144 -398.542002) (xy 406.317104 -398.492948) (xy 406.328881 -398.445164)
			(xy 406.348172 -398.399888) (xy 406.374475 -398.358292) (xy 406.40711 -398.321455) (xy 406.445231 -398.29033)
			(xy 406.487852 -398.265723) (xy 406.533868 -398.248271) (xy 406.582087 -398.238427) (xy 406.631262 -398.236446)
			(xy 406.680117 -398.242378) (xy 406.727388 -398.25607) (xy 406.77185 -398.277168) (xy 406.812353 -398.305124)
			(xy 406.847846 -398.339216) (xy 406.877411 -398.37856) (xy 406.900282 -398.422137) (xy 406.915866 -398.468818)
			(xy 406.923761 -398.517395) (xy 406.924256 -398.542002) (xy 407.513294 -398.542002) (xy 407.517254 -398.492948)
			(xy 407.529031 -398.445164) (xy 407.548322 -398.399888) (xy 407.574625 -398.358292) (xy 407.60726 -398.321455)
			(xy 407.645381 -398.29033) (xy 407.688002 -398.265723) (xy 407.734018 -398.248271) (xy 407.782237 -398.238427)
			(xy 407.831412 -398.236446) (xy 407.880267 -398.242378) (xy 407.927538 -398.25607) (xy 407.972 -398.277168)
			(xy 408.012503 -398.305124) (xy 408.047996 -398.339216) (xy 408.077561 -398.37856) (xy 408.100432 -398.422137)
			(xy 408.116016 -398.468818) (xy 408.123911 -398.517395) (xy 408.124406 -398.542002) (xy 408.71319 -398.542002)
			(xy 408.71715 -398.492948) (xy 408.728927 -398.445164) (xy 408.748218 -398.399888) (xy 408.774521 -398.358292)
			(xy 408.807156 -398.321455) (xy 408.845277 -398.29033) (xy 408.887898 -398.265723) (xy 408.933914 -398.248271)
			(xy 408.982133 -398.238427) (xy 409.031308 -398.236446) (xy 409.080163 -398.242378) (xy 409.127434 -398.25607)
			(xy 409.171896 -398.277168) (xy 409.212399 -398.305124) (xy 409.247892 -398.339216) (xy 409.277457 -398.37856)
			(xy 409.300328 -398.422137) (xy 409.315912 -398.468818) (xy 409.323807 -398.517395) (xy 409.324302 -398.542002)
			(xy 409.913086 -398.542002) (xy 409.917046 -398.492948) (xy 409.928823 -398.445164) (xy 409.948114 -398.399888)
			(xy 409.974417 -398.358292) (xy 410.007052 -398.321455) (xy 410.045173 -398.29033) (xy 410.087794 -398.265723)
			(xy 410.13381 -398.248271) (xy 410.182029 -398.238427) (xy 410.231204 -398.236446) (xy 410.280059 -398.242378)
			(xy 410.32733 -398.25607) (xy 410.371792 -398.277168) (xy 410.412295 -398.305124) (xy 410.447788 -398.339216)
			(xy 410.477353 -398.37856) (xy 410.500224 -398.422137) (xy 410.515808 -398.468818) (xy 410.523703 -398.517395)
			(xy 410.524198 -398.542002) (xy 411.113236 -398.542002) (xy 411.117196 -398.492948) (xy 411.128973 -398.445164)
			(xy 411.148264 -398.399888) (xy 411.174567 -398.358292) (xy 411.207202 -398.321455) (xy 411.245323 -398.29033)
			(xy 411.287944 -398.265723) (xy 411.33396 -398.248271) (xy 411.382179 -398.238427) (xy 411.431354 -398.236446)
			(xy 411.480209 -398.242378) (xy 411.52748 -398.25607) (xy 411.571942 -398.277168) (xy 411.612445 -398.305124)
			(xy 411.647938 -398.339216) (xy 411.677503 -398.37856) (xy 411.700374 -398.422137) (xy 411.715958 -398.468818)
			(xy 411.723853 -398.517395) (xy 411.724348 -398.542002) (xy 412.313132 -398.542002) (xy 412.317092 -398.492948)
			(xy 412.328869 -398.445164) (xy 412.34816 -398.399888) (xy 412.374463 -398.358292) (xy 412.407098 -398.321455)
			(xy 412.445219 -398.29033) (xy 412.48784 -398.265723) (xy 412.533856 -398.248271) (xy 412.582075 -398.238427)
			(xy 412.63125 -398.236446) (xy 412.680105 -398.242378) (xy 412.727376 -398.25607) (xy 412.771838 -398.277168)
			(xy 412.812341 -398.305124) (xy 412.847834 -398.339216) (xy 412.877399 -398.37856) (xy 412.90027 -398.422137)
			(xy 412.915854 -398.468818) (xy 412.923749 -398.517395) (xy 412.924244 -398.542002) (xy 413.513282 -398.542002)
			(xy 413.517242 -398.492948) (xy 413.529019 -398.445164) (xy 413.54831 -398.399888) (xy 413.574613 -398.358292)
			(xy 413.607248 -398.321455) (xy 413.645369 -398.29033) (xy 413.68799 -398.265723) (xy 413.734006 -398.248271)
			(xy 413.782225 -398.238427) (xy 413.8314 -398.236446) (xy 413.880255 -398.242378) (xy 413.927526 -398.25607)
			(xy 413.971988 -398.277168) (xy 414.012491 -398.305124) (xy 414.047984 -398.339216) (xy 414.077549 -398.37856)
			(xy 414.10042 -398.422137) (xy 414.116004 -398.468818) (xy 414.123899 -398.517395) (xy 414.124394 -398.542002)
			(xy 414.713178 -398.542002) (xy 414.717138 -398.492948) (xy 414.728915 -398.445164) (xy 414.748206 -398.399888)
			(xy 414.774509 -398.358292) (xy 414.807144 -398.321455) (xy 414.845265 -398.29033) (xy 414.887886 -398.265723)
			(xy 414.933902 -398.248271) (xy 414.982121 -398.238427) (xy 415.031296 -398.236446) (xy 415.080151 -398.242378)
			(xy 415.127422 -398.25607) (xy 415.171884 -398.277168) (xy 415.212387 -398.305124) (xy 415.24788 -398.339216)
			(xy 415.277445 -398.37856) (xy 415.300316 -398.422137) (xy 415.3159 -398.468818) (xy 415.323795 -398.517395)
			(xy 415.32429 -398.542002) (xy 415.913074 -398.542002) (xy 415.917034 -398.492948) (xy 415.928811 -398.445164)
			(xy 415.948102 -398.399888) (xy 415.974405 -398.358292) (xy 416.00704 -398.321455) (xy 416.045161 -398.29033)
			(xy 416.087782 -398.265723) (xy 416.133798 -398.248271) (xy 416.182017 -398.238427) (xy 416.231192 -398.236446)
			(xy 416.280047 -398.242378) (xy 416.327318 -398.25607) (xy 416.37178 -398.277168) (xy 416.412283 -398.305124)
			(xy 416.447776 -398.339216) (xy 416.477341 -398.37856) (xy 416.500212 -398.422137) (xy 416.515796 -398.468818)
			(xy 416.523691 -398.517395) (xy 416.524186 -398.542002) (xy 417.113224 -398.542002) (xy 417.117184 -398.492948)
			(xy 417.128961 -398.445164) (xy 417.148252 -398.399888) (xy 417.174555 -398.358292) (xy 417.20719 -398.321455)
			(xy 417.245311 -398.29033) (xy 417.287932 -398.265723) (xy 417.333948 -398.248271) (xy 417.382167 -398.238427)
			(xy 417.431342 -398.236446) (xy 417.480197 -398.242378) (xy 417.527468 -398.25607) (xy 417.57193 -398.277168)
			(xy 417.612433 -398.305124) (xy 417.647926 -398.339216) (xy 417.677491 -398.37856) (xy 417.700362 -398.422137)
			(xy 417.715946 -398.468818) (xy 417.723841 -398.517395) (xy 417.724336 -398.542002) (xy 418.31312 -398.542002)
			(xy 418.31708 -398.492948) (xy 418.328857 -398.445164) (xy 418.348148 -398.399888) (xy 418.374451 -398.358292)
			(xy 418.407086 -398.321455) (xy 418.445207 -398.29033) (xy 418.487828 -398.265723) (xy 418.533844 -398.248271)
			(xy 418.582063 -398.238427) (xy 418.631238 -398.236446) (xy 418.680093 -398.242378) (xy 418.727364 -398.25607)
			(xy 418.771826 -398.277168) (xy 418.812329 -398.305124) (xy 418.847822 -398.339216) (xy 418.877387 -398.37856)
			(xy 418.900258 -398.422137) (xy 418.915842 -398.468818) (xy 418.923737 -398.517395) (xy 418.924232 -398.542002)
			(xy 419.51327 -398.542002) (xy 419.51723 -398.492948) (xy 419.529007 -398.445164) (xy 419.548298 -398.399888)
			(xy 419.574601 -398.358292) (xy 419.607236 -398.321455) (xy 419.645357 -398.29033) (xy 419.687978 -398.265723)
			(xy 419.733994 -398.248271) (xy 419.782213 -398.238427) (xy 419.831388 -398.236446) (xy 419.880243 -398.242378)
			(xy 419.927514 -398.25607) (xy 419.971976 -398.277168) (xy 420.012479 -398.305124) (xy 420.047972 -398.339216)
			(xy 420.077537 -398.37856) (xy 420.100408 -398.422137) (xy 420.115992 -398.468818) (xy 420.123887 -398.517395)
			(xy 420.124382 -398.542002) (xy 420.713166 -398.542002) (xy 420.717126 -398.492948) (xy 420.728903 -398.445164)
			(xy 420.748194 -398.399888) (xy 420.774497 -398.358292) (xy 420.807132 -398.321455) (xy 420.845253 -398.29033)
			(xy 420.887874 -398.265723) (xy 420.93389 -398.248271) (xy 420.982109 -398.238427) (xy 421.031284 -398.236446)
			(xy 421.080139 -398.242378) (xy 421.12741 -398.25607) (xy 421.171872 -398.277168) (xy 421.212375 -398.305124)
			(xy 421.247868 -398.339216) (xy 421.277433 -398.37856) (xy 421.300304 -398.422137) (xy 421.315888 -398.468818)
			(xy 421.323783 -398.517395) (xy 421.324278 -398.542002) (xy 421.323783 -398.566609) (xy 421.323559 -398.567989)
			(xy 422.042846 -398.567989) (xy 422.042846 -398.516015) (xy 422.050976 -398.46468) (xy 422.067037 -398.41525)
			(xy 422.090633 -398.36894) (xy 422.121183 -398.326892) (xy 422.157934 -398.290141) (xy 422.199982 -398.259591)
			(xy 422.246292 -398.235995) (xy 422.295722 -398.219934) (xy 422.347057 -398.211804) (xy 422.399031 -398.211804)
			(xy 422.450366 -398.219934) (xy 422.499796 -398.235995) (xy 422.546106 -398.259591) (xy 422.588154 -398.290141)
			(xy 422.624905 -398.326892) (xy 422.655455 -398.36894) (xy 422.679051 -398.41525) (xy 422.695112 -398.46468)
			(xy 422.703242 -398.516015) (xy 422.703752 -398.542002) (xy 422.703242 -398.567989) (xy 422.695112 -398.619324)
			(xy 422.679051 -398.668754) (xy 422.655455 -398.715064) (xy 422.624905 -398.757112) (xy 422.588154 -398.793863)
			(xy 422.546106 -398.824413) (xy 422.499796 -398.848009) (xy 422.450366 -398.86407) (xy 422.399031 -398.8722)
			(xy 422.347057 -398.8722) (xy 422.295722 -398.86407) (xy 422.246292 -398.848009) (xy 422.199982 -398.824413)
			(xy 422.157934 -398.793863) (xy 422.121183 -398.757112) (xy 422.090633 -398.715064) (xy 422.067037 -398.668754)
			(xy 422.050976 -398.619324) (xy 422.042846 -398.567989) (xy 421.323559 -398.567989) (xy 421.315888 -398.615186)
			(xy 421.300304 -398.661867) (xy 421.277433 -398.705444) (xy 421.247868 -398.744788) (xy 421.212375 -398.77888)
			(xy 421.171872 -398.806836) (xy 421.12741 -398.827934) (xy 421.080139 -398.841626) (xy 421.031284 -398.847558)
			(xy 420.982109 -398.845577) (xy 420.93389 -398.835733) (xy 420.887874 -398.818281) (xy 420.845253 -398.793674)
			(xy 420.807132 -398.762549) (xy 420.774497 -398.725712) (xy 420.748194 -398.684116) (xy 420.728903 -398.63884)
			(xy 420.717126 -398.591056) (xy 420.713166 -398.542002) (xy 420.124382 -398.542002) (xy 420.123887 -398.566609)
			(xy 420.115992 -398.615186) (xy 420.100408 -398.661867) (xy 420.077537 -398.705444) (xy 420.047972 -398.744788)
			(xy 420.012479 -398.77888) (xy 419.971976 -398.806836) (xy 419.927514 -398.827934) (xy 419.880243 -398.841626)
			(xy 419.831388 -398.847558) (xy 419.782213 -398.845577) (xy 419.733994 -398.835733) (xy 419.687978 -398.818281)
			(xy 419.645357 -398.793674) (xy 419.607236 -398.762549) (xy 419.574601 -398.725712) (xy 419.548298 -398.684116)
			(xy 419.529007 -398.63884) (xy 419.51723 -398.591056) (xy 419.51327 -398.542002) (xy 418.924232 -398.542002)
			(xy 418.923737 -398.566609) (xy 418.915842 -398.615186) (xy 418.900258 -398.661867) (xy 418.877387 -398.705444)
			(xy 418.847822 -398.744788) (xy 418.812329 -398.77888) (xy 418.771826 -398.806836) (xy 418.727364 -398.827934)
			(xy 418.680093 -398.841626) (xy 418.631238 -398.847558) (xy 418.582063 -398.845577) (xy 418.533844 -398.835733)
			(xy 418.487828 -398.818281) (xy 418.445207 -398.793674) (xy 418.407086 -398.762549) (xy 418.374451 -398.725712)
			(xy 418.348148 -398.684116) (xy 418.328857 -398.63884) (xy 418.31708 -398.591056) (xy 418.31312 -398.542002)
			(xy 417.724336 -398.542002) (xy 417.723841 -398.566609) (xy 417.715946 -398.615186) (xy 417.700362 -398.661867)
			(xy 417.677491 -398.705444) (xy 417.647926 -398.744788) (xy 417.612433 -398.77888) (xy 417.57193 -398.806836)
			(xy 417.527468 -398.827934) (xy 417.480197 -398.841626) (xy 417.431342 -398.847558) (xy 417.382167 -398.845577)
			(xy 417.333948 -398.835733) (xy 417.287932 -398.818281) (xy 417.245311 -398.793674) (xy 417.20719 -398.762549)
			(xy 417.174555 -398.725712) (xy 417.148252 -398.684116) (xy 417.128961 -398.63884) (xy 417.117184 -398.591056)
			(xy 417.113224 -398.542002) (xy 416.524186 -398.542002) (xy 416.523691 -398.566609) (xy 416.515796 -398.615186)
			(xy 416.500212 -398.661867) (xy 416.477341 -398.705444) (xy 416.447776 -398.744788) (xy 416.412283 -398.77888)
			(xy 416.37178 -398.806836) (xy 416.327318 -398.827934) (xy 416.280047 -398.841626) (xy 416.231192 -398.847558)
			(xy 416.182017 -398.845577) (xy 416.133798 -398.835733) (xy 416.087782 -398.818281) (xy 416.045161 -398.793674)
			(xy 416.00704 -398.762549) (xy 415.974405 -398.725712) (xy 415.948102 -398.684116) (xy 415.928811 -398.63884)
			(xy 415.917034 -398.591056) (xy 415.913074 -398.542002) (xy 415.32429 -398.542002) (xy 415.323795 -398.566609)
			(xy 415.3159 -398.615186) (xy 415.300316 -398.661867) (xy 415.277445 -398.705444) (xy 415.24788 -398.744788)
			(xy 415.212387 -398.77888) (xy 415.171884 -398.806836) (xy 415.127422 -398.827934) (xy 415.080151 -398.841626)
			(xy 415.031296 -398.847558) (xy 414.982121 -398.845577) (xy 414.933902 -398.835733) (xy 414.887886 -398.818281)
			(xy 414.845265 -398.793674) (xy 414.807144 -398.762549) (xy 414.774509 -398.725712) (xy 414.748206 -398.684116)
			(xy 414.728915 -398.63884) (xy 414.717138 -398.591056) (xy 414.713178 -398.542002) (xy 414.124394 -398.542002)
			(xy 414.123899 -398.566609) (xy 414.116004 -398.615186) (xy 414.10042 -398.661867) (xy 414.077549 -398.705444)
			(xy 414.047984 -398.744788) (xy 414.012491 -398.77888) (xy 413.971988 -398.806836) (xy 413.927526 -398.827934)
			(xy 413.880255 -398.841626) (xy 413.8314 -398.847558) (xy 413.782225 -398.845577) (xy 413.734006 -398.835733)
			(xy 413.68799 -398.818281) (xy 413.645369 -398.793674) (xy 413.607248 -398.762549) (xy 413.574613 -398.725712)
			(xy 413.54831 -398.684116) (xy 413.529019 -398.63884) (xy 413.517242 -398.591056) (xy 413.513282 -398.542002)
			(xy 412.924244 -398.542002) (xy 412.923749 -398.566609) (xy 412.915854 -398.615186) (xy 412.90027 -398.661867)
			(xy 412.877399 -398.705444) (xy 412.847834 -398.744788) (xy 412.812341 -398.77888) (xy 412.771838 -398.806836)
			(xy 412.727376 -398.827934) (xy 412.680105 -398.841626) (xy 412.63125 -398.847558) (xy 412.582075 -398.845577)
			(xy 412.533856 -398.835733) (xy 412.48784 -398.818281) (xy 412.445219 -398.793674) (xy 412.407098 -398.762549)
			(xy 412.374463 -398.725712) (xy 412.34816 -398.684116) (xy 412.328869 -398.63884) (xy 412.317092 -398.591056)
			(xy 412.313132 -398.542002) (xy 411.724348 -398.542002) (xy 411.723853 -398.566609) (xy 411.715958 -398.615186)
			(xy 411.700374 -398.661867) (xy 411.677503 -398.705444) (xy 411.647938 -398.744788) (xy 411.612445 -398.77888)
			(xy 411.571942 -398.806836) (xy 411.52748 -398.827934) (xy 411.480209 -398.841626) (xy 411.431354 -398.847558)
			(xy 411.382179 -398.845577) (xy 411.33396 -398.835733) (xy 411.287944 -398.818281) (xy 411.245323 -398.793674)
			(xy 411.207202 -398.762549) (xy 411.174567 -398.725712) (xy 411.148264 -398.684116) (xy 411.128973 -398.63884)
			(xy 411.117196 -398.591056) (xy 411.113236 -398.542002) (xy 410.524198 -398.542002) (xy 410.523703 -398.566609)
			(xy 410.515808 -398.615186) (xy 410.500224 -398.661867) (xy 410.477353 -398.705444) (xy 410.447788 -398.744788)
			(xy 410.412295 -398.77888) (xy 410.371792 -398.806836) (xy 410.32733 -398.827934) (xy 410.280059 -398.841626)
			(xy 410.231204 -398.847558) (xy 410.182029 -398.845577) (xy 410.13381 -398.835733) (xy 410.087794 -398.818281)
			(xy 410.045173 -398.793674) (xy 410.007052 -398.762549) (xy 409.974417 -398.725712) (xy 409.948114 -398.684116)
			(xy 409.928823 -398.63884) (xy 409.917046 -398.591056) (xy 409.913086 -398.542002) (xy 409.324302 -398.542002)
			(xy 409.323807 -398.566609) (xy 409.315912 -398.615186) (xy 409.300328 -398.661867) (xy 409.277457 -398.705444)
			(xy 409.247892 -398.744788) (xy 409.212399 -398.77888) (xy 409.171896 -398.806836) (xy 409.127434 -398.827934)
			(xy 409.080163 -398.841626) (xy 409.031308 -398.847558) (xy 408.982133 -398.845577) (xy 408.933914 -398.835733)
			(xy 408.887898 -398.818281) (xy 408.845277 -398.793674) (xy 408.807156 -398.762549) (xy 408.774521 -398.725712)
			(xy 408.748218 -398.684116) (xy 408.728927 -398.63884) (xy 408.71715 -398.591056) (xy 408.71319 -398.542002)
			(xy 408.124406 -398.542002) (xy 408.123911 -398.566609) (xy 408.116016 -398.615186) (xy 408.100432 -398.661867)
			(xy 408.077561 -398.705444) (xy 408.047996 -398.744788) (xy 408.012503 -398.77888) (xy 407.972 -398.806836)
			(xy 407.927538 -398.827934) (xy 407.880267 -398.841626) (xy 407.831412 -398.847558) (xy 407.782237 -398.845577)
			(xy 407.734018 -398.835733) (xy 407.688002 -398.818281) (xy 407.645381 -398.793674) (xy 407.60726 -398.762549)
			(xy 407.574625 -398.725712) (xy 407.548322 -398.684116) (xy 407.529031 -398.63884) (xy 407.517254 -398.591056)
			(xy 407.513294 -398.542002) (xy 406.924256 -398.542002) (xy 406.923761 -398.566609) (xy 406.915866 -398.615186)
			(xy 406.900282 -398.661867) (xy 406.877411 -398.705444) (xy 406.847846 -398.744788) (xy 406.812353 -398.77888)
			(xy 406.77185 -398.806836) (xy 406.727388 -398.827934) (xy 406.680117 -398.841626) (xy 406.631262 -398.847558)
			(xy 406.582087 -398.845577) (xy 406.533868 -398.835733) (xy 406.487852 -398.818281) (xy 406.445231 -398.793674)
			(xy 406.40711 -398.762549) (xy 406.374475 -398.725712) (xy 406.348172 -398.684116) (xy 406.328881 -398.63884)
			(xy 406.317104 -398.591056) (xy 406.313144 -398.542002) (xy 405.72436 -398.542002) (xy 405.723865 -398.566609)
			(xy 405.71597 -398.615186) (xy 405.700386 -398.661867) (xy 405.677515 -398.705444) (xy 405.64795 -398.744788)
			(xy 405.612457 -398.77888) (xy 405.571954 -398.806836) (xy 405.527492 -398.827934) (xy 405.480221 -398.841626)
			(xy 405.431366 -398.847558) (xy 405.382191 -398.845577) (xy 405.333972 -398.835733) (xy 405.287956 -398.818281)
			(xy 405.245335 -398.793674) (xy 405.207214 -398.762549) (xy 405.174579 -398.725712) (xy 405.148276 -398.684116)
			(xy 405.128985 -398.63884) (xy 405.117208 -398.591056) (xy 405.113248 -398.542002) (xy 404.52421 -398.542002)
			(xy 404.523715 -398.566609) (xy 404.51582 -398.615186) (xy 404.500236 -398.661867) (xy 404.477365 -398.705444)
			(xy 404.4478 -398.744788) (xy 404.412307 -398.77888) (xy 404.371804 -398.806836) (xy 404.327342 -398.827934)
			(xy 404.280071 -398.841626) (xy 404.231216 -398.847558) (xy 404.182041 -398.845577) (xy 404.133822 -398.835733)
			(xy 404.087806 -398.818281) (xy 404.045185 -398.793674) (xy 404.007064 -398.762549) (xy 403.974429 -398.725712)
			(xy 403.948126 -398.684116) (xy 403.928835 -398.63884) (xy 403.917058 -398.591056) (xy 403.913098 -398.542002)
			(xy 403.32406 -398.542002) (xy 403.323565 -398.566609) (xy 403.31567 -398.615186) (xy 403.300086 -398.661867)
			(xy 403.277215 -398.705444) (xy 403.24765 -398.744788) (xy 403.212157 -398.77888) (xy 403.171654 -398.806836)
			(xy 403.127192 -398.827934) (xy 403.079921 -398.841626) (xy 403.031066 -398.847558) (xy 402.981891 -398.845577)
			(xy 402.933672 -398.835733) (xy 402.887656 -398.818281) (xy 402.845035 -398.793674) (xy 402.806914 -398.762549)
			(xy 402.774279 -398.725712) (xy 402.747976 -398.684116) (xy 402.728685 -398.63884) (xy 402.716908 -398.591056)
			(xy 402.712948 -398.542002) (xy 401.16954 -398.542002) (xy 401.168596 -398.548469) (xy 401.149518 -398.61226)
			(xy 401.121386 -398.672608) (xy 401.103592 -398.700752) (xy 401.098544 -398.709276) (xy 401.094722 -398.728693)
			(xy 401.098539 -398.748112) (xy 401.103592 -398.756632) (xy 401.12136 -398.784787) (xy 401.149457 -398.845144)
			(xy 401.168528 -398.90893) (xy 401.178173 -398.974804) (xy 401.178776 -399.008092) (xy 401.178335 -399.037392)
			(xy 401.170887 -399.095516) (xy 401.156063 -399.152208) (xy 401.145502 -399.179542) (xy 401.141438 -399.189194)
			(xy 401.141946 -399.20926) (xy 401.179792 -399.295112) (xy 401.19427 -399.309082) (xy 401.204176 -399.312638)
			(xy 401.227555 -399.321794) (xy 401.271398 -399.34626) (xy 401.311042 -399.377071) (xy 401.345574 -399.413518)
			(xy 401.374202 -399.454766) (xy 401.396268 -399.499865) (xy 401.411265 -399.547781) (xy 401.41885 -399.597414)
			(xy 401.419314 -399.622518) (xy 401.418804 -399.648505) (xy 401.410674 -399.69984) (xy 401.394613 -399.74927)
			(xy 401.371017 -399.79558) (xy 401.340467 -399.837628) (xy 401.303716 -399.874379) (xy 401.261668 -399.904929)
			(xy 401.215358 -399.928525) (xy 401.165928 -399.944586) (xy 401.114593 -399.952716) (xy 401.062619 -399.952716)
			(xy 401.011284 -399.944586) (xy 400.961854 -399.928525) (xy 400.915544 -399.904929) (xy 400.873496 -399.874379)
			(xy 400.836745 -399.837628) (xy 400.806195 -399.79558) (xy 400.782599 -399.74927) (xy 400.766538 -399.69984)
			(xy 400.758408 -399.648505) (xy 400.757898 -399.622518) (xy 400.757999 -399.611307) (xy 400.759525 -399.588936)
			(xy 400.760946 -399.577814) (xy 400.76247 -399.5674) (xy 400.757136 -399.547842) (xy 400.699478 -399.473928)
			(xy 400.681698 -399.464276) (xy 400.671284 -399.463006) (xy 400.641104 -399.459148) (xy 400.582028 -399.444593)
			(xy 400.525403 -399.422337) (xy 400.472227 -399.392773) (xy 400.423439 -399.356422) (xy 400.379898 -399.313926)
			(xy 400.342374 -399.266034) (xy 400.311528 -399.213591) (xy 400.287905 -399.157523) (xy 400.271921 -399.098818)
			(xy 400.263859 -399.038513) (xy 400.26336 -399.008092) (xy 397.467133 -399.008092) (xy 397.475844 -399.012215)
			(xy 397.5208 -399.041872) (xy 397.561137 -399.077557) (xy 397.596055 -399.11856) (xy 397.624859 -399.164067)
			(xy 397.646976 -399.213172) (xy 397.661968 -399.2649) (xy 397.669535 -399.318222) (xy 397.67002 -399.34515)
			(xy 397.668496 -399.378932) (xy 397.66748 -399.3896) (xy 397.674084 -399.409412) (xy 397.737584 -399.480532)
			(xy 397.756634 -399.489422) (xy 397.767302 -399.489676) (xy 397.796704 -399.490832) (xy 397.854966 -399.499086)
			(xy 397.911884 -399.514012) (xy 397.966699 -399.535411) (xy 398.018675 -399.562997) (xy 398.043146 -399.579338)
			(xy 398.051898 -399.584809) (xy 398.072102 -399.588937) (xy 398.092306 -399.584809) (xy 398.101058 -399.579338)
			(xy 398.126584 -399.56228) (xy 398.180946 -399.533746) (xy 398.238349 -399.511971) (xy 398.297958 -399.497271)
			(xy 398.358905 -399.489861) (xy 398.389602 -399.489422) (xy 398.420297 -399.489901) (xy 398.481238 -399.497321)
			(xy 398.540843 -399.512019) (xy 398.598248 -399.533779) (xy 398.652619 -399.562286) (xy 398.678146 -399.579338)
			(xy 398.686898 -399.584809) (xy 398.707102 -399.588937) (xy 398.727306 -399.584809) (xy 398.736058 -399.579338)
			(xy 398.761584 -399.56228) (xy 398.815946 -399.533746) (xy 398.873349 -399.511971) (xy 398.932958 -399.497271)
			(xy 398.993905 -399.489861) (xy 399.024602 -399.489422) (xy 399.055333 -399.489868) (xy 399.116348 -399.497277)
			(xy 399.176025 -399.511987) (xy 399.233493 -399.533782) (xy 399.287915 -399.562347) (xy 399.338497 -399.597263)
			(xy 399.384501 -399.638022) (xy 399.425257 -399.684028) (xy 399.46017 -399.734613) (xy 399.488731 -399.789036)
			(xy 399.510523 -399.846506) (xy 399.525229 -399.906184) (xy 399.532634 -399.967199) (xy 399.53311 -399.99793)
			(xy 399.532535 -400.03214) (xy 399.523335 -400.099938) (xy 399.505144 -400.165896) (xy 399.492216 -400.197574)
			(xy 399.488152 -400.207226) (xy 399.488152 -400.21764) (xy 399.488646 -400.227646) (xy 399.496311 -400.246132)
			(xy 399.510461 -400.260284) (xy 399.528946 -400.267952) (xy 399.538952 -400.26844) (xy 399.616676 -400.26844)
			(xy 399.637504 -400.258534) (xy 399.644616 -400.24939) (xy 399.665372 -400.224359) (xy 399.71221 -400.179252)
			(xy 399.764413 -400.14048) (xy 399.821131 -400.108676) (xy 399.881439 -400.084358) (xy 399.944354 -400.067922)
			(xy 400.008851 -400.059637) (xy 400.073877 -400.059637) (xy 400.138374 -400.067922) (xy 400.201289 -400.084358)
			(xy 400.261597 -400.108676) (xy 400.318315 -400.14048) (xy 400.370518 -400.179252) (xy 400.417356 -400.224359)
			(xy 400.438112 -400.24939) (xy 400.445747 -400.257896) (xy 400.466324 -400.267774) (xy 400.477736 -400.26844)
			(xy 401.690332 -400.26844) (xy 401.70049 -400.267994) (xy 401.719226 -400.260142) (xy 401.726654 -400.2532)
			(xy 401.78482 -400.194018) (xy 401.792186 -400.175222) (xy 401.791932 -400.164808) (xy 401.791932 -400.15795)
			(xy 401.792442 -400.131963) (xy 401.800572 -400.080628) (xy 401.816633 -400.031198) (xy 401.840229 -399.984888)
			(xy 401.870779 -399.94284) (xy 401.90753 -399.906089) (xy 401.949578 -399.875539) (xy 401.995888 -399.851943)
			(xy 402.045318 -399.835882) (xy 402.096653 -399.827752) (xy 402.148627 -399.827752) (xy 402.199962 -399.835882)
			(xy 402.249392 -399.851943) (xy 402.295702 -399.875539) (xy 402.33775 -399.906089) (xy 402.374501 -399.94284)
			(xy 402.405051 -399.984888) (xy 402.428647 -400.031198) (xy 402.444708 -400.080628) (xy 402.452838 -400.131963)
			(xy 402.453348 -400.15795) (xy 402.453348 -400.164808) (xy 402.453094 -400.175222) (xy 402.46046 -400.194018)
			(xy 402.518626 -400.2532) (xy 402.526053 -400.260143) (xy 402.54479 -400.26799) (xy 402.554948 -400.26844)
			(xy 403.088094 -400.26844) (xy 403.098105 -400.267954) (xy 403.116606 -400.260297) (xy 403.130771 -400.246145)
			(xy 403.138444 -400.227651) (xy 403.138894 -400.21764) (xy 403.138894 -400.216878) (xy 403.138894 -400.212814)
			(xy 403.139416 -400.187559) (xy 403.147729 -400.137737) (xy 403.16413 -400.089963) (xy 403.188171 -400.04554)
			(xy 403.219195 -400.00568) (xy 403.256357 -399.97147) (xy 403.298643 -399.943844) (xy 403.344899 -399.923554)
			(xy 403.393864 -399.911154) (xy 403.444202 -399.906983) (xy 403.49454 -399.911154) (xy 403.543505 -399.923554)
			(xy 403.589761 -399.943844) (xy 403.632047 -399.97147) (xy 403.669209 -400.00568) (xy 403.700233 -400.04554)
			(xy 403.724274 -400.089963) (xy 403.740675 -400.137737) (xy 403.748988 -400.187559) (xy 403.74951 -400.212814)
			(xy 403.74951 -400.21764) (xy 403.750005 -400.227642) (xy 403.757672 -400.246118) (xy 403.771824 -400.260256)
			(xy 403.790308 -400.267905) (xy 403.80031 -400.26844) (xy 404.288244 -400.26844) (xy 404.298249 -400.267945)
			(xy 404.316732 -400.260279) (xy 404.330881 -400.246129) (xy 404.338546 -400.227645) (xy 404.339044 -400.21764)
			(xy 404.339044 -400.216878) (xy 404.339044 -400.212814) (xy 404.339566 -400.187559) (xy 404.347879 -400.137737)
			(xy 404.36428 -400.089963) (xy 404.388321 -400.04554) (xy 404.419345 -400.00568) (xy 404.456507 -399.97147)
			(xy 404.498793 -399.943844) (xy 404.545049 -399.923554) (xy 404.594014 -399.911154) (xy 404.644352 -399.906983)
			(xy 404.69469 -399.911154) (xy 404.743655 -399.923554) (xy 404.789911 -399.943844) (xy 404.832197 -399.97147)
			(xy 404.869359 -400.00568) (xy 404.900383 -400.04554) (xy 404.924424 -400.089963) (xy 404.940825 -400.137737)
			(xy 404.949138 -400.187559) (xy 404.94966 -400.212814) (xy 404.949182 -400.237216) (xy 404.941422 -400.285398)
			(xy 404.926103 -400.331734) (xy 404.903613 -400.375047) (xy 404.889462 -400.394932) (xy 404.883874 -400.402552)
			(xy 404.878794 -400.420332) (xy 404.886922 -400.5072) (xy 404.895304 -400.52371) (xy 404.902416 -400.530314)
			(xy 404.921509 -400.548447) (xy 404.955027 -400.589057) (xy 404.982641 -400.63389) (xy 405.003826 -400.682096)
			(xy 405.018181 -400.732757) (xy 405.025431 -400.78491) (xy 405.02586 -400.811238) (xy 405.02586 -400.986498)
			(xy 405.026333 -400.996467) (xy 405.033899 -401.014912) (xy 405.040592 -401.022312) (xy 405.375872 -401.357592)
			(xy 405.383235 -401.364421) (xy 405.401746 -401.372165) (xy 405.421812 -401.372214) (xy 405.431244 -401.368768)
			(xy 405.445722 -401.362672) (xy 405.46274 -401.337272) (xy 405.46274 -400.811238) (xy 405.46318 -400.784891)
			(xy 405.47042 -400.732698) (xy 405.484767 -400.681996) (xy 405.50595 -400.633748) (xy 405.533565 -400.588871)
			(xy 405.567088 -400.548217) (xy 405.586184 -400.53006) (xy 405.593296 -400.52371) (xy 405.601424 -400.506946)
			(xy 405.609806 -400.420332) (xy 405.604726 -400.402552) (xy 405.599138 -400.394678) (xy 405.584981 -400.374833)
			(xy 405.562496 -400.331585) (xy 405.547179 -400.285309) (xy 405.53942 -400.237186) (xy 405.53894 -400.212814)
			(xy 405.539462 -400.187559) (xy 405.547775 -400.137737) (xy 405.564176 -400.089963) (xy 405.588217 -400.04554)
			(xy 405.619241 -400.00568) (xy 405.656403 -399.97147) (xy 405.698689 -399.943844) (xy 405.744945 -399.923554)
			(xy 405.79391 -399.911154) (xy 405.844248 -399.906983) (xy 405.894586 -399.911154) (xy 405.943551 -399.923554)
			(xy 405.989807 -399.943844) (xy 406.032093 -399.97147) (xy 406.069255 -400.00568) (xy 406.100279 -400.04554)
			(xy 406.12432 -400.089963) (xy 406.140721 -400.137737) (xy 406.149034 -400.187559) (xy 406.149556 -400.212814)
			(xy 406.149058 -400.237184) (xy 406.141278 -400.2853) (xy 406.125966 -400.331573) (xy 406.103509 -400.374832)
			(xy 406.089358 -400.394678) (xy 406.08377 -400.402552) (xy 406.07869 -400.420332) (xy 406.087072 -400.506946)
			(xy 406.0952 -400.52371) (xy 406.102312 -400.53006) (xy 406.121402 -400.548221) (xy 406.154911 -400.588882)
			(xy 406.182516 -400.633761) (xy 406.203694 -400.682007) (xy 406.218043 -400.732705) (xy 406.22529 -400.784893)
			(xy 406.225756 -400.811238) (xy 406.225756 -401.674838) (xy 406.662636 -401.674838) (xy 406.662636 -400.811238)
			(xy 406.663105 -400.784893) (xy 406.670352 -400.732705) (xy 406.6847 -400.682007) (xy 406.705877 -400.633761)
			(xy 406.733482 -400.588882) (xy 406.76699 -400.548221) (xy 406.78608 -400.53006) (xy 406.793192 -400.52371)
			(xy 406.80132 -400.506946) (xy 406.809702 -400.420332) (xy 406.804622 -400.402552) (xy 406.799034 -400.394678)
			(xy 406.784882 -400.374833) (xy 406.762425 -400.331573) (xy 406.747114 -400.2853) (xy 406.739334 -400.237184)
			(xy 406.738836 -400.212814) (xy 406.739358 -400.187559) (xy 406.747671 -400.137737) (xy 406.764072 -400.089963)
			(xy 406.788113 -400.04554) (xy 406.819137 -400.00568) (xy 406.856299 -399.97147) (xy 406.898585 -399.943844)
			(xy 406.944841 -399.923554) (xy 406.993806 -399.911154) (xy 407.044144 -399.906983) (xy 407.094482 -399.911154)
			(xy 407.143447 -399.923554) (xy 407.189703 -399.943844) (xy 407.231989 -399.97147) (xy 407.269151 -400.00568)
			(xy 407.300175 -400.04554) (xy 407.324216 -400.089963) (xy 407.340617 -400.137737) (xy 407.34893 -400.187559)
			(xy 407.349452 -400.212814) (xy 407.348973 -400.237186) (xy 407.341215 -400.285309) (xy 407.325897 -400.331585)
			(xy 407.303411 -400.374833) (xy 407.289254 -400.394678) (xy 407.283666 -400.402552) (xy 407.278586 -400.420332)
			(xy 407.286968 -400.506946) (xy 407.295096 -400.52371) (xy 407.302208 -400.53006) (xy 407.321303 -400.548218)
			(xy 407.354826 -400.588872) (xy 407.382442 -400.633749) (xy 407.403624 -400.681996) (xy 407.417972 -400.732698)
			(xy 407.425212 -400.784892) (xy 407.425652 -400.811238) (xy 407.425652 -401.674838) (xy 407.862532 -401.674838)
			(xy 407.862532 -400.811238) (xy 407.863014 -400.784883) (xy 407.870277 -400.732674) (xy 407.884656 -400.681962)
			(xy 407.905877 -400.633711) (xy 407.933536 -400.58884) (xy 407.967108 -400.548203) (xy 407.98623 -400.53006)
			(xy 407.993342 -400.52371) (xy 408.00147 -400.506946) (xy 408.009852 -400.420332) (xy 408.004772 -400.402552)
			(xy 407.999184 -400.394678) (xy 407.985038 -400.374828) (xy 407.962579 -400.331571) (xy 407.947265 -400.285299)
			(xy 407.939485 -400.237184) (xy 407.938986 -400.212814) (xy 407.939508 -400.187559) (xy 407.947821 -400.137737)
			(xy 407.964222 -400.089963) (xy 407.988263 -400.04554) (xy 408.019287 -400.00568) (xy 408.056449 -399.97147)
			(xy 408.098735 -399.943844) (xy 408.144991 -399.923554) (xy 408.193956 -399.911154) (xy 408.244294 -399.906983)
			(xy 408.294632 -399.911154) (xy 408.343597 -399.923554) (xy 408.389853 -399.943844) (xy 408.432139 -399.97147)
			(xy 408.469301 -400.00568) (xy 408.500325 -400.04554) (xy 408.524366 -400.089963) (xy 408.540767 -400.137737)
			(xy 408.54908 -400.187559) (xy 408.549602 -400.212814) (xy 408.549133 -400.237187) (xy 408.541373 -400.285311)
			(xy 408.526053 -400.331586) (xy 408.503563 -400.374834) (xy 408.489404 -400.394678) (xy 408.483816 -400.402552)
			(xy 408.478736 -400.420332) (xy 408.487118 -400.506946) (xy 408.495246 -400.52371) (xy 408.502358 -400.53006)
			(xy 408.521493 -400.548192) (xy 408.555081 -400.588824) (xy 408.582752 -400.633694) (xy 408.603979 -400.681947)
			(xy 408.618358 -400.732665) (xy 408.625613 -400.78488) (xy 408.626056 -400.811238) (xy 408.626056 -401.674838)
			(xy 409.062428 -401.674838) (xy 409.062428 -400.811238) (xy 409.062912 -400.784883) (xy 409.070174 -400.732674)
			(xy 409.084553 -400.681962) (xy 409.105774 -400.633712) (xy 409.133433 -400.58884) (xy 409.167004 -400.548203)
			(xy 409.186126 -400.53006) (xy 409.193238 -400.52371) (xy 409.201366 -400.506946) (xy 409.209748 -400.420332)
			(xy 409.204668 -400.402552) (xy 409.19908 -400.394678) (xy 409.184933 -400.374829) (xy 409.162474 -400.331571)
			(xy 409.147161 -400.285299) (xy 409.13938 -400.237184) (xy 409.138882 -400.212814) (xy 409.139404 -400.187559)
			(xy 409.147717 -400.137737) (xy 409.164118 -400.089963) (xy 409.188159 -400.04554) (xy 409.219183 -400.00568)
			(xy 409.256345 -399.97147) (xy 409.298631 -399.943844) (xy 409.344887 -399.923554) (xy 409.393852 -399.911154)
			(xy 409.44419 -399.906983) (xy 409.494528 -399.911154) (xy 409.543493 -399.923554) (xy 409.589749 -399.943844)
			(xy 409.632035 -399.97147) (xy 409.669197 -400.00568) (xy 409.700221 -400.04554) (xy 409.724262 -400.089963)
			(xy 409.740663 -400.137737) (xy 409.748976 -400.187559) (xy 409.749498 -400.212814) (xy 409.74903 -400.237187)
			(xy 409.74127 -400.285311) (xy 409.725949 -400.331587) (xy 409.703459 -400.374834) (xy 409.6893 -400.394678)
			(xy 409.683712 -400.402552) (xy 409.678632 -400.420332) (xy 409.687014 -400.506946) (xy 409.695142 -400.52371)
			(xy 409.702254 -400.53006) (xy 409.721389 -400.548193) (xy 409.754976 -400.588824) (xy 409.782648 -400.633694)
			(xy 409.803875 -400.681948) (xy 409.818253 -400.732665) (xy 409.825509 -400.78488) (xy 409.825952 -400.811238)
			(xy 409.825952 -401.674838) (xy 410.262832 -401.674838) (xy 410.262832 -400.811238) (xy 410.263302 -400.784894)
			(xy 410.270549 -400.732705) (xy 410.284897 -400.682007) (xy 410.306074 -400.633761) (xy 410.333678 -400.588882)
			(xy 410.367187 -400.548221) (xy 410.386276 -400.53006) (xy 410.393388 -400.52371) (xy 410.401516 -400.506946)
			(xy 410.409898 -400.420332) (xy 410.404818 -400.402552) (xy 410.39923 -400.394678) (xy 410.385077 -400.374833)
			(xy 410.362621 -400.331573) (xy 410.34731 -400.2853) (xy 410.33953 -400.237184) (xy 410.339032 -400.212814)
			(xy 410.339554 -400.187559) (xy 410.347867 -400.137737) (xy 410.364268 -400.089963) (xy 410.388309 -400.04554)
			(xy 410.419333 -400.00568) (xy 410.456495 -399.97147) (xy 410.498781 -399.943844) (xy 410.545037 -399.923554)
			(xy 410.594002 -399.911154) (xy 410.64434 -399.906983) (xy 410.694678 -399.911154) (xy 410.743643 -399.923554)
			(xy 410.789899 -399.943844) (xy 410.832185 -399.97147) (xy 410.869347 -400.00568) (xy 410.900371 -400.04554)
			(xy 410.924412 -400.089963) (xy 410.940813 -400.137737) (xy 410.949126 -400.187559) (xy 410.949648 -400.212814)
			(xy 410.94917 -400.237186) (xy 410.941411 -400.28531) (xy 410.926093 -400.331585) (xy 410.903607 -400.374833)
			(xy 410.88945 -400.394678) (xy 410.883862 -400.402552) (xy 410.878782 -400.420332) (xy 410.887164 -400.506946)
			(xy 410.895292 -400.52371) (xy 410.902404 -400.53006) (xy 410.921498 -400.548219) (xy 410.955022 -400.588873)
			(xy 410.982637 -400.633749) (xy 411.00382 -400.681997) (xy 411.018168 -400.732698) (xy 411.025408 -400.784892)
			(xy 411.025848 -400.811238) (xy 411.025848 -401.674838) (xy 411.462728 -401.674838) (xy 411.462728 -400.811238)
			(xy 411.463167 -400.784892) (xy 411.470416 -400.732701) (xy 411.484768 -400.682002) (xy 411.505951 -400.633755)
			(xy 411.533562 -400.588877) (xy 411.567078 -400.548219) (xy 411.586172 -400.53006) (xy 411.593284 -400.52371)
			(xy 411.601412 -400.506946) (xy 411.609794 -400.420332) (xy 411.604714 -400.402552) (xy 411.599126 -400.394678)
			(xy 411.584973 -400.374833) (xy 411.562517 -400.331574) (xy 411.547205 -400.2853) (xy 411.539426 -400.237184)
			(xy 411.538928 -400.212814) (xy 411.53945 -400.187559) (xy 411.547763 -400.137737) (xy 411.564164 -400.089963)
			(xy 411.588205 -400.04554) (xy 411.619229 -400.00568) (xy 411.656391 -399.97147) (xy 411.698677 -399.943844)
			(xy 411.744933 -399.923554) (xy 411.793898 -399.911154) (xy 411.844236 -399.906983) (xy 411.894574 -399.911154)
			(xy 411.943539 -399.923554) (xy 411.989795 -399.943844) (xy 412.032081 -399.97147) (xy 412.069243 -400.00568)
			(xy 412.100267 -400.04554) (xy 412.124308 -400.089963) (xy 412.140709 -400.137737) (xy 412.149022 -400.187559)
			(xy 412.149544 -400.212814) (xy 412.149067 -400.237186) (xy 412.141308 -400.28531) (xy 412.12599 -400.331585)
			(xy 412.103503 -400.374833) (xy 412.089346 -400.394678) (xy 412.083758 -400.402552) (xy 412.078678 -400.420332)
			(xy 412.08706 -400.506946) (xy 412.095188 -400.52371) (xy 412.1023 -400.53006) (xy 412.121413 -400.5482)
			(xy 412.154931 -400.58886) (xy 412.182542 -400.633741) (xy 412.203721 -400.681992) (xy 412.218066 -400.732696)
			(xy 412.225304 -400.784891) (xy 412.225744 -400.811238) (xy 412.225744 -401.674838) (xy 412.662624 -401.674838)
			(xy 412.662624 -400.811238) (xy 412.663058 -400.784911) (xy 412.670308 -400.732757) (xy 412.684662 -400.682096)
			(xy 412.705846 -400.633891) (xy 412.733459 -400.589057) (xy 412.766976 -400.548447) (xy 412.786068 -400.530314)
			(xy 412.79318 -400.52371) (xy 412.801562 -400.5072) (xy 412.80969 -400.420332) (xy 412.80461 -400.402552)
			(xy 412.799022 -400.394932) (xy 412.784869 -400.375048) (xy 412.76238 -400.331735) (xy 412.747062 -400.285398)
			(xy 412.739302 -400.237216) (xy 412.738824 -400.212814) (xy 412.739346 -400.187559) (xy 412.747659 -400.137737)
			(xy 412.76406 -400.089963) (xy 412.788101 -400.04554) (xy 412.819125 -400.00568) (xy 412.856287 -399.97147)
			(xy 412.898573 -399.943844) (xy 412.944829 -399.923554) (xy 412.993794 -399.911154) (xy 413.044132 -399.906983)
			(xy 413.09447 -399.911154) (xy 413.143435 -399.923554) (xy 413.189691 -399.943844) (xy 413.231977 -399.97147)
			(xy 413.269139 -400.00568) (xy 413.300163 -400.04554) (xy 413.324204 -400.089963) (xy 413.340605 -400.137737)
			(xy 413.348918 -400.187559) (xy 413.34944 -400.212814) (xy 413.348944 -400.237172) (xy 413.341232 -400.285275)
			(xy 413.325988 -400.331545) (xy 413.303599 -400.374812) (xy 413.289496 -400.394678) (xy 413.283654 -400.402298)
			(xy 413.278828 -400.420078) (xy 413.286956 -400.506946) (xy 413.295338 -400.523456) (xy 413.30245 -400.53006)
			(xy 413.321584 -400.548194) (xy 413.355172 -400.588825) (xy 413.382843 -400.633694) (xy 413.404071 -400.681948)
			(xy 413.418449 -400.732665) (xy 413.425705 -400.78488) (xy 413.426148 -400.811238) (xy 413.426148 -401.674838)
			(xy 413.86252 -401.674838) (xy 413.86252 -400.811238) (xy 413.863006 -400.784883) (xy 413.870269 -400.732675)
			(xy 413.884647 -400.681963) (xy 413.905867 -400.633712) (xy 413.933526 -400.588841) (xy 413.967096 -400.548203)
			(xy 413.986218 -400.53006) (xy 413.99333 -400.52371) (xy 414.001458 -400.506946) (xy 414.00984 -400.420332)
			(xy 414.00476 -400.402552) (xy 413.999172 -400.394678) (xy 413.985024 -400.374829) (xy 413.962566 -400.331572)
			(xy 413.947253 -400.285299) (xy 413.939472 -400.237184) (xy 413.938974 -400.212814) (xy 413.939496 -400.187559)
			(xy 413.947809 -400.137737) (xy 413.96421 -400.089963) (xy 413.988251 -400.04554) (xy 414.019275 -400.00568)
			(xy 414.056437 -399.97147) (xy 414.098723 -399.943844) (xy 414.144979 -399.923554) (xy 414.193944 -399.911154)
			(xy 414.244282 -399.906983) (xy 414.29462 -399.911154) (xy 414.343585 -399.923554) (xy 414.389841 -399.943844)
			(xy 414.432127 -399.97147) (xy 414.469289 -400.00568) (xy 414.500313 -400.04554) (xy 414.524354 -400.089963)
			(xy 414.540755 -400.137737) (xy 414.549068 -400.187559) (xy 414.54959 -400.212814) (xy 414.549123 -400.237187)
			(xy 414.541363 -400.285311) (xy 414.526042 -400.331587) (xy 414.503552 -400.374834) (xy 414.489392 -400.394678)
			(xy 414.483804 -400.402552) (xy 414.478724 -400.420332) (xy 414.487106 -400.506946) (xy 414.495234 -400.52371)
			(xy 414.502346 -400.53006) (xy 414.521479 -400.548195) (xy 414.555067 -400.588825) (xy 414.582739 -400.633695)
			(xy 414.603967 -400.681948) (xy 414.618345 -400.732665) (xy 414.625601 -400.78488) (xy 414.626044 -400.811238)
			(xy 414.626044 -401.674838) (xy 415.062924 -401.674838) (xy 415.062924 -400.811238) (xy 415.063348 -400.784921)
			(xy 415.070573 -400.732785) (xy 415.084891 -400.682136) (xy 415.106031 -400.633934) (xy 415.133592 -400.589093)
			(xy 415.167051 -400.548463) (xy 415.186114 -400.530314) (xy 415.193226 -400.52371) (xy 415.201608 -400.5072)
			(xy 415.209736 -400.420332) (xy 415.204656 -400.402552) (xy 415.199068 -400.394932) (xy 415.184908 -400.375053)
			(xy 415.162423 -400.331737) (xy 415.147106 -400.285399) (xy 415.139348 -400.237216) (xy 415.13887 -400.212814)
			(xy 415.139392 -400.187559) (xy 415.147705 -400.137737) (xy 415.164106 -400.089963) (xy 415.188147 -400.04554)
			(xy 415.219171 -400.00568) (xy 415.256333 -399.97147) (xy 415.298619 -399.943844) (xy 415.344875 -399.923554)
			(xy 415.39384 -399.911154) (xy 415.444178 -399.906983) (xy 415.494516 -399.911154) (xy 415.543481 -399.923554)
			(xy 415.589737 -399.943844) (xy 415.632023 -399.97147) (xy 415.669185 -400.00568) (xy 415.700209 -400.04554)
			(xy 415.72425 -400.089963) (xy 415.740651 -400.137737) (xy 415.748964 -400.187559) (xy 415.749486 -400.212814)
			(xy 415.749 -400.237173) (xy 415.741286 -400.285276) (xy 415.72604 -400.331547) (xy 415.703647 -400.374813)
			(xy 415.689542 -400.394678) (xy 415.6837 -400.402298) (xy 415.678874 -400.420078) (xy 415.687002 -400.506946)
			(xy 415.695384 -400.523456) (xy 415.702496 -400.53006) (xy 415.721608 -400.548201) (xy 415.755127 -400.58886)
			(xy 415.782738 -400.633741) (xy 415.803917 -400.681992) (xy 415.818262 -400.732696) (xy 415.8255 -400.784891)
			(xy 415.82594 -400.811238) (xy 415.82594 -401.674838) (xy 416.26282 -401.674838) (xy 416.26282 -400.811238)
			(xy 416.263262 -400.784892) (xy 416.27051 -400.732702) (xy 416.284862 -400.682002) (xy 416.306044 -400.633756)
			(xy 416.333655 -400.588877) (xy 416.367171 -400.548219) (xy 416.386264 -400.53006) (xy 416.393376 -400.52371)
			(xy 416.401504 -400.506946) (xy 416.409886 -400.420332) (xy 416.404806 -400.402552) (xy 416.399218 -400.394678)
			(xy 416.385064 -400.374834) (xy 416.362608 -400.331574) (xy 416.347297 -400.2853) (xy 416.339518 -400.237184)
			(xy 416.33902 -400.212814) (xy 416.339542 -400.187559) (xy 416.347855 -400.137737) (xy 416.364256 -400.089963)
			(xy 416.388297 -400.04554) (xy 416.419321 -400.00568) (xy 416.456483 -399.97147) (xy 416.498769 -399.943844)
			(xy 416.545025 -399.923554) (xy 416.59399 -399.911154) (xy 416.644328 -399.906983) (xy 416.694666 -399.911154)
			(xy 416.743631 -399.923554) (xy 416.789887 -399.943844) (xy 416.832173 -399.97147) (xy 416.869335 -400.00568)
			(xy 416.900359 -400.04554) (xy 416.9244 -400.089963) (xy 416.940801 -400.137737) (xy 416.949114 -400.187559)
			(xy 416.949636 -400.212814) (xy 416.94916 -400.237186) (xy 416.941401 -400.28531) (xy 416.926083 -400.331585)
			(xy 416.903596 -400.374833) (xy 416.889438 -400.394678) (xy 416.88385 -400.402552) (xy 416.87877 -400.420332)
			(xy 416.887152 -400.506946) (xy 416.89528 -400.52371) (xy 416.902392 -400.53006) (xy 416.921503 -400.548201)
			(xy 416.955022 -400.588861) (xy 416.982633 -400.633742) (xy 417.003813 -400.681992) (xy 417.018158 -400.732696)
			(xy 417.025396 -400.784891) (xy 417.025836 -400.811238) (xy 417.025836 -401.674838) (xy 417.462716 -401.674838)
			(xy 417.462716 -400.811238) (xy 417.463159 -400.784892) (xy 417.470408 -400.732702) (xy 417.484759 -400.682002)
			(xy 417.505941 -400.633756) (xy 417.533552 -400.588878) (xy 417.567067 -400.548219) (xy 417.58616 -400.53006)
			(xy 417.593272 -400.52371) (xy 417.6014 -400.506946) (xy 417.609782 -400.420332) (xy 417.604702 -400.402552)
			(xy 417.599114 -400.394678) (xy 417.584959 -400.374834) (xy 417.562504 -400.331574) (xy 417.547193 -400.2853)
			(xy 417.539414 -400.237184) (xy 417.538916 -400.212814) (xy 417.539438 -400.187559) (xy 417.547751 -400.137737)
			(xy 417.564152 -400.089963) (xy 417.588193 -400.04554) (xy 417.619217 -400.00568) (xy 417.656379 -399.97147)
			(xy 417.698665 -399.943844) (xy 417.744921 -399.923554) (xy 417.793886 -399.911154) (xy 417.844224 -399.906983)
			(xy 417.894562 -399.911154) (xy 417.943527 -399.923554) (xy 417.989783 -399.943844) (xy 418.032069 -399.97147)
			(xy 418.069231 -400.00568) (xy 418.100255 -400.04554) (xy 418.124296 -400.089963) (xy 418.140697 -400.137737)
			(xy 418.14901 -400.187559) (xy 418.149532 -400.212814) (xy 418.149057 -400.237186) (xy 418.141298 -400.28531)
			(xy 418.125979 -400.331585) (xy 418.103492 -400.374833) (xy 418.089334 -400.394678) (xy 418.083746 -400.402552)
			(xy 418.078666 -400.420332) (xy 418.087048 -400.506946) (xy 418.095176 -400.52371) (xy 418.102288 -400.53006)
			(xy 418.121398 -400.548202) (xy 418.154917 -400.588861) (xy 418.182529 -400.633742) (xy 418.203708 -400.681992)
			(xy 418.218054 -400.732696) (xy 418.225292 -400.784891) (xy 418.225732 -400.811238) (xy 418.225732 -401.674838)
			(xy 418.662612 -401.674838) (xy 418.662612 -400.811238) (xy 418.663056 -400.784892) (xy 418.670305 -400.732702)
			(xy 418.684656 -400.682003) (xy 418.705838 -400.633756) (xy 418.733448 -400.588878) (xy 418.766963 -400.548219)
			(xy 418.786056 -400.53006) (xy 418.793168 -400.52371) (xy 418.801296 -400.506946) (xy 418.809678 -400.420332)
			(xy 418.804598 -400.402552) (xy 418.79901 -400.394678) (xy 418.784867 -400.374826) (xy 418.762406 -400.33157)
			(xy 418.747092 -400.285298) (xy 418.739311 -400.237184) (xy 418.738812 -400.212814) (xy 418.739334 -400.187559)
			(xy 418.747647 -400.137737) (xy 418.764048 -400.089963) (xy 418.788089 -400.04554) (xy 418.819113 -400.00568)
			(xy 418.856275 -399.97147) (xy 418.898561 -399.943844) (xy 418.944817 -399.923554) (xy 418.993782 -399.911154)
			(xy 419.04412 -399.906983) (xy 419.094458 -399.911154) (xy 419.143423 -399.923554) (xy 419.189679 -399.943844)
			(xy 419.231965 -399.97147) (xy 419.269127 -400.00568) (xy 419.300151 -400.04554) (xy 419.324192 -400.089963)
			(xy 419.340593 -400.137737) (xy 419.348906 -400.187559) (xy 419.349428 -400.212814) (xy 419.348954 -400.237187)
			(xy 419.341195 -400.28531) (xy 419.325876 -400.331586) (xy 419.303388 -400.374834) (xy 419.28923 -400.394678)
			(xy 419.283642 -400.402552) (xy 419.278562 -400.420332) (xy 419.286944 -400.506946) (xy 419.295072 -400.52371)
			(xy 419.302184 -400.53006) (xy 419.321294 -400.548203) (xy 419.354813 -400.588862) (xy 419.382425 -400.633742)
			(xy 419.403604 -400.681993) (xy 419.41795 -400.732696) (xy 419.425188 -400.784891) (xy 419.425628 -400.811238)
			(xy 419.425628 -401.674838) (xy 419.862508 -401.674838) (xy 419.862508 -400.811238) (xy 419.862966 -400.784881)
			(xy 419.87023 -400.732671) (xy 419.884612 -400.681957) (xy 419.905837 -400.633706) (xy 419.933502 -400.588836)
			(xy 419.96708 -400.548201) (xy 419.986206 -400.53006) (xy 419.993318 -400.52371) (xy 420.001446 -400.506946)
			(xy 420.009828 -400.420332) (xy 420.004748 -400.402552) (xy 419.99916 -400.394678) (xy 419.985011 -400.37483)
			(xy 419.962553 -400.331572) (xy 419.94724 -400.285299) (xy 419.93946 -400.237184) (xy 419.938962 -400.212814)
			(xy 419.939484 -400.187559) (xy 419.947797 -400.137737) (xy 419.964198 -400.089963) (xy 419.988239 -400.04554)
			(xy 420.019263 -400.00568) (xy 420.056425 -399.97147) (xy 420.098711 -399.943844) (xy 420.144967 -399.923554)
			(xy 420.193932 -399.911154) (xy 420.24427 -399.906983) (xy 420.294608 -399.911154) (xy 420.343573 -399.923554)
			(xy 420.389829 -399.943844) (xy 420.432115 -399.97147) (xy 420.469277 -400.00568) (xy 420.500301 -400.04554)
			(xy 420.524342 -400.089963) (xy 420.540743 -400.137737) (xy 420.549056 -400.187559) (xy 420.549578 -400.212814)
			(xy 420.549114 -400.237187) (xy 420.541353 -400.285311) (xy 420.526032 -400.331587) (xy 420.50354 -400.374834)
			(xy 420.48938 -400.394678) (xy 420.483792 -400.402552) (xy 420.478712 -400.420332) (xy 420.487094 -400.506946)
			(xy 420.495222 -400.52371) (xy 420.502334 -400.53006) (xy 420.521465 -400.548197) (xy 420.555054 -400.588827)
			(xy 420.582726 -400.633696) (xy 420.603954 -400.681949) (xy 420.618333 -400.732666) (xy 420.625589 -400.78488)
			(xy 420.626032 -400.811238) (xy 420.626032 -401.674838) (xy 421.062404 -401.674838) (xy 421.062404 -400.811238)
			(xy 421.062863 -400.784881) (xy 421.070127 -400.732671) (xy 421.084509 -400.681958) (xy 421.105734 -400.633706)
			(xy 421.133399 -400.588836) (xy 421.166977 -400.548201) (xy 421.186102 -400.53006) (xy 421.193214 -400.52371)
			(xy 421.201342 -400.506946) (xy 421.209724 -400.420332) (xy 421.204644 -400.402552) (xy 421.199056 -400.394678)
			(xy 421.184906 -400.374831) (xy 421.162449 -400.331572) (xy 421.147136 -400.2853) (xy 421.139356 -400.237184)
			(xy 421.138858 -400.212814) (xy 421.13938 -400.187559) (xy 421.147693 -400.137737) (xy 421.164094 -400.089963)
			(xy 421.188135 -400.04554) (xy 421.219159 -400.00568) (xy 421.256321 -399.97147) (xy 421.298607 -399.943844)
			(xy 421.344863 -399.923554) (xy 421.393828 -399.911154) (xy 421.444166 -399.906983) (xy 421.494504 -399.911154)
			(xy 421.543469 -399.923554) (xy 421.589725 -399.943844) (xy 421.632011 -399.97147) (xy 421.669173 -400.00568)
			(xy 421.700197 -400.04554) (xy 421.724238 -400.089963) (xy 421.740639 -400.137737) (xy 421.748952 -400.187559)
			(xy 421.749474 -400.212814) (xy 421.748991 -400.237186) (xy 421.741233 -400.285309) (xy 421.725916 -400.331584)
			(xy 421.703432 -400.374833) (xy 421.689276 -400.394678) (xy 421.683688 -400.402552) (xy 421.678608 -400.420332)
			(xy 421.68699 -400.506946) (xy 421.695118 -400.52371) (xy 421.70223 -400.53006) (xy 421.72136 -400.548198)
			(xy 421.754949 -400.588827) (xy 421.782622 -400.633696) (xy 421.80385 -400.681949) (xy 421.818229 -400.732666)
			(xy 421.825485 -400.78488) (xy 421.825928 -400.811238) (xy 421.825928 -401.461986) (xy 421.826311 -401.470962)
			(xy 421.832546 -401.487798) (xy 421.844191 -401.501464) (xy 421.851836 -401.506182) (xy 421.941244 -401.55622)
			(xy 421.96893 -401.555712) (xy 421.980614 -401.548346) (xy 422.003289 -401.534927) (xy 422.051537 -401.513754)
			(xy 422.102234 -401.499406) (xy 422.154422 -401.492154) (xy 422.180766 -401.491704) (xy 422.208021 -401.492141)
			(xy 422.261978 -401.499894) (xy 422.314281 -401.515247) (xy 422.363867 -401.537889) (xy 422.409726 -401.567357)
			(xy 422.450924 -401.603052) (xy 422.486623 -401.644247) (xy 422.516095 -401.690103) (xy 422.52838 -401.717002)
			(xy 423.860974 -401.717002) (xy 423.865045 -401.66138) (xy 423.877171 -401.606943) (xy 423.897094 -401.554852)
			(xy 423.92439 -401.506217) (xy 423.958476 -401.462074) (xy 423.998625 -401.423365) (xy 424.043983 -401.390914)
			(xy 424.093583 -401.365413) (xy 424.146367 -401.347406) (xy 424.20121 -401.337276) (xy 424.256944 -401.335239)
			(xy 424.312381 -401.341339) (xy 424.366338 -401.355445) (xy 424.417667 -401.377257) (xy 424.465273 -401.406311)
			(xy 424.508141 -401.441986) (xy 424.545358 -401.483523) (xy 424.576131 -401.530036) (xy 424.599803 -401.580533)
			(xy 424.615871 -401.63394) (xy 424.623991 -401.689116) (xy 424.6245 -401.717002) (xy 424.623991 -401.744888)
			(xy 424.615871 -401.800064) (xy 424.599803 -401.853471) (xy 424.576131 -401.903968) (xy 424.545358 -401.950481)
			(xy 424.508141 -401.992018) (xy 424.465273 -402.027693) (xy 424.417667 -402.056747) (xy 424.374379 -402.075142)
			(xy 424.921934 -402.075142) (xy 424.922416 -402.042998) (xy 424.930503 -401.979221) (xy 424.946567 -401.916972)
			(xy 424.970351 -401.857245) (xy 425.001475 -401.800994) (xy 425.039443 -401.749115) (xy 425.083648 -401.702437)
			(xy 425.133386 -401.661705) (xy 425.187862 -401.627569) (xy 425.216828 -401.613624) (xy 425.226539 -401.608563)
			(xy 425.240773 -401.591947) (xy 425.246854 -401.570929) (xy 425.245784 -401.56003) (xy 425.243166 -401.541408)
			(xy 425.240373 -401.503904) (xy 425.240196 -401.4851) (xy 425.240698 -401.453139) (xy 425.248709 -401.389721)
			(xy 425.264606 -401.327807) (xy 425.288138 -401.268374) (xy 425.318932 -401.212359) (xy 425.356505 -401.160644)
			(xy 425.400262 -401.114047) (xy 425.449515 -401.073302) (xy 425.503486 -401.039051) (xy 425.561325 -401.011834)
			(xy 425.622118 -400.992081) (xy 425.684908 -400.980103) (xy 425.748704 -400.97609) (xy 425.8125 -400.980103)
			(xy 425.87529 -400.992081) (xy 425.936083 -401.011834) (xy 425.993922 -401.039051) (xy 426.047893 -401.073302)
			(xy 426.097146 -401.114047) (xy 426.140903 -401.160644) (xy 426.178476 -401.212359) (xy 426.20927 -401.268374)
			(xy 426.232802 -401.327807) (xy 426.248699 -401.389721) (xy 426.25671 -401.453139) (xy 426.257212 -401.4851)
			(xy 426.256739 -401.517244) (xy 426.248647 -401.581021) (xy 426.23258 -401.643268) (xy 426.208794 -401.702994)
			(xy 426.177669 -401.759245) (xy 426.139701 -401.811123) (xy 426.095495 -401.857801) (xy 426.045758 -401.898534)
			(xy 425.991283 -401.932672) (xy 425.962318 -401.946618) (xy 425.952626 -401.951706) (xy 425.938397 -401.968313)
			(xy 425.932304 -401.989317) (xy 425.933362 -402.000212) (xy 425.935973 -402.018835) (xy 425.938771 -402.056338)
			(xy 425.93895 -402.075142) (xy 425.938448 -402.107103) (xy 425.930437 -402.170521) (xy 425.91454 -402.232435)
			(xy 425.891008 -402.291868) (xy 425.860214 -402.347883) (xy 425.822641 -402.399598) (xy 425.778884 -402.446195)
			(xy 425.729631 -402.48694) (xy 425.67566 -402.521191) (xy 425.617821 -402.548408) (xy 425.557028 -402.568161)
			(xy 425.494238 -402.580139) (xy 425.430442 -402.584153) (xy 425.366646 -402.580139) (xy 425.303856 -402.568161)
			(xy 425.243063 -402.548408) (xy 425.185224 -402.521191) (xy 425.131253 -402.48694) (xy 425.082 -402.446195)
			(xy 425.038243 -402.399598) (xy 425.00067 -402.347883) (xy 424.969876 -402.291868) (xy 424.946344 -402.232435)
			(xy 424.930447 -402.170521) (xy 424.922436 -402.107103) (xy 424.921934 -402.075142) (xy 424.374379 -402.075142)
			(xy 424.366338 -402.078559) (xy 424.312381 -402.092665) (xy 424.256944 -402.098765) (xy 424.20121 -402.096728)
			(xy 424.146367 -402.086598) (xy 424.093583 -402.068591) (xy 424.043983 -402.04309) (xy 423.998625 -402.010639)
			(xy 423.958476 -401.97193) (xy 423.92439 -401.927787) (xy 423.897094 -401.879152) (xy 423.877171 -401.827061)
			(xy 423.865045 -401.772624) (xy 423.860974 -401.717002) (xy 422.52838 -401.717002) (xy 422.538741 -401.739687)
			(xy 422.554099 -401.791989) (xy 422.561857 -401.845945) (xy 422.561857 -401.900455) (xy 422.554099 -401.954411)
			(xy 422.538741 -402.006713) (xy 422.516095 -402.056297) (xy 422.486623 -402.102153) (xy 422.450924 -402.143348)
			(xy 422.409726 -402.179043) (xy 422.363867 -402.208511) (xy 422.314281 -402.231153) (xy 422.261978 -402.246506)
			(xy 422.208021 -402.254259) (xy 422.180766 -402.25472) (xy 422.153811 -402.25425) (xy 422.100439 -402.246644)
			(xy 422.048669 -402.231603) (xy 421.999531 -402.209425) (xy 421.954003 -402.180553) (xy 421.912992 -402.14556)
			(xy 421.877313 -402.105144) (xy 421.847678 -402.060109) (xy 421.824676 -402.011352) (xy 421.816276 -401.985734)
			(xy 421.813444 -401.977653) (xy 421.803283 -401.963883) (xy 421.789148 -401.954237) (xy 421.78097 -401.951698)
			(xy 421.72255 -401.93595) (xy 421.712898 -401.945856) (xy 421.706294 -401.95246) (xy 421.698674 -401.969224)
			(xy 421.69334 -402.05533) (xy 421.698674 -402.07311) (xy 421.704516 -402.080476) (xy 421.721017 -402.102469)
			(xy 421.747294 -402.15076) (xy 421.765228 -402.20273) (xy 421.774325 -402.256949) (xy 421.774874 -402.284438)
			(xy 421.774364 -402.310425) (xy 421.766234 -402.36176) (xy 421.750173 -402.41119) (xy 421.726577 -402.4575)
			(xy 421.696027 -402.499548) (xy 421.659276 -402.536299) (xy 421.617228 -402.566849) (xy 421.570918 -402.590445)
			(xy 421.521488 -402.606506) (xy 421.470153 -402.614636) (xy 421.418179 -402.614636) (xy 421.366844 -402.606506)
			(xy 421.317414 -402.590445) (xy 421.271104 -402.566849) (xy 421.229056 -402.536299) (xy 421.192305 -402.499548)
			(xy 421.161755 -402.4575) (xy 421.138159 -402.41119) (xy 421.122098 -402.36176) (xy 421.113968 -402.310425)
			(xy 421.113458 -402.284438) (xy 421.11402 -402.256948) (xy 421.123094 -402.202723) (xy 421.141017 -402.150747)
			(xy 421.167293 -402.102453) (xy 421.183816 -402.080476) (xy 421.189658 -402.07311) (xy 421.194992 -402.05533)
			(xy 421.189658 -401.969224) (xy 421.182038 -401.95246) (xy 421.175434 -401.945856) (xy 421.154383 -401.924248)
			(xy 421.11874 -401.875581) (xy 421.091203 -401.82191) (xy 421.072457 -401.764573) (xy 421.062971 -401.705)
			(xy 421.062404 -401.674838) (xy 420.626032 -401.674838) (xy 420.625607 -401.701012) (xy 420.61841 -401.752864)
			(xy 420.604197 -401.803247) (xy 420.583236 -401.851216) (xy 420.555918 -401.895872) (xy 420.522757 -401.936378)
			(xy 420.503858 -401.954492) (xy 420.496492 -401.96135) (xy 420.488364 -401.978876) (xy 420.48303 -402.069046)
			(xy 420.489126 -402.087334) (xy 420.49573 -402.094954) (xy 420.510635 -402.112995) (xy 420.535697 -402.152514)
			(xy 420.554944 -402.195169) (xy 420.56799 -402.240109) (xy 420.574576 -402.28644) (xy 420.574978 -402.309838)
			(xy 420.574468 -402.335825) (xy 420.566338 -402.38716) (xy 420.550277 -402.43659) (xy 420.526681 -402.4829)
			(xy 420.496131 -402.524948) (xy 420.45938 -402.561699) (xy 420.417332 -402.592249) (xy 420.371022 -402.615845)
			(xy 420.321592 -402.631906) (xy 420.270257 -402.640036) (xy 420.218283 -402.640036) (xy 420.166948 -402.631906)
			(xy 420.117518 -402.615845) (xy 420.071208 -402.592249) (xy 420.02916 -402.561699) (xy 419.992409 -402.524948)
			(xy 419.961859 -402.4829) (xy 419.938263 -402.43659) (xy 419.922202 -402.38716) (xy 419.914072 -402.335825)
			(xy 419.913562 -402.309838) (xy 419.913984 -402.286442) (xy 419.92057 -402.240114) (xy 419.933617 -402.195177)
			(xy 419.952864 -402.152526) (xy 419.977928 -402.113012) (xy 419.99281 -402.094954) (xy 419.999414 -402.087334)
			(xy 420.00551 -402.069046) (xy 420.000176 -401.978876) (xy 419.992048 -401.96135) (xy 419.984682 -401.954492)
			(xy 419.965782 -401.936379) (xy 419.93262 -401.895875) (xy 419.905304 -401.851219) (xy 419.884347 -401.803249)
			(xy 419.870142 -401.752865) (xy 419.862956 -401.701012) (xy 419.862508 -401.674838) (xy 419.425628 -401.674838)
			(xy 419.425147 -401.701) (xy 419.417998 -401.752834) (xy 419.403839 -401.803207) (xy 419.382935 -401.851175)
			(xy 419.355677 -401.895839) (xy 419.322577 -401.936364) (xy 419.303708 -401.954492) (xy 419.296342 -401.96135)
			(xy 419.288214 -401.978876) (xy 419.28288 -402.069046) (xy 419.288976 -402.087334) (xy 419.29558 -402.094954)
			(xy 419.310477 -402.113001) (xy 419.335542 -402.152517) (xy 419.354791 -402.195171) (xy 419.367839 -402.24011)
			(xy 419.374426 -402.28644) (xy 419.374828 -402.309838) (xy 419.374318 -402.335825) (xy 419.366188 -402.38716)
			(xy 419.350127 -402.43659) (xy 419.326531 -402.4829) (xy 419.295981 -402.524948) (xy 419.25923 -402.561699)
			(xy 419.217182 -402.592249) (xy 419.170872 -402.615845) (xy 419.121442 -402.631906) (xy 419.070107 -402.640036)
			(xy 419.018133 -402.640036) (xy 418.966798 -402.631906) (xy 418.917368 -402.615845) (xy 418.871058 -402.592249)
			(xy 418.82901 -402.561699) (xy 418.792259 -402.524948) (xy 418.761709 -402.4829) (xy 418.738113 -402.43659)
			(xy 418.722052 -402.38716) (xy 418.713922 -402.335825) (xy 418.713412 -402.309838) (xy 418.713846 -402.286442)
			(xy 418.720431 -402.240116) (xy 418.733476 -402.195179) (xy 418.75272 -402.152528) (xy 418.77778 -402.113013)
			(xy 418.79266 -402.094954) (xy 418.799264 -402.087334) (xy 418.80536 -402.069046) (xy 418.800026 -401.978876)
			(xy 418.791898 -401.96135) (xy 418.784532 -401.954492) (xy 418.765644 -401.93638) (xy 418.732525 -401.895861)
			(xy 418.705254 -401.851197) (xy 418.684342 -401.803225) (xy 418.670182 -401.752846) (xy 418.663039 -401.701004)
			(xy 418.662612 -401.674838) (xy 418.225732 -401.674838) (xy 418.225199 -401.703743) (xy 418.216494 -401.760893)
			(xy 418.199273 -401.816077) (xy 418.17393 -401.868035) (xy 418.141044 -401.915579) (xy 418.121592 -401.936966)
			(xy 418.115496 -401.94357) (xy 418.108384 -401.959572) (xy 418.102796 -402.041868) (xy 418.107622 -402.058886)
			(xy 418.112702 -402.065998) (xy 418.127345 -402.087224) (xy 418.150595 -402.133247) (xy 418.166419 -402.182321)
			(xy 418.174433 -402.233257) (xy 418.174932 -402.259038) (xy 418.174422 -402.285025) (xy 418.166292 -402.33636)
			(xy 418.150231 -402.38579) (xy 418.126635 -402.4321) (xy 418.096085 -402.474148) (xy 418.059334 -402.510899)
			(xy 418.017286 -402.541449) (xy 417.970976 -402.565045) (xy 417.921546 -402.581106) (xy 417.870211 -402.589236)
			(xy 417.818237 -402.589236) (xy 417.766902 -402.581106) (xy 417.717472 -402.565045) (xy 417.671162 -402.541449)
			(xy 417.629114 -402.510899) (xy 417.592363 -402.474148) (xy 417.561813 -402.4321) (xy 417.538217 -402.38579)
			(xy 417.522156 -402.33636) (xy 417.514026 -402.285025) (xy 417.513516 -402.259038) (xy 417.513986 -402.233254)
			(xy 417.521994 -402.182313) (xy 417.537821 -402.133234) (xy 417.561083 -402.087212) (xy 417.575746 -402.065998)
			(xy 417.580826 -402.058886) (xy 417.585652 -402.041868) (xy 417.580064 -401.959572) (xy 417.572952 -401.94357)
			(xy 417.566856 -401.936966) (xy 417.547366 -401.91561) (xy 417.51446 -401.86807) (xy 417.489111 -401.816106)
			(xy 417.471901 -401.760909) (xy 417.463224 -401.703747) (xy 417.462716 -401.674838) (xy 417.025836 -401.674838)
			(xy 417.025384 -401.701002) (xy 417.018233 -401.752838) (xy 417.00407 -401.803212) (xy 416.983161 -401.851181)
			(xy 416.955897 -401.895844) (xy 416.922789 -401.936366) (xy 416.903916 -401.954492) (xy 416.89655 -401.96135)
			(xy 416.888422 -401.978876) (xy 416.883088 -402.069046) (xy 416.889184 -402.087334) (xy 416.895788 -402.094954)
			(xy 416.910686 -402.113) (xy 416.935751 -402.152517) (xy 416.955 -402.19517) (xy 416.968047 -402.24011)
			(xy 416.974634 -402.28644) (xy 416.975036 -402.309838) (xy 416.974526 -402.335825) (xy 416.966396 -402.38716)
			(xy 416.950335 -402.43659) (xy 416.926739 -402.4829) (xy 416.896189 -402.524948) (xy 416.859438 -402.561699)
			(xy 416.81739 -402.592249) (xy 416.77108 -402.615845) (xy 416.72165 -402.631906) (xy 416.670315 -402.640036)
			(xy 416.618341 -402.640036) (xy 416.567006 -402.631906) (xy 416.517576 -402.615845) (xy 416.471266 -402.592249)
			(xy 416.429218 -402.561699) (xy 416.392467 -402.524948) (xy 416.361917 -402.4829) (xy 416.338321 -402.43659)
			(xy 416.32226 -402.38716) (xy 416.31413 -402.335825) (xy 416.31362 -402.309838) (xy 416.314052 -402.286442)
			(xy 416.320637 -402.240116) (xy 416.333683 -402.195179) (xy 416.352927 -402.152528) (xy 416.377987 -402.113012)
			(xy 416.392868 -402.094954) (xy 416.399472 -402.087334) (xy 416.405568 -402.069046) (xy 416.400234 -401.978876)
			(xy 416.392106 -401.96135) (xy 416.38474 -401.954492) (xy 416.365853 -401.936378) (xy 416.332734 -401.89586)
			(xy 416.305462 -401.851196) (xy 416.28455 -401.803225) (xy 416.27039 -401.752846) (xy 416.263247 -401.701004)
			(xy 416.26282 -401.674838) (xy 415.82594 -401.674838) (xy 415.825486 -401.701002) (xy 415.818335 -401.752838)
			(xy 415.804173 -401.803212) (xy 415.783264 -401.85118) (xy 415.756 -401.895844) (xy 415.722893 -401.936366)
			(xy 415.70402 -401.954492) (xy 415.696654 -401.96135) (xy 415.688526 -401.978876) (xy 415.683192 -402.069046)
			(xy 415.689288 -402.087334) (xy 415.695892 -402.094954) (xy 415.710791 -402.112999) (xy 415.735856 -402.152516)
			(xy 415.755104 -402.19517) (xy 415.768151 -402.24011) (xy 415.774738 -402.28644) (xy 415.77514 -402.309838)
			(xy 415.77463 -402.335825) (xy 415.7665 -402.38716) (xy 415.750439 -402.43659) (xy 415.726843 -402.4829)
			(xy 415.696293 -402.524948) (xy 415.659542 -402.561699) (xy 415.617494 -402.592249) (xy 415.571184 -402.615845)
			(xy 415.521754 -402.631906) (xy 415.470419 -402.640036) (xy 415.418445 -402.640036) (xy 415.36711 -402.631906)
			(xy 415.31768 -402.615845) (xy 415.27137 -402.592249) (xy 415.229322 -402.561699) (xy 415.192571 -402.524948)
			(xy 415.162021 -402.4829) (xy 415.138425 -402.43659) (xy 415.122364 -402.38716) (xy 415.114234 -402.335825)
			(xy 415.113724 -402.309838) (xy 415.114155 -402.286442) (xy 415.120741 -402.240116) (xy 415.133786 -402.195179)
			(xy 415.153031 -402.152528) (xy 415.178091 -402.113012) (xy 415.192972 -402.094954) (xy 415.199576 -402.087334)
			(xy 415.205672 -402.069046) (xy 415.200338 -401.978876) (xy 415.19221 -401.96135) (xy 415.184844 -401.954492)
			(xy 415.165958 -401.936377) (xy 415.132838 -401.89586) (xy 415.105567 -401.851196) (xy 415.084654 -401.803225)
			(xy 415.070494 -401.752845) (xy 415.063351 -401.701004) (xy 415.062924 -401.674838) (xy 414.626044 -401.674838)
			(xy 414.625615 -401.701012) (xy 414.618418 -401.752864) (xy 414.604206 -401.803246) (xy 414.583246 -401.851215)
			(xy 414.555929 -401.895871) (xy 414.522768 -401.936378) (xy 414.50387 -401.954492) (xy 414.496504 -401.96135)
			(xy 414.488376 -401.978876) (xy 414.483042 -402.069046) (xy 414.489138 -402.087334) (xy 414.495742 -402.094954)
			(xy 414.510648 -402.112993) (xy 414.53571 -402.152513) (xy 414.554956 -402.195168) (xy 414.568002 -402.240109)
			(xy 414.574588 -402.28644) (xy 414.57499 -402.309838) (xy 414.57448 -402.335825) (xy 414.56635 -402.38716)
			(xy 414.550289 -402.43659) (xy 414.526693 -402.4829) (xy 414.496143 -402.524948) (xy 414.459392 -402.561699)
			(xy 414.417344 -402.592249) (xy 414.371034 -402.615845) (xy 414.321604 -402.631906) (xy 414.270269 -402.640036)
			(xy 414.218295 -402.640036) (xy 414.16696 -402.631906) (xy 414.11753 -402.615845) (xy 414.07122 -402.592249)
			(xy 414.029172 -402.561699) (xy 413.992421 -402.524948) (xy 413.961871 -402.4829) (xy 413.938275 -402.43659)
			(xy 413.922214 -402.38716) (xy 413.914084 -402.335825) (xy 413.913574 -402.309838) (xy 413.913993 -402.286441)
			(xy 413.92058 -402.240114) (xy 413.933627 -402.195177) (xy 413.952875 -402.152526) (xy 413.977939 -402.113011)
			(xy 413.992822 -402.094954) (xy 413.999426 -402.087334) (xy 414.005522 -402.069046) (xy 414.000188 -401.978876)
			(xy 413.99206 -401.96135) (xy 413.984694 -401.954492) (xy 413.965797 -401.936377) (xy 413.932633 -401.895873)
			(xy 413.905317 -401.851218) (xy 413.884359 -401.803248) (xy 413.870154 -401.752864) (xy 413.862968 -401.701012)
			(xy 413.86252 -401.674838) (xy 413.426148 -401.674838) (xy 413.425718 -401.701012) (xy 413.418521 -401.752863)
			(xy 413.404309 -401.803246) (xy 413.383349 -401.851215) (xy 413.356032 -401.895871) (xy 413.322872 -401.936377)
			(xy 413.303974 -401.954492) (xy 413.296608 -401.96135) (xy 413.28848 -401.978876) (xy 413.283146 -402.069046)
			(xy 413.289242 -402.087334) (xy 413.295846 -402.094954) (xy 413.310753 -402.112993) (xy 413.335815 -402.152512)
			(xy 413.35506 -402.195168) (xy 413.368106 -402.240109) (xy 413.374692 -402.28644) (xy 413.375094 -402.309838)
			(xy 413.374584 -402.335825) (xy 413.366454 -402.38716) (xy 413.350393 -402.43659) (xy 413.326797 -402.4829)
			(xy 413.296247 -402.524948) (xy 413.259496 -402.561699) (xy 413.217448 -402.592249) (xy 413.171138 -402.615845)
			(xy 413.121708 -402.631906) (xy 413.070373 -402.640036) (xy 413.018399 -402.640036) (xy 412.967064 -402.631906)
			(xy 412.917634 -402.615845) (xy 412.871324 -402.592249) (xy 412.829276 -402.561699) (xy 412.792525 -402.524948)
			(xy 412.761975 -402.4829) (xy 412.738379 -402.43659) (xy 412.722318 -402.38716) (xy 412.714188 -402.335825)
			(xy 412.713678 -402.309838) (xy 412.714096 -402.286441) (xy 412.720683 -402.240114) (xy 412.73373 -402.195177)
			(xy 412.752978 -402.152525) (xy 412.778043 -402.113011) (xy 412.792926 -402.094954) (xy 412.79953 -402.087334)
			(xy 412.805626 -402.069046) (xy 412.800292 -401.978876) (xy 412.792164 -401.96135) (xy 412.784798 -401.954492)
			(xy 412.765901 -401.936376) (xy 412.732738 -401.895873) (xy 412.705421 -401.851218) (xy 412.684464 -401.803248)
			(xy 412.670258 -401.752864) (xy 412.663072 -401.701012) (xy 412.662624 -401.674838) (xy 412.225744 -401.674838)
			(xy 412.225188 -401.704987) (xy 412.215732 -401.764539) (xy 412.197029 -401.821862) (xy 412.169545 -401.875532)
			(xy 412.133963 -401.924212) (xy 412.112968 -401.945856) (xy 412.106364 -401.95246) (xy 412.098744 -401.969224)
			(xy 412.09341 -402.05533) (xy 412.098744 -402.07311) (xy 412.104586 -402.080476) (xy 412.121096 -402.102462)
			(xy 412.147369 -402.150756) (xy 412.1653 -402.202728) (xy 412.174396 -402.256949) (xy 412.174944 -402.284438)
			(xy 412.174434 -402.310425) (xy 412.166304 -402.36176) (xy 412.150243 -402.41119) (xy 412.126647 -402.4575)
			(xy 412.096097 -402.499548) (xy 412.059346 -402.536299) (xy 412.017298 -402.566849) (xy 411.970988 -402.590445)
			(xy 411.921558 -402.606506) (xy 411.870223 -402.614636) (xy 411.818249 -402.614636) (xy 411.766914 -402.606506)
			(xy 411.717484 -402.590445) (xy 411.671174 -402.566849) (xy 411.629126 -402.536299) (xy 411.592375 -402.499548)
			(xy 411.561825 -402.4575) (xy 411.538229 -402.41119) (xy 411.522168 -402.36176) (xy 411.514038 -402.310425)
			(xy 411.513528 -402.284438) (xy 411.514075 -402.256947) (xy 411.523152 -402.202721) (xy 411.541078 -402.150744)
			(xy 411.56736 -402.102451) (xy 411.583886 -402.080476) (xy 411.589728 -402.07311) (xy 411.595062 -402.05533)
			(xy 411.589728 -401.969224) (xy 411.582108 -401.95246) (xy 411.575504 -401.945856) (xy 411.554509 -401.92421)
			(xy 411.518917 -401.875536) (xy 411.491428 -401.821867) (xy 411.472726 -401.764542) (xy 411.463278 -401.704988)
			(xy 411.462728 -401.674838) (xy 411.025848 -401.674838) (xy 411.025311 -401.703742) (xy 411.016606 -401.760892)
			(xy 410.999386 -401.816077) (xy 410.974044 -401.868035) (xy 410.941159 -401.915579) (xy 410.921708 -401.936966)
			(xy 410.915612 -401.94357) (xy 410.9085 -401.959572) (xy 410.902912 -402.041868) (xy 410.907738 -402.058886)
			(xy 410.912818 -402.065998) (xy 410.92745 -402.087231) (xy 410.950706 -402.13325) (xy 410.966533 -402.182322)
			(xy 410.974549 -402.233257) (xy 410.975048 -402.259038) (xy 410.974538 -402.285025) (xy 410.966408 -402.33636)
			(xy 410.950347 -402.38579) (xy 410.926751 -402.4321) (xy 410.896201 -402.474148) (xy 410.85945 -402.510899)
			(xy 410.817402 -402.541449) (xy 410.771092 -402.565045) (xy 410.721662 -402.581106) (xy 410.670327 -402.589236)
			(xy 410.618353 -402.589236) (xy 410.567018 -402.581106) (xy 410.517588 -402.565045) (xy 410.471278 -402.541449)
			(xy 410.42923 -402.510899) (xy 410.392479 -402.474148) (xy 410.361929 -402.4321) (xy 410.338333 -402.38579)
			(xy 410.322272 -402.33636) (xy 410.314142 -402.285025) (xy 410.313632 -402.259038) (xy 410.314117 -402.233255)
			(xy 410.322123 -402.182315) (xy 410.337946 -402.133237) (xy 410.361202 -402.087213) (xy 410.375862 -402.065998)
			(xy 410.380942 -402.058886) (xy 410.385768 -402.041868) (xy 410.38018 -401.959572) (xy 410.373068 -401.94357)
			(xy 410.366972 -401.936966) (xy 410.347484 -401.915607) (xy 410.314578 -401.868068) (xy 410.289228 -401.816105)
			(xy 410.272017 -401.760909) (xy 410.26334 -401.703747) (xy 410.262832 -401.674838) (xy 409.825952 -401.674838)
			(xy 409.82552 -401.701012) (xy 409.818324 -401.752863) (xy 409.804112 -401.803246) (xy 409.783152 -401.851215)
			(xy 409.755836 -401.895871) (xy 409.722676 -401.936377) (xy 409.703778 -401.954492) (xy 409.696412 -401.96135)
			(xy 409.688284 -401.978876) (xy 409.68295 -402.069046) (xy 409.689046 -402.087334) (xy 409.69565 -402.094954)
			(xy 409.710558 -402.112992) (xy 409.735619 -402.152512) (xy 409.754865 -402.195168) (xy 409.76791 -402.240109)
			(xy 409.774496 -402.28644) (xy 409.774898 -402.309838) (xy 409.774388 -402.335825) (xy 409.766258 -402.38716)
			(xy 409.750197 -402.43659) (xy 409.726601 -402.4829) (xy 409.696051 -402.524948) (xy 409.6593 -402.561699)
			(xy 409.617252 -402.592249) (xy 409.570942 -402.615845) (xy 409.521512 -402.631906) (xy 409.470177 -402.640036)
			(xy 409.418203 -402.640036) (xy 409.366868 -402.631906) (xy 409.317438 -402.615845) (xy 409.271128 -402.592249)
			(xy 409.22908 -402.561699) (xy 409.192329 -402.524948) (xy 409.161779 -402.4829) (xy 409.138183 -402.43659)
			(xy 409.122122 -402.38716) (xy 409.113992 -402.335825) (xy 409.113482 -402.309838) (xy 409.113923 -402.286442)
			(xy 409.120508 -402.240117) (xy 409.133551 -402.195181) (xy 409.152793 -402.152529) (xy 409.177851 -402.113013)
			(xy 409.19273 -402.094954) (xy 409.199334 -402.087334) (xy 409.20543 -402.069046) (xy 409.200096 -401.978876)
			(xy 409.191968 -401.96135) (xy 409.184602 -401.954492) (xy 409.165706 -401.936375) (xy 409.132543 -401.895872)
			(xy 409.105226 -401.851217) (xy 409.084268 -401.803248) (xy 409.070062 -401.752864) (xy 409.062876 -401.701012)
			(xy 409.062428 -401.674838) (xy 408.626056 -401.674838) (xy 408.625624 -401.701012) (xy 408.618427 -401.752863)
			(xy 408.604216 -401.803246) (xy 408.583256 -401.851215) (xy 408.55594 -401.895871) (xy 408.52278 -401.936378)
			(xy 408.503882 -401.954492) (xy 408.496516 -401.96135) (xy 408.488388 -401.978876) (xy 408.483054 -402.069046)
			(xy 408.48915 -402.087334) (xy 408.495754 -402.094954) (xy 408.510647 -402.113004) (xy 408.535714 -402.152519)
			(xy 408.554964 -402.195172) (xy 408.568013 -402.240111) (xy 408.5746 -402.28644) (xy 408.575002 -402.309838)
			(xy 408.574492 -402.335825) (xy 408.566362 -402.38716) (xy 408.550301 -402.43659) (xy 408.526705 -402.4829)
			(xy 408.496155 -402.524948) (xy 408.459404 -402.561699) (xy 408.417356 -402.592249) (xy 408.371046 -402.615845)
			(xy 408.321616 -402.631906) (xy 408.270281 -402.640036) (xy 408.218307 -402.640036) (xy 408.166972 -402.631906)
			(xy 408.117542 -402.615845) (xy 408.071232 -402.592249) (xy 408.029184 -402.561699) (xy 407.992433 -402.524948)
			(xy 407.961883 -402.4829) (xy 407.938287 -402.43659) (xy 407.922226 -402.38716) (xy 407.914096 -402.335825)
			(xy 407.913586 -402.309838) (xy 407.914026 -402.286442) (xy 407.920611 -402.240117) (xy 407.933654 -402.19518)
			(xy 407.952897 -402.152529) (xy 407.977955 -402.113013) (xy 407.992834 -402.094954) (xy 407.999438 -402.087334)
			(xy 408.005534 -402.069046) (xy 408.0002 -401.978876) (xy 407.992072 -401.96135) (xy 407.984706 -401.954492)
			(xy 407.965811 -401.936375) (xy 407.932647 -401.895872) (xy 407.90533 -401.851217) (xy 407.884372 -401.803247)
			(xy 407.870166 -401.752864) (xy 407.86298 -401.701012) (xy 407.862532 -401.674838) (xy 407.425652 -401.674838)
			(xy 407.425114 -401.703742) (xy 407.416409 -401.760892) (xy 407.399189 -401.816076) (xy 407.373847 -401.868034)
			(xy 407.340963 -401.915579) (xy 407.321512 -401.936966) (xy 407.315416 -401.94357) (xy 407.308304 -401.959572)
			(xy 407.302716 -402.041868) (xy 407.307542 -402.058886) (xy 407.312622 -402.065998) (xy 407.327255 -402.08723)
			(xy 407.35051 -402.13325) (xy 407.366337 -402.182322) (xy 407.374353 -402.233257) (xy 407.374852 -402.259038)
			(xy 407.374342 -402.285025) (xy 407.366212 -402.33636) (xy 407.350151 -402.38579) (xy 407.326555 -402.4321)
			(xy 407.296005 -402.474148) (xy 407.259254 -402.510899) (xy 407.217206 -402.541449) (xy 407.170896 -402.565045)
			(xy 407.121466 -402.581106) (xy 407.070131 -402.589236) (xy 407.018157 -402.589236) (xy 406.966822 -402.581106)
			(xy 406.917392 -402.565045) (xy 406.871082 -402.541449) (xy 406.829034 -402.510899) (xy 406.792283 -402.474148)
			(xy 406.761733 -402.4321) (xy 406.738137 -402.38579) (xy 406.722076 -402.33636) (xy 406.713946 -402.285025)
			(xy 406.713436 -402.259038) (xy 406.71392 -402.233255) (xy 406.721926 -402.182315) (xy 406.737749 -402.133237)
			(xy 406.761006 -402.087213) (xy 406.775666 -402.065998) (xy 406.780746 -402.058886) (xy 406.785572 -402.041868)
			(xy 406.779984 -401.959572) (xy 406.772872 -401.94357) (xy 406.766776 -401.936966) (xy 406.747289 -401.915607)
			(xy 406.714382 -401.868068) (xy 406.689033 -401.816105) (xy 406.671821 -401.760909) (xy 406.663144 -401.703747)
			(xy 406.662636 -401.674838) (xy 406.225756 -401.674838) (xy 406.225186 -401.70524) (xy 406.215582 -401.765279)
			(xy 406.196576 -401.823034) (xy 406.168648 -401.877043) (xy 406.132506 -401.925938) (xy 406.111202 -401.947634)
			(xy 406.103836 -401.954746) (xy 406.095962 -401.973288) (xy 406.095454 -402.055838) (xy 406.095839 -402.065973)
			(xy 406.103559 -402.08471) (xy 406.11044 -402.09216) (xy 408.289717 -404.271437) (xy 428.841656 -404.271437)
			(xy 428.841656 -404.207515) (xy 428.849667 -404.144097) (xy 428.865564 -404.082183) (xy 428.889096 -404.02275)
			(xy 428.91989 -403.966735) (xy 428.957463 -403.91502) (xy 429.00122 -403.868423) (xy 429.050473 -403.827678)
			(xy 429.104444 -403.793427) (xy 429.162283 -403.76621) (xy 429.223076 -403.746457) (xy 429.285866 -403.734479)
			(xy 429.349662 -403.730466) (xy 429.413458 -403.734479) (xy 429.476248 -403.746457) (xy 429.537041 -403.76621)
			(xy 429.59488 -403.793427) (xy 429.648851 -403.827678) (xy 429.698104 -403.868423) (xy 429.741861 -403.91502)
			(xy 429.779434 -403.966735) (xy 429.810228 -404.02275) (xy 429.83376 -404.082183) (xy 429.849657 -404.144097)
			(xy 429.857668 -404.207515) (xy 429.85817 -404.239476) (xy 429.857668 -404.271437) (xy 429.849657 -404.334855)
			(xy 429.83376 -404.396769) (xy 429.810228 -404.456202) (xy 429.779434 -404.512217) (xy 429.741861 -404.563932)
			(xy 429.698104 -404.610529) (xy 429.648851 -404.651274) (xy 429.59488 -404.685525) (xy 429.537041 -404.712742)
			(xy 429.476248 -404.732495) (xy 429.413458 -404.744473) (xy 429.349662 -404.748487) (xy 429.285866 -404.744473)
			(xy 429.223076 -404.732495) (xy 429.162283 -404.712742) (xy 429.104444 -404.685525) (xy 429.050473 -404.651274)
			(xy 429.00122 -404.610529) (xy 428.957463 -404.563932) (xy 428.91989 -404.512217) (xy 428.889096 -404.456202)
			(xy 428.865564 -404.396769) (xy 428.849667 -404.334855) (xy 428.841656 -404.271437) (xy 408.289717 -404.271437)
			(xy 411.909514 -407.891234) (xy 411.91691 -407.898085) (xy 411.935509 -407.905825) (xy 411.945582 -407.90622)
		)
		(stroke
			(width 0)
			(type solid)
		)
		(fill yes)
		(layer "In13.Cu")
		(net "P1V8_CPU0_RT_1D")
	)
	(gr_poly
		(pts
			(xy 350.869504 -251.17552) (xy 350.881263 -251.174932) (xy 350.902326 -251.164475) (xy 350.90989 -251.155454)
			(xy 350.966024 -251.08154) (xy 350.970596 -251.058426) (xy 350.967294 -251.046742) (xy 350.961954 -251.026524)
			(xy 350.956222 -250.985101) (xy 350.955864 -250.964192) (xy 350.956386 -250.938937) (xy 350.964699 -250.889115)
			(xy 350.9811 -250.841341) (xy 351.005141 -250.796918) (xy 351.036165 -250.757058) (xy 351.073327 -250.722848)
			(xy 351.115613 -250.695222) (xy 351.161869 -250.674932) (xy 351.210834 -250.662532) (xy 351.261172 -250.658361)
			(xy 351.31151 -250.662532) (xy 351.360475 -250.674932) (xy 351.406731 -250.695222) (xy 351.449017 -250.722848)
			(xy 351.486179 -250.757058) (xy 351.517203 -250.796918) (xy 351.541244 -250.841341) (xy 351.557645 -250.889115)
			(xy 351.565958 -250.938937) (xy 351.56648 -250.964192) (xy 351.566119 -250.9851) (xy 351.560385 -251.026523)
			(xy 351.55505 -251.046742) (xy 351.551748 -251.058426) (xy 351.55632 -251.08154) (xy 351.612454 -251.155454)
			(xy 351.620099 -251.164477) (xy 351.641282 -251.174931) (xy 351.653094 -251.17552) (xy 352.749358 -251.17552)
			(xy 352.761111 -251.174921) (xy 352.782155 -251.16445) (xy 352.789744 -251.155454) (xy 352.845878 -251.08154)
			(xy 352.85045 -251.058426) (xy 352.847148 -251.046742) (xy 352.841809 -251.026523) (xy 352.836077 -250.985101)
			(xy 352.835718 -250.964192) (xy 352.83624 -250.938937) (xy 352.844553 -250.889115) (xy 352.860954 -250.841341)
			(xy 352.884995 -250.796918) (xy 352.916019 -250.757058) (xy 352.953181 -250.722848) (xy 352.995467 -250.695222)
			(xy 353.041723 -250.674932) (xy 353.090688 -250.662532) (xy 353.141026 -250.658361) (xy 353.191364 -250.662532)
			(xy 353.240329 -250.674932) (xy 353.286585 -250.695222) (xy 353.328871 -250.722848) (xy 353.366033 -250.757058)
			(xy 353.397057 -250.796918) (xy 353.421098 -250.841341) (xy 353.437499 -250.889115) (xy 353.445812 -250.938937)
			(xy 353.446334 -250.964192) (xy 353.445973 -250.9851) (xy 353.440238 -251.026522) (xy 353.434904 -251.046742)
			(xy 353.431602 -251.058426) (xy 353.436174 -251.08154) (xy 353.492308 -251.155454) (xy 353.49995 -251.164485)
			(xy 353.521133 -251.174958) (xy 353.532948 -251.17552) (xy 354.629466 -251.17552) (xy 354.641218 -251.174919)
			(xy 354.662259 -251.164447) (xy 354.669852 -251.155454) (xy 354.725986 -251.08154) (xy 354.730558 -251.058426)
			(xy 354.727256 -251.046742) (xy 354.721917 -251.026523) (xy 354.716185 -250.985101) (xy 354.715826 -250.964192)
			(xy 354.716348 -250.938937) (xy 354.724661 -250.889115) (xy 354.741062 -250.841341) (xy 354.765103 -250.796918)
			(xy 354.796127 -250.757058) (xy 354.833289 -250.722848) (xy 354.875575 -250.695222) (xy 354.921831 -250.674932)
			(xy 354.970796 -250.662532) (xy 355.021134 -250.658361) (xy 355.071472 -250.662532) (xy 355.120437 -250.674932)
			(xy 355.166693 -250.695222) (xy 355.208979 -250.722848) (xy 355.246141 -250.757058) (xy 355.277165 -250.796918)
			(xy 355.301206 -250.841341) (xy 355.317607 -250.889115) (xy 355.32592 -250.938937) (xy 355.326442 -250.964192)
			(xy 355.326081 -250.9851) (xy 355.320346 -251.026522) (xy 355.315012 -251.046742) (xy 355.31171 -251.058426)
			(xy 355.316282 -251.08154) (xy 355.372416 -251.155454) (xy 355.380059 -251.164483) (xy 355.401241 -251.174953)
			(xy 355.413056 -251.17552) (xy 356.509574 -251.17552) (xy 356.521325 -251.174917) (xy 356.542364 -251.164443)
			(xy 356.54996 -251.155454) (xy 356.606094 -251.08154) (xy 356.610666 -251.058426) (xy 356.607364 -251.046742)
			(xy 356.602025 -251.026523) (xy 356.596293 -250.985101) (xy 356.595934 -250.964192) (xy 356.596456 -250.938937)
			(xy 356.604769 -250.889115) (xy 356.62117 -250.841341) (xy 356.645211 -250.796918) (xy 356.676235 -250.757058)
			(xy 356.713397 -250.722848) (xy 356.755683 -250.695222) (xy 356.801939 -250.674932) (xy 356.850904 -250.662532)
			(xy 356.901242 -250.658361) (xy 356.95158 -250.662532) (xy 357.000545 -250.674932) (xy 357.046801 -250.695222)
			(xy 357.089087 -250.722848) (xy 357.126249 -250.757058) (xy 357.157273 -250.796918) (xy 357.181314 -250.841341)
			(xy 357.197715 -250.889115) (xy 357.206028 -250.938937) (xy 357.20655 -250.964192) (xy 357.206189 -250.9851)
			(xy 357.200454 -251.026522) (xy 357.19512 -251.046742) (xy 357.191818 -251.058426) (xy 357.19639 -251.08154)
			(xy 357.252524 -251.155454) (xy 357.260168 -251.164482) (xy 357.28135 -251.174948) (xy 357.293164 -251.17552)
			(xy 357.449374 -251.17552) (xy 357.461125 -251.174917) (xy 357.482164 -251.164443) (xy 357.48976 -251.155454)
			(xy 357.545894 -251.08154) (xy 357.550466 -251.058426) (xy 357.547164 -251.046742) (xy 357.541825 -251.026523)
			(xy 357.536093 -250.985101) (xy 357.535734 -250.964192) (xy 357.536256 -250.938937) (xy 357.544569 -250.889115)
			(xy 357.56097 -250.841341) (xy 357.585011 -250.796918) (xy 357.616035 -250.757058) (xy 357.653197 -250.722848)
			(xy 357.695483 -250.695222) (xy 357.741739 -250.674932) (xy 357.790704 -250.662532) (xy 357.841042 -250.658361)
			(xy 357.89138 -250.662532) (xy 357.940345 -250.674932) (xy 357.986601 -250.695222) (xy 358.028887 -250.722848)
			(xy 358.066049 -250.757058) (xy 358.097073 -250.796918) (xy 358.121114 -250.841341) (xy 358.137515 -250.889115)
			(xy 358.145828 -250.938937) (xy 358.14635 -250.964192) (xy 358.145989 -250.9851) (xy 358.140254 -251.026522)
			(xy 358.13492 -251.046742) (xy 358.131618 -251.058426) (xy 358.13619 -251.08154) (xy 358.192324 -251.155454)
			(xy 358.199968 -251.164482) (xy 358.22115 -251.174948) (xy 358.232964 -251.17552) (xy 359.010204 -251.17552)
			(xy 359.015158 -251.175401) (xy 359.02488 -251.173482) (xy 359.029508 -251.17171) (xy 359.056178 -251.160788)
			(xy 359.063036 -251.15393) (xy 359.082378 -251.13583) (xy 359.125594 -251.105198) (xy 359.173002 -251.081565)
			(xy 359.223475 -251.065491) (xy 359.275818 -251.057358) (xy 359.32879 -251.057358) (xy 359.381133 -251.065491)
			(xy 359.431606 -251.081565) (xy 359.479014 -251.105198) (xy 359.52223 -251.13583) (xy 359.541572 -251.15393)
			(xy 359.54843 -251.160788) (xy 359.5751 -251.17171) (xy 359.579728 -251.173482) (xy 359.58945 -251.1754)
			(xy 359.594404 -251.17552) (xy 359.924604 -251.17552) (xy 359.929558 -251.175401) (xy 359.93928 -251.173482)
			(xy 359.943908 -251.17171) (xy 359.970578 -251.160788) (xy 359.977436 -251.15393) (xy 359.996778 -251.13583)
			(xy 360.039994 -251.105198) (xy 360.087402 -251.081565) (xy 360.137875 -251.065491) (xy 360.190218 -251.057358)
			(xy 360.24319 -251.057358) (xy 360.295533 -251.065491) (xy 360.346006 -251.081565) (xy 360.393414 -251.105198)
			(xy 360.43663 -251.13583) (xy 360.455972 -251.15393) (xy 360.46283 -251.160788) (xy 360.4895 -251.17171)
			(xy 360.494128 -251.173482) (xy 360.50385 -251.1754) (xy 360.508804 -251.17552) (xy 361.20324 -251.17552)
			(xy 361.214995 -251.174925) (xy 361.236045 -251.164459) (xy 361.243626 -251.155454) (xy 361.29976 -251.08154)
			(xy 361.304332 -251.058426) (xy 361.30103 -251.046742) (xy 361.295691 -251.026523) (xy 361.28996 -250.985101)
			(xy 361.2896 -250.964192) (xy 361.290122 -250.938937) (xy 361.298435 -250.889115) (xy 361.314836 -250.841341)
			(xy 361.338877 -250.796918) (xy 361.369901 -250.757058) (xy 361.407063 -250.722848) (xy 361.449349 -250.695222)
			(xy 361.495605 -250.674932) (xy 361.54457 -250.662532) (xy 361.594908 -250.658361) (xy 361.645246 -250.662532)
			(xy 361.694211 -250.674932) (xy 361.740467 -250.695222) (xy 361.782753 -250.722848) (xy 361.819915 -250.757058)
			(xy 361.850939 -250.796918) (xy 361.87498 -250.841341) (xy 361.891381 -250.889115) (xy 361.899694 -250.938937)
			(xy 361.900216 -250.964192) (xy 361.899855 -250.9851) (xy 361.89412 -251.026522) (xy 361.888786 -251.046742)
			(xy 361.885484 -251.058426) (xy 361.890056 -251.08154) (xy 361.94619 -251.155454) (xy 361.953838 -251.164471)
			(xy 361.975021 -251.17491) (xy 361.98683 -251.17552) (xy 362.14304 -251.17552) (xy 362.154795 -251.174925)
			(xy 362.175845 -251.164459) (xy 362.183426 -251.155454) (xy 362.23956 -251.08154) (xy 362.244132 -251.058426)
			(xy 362.24083 -251.046742) (xy 362.235491 -251.026523) (xy 362.22976 -250.985101) (xy 362.2294 -250.964192)
			(xy 362.229922 -250.938937) (xy 362.238235 -250.889115) (xy 362.254636 -250.841341) (xy 362.278677 -250.796918)
			(xy 362.309701 -250.757058) (xy 362.346863 -250.722848) (xy 362.389149 -250.695222) (xy 362.435405 -250.674932)
			(xy 362.48437 -250.662532) (xy 362.534708 -250.658361) (xy 362.585046 -250.662532) (xy 362.634011 -250.674932)
			(xy 362.680267 -250.695222) (xy 362.722553 -250.722848) (xy 362.759715 -250.757058) (xy 362.790739 -250.796918)
			(xy 362.81478 -250.841341) (xy 362.831181 -250.889115) (xy 362.839494 -250.938937) (xy 362.840016 -250.964192)
			(xy 362.839655 -250.9851) (xy 362.83392 -251.026522) (xy 362.828586 -251.046742) (xy 362.825284 -251.058426)
			(xy 362.829856 -251.08154) (xy 362.88599 -251.155454) (xy 362.893638 -251.164471) (xy 362.914821 -251.17491)
			(xy 362.92663 -251.17552) (xy 363.083094 -251.17552) (xy 363.094843 -251.174913) (xy 363.115875 -251.164434)
			(xy 363.12348 -251.155454) (xy 363.179614 -251.08154) (xy 363.184186 -251.058426) (xy 363.180884 -251.046742)
			(xy 363.175544 -251.026524) (xy 363.169812 -250.985101) (xy 363.169454 -250.964192) (xy 363.169976 -250.938937)
			(xy 363.178289 -250.889115) (xy 363.19469 -250.841341) (xy 363.218731 -250.796918) (xy 363.249755 -250.757058)
			(xy 363.286917 -250.722848) (xy 363.329203 -250.695222) (xy 363.375459 -250.674932) (xy 363.424424 -250.662532)
			(xy 363.474762 -250.658361) (xy 363.5251 -250.662532) (xy 363.574065 -250.674932) (xy 363.620321 -250.695222)
			(xy 363.662607 -250.722848) (xy 363.699769 -250.757058) (xy 363.730793 -250.796918) (xy 363.754834 -250.841341)
			(xy 363.771235 -250.889115) (xy 363.779548 -250.938937) (xy 363.78007 -250.964192) (xy 363.779709 -250.9851)
			(xy 363.773975 -251.026523) (xy 363.76864 -251.046742) (xy 363.765338 -251.058426) (xy 363.76991 -251.08154)
			(xy 363.826044 -251.155454) (xy 363.833689 -251.164478) (xy 363.854871 -251.174937) (xy 363.866684 -251.17552)
			(xy 364.963202 -251.17552) (xy 364.974961 -251.174933) (xy 364.996024 -251.164476) (xy 365.003588 -251.155454)
			(xy 365.059722 -251.08154) (xy 365.064294 -251.058426) (xy 365.060992 -251.046742) (xy 365.055652 -251.026524)
			(xy 365.04992 -250.985101) (xy 365.049562 -250.964192) (xy 365.050084 -250.938937) (xy 365.058397 -250.889115)
			(xy 365.074798 -250.841341) (xy 365.098839 -250.796918) (xy 365.129863 -250.757058) (xy 365.167025 -250.722848)
			(xy 365.209311 -250.695222) (xy 365.255567 -250.674932) (xy 365.304532 -250.662532) (xy 365.35487 -250.658361)
			(xy 365.405208 -250.662532) (xy 365.454173 -250.674932) (xy 365.500429 -250.695222) (xy 365.542715 -250.722848)
			(xy 365.579877 -250.757058) (xy 365.610901 -250.796918) (xy 365.634942 -250.841341) (xy 365.651343 -250.889115)
			(xy 365.659656 -250.938937) (xy 365.660178 -250.964192) (xy 365.659817 -250.9851) (xy 365.654083 -251.026523)
			(xy 365.648748 -251.046742) (xy 365.645446 -251.058426) (xy 365.650018 -251.08154) (xy 365.706152 -251.155454)
			(xy 365.713797 -251.164477) (xy 365.73498 -251.174932) (xy 365.746792 -251.17552) (xy 365.903256 -251.17552)
			(xy 365.915009 -251.174921) (xy 365.936054 -251.164451) (xy 365.943642 -251.155454) (xy 365.999776 -251.08154)
			(xy 366.004348 -251.058426) (xy 366.001046 -251.046742) (xy 365.995707 -251.026523) (xy 365.989976 -250.985101)
			(xy 365.989616 -250.964192) (xy 365.990138 -250.938937) (xy 365.998451 -250.889115) (xy 366.014852 -250.841341)
			(xy 366.038893 -250.796918) (xy 366.069917 -250.757058) (xy 366.107079 -250.722848) (xy 366.149365 -250.695222)
			(xy 366.195621 -250.674932) (xy 366.244586 -250.662532) (xy 366.294924 -250.658361) (xy 366.345262 -250.662532)
			(xy 366.394227 -250.674932) (xy 366.440483 -250.695222) (xy 366.482769 -250.722848) (xy 366.519931 -250.757058)
			(xy 366.550955 -250.796918) (xy 366.574996 -250.841341) (xy 366.591397 -250.889115) (xy 366.59971 -250.938937)
			(xy 366.600232 -250.964192) (xy 366.599871 -250.9851) (xy 366.594136 -251.026522) (xy 366.588802 -251.046742)
			(xy 366.5855 -251.058426) (xy 366.590072 -251.08154) (xy 366.646206 -251.155454) (xy 366.653855 -251.164468)
			(xy 366.675038 -251.174901) (xy 366.686846 -251.17552) (xy 366.843056 -251.17552) (xy 366.854809 -251.174921)
			(xy 366.875854 -251.164451) (xy 366.883442 -251.155454) (xy 366.939576 -251.08154) (xy 366.944148 -251.058426)
			(xy 366.940846 -251.046742) (xy 366.935507 -251.026523) (xy 366.929776 -250.985101) (xy 366.929416 -250.964192)
			(xy 366.929938 -250.938937) (xy 366.938251 -250.889115) (xy 366.954652 -250.841341) (xy 366.978693 -250.796918)
			(xy 367.009717 -250.757058) (xy 367.046879 -250.722848) (xy 367.089165 -250.695222) (xy 367.135421 -250.674932)
			(xy 367.184386 -250.662532) (xy 367.234724 -250.658361) (xy 367.285062 -250.662532) (xy 367.334027 -250.674932)
			(xy 367.380283 -250.695222) (xy 367.422569 -250.722848) (xy 367.459731 -250.757058) (xy 367.490755 -250.796918)
			(xy 367.514796 -250.841341) (xy 367.531197 -250.889115) (xy 367.53951 -250.938937) (xy 367.540032 -250.964192)
			(xy 367.539671 -250.9851) (xy 367.533936 -251.026522) (xy 367.528602 -251.046742) (xy 367.5253 -251.058426)
			(xy 367.529872 -251.08154) (xy 367.586006 -251.155454) (xy 367.593655 -251.164468) (xy 367.614838 -251.174901)
			(xy 367.626646 -251.17552) (xy 368.723164 -251.17552) (xy 368.734916 -251.17492) (xy 368.755958 -251.164448)
			(xy 368.76355 -251.155454) (xy 368.819684 -251.08154) (xy 368.824256 -251.058426) (xy 368.820954 -251.046742)
			(xy 368.815615 -251.026523) (xy 368.809883 -250.985101) (xy 368.809524 -250.964192) (xy 368.810046 -250.938937)
			(xy 368.818359 -250.889115) (xy 368.83476 -250.841341) (xy 368.858801 -250.796918) (xy 368.889825 -250.757058)
			(xy 368.926987 -250.722848) (xy 368.969273 -250.695222) (xy 369.015529 -250.674932) (xy 369.064494 -250.662532)
			(xy 369.114832 -250.658361) (xy 369.16517 -250.662532) (xy 369.214135 -250.674932) (xy 369.260391 -250.695222)
			(xy 369.302677 -250.722848) (xy 369.339839 -250.757058) (xy 369.370863 -250.796918) (xy 369.394904 -250.841341)
			(xy 369.411305 -250.889115) (xy 369.419618 -250.938937) (xy 369.42014 -250.964192) (xy 369.419779 -250.9851)
			(xy 369.414044 -251.026522) (xy 369.40871 -251.046742) (xy 369.405408 -251.058426) (xy 369.40998 -251.08154)
			(xy 369.466114 -251.155454) (xy 369.473757 -251.164484) (xy 369.494939 -251.174954) (xy 369.506754 -251.17552)
			(xy 369.663218 -251.17552) (xy 369.674975 -251.174929) (xy 369.696033 -251.164469) (xy 369.703604 -251.155454)
			(xy 369.759738 -251.08154) (xy 369.76431 -251.058426) (xy 369.761008 -251.046742) (xy 369.755668 -251.026524)
			(xy 369.749935 -250.985101) (xy 369.749578 -250.964192) (xy 369.7501 -250.938937) (xy 369.758413 -250.889115)
			(xy 369.774814 -250.841341) (xy 369.798855 -250.796918) (xy 369.829879 -250.757058) (xy 369.867041 -250.722848)
			(xy 369.909327 -250.695222) (xy 369.955583 -250.674932) (xy 370.004548 -250.662532) (xy 370.054886 -250.658361)
			(xy 370.105224 -250.662532) (xy 370.154189 -250.674932) (xy 370.200445 -250.695222) (xy 370.242731 -250.722848)
			(xy 370.279893 -250.757058) (xy 370.310917 -250.796918) (xy 370.334958 -250.841341) (xy 370.351359 -250.889115)
			(xy 370.359672 -250.938937) (xy 370.360194 -250.964192) (xy 370.359833 -250.9851) (xy 370.354097 -251.026522)
			(xy 370.348764 -251.046742) (xy 370.345462 -251.058426) (xy 370.350034 -251.08154) (xy 370.406168 -251.155454)
			(xy 370.413814 -251.164474) (xy 370.434997 -251.174923) (xy 370.446808 -251.17552) (xy 370.603018 -251.17552)
			(xy 370.614775 -251.174929) (xy 370.635833 -251.164469) (xy 370.643404 -251.155454) (xy 370.699538 -251.08154)
			(xy 370.70411 -251.058426) (xy 370.700808 -251.046742) (xy 370.695468 -251.026524) (xy 370.689735 -250.985101)
			(xy 370.689378 -250.964192) (xy 370.6899 -250.938937) (xy 370.698213 -250.889115) (xy 370.714614 -250.841341)
			(xy 370.738655 -250.796918) (xy 370.769679 -250.757058) (xy 370.806841 -250.722848) (xy 370.849127 -250.695222)
			(xy 370.895383 -250.674932) (xy 370.944348 -250.662532) (xy 370.994686 -250.658361) (xy 371.045024 -250.662532)
			(xy 371.093989 -250.674932) (xy 371.140245 -250.695222) (xy 371.182531 -250.722848) (xy 371.219693 -250.757058)
			(xy 371.250717 -250.796918) (xy 371.274758 -250.841341) (xy 371.291159 -250.889115) (xy 371.299472 -250.938937)
			(xy 371.299994 -250.964192) (xy 371.299633 -250.9851) (xy 371.293897 -251.026522) (xy 371.288564 -251.046742)
			(xy 371.285262 -251.058426) (xy 371.289834 -251.08154) (xy 371.345968 -251.155454) (xy 371.353565 -251.164433)
			(xy 371.374609 -251.174879) (xy 371.386354 -251.17552) (xy 372.483126 -251.17552) (xy 372.494883 -251.174927)
			(xy 372.515938 -251.164465) (xy 372.523512 -251.155454) (xy 372.579646 -251.08154) (xy 372.584218 -251.058426)
			(xy 372.580916 -251.046742) (xy 372.575576 -251.026524) (xy 372.569843 -250.985101) (xy 372.569486 -250.964192)
			(xy 372.569957 -250.940201) (xy 372.577464 -250.89281) (xy 372.592292 -250.847177) (xy 372.614076 -250.804425)
			(xy 372.64228 -250.765607) (xy 372.676208 -250.731678) (xy 372.715026 -250.703475) (xy 372.757778 -250.681692)
			(xy 372.803412 -250.666864) (xy 372.850803 -250.659357) (xy 372.874794 -250.658884) (xy 372.899487 -250.659359)
			(xy 372.94823 -250.667307) (xy 372.995058 -250.682996) (xy 373.038751 -250.706018) (xy 373.078168 -250.735773)
			(xy 373.112282 -250.771483) (xy 373.140204 -250.812219) (xy 373.161205 -250.856918) (xy 373.174739 -250.904414)
			(xy 373.17807 -250.928886) (xy 373.179848 -250.943618) (xy 373.197882 -250.966224) (xy 373.298212 -251.001022)
			(xy 373.299736 -251.00153) (xy 373.29999 -251.00153) (xy 373.308882 -251.003866) (xy 373.327219 -251.002758)
			(xy 373.343997 -250.995277) (xy 373.35079 -250.989084) (xy 373.99341 -250.346464) (xy 374.000261 -250.339068)
			(xy 374.007996 -250.320469) (xy 374.008396 -250.310396) (xy 374.008396 -250.284488) (xy 374.004332 -250.274836)
			(xy 373.996015 -250.254544) (xy 373.984623 -250.212196) (xy 373.979403 -250.168654) (xy 373.980461 -250.124813)
			(xy 373.983758 -250.103132) (xy 373.988179 -250.079779) (xy 374.003291 -250.03472) (xy 374.025203 -249.992546)
			(xy 374.053384 -249.954276) (xy 374.087155 -249.920835) (xy 374.125699 -249.89303) (xy 374.168086 -249.871533)
			(xy 374.213291 -249.856863) (xy 374.260224 -249.849374) (xy 374.283986 -249.848878) (xy 374.294146 -249.848878)
			(xy 374.312434 -249.841258) (xy 374.370346 -249.783346) (xy 374.370854 -249.782838) (xy 374.377435 -249.775456)
			(xy 374.384882 -249.757157) (xy 374.385332 -249.747278) (xy 374.385332 -247.32107) (xy 374.384904 -247.311002)
			(xy 374.377186 -247.292402) (xy 374.370346 -247.285002) (xy 374.312434 -247.22709) (xy 374.294146 -247.21947)
			(xy 374.283986 -247.21947) (xy 374.258773 -247.218893) (xy 374.209048 -247.210488) (xy 374.161382 -247.194026)
			(xy 374.117069 -247.169953) (xy 374.077315 -247.138925) (xy 374.043201 -247.101785) (xy 374.015655 -247.059543)
			(xy 373.995426 -247.013349) (xy 373.983064 -246.964458) (xy 373.978906 -246.9142) (xy 373.983064 -246.863942)
			(xy 373.995426 -246.815051) (xy 374.015655 -246.768857) (xy 374.043201 -246.726615) (xy 374.077315 -246.689475)
			(xy 374.117069 -246.658447) (xy 374.161382 -246.634374) (xy 374.209048 -246.617912) (xy 374.258773 -246.609507)
			(xy 374.283986 -246.608854) (xy 374.294146 -246.608854) (xy 374.312434 -246.601234) (xy 374.370346 -246.543322)
			(xy 374.370854 -246.542814) (xy 374.377431 -246.535431) (xy 374.384869 -246.517132) (xy 374.385332 -246.507254)
			(xy 374.385332 -244.081046) (xy 374.384831 -244.070993) (xy 374.377117 -244.052425) (xy 374.370346 -244.044978)
			(xy 374.312434 -243.987066) (xy 374.294146 -243.979446) (xy 374.283986 -243.979446) (xy 374.258766 -243.978868)
			(xy 374.20903 -243.970462) (xy 374.161351 -243.953995) (xy 374.117027 -243.929917) (xy 374.077263 -243.898881)
			(xy 374.043141 -243.861731) (xy 374.015588 -243.819479) (xy 373.995354 -243.773273) (xy 373.982989 -243.72437)
			(xy 373.97883 -243.6741) (xy 373.982989 -243.62383) (xy 373.995354 -243.574927) (xy 374.015588 -243.528721)
			(xy 374.043141 -243.486469) (xy 374.077263 -243.449319) (xy 374.117027 -243.418283) (xy 374.161351 -243.394205)
			(xy 374.20903 -243.377738) (xy 374.258766 -243.369332) (xy 374.283986 -243.36883) (xy 374.294146 -243.36883)
			(xy 374.312434 -243.36121) (xy 374.370346 -243.303298) (xy 374.370854 -243.30279) (xy 374.377443 -243.295411)
			(xy 374.384909 -243.277112) (xy 374.385332 -243.26723) (xy 374.385332 -240.841022) (xy 374.384827 -240.830971)
			(xy 374.377107 -240.812409) (xy 374.370346 -240.804954) (xy 374.312434 -240.747042) (xy 374.294146 -240.739422)
			(xy 374.283986 -240.739422) (xy 374.258768 -240.738845) (xy 374.209036 -240.730439) (xy 374.161361 -240.713973)
			(xy 374.11704 -240.689897) (xy 374.077279 -240.658863) (xy 374.04316 -240.621717) (xy 374.015609 -240.579468)
			(xy 373.995377 -240.533266) (xy 373.983013 -240.484366) (xy 373.978854 -240.4341) (xy 373.983013 -240.383834)
			(xy 373.995377 -240.334934) (xy 374.015609 -240.288732) (xy 374.04316 -240.246483) (xy 374.077279 -240.209337)
			(xy 374.11704 -240.178303) (xy 374.161361 -240.154227) (xy 374.209036 -240.137761) (xy 374.258768 -240.129355)
			(xy 374.283986 -240.128806) (xy 374.294146 -240.128806) (xy 374.312434 -240.121186) (xy 374.370346 -240.063274)
			(xy 374.370854 -240.062766) (xy 374.377439 -240.055386) (xy 374.384896 -240.037087) (xy 374.385332 -240.027206)
			(xy 374.385332 -237.600998) (xy 374.384909 -237.590927) (xy 374.377198 -237.57232) (xy 374.370346 -237.56493)
			(xy 374.312434 -237.507018) (xy 374.294146 -237.499398) (xy 374.283986 -237.499398) (xy 374.25877 -237.498821)
			(xy 374.209041 -237.490415) (xy 374.16137 -237.473951) (xy 374.117053 -237.449876) (xy 374.077296 -237.418845)
			(xy 374.043179 -237.381702) (xy 374.01563 -237.339456) (xy 373.9954 -237.293258) (xy 373.983037 -237.244362)
			(xy 373.978878 -237.1941) (xy 373.983037 -237.143838) (xy 373.9954 -237.094942) (xy 374.01563 -237.048744)
			(xy 374.043179 -237.006498) (xy 374.077296 -236.969355) (xy 374.117053 -236.938324) (xy 374.16137 -236.914249)
			(xy 374.209042 -236.897785) (xy 374.25877 -236.889379) (xy 374.283986 -236.888782) (xy 374.294146 -236.888782)
			(xy 374.312434 -236.881162) (xy 374.370346 -236.82325) (xy 374.370854 -236.822742) (xy 374.377435 -236.815361)
			(xy 374.384884 -236.797062) (xy 374.385332 -236.787182) (xy 374.385332 -235.980986) (xy 374.384907 -235.970916)
			(xy 374.377193 -235.952312) (xy 374.370346 -235.944918) (xy 374.312434 -235.887006) (xy 374.294146 -235.879386)
			(xy 374.283986 -235.879386) (xy 374.258771 -235.878809) (xy 374.209044 -235.870404) (xy 374.161375 -235.85394)
			(xy 374.11706 -235.829866) (xy 374.077304 -235.798836) (xy 374.043188 -235.761695) (xy 374.015641 -235.719451)
			(xy 373.995411 -235.673254) (xy 373.983049 -235.62436) (xy 373.97889 -235.5741) (xy 373.983049 -235.52384)
			(xy 373.995411 -235.474946) (xy 374.015641 -235.428749) (xy 374.043188 -235.386505) (xy 374.077304 -235.349363)
			(xy 374.11706 -235.318334) (xy 374.161375 -235.29426) (xy 374.209044 -235.277796) (xy 374.258771 -235.269391)
			(xy 374.283986 -235.26877) (xy 374.294146 -235.26877) (xy 374.312434 -235.26115) (xy 374.370346 -235.203238)
			(xy 374.370854 -235.20273) (xy 374.377434 -235.195348) (xy 374.384878 -235.177049) (xy 374.385332 -235.16717)
			(xy 374.385332 -232.740962) (xy 374.384903 -232.730894) (xy 374.377182 -232.712297) (xy 374.370346 -232.704894)
			(xy 374.312434 -232.646982) (xy 374.294146 -232.639362) (xy 374.283986 -232.639362) (xy 374.258773 -232.638785)
			(xy 374.20905 -232.63038) (xy 374.161385 -232.613918) (xy 374.117073 -232.589846) (xy 374.07732 -232.558819)
			(xy 374.043207 -232.52168) (xy 374.015662 -232.479439) (xy 373.995434 -232.433246) (xy 373.983072 -232.384356)
			(xy 373.978914 -232.3341) (xy 373.983072 -232.283843) (xy 373.995434 -232.234954) (xy 374.015662 -232.188761)
			(xy 374.043207 -232.14652) (xy 374.07732 -232.109381) (xy 374.117073 -232.078354) (xy 374.161385 -232.054282)
			(xy 374.20905 -232.03782) (xy 374.258773 -232.029415) (xy 374.283986 -232.028746) (xy 374.294146 -232.028746)
			(xy 374.312434 -232.021126) (xy 374.370346 -231.963214) (xy 374.370854 -231.962706) (xy 374.37743 -231.955323)
			(xy 374.384865 -231.937023) (xy 374.385332 -231.927146) (xy 374.385332 -229.501192) (xy 374.384908 -229.491122)
			(xy 374.377195 -229.472516) (xy 374.370346 -229.465124) (xy 374.312434 -229.407212) (xy 374.294146 -229.399592)
			(xy 374.283986 -229.399592) (xy 374.258771 -229.399015) (xy 374.209043 -229.39061) (xy 374.161373 -229.374146)
			(xy 374.117057 -229.350071) (xy 374.0773 -229.319041) (xy 374.043183 -229.281898) (xy 374.015636 -229.239654)
			(xy 373.995405 -229.193456) (xy 373.983043 -229.144561) (xy 373.978884 -229.0943) (xy 373.983043 -229.044039)
			(xy 373.995405 -228.995144) (xy 374.015636 -228.948946) (xy 374.043184 -228.906702) (xy 374.0773 -228.869559)
			(xy 374.117057 -228.838529) (xy 374.161373 -228.814454) (xy 374.209043 -228.79799) (xy 374.258771 -228.789585)
			(xy 374.283986 -228.788976) (xy 374.294146 -228.788976) (xy 374.312434 -228.781356) (xy 374.370346 -228.723444)
			(xy 374.370854 -228.722936) (xy 374.377435 -228.715554) (xy 374.384881 -228.697255) (xy 374.385332 -228.687376)
			(xy 374.385332 -226.261168) (xy 374.384904 -226.2511) (xy 374.377185 -226.232501) (xy 374.370346 -226.2251)
			(xy 374.312434 -226.167188) (xy 374.294146 -226.159568) (xy 374.283986 -226.159568) (xy 374.258773 -226.158991)
			(xy 374.209049 -226.150586) (xy 374.161382 -226.134124) (xy 374.11707 -226.110051) (xy 374.077316 -226.079023)
			(xy 374.043202 -226.041883) (xy 374.015657 -225.999642) (xy 373.995428 -225.953448) (xy 373.983066 -225.904557)
			(xy 373.978908 -225.8543) (xy 373.983066 -225.804042) (xy 373.995428 -225.755152) (xy 374.015657 -225.708958)
			(xy 374.043203 -225.666716) (xy 374.077316 -225.629577) (xy 374.11707 -225.598549) (xy 374.161383 -225.574476)
			(xy 374.209049 -225.558014) (xy 374.258773 -225.549609) (xy 374.283986 -225.548952) (xy 374.294146 -225.548952)
			(xy 374.312434 -225.541332) (xy 374.370346 -225.48342) (xy 374.370854 -225.482912) (xy 374.377431 -225.475529)
			(xy 374.384868 -225.45723) (xy 374.385332 -225.447352) (xy 374.385332 -215.91016) (xy 374.385763 -215.900094)
			(xy 374.393491 -215.881503) (xy 374.400318 -215.874092) (xy 379.79604 -210.47837) (xy 379.801942 -210.471912)
			(xy 379.809361 -210.456082) (xy 379.811019 -210.438679) (xy 379.809248 -210.43011) (xy 379.78461 -210.332574)
			(xy 379.766322 -210.31327) (xy 379.753368 -210.30946) (xy 379.731379 -210.302532) (xy 379.688641 -210.285233)
			(xy 379.668024 -210.274916) (xy 379.662944 -210.272376) (xy 379.649736 -210.269074) (xy 379.638796 -210.266891)
			(xy 379.616916 -210.271108) (xy 379.607572 -210.277202) (xy 379.523752 -210.337908) (xy 379.51283 -210.364324)
			(xy 379.515116 -210.378548) (xy 379.515624 -210.382612) (xy 379.517854 -210.397434) (xy 379.520271 -210.427314)
			(xy 379.52045 -210.442302) (xy 379.519964 -210.469553) (xy 379.512208 -210.523501) (xy 379.496853 -210.575796)
			(xy 379.474211 -210.625373) (xy 379.444745 -210.671223) (xy 379.409054 -210.712414) (xy 379.367863 -210.748105)
			(xy 379.322013 -210.777571) (xy 379.272436 -210.800213) (xy 379.220141 -210.815568) (xy 379.166193 -210.823324)
			(xy 379.111691 -210.823324) (xy 379.057743 -210.815568) (xy 379.005448 -210.800213) (xy 378.955871 -210.777571)
			(xy 378.910021 -210.748105) (xy 378.86883 -210.712414) (xy 378.833139 -210.671223) (xy 378.803673 -210.625373)
			(xy 378.781031 -210.575796) (xy 378.765676 -210.523501) (xy 378.75792 -210.469553) (xy 378.757434 -210.442302)
			(xy 378.757951 -210.413931) (xy 378.766365 -210.357816) (xy 378.774198 -210.330542) (xy 378.7775 -210.319366)
			(xy 378.773944 -210.296252) (xy 378.714254 -210.211416) (xy 378.69368 -210.199986) (xy 378.681996 -210.199478)
			(xy 378.65019 -210.197405) (xy 378.587421 -210.18632) (xy 378.526528 -210.167483) (xy 378.468465 -210.141186)
			(xy 378.414141 -210.107844) (xy 378.364408 -210.067977) (xy 378.320043 -210.02221) (xy 378.300488 -209.99704)
			(xy 378.291852 -209.985356) (xy 378.265436 -209.974942) (xy 378.162312 -209.992468) (xy 378.153174 -209.994463)
			(xy 378.137118 -210.004022) (xy 378.125561 -210.018707) (xy 378.122434 -210.02752) (xy 378.112299 -210.05809)
			(xy 378.08537 -210.116595) (xy 378.051267 -210.171231) (xy 378.010536 -210.221121) (xy 377.96383 -210.265467)
			(xy 377.911897 -210.303558) (xy 377.855568 -210.334785) (xy 377.795746 -210.358647) (xy 377.733389 -210.374761)
			(xy 377.669497 -210.38287) (xy 377.637294 -210.383374) (xy 377.605335 -210.382872) (xy 377.541922 -210.37486)
			(xy 377.480013 -210.358964) (xy 377.420584 -210.335434) (xy 377.364574 -210.304641) (xy 377.312864 -210.267071)
			(xy 377.26627 -210.223316) (xy 377.225528 -210.174067) (xy 377.19128 -210.1201) (xy 377.164065 -210.062265)
			(xy 377.144314 -210.001476) (xy 377.132337 -209.938691) (xy 377.128323 -209.8749) (xy 377.132337 -209.811109)
			(xy 377.144314 -209.748324) (xy 377.164065 -209.687535) (xy 377.19128 -209.6297) (xy 377.225528 -209.575733)
			(xy 377.26627 -209.526484) (xy 377.312864 -209.482729) (xy 377.364574 -209.445159) (xy 377.420584 -209.414366)
			(xy 377.480013 -209.390836) (xy 377.541922 -209.37494) (xy 377.605335 -209.366928) (xy 377.637294 -209.366358)
			(xy 377.637548 -209.366358) (xy 377.671181 -209.366912) (xy 377.737857 -209.375804) (xy 377.802777 -209.393415)
			(xy 377.864807 -209.419436) (xy 377.922863 -209.453412) (xy 377.975929 -209.494749) (xy 378.023078 -209.542725)
			(xy 378.043694 -209.569304) (xy 378.043948 -209.569304) (xy 378.049842 -209.576482) (xy 378.065546 -209.586367)
			(xy 378.083748 -209.589978) (xy 378.09297 -209.588862) (xy 378.182124 -209.573876) (xy 378.19126 -209.571878)
			(xy 378.207314 -209.562316) (xy 378.218873 -209.547636) (xy 378.222002 -209.538824) (xy 378.232135 -209.50825)
			(xy 378.259059 -209.449736) (xy 378.293158 -209.395092) (xy 378.333886 -209.345192) (xy 378.380591 -209.300836)
			(xy 378.432525 -209.262735) (xy 378.488855 -209.231499) (xy 378.548679 -209.207628) (xy 378.611039 -209.191504)
			(xy 378.674936 -209.183386) (xy 378.707142 -209.18297) (xy 378.737872 -209.183437) (xy 378.798883 -209.190849)
			(xy 378.858556 -209.205561) (xy 378.91602 -209.227358) (xy 378.970439 -209.255922) (xy 379.021018 -209.290837)
			(xy 379.067021 -209.331594) (xy 379.107775 -209.377597) (xy 379.142688 -209.428178) (xy 379.17125 -209.482598)
			(xy 379.193045 -209.540063) (xy 379.207754 -209.599737) (xy 379.215165 -209.660748) (xy 379.21565 -209.691478)
			(xy 379.215221 -209.721412) (xy 379.208191 -209.780865) (xy 379.194213 -209.839079) (xy 379.173483 -209.895243)
			(xy 379.160278 -209.92211) (xy 379.158754 -209.925412) (xy 379.15596 -209.933286) (xy 379.153363 -209.942553)
			(xy 379.154524 -209.96175) (xy 379.158246 -209.970624) (xy 379.19152 -210.042506) (xy 379.194099 -210.047655)
			(xy 379.201151 -210.056754) (xy 379.20549 -210.06054) (xy 379.21438 -210.067906) (xy 379.226064 -210.0707)
			(xy 379.226318 -210.070954) (xy 379.239313 -210.0741) (xy 379.264864 -210.081979) (xy 379.277372 -210.086702)
			(xy 379.290834 -210.092036) (xy 379.319282 -210.086702) (xy 379.396752 -210.015836) (xy 379.40553 -210.006987)
			(xy 379.413907 -209.983544) (xy 379.412754 -209.971132) (xy 379.411738 -209.964274) (xy 379.410976 -209.960972)
			(xy 379.401978 -209.927073) (xy 379.392291 -209.857609) (xy 379.391672 -209.822542) (xy 379.392115 -209.791808)
			(xy 379.39952 -209.730787) (xy 379.414225 -209.671104) (xy 379.436018 -209.613628) (xy 379.46458 -209.559199)
			(xy 379.499495 -209.508609) (xy 379.540253 -209.462597) (xy 379.58626 -209.421833) (xy 379.636846 -209.386912)
			(xy 379.691272 -209.358344) (xy 379.748745 -209.336544) (xy 379.808426 -209.321831) (xy 379.869446 -209.314419)
			(xy 379.90018 -209.314034) (xy 379.912902 -209.314112) (xy 379.938314 -209.31538) (xy 379.95098 -209.316574)
			(xy 379.984047 -209.320445) (xy 380.048854 -209.335689) (xy 380.111119 -209.359258) (xy 380.169777 -209.390749)
			(xy 380.223825 -209.429623) (xy 380.27234 -209.475216) (xy 380.314491 -209.526748) (xy 380.34956 -209.58334)
			(xy 380.376946 -209.644023) (xy 380.387098 -209.67573) (xy 380.390908 -209.688684) (xy 380.410212 -209.706972)
			(xy 380.507748 -209.73161) (xy 380.516313 -209.733403) (xy 380.533721 -209.731735) (xy 380.549554 -209.724311)
			(xy 380.556008 -209.718402) (xy 381.89789 -208.37652) (xy 381.905287 -208.36967) (xy 381.923885 -208.361928)
			(xy 381.933958 -208.361534) (xy 382.117092 -208.361534) (xy 382.127161 -208.361111) (xy 382.145762 -208.353391)
			(xy 382.15316 -208.346548) (xy 382.276604 -208.223104) (xy 382.28302 -208.216081) (xy 382.290578 -208.198638)
			(xy 382.291271 -208.179641) (xy 382.288542 -208.170526) (xy 382.25349 -208.070196) (xy 382.231138 -208.052162)
			(xy 382.216152 -208.050384) (xy 382.184877 -208.046304) (xy 382.123592 -208.031398) (xy 382.064618 -208.009033)
			(xy 382.00886 -207.979551) (xy 381.957172 -207.943406) (xy 381.93345 -207.922622) (xy 381.926576 -207.916896)
			(xy 381.909985 -207.910229) (xy 381.892113 -207.909679) (xy 381.875144 -207.915313) (xy 381.867918 -207.92059)
			(xy 381.840886 -207.941181) (xy 381.782397 -207.975774) (xy 381.719825 -208.002274) (xy 381.654282 -208.02021)
			(xy 381.586934 -208.029262) (xy 381.552958 -208.02981) (xy 381.522229 -208.029343) (xy 381.461218 -208.021931)
			(xy 381.401546 -208.007219) (xy 381.344083 -207.985421) (xy 381.289665 -207.956857) (xy 381.239087 -207.921942)
			(xy 381.193087 -207.881185) (xy 381.152333 -207.835181) (xy 381.117422 -207.7846) (xy 381.088862 -207.730181)
			(xy 381.067069 -207.672715) (xy 381.052362 -207.613042) (xy 381.044954 -207.552031) (xy 381.04445 -207.521302)
			(xy 381.044814 -207.494359) (xy 381.050537 -207.440778) (xy 381.05588 -207.414368) (xy 381.057912 -207.404462)
			(xy 381.05461 -207.385412) (xy 381.006858 -207.30845) (xy 380.991364 -207.29702) (xy 380.981712 -207.29448)
			(xy 380.941326 -207.282542) (xy 380.93171 -207.279676) (xy 380.911699 -207.280909) (xy 380.893689 -207.289721)
			(xy 380.880433 -207.304763) (xy 380.873956 -207.323737) (xy 380.875248 -207.343746) (xy 380.87935 -207.3529)
			(xy 380.891697 -207.379237) (xy 380.909139 -207.434724) (xy 380.917931 -207.492219) (xy 380.918466 -207.521302)
			(xy 380.91798 -207.54855) (xy 380.910224 -207.60249) (xy 380.894871 -207.654778) (xy 380.872233 -207.704348)
			(xy 380.842772 -207.750193) (xy 380.807085 -207.791378) (xy 380.765901 -207.827065) (xy 380.720058 -207.856528)
			(xy 380.670488 -207.879167) (xy 380.6182 -207.894522) (xy 380.56426 -207.902279) (xy 380.509765 -207.902281)
			(xy 380.455824 -207.894527) (xy 380.403536 -207.879176) (xy 380.353965 -207.85654) (xy 380.308119 -207.82708)
			(xy 380.266933 -207.791396) (xy 380.231244 -207.750213) (xy 380.201779 -207.704371) (xy 380.179138 -207.654801)
			(xy 380.163781 -207.602515) (xy 380.156022 -207.548575) (xy 380.156018 -207.49408) (xy 380.16377 -207.440139)
			(xy 380.179119 -207.38785) (xy 380.201753 -207.338278) (xy 380.231211 -207.292431) (xy 380.266894 -207.251243)
			(xy 380.308075 -207.215552) (xy 380.353917 -207.186086) (xy 380.403485 -207.163443) (xy 380.455771 -207.148084)
			(xy 380.509711 -207.140323) (xy 380.536958 -207.139794) (xy 380.543054 -207.139794) (xy 380.556262 -207.140048)
			(xy 380.578868 -207.128364) (xy 380.641098 -207.036162) (xy 380.643384 -207.010762) (xy 380.638558 -206.998824)
			(xy 380.625965 -206.967505) (xy 380.60822 -206.902375) (xy 380.599241 -206.835471) (xy 380.59868 -206.80172)
			(xy 380.599151 -206.770323) (xy 380.606891 -206.708007) (xy 380.622243 -206.647118) (xy 380.644975 -206.588583)
			(xy 380.674739 -206.533291) (xy 380.711084 -206.482083) (xy 380.753456 -206.435739) (xy 380.801211 -206.394964)
			(xy 380.853622 -206.360378) (xy 380.909892 -206.332507) (xy 380.969165 -206.311774) (xy 380.999746 -206.304642)
			(xy 381.008399 -206.302452) (xy 381.023501 -206.29296) (xy 381.02921 -206.2861) (xy 381.047752 -206.26197)
			(xy 381.052813 -206.254769) (xy 381.05813 -206.238006) (xy 381.058166 -206.229204) (xy 381.057912 -206.215488)
			(xy 381.058314 -206.190884) (xy 381.064688 -206.14209) (xy 381.070612 -206.118206) (xy 381.073152 -206.1083)
			(xy 381.070358 -206.088234) (xy 381.023876 -206.008732) (xy 381.007874 -205.99654) (xy 380.997968 -205.994)
			(xy 380.965769 -205.984991) (xy 380.903884 -205.959671) (xy 380.845849 -205.926464) (xy 380.792664 -205.885941)
			(xy 380.745245 -205.838802) (xy 380.704408 -205.785857) (xy 380.670858 -205.728019) (xy 380.645173 -205.666286)
			(xy 380.627795 -205.60172) (xy 380.619024 -205.535434) (xy 380.618492 -205.502002) (xy 380.618994 -205.470041)
			(xy 380.627005 -205.406623) (xy 380.642902 -205.344709) (xy 380.666434 -205.285276) (xy 380.697228 -205.229261)
			(xy 380.734801 -205.177546) (xy 380.778558 -205.130949) (xy 380.827811 -205.090204) (xy 380.881782 -205.055953)
			(xy 380.939621 -205.028736) (xy 381.000414 -205.008983) (xy 381.063204 -204.997005) (xy 381.127 -204.992992)
			(xy 381.190796 -204.997005) (xy 381.253586 -205.008983) (xy 381.314379 -205.028736) (xy 381.372218 -205.055953)
			(xy 381.426189 -205.090204) (xy 381.475442 -205.130949) (xy 381.519199 -205.177546) (xy 381.556772 -205.229261)
			(xy 381.587566 -205.285276) (xy 381.611098 -205.344709) (xy 381.626995 -205.406623) (xy 381.635006 -205.470041)
			(xy 381.635508 -205.502002) (xy 381.635028 -205.533084) (xy 381.627421 -205.594782) (xy 381.612345 -205.655092)
			(xy 381.590024 -205.713112) (xy 381.575818 -205.740762) (xy 381.571246 -205.749906) (xy 381.569214 -205.769972)
			(xy 381.596138 -205.85811) (xy 381.609092 -205.873604) (xy 381.617982 -205.87843) (xy 381.643838 -205.892735)
			(xy 381.69118 -205.928093) (xy 381.732497 -205.970334) (xy 381.766799 -206.018447) (xy 381.793264 -206.071277)
			(xy 381.811258 -206.127559) (xy 381.820349 -206.185944) (xy 381.820928 -206.215488) (xy 381.820381 -206.244589)
			(xy 381.811547 -206.302118) (xy 381.794083 -206.357638) (xy 381.768393 -206.409864) (xy 381.735072 -206.457585)
			(xy 381.694893 -206.499694) (xy 381.648787 -206.535216) (xy 381.62357 -206.549752) (xy 381.616036 -206.554283)
			(xy 381.604352 -206.567404) (xy 381.60071 -206.575406) (xy 381.589788 -206.6036) (xy 381.586854 -206.612082)
			(xy 381.586344 -206.63001) (xy 381.588772 -206.638652) (xy 381.597314 -206.66498) (xy 381.609289 -206.719021)
			(xy 381.615317 -206.774044) (xy 381.615696 -206.80172) (xy 381.61533 -206.828663) (xy 381.609605 -206.882243)
			(xy 381.604266 -206.908654) (xy 381.602234 -206.91856) (xy 381.605536 -206.93761) (xy 381.653288 -207.014572)
			(xy 381.668782 -207.026002) (xy 381.678434 -207.028542) (xy 381.708187 -207.036602) (xy 381.765637 -207.058952)
			(xy 381.819968 -207.088076) (xy 381.870384 -207.123547) (xy 381.893572 -207.143858) (xy 381.900446 -207.149582)
			(xy 381.917034 -207.156244) (xy 381.934902 -207.156788) (xy 381.951865 -207.151148) (xy 381.959104 -207.14589)
			(xy 381.986136 -207.125301) (xy 382.044626 -207.090712) (xy 382.107199 -207.064216) (xy 382.172742 -207.046284)
			(xy 382.240088 -207.037235) (xy 382.274064 -207.03667) (xy 382.30494 -207.037122) (xy 382.366237 -207.044595)
			(xy 382.426179 -207.059436) (xy 382.483882 -207.081426) (xy 382.538497 -207.110242) (xy 382.589222 -207.14546)
			(xy 382.635308 -207.18656) (xy 382.676079 -207.232939) (xy 382.710933 -207.283913) (xy 382.739359 -207.338733)
			(xy 382.760937 -207.396592) (xy 382.775349 -207.456638) (xy 382.77927 -207.487266) (xy 382.781048 -207.502252)
			(xy 382.799082 -207.524604) (xy 382.899412 -207.559656) (xy 382.90852 -207.562429) (xy 382.927534 -207.56174)
			(xy 382.944989 -207.554169) (xy 382.95199 -207.547718) (xy 383.204466 -207.295242) (xy 383.210733 -207.28838)
			(xy 383.218306 -207.271427) (xy 383.219357 -207.252889) (xy 383.213747 -207.235189) (xy 383.208276 -207.227678)
			(xy 383.187441 -207.200584) (xy 383.152453 -207.141869) (xy 383.125644 -207.078998) (xy 383.107499 -207.013101)
			(xy 383.098345 -206.945368) (xy 383.097786 -206.911194) (xy 383.09825 -206.880463) (xy 383.105659 -206.81945)
			(xy 383.120369 -206.759774) (xy 383.142164 -206.702306) (xy 383.170727 -206.647885) (xy 383.205641 -206.597303)
			(xy 383.246398 -206.551298) (xy 383.292403 -206.510541) (xy 383.342985 -206.475627) (xy 383.397406 -206.447064)
			(xy 383.454874 -206.425269) (xy 383.51455 -206.410559) (xy 383.575563 -206.40315) (xy 383.606294 -206.402686)
			(xy 383.637536 -206.403702) (xy 383.646474 -206.403898) (xy 383.663596 -206.398796) (xy 383.677933 -206.388135)
			(xy 383.687748 -206.373206) (xy 383.690114 -206.364586) (xy 383.697989 -206.333578) (xy 383.720446 -206.273673)
			(xy 383.750234 -206.217055) (xy 383.786883 -206.164617) (xy 383.80797 -206.140558) (xy 383.81432 -206.133446)
			(xy 383.821178 -206.115666) (xy 383.82067 -206.028036) (xy 383.813558 -206.01051) (xy 383.807208 -206.003398)
			(xy 383.786125 -205.979854) (xy 383.74934 -205.928461) (xy 383.719208 -205.872904) (xy 383.696193 -205.814042)
			(xy 383.680652 -205.752781) (xy 383.672823 -205.690067) (xy 383.672334 -205.658466) (xy 383.672782 -205.627736)
			(xy 383.680194 -205.566725) (xy 383.694906 -205.507052) (xy 383.716704 -205.449588) (xy 383.74527 -205.39517)
			(xy 383.780187 -205.344592) (xy 383.820946 -205.298592) (xy 383.866952 -205.25784) (xy 383.917535 -205.222931)
			(xy 383.971957 -205.194373) (xy 384.029425 -205.172584) (xy 384.0891 -205.15788) (xy 384.150112 -205.150477)
			(xy 384.180842 -205.149958) (xy 384.212782 -205.15046) (xy 384.276158 -205.158463) (xy 384.338033 -205.174336)
			(xy 384.397435 -205.197831) (xy 384.453427 -205.228578) (xy 384.50513 -205.266093) (xy 384.55173 -205.309785)
			(xy 384.592493 -205.358968) (xy 384.626778 -205.412867) (xy 384.640836 -205.44155) (xy 384.645916 -205.452726)
			(xy 384.665728 -205.467712) (xy 384.759708 -205.483968) (xy 384.771877 -205.485408) (xy 384.79523 -205.478112)
			(xy 384.804412 -205.469998) (xy 391.717276 -198.557134) (xy 391.724115 -198.549733) (xy 391.731829 -198.531135)
			(xy 391.732262 -198.521066) (xy 391.732262 -194.572636) (xy 391.724642 -194.55384) (xy 391.717276 -194.546728)
			(xy 391.495788 -194.32524) (xy 391.488391 -194.318391) (xy 391.469792 -194.310655) (xy 391.45972 -194.310254)
			(xy 371.536214 -194.310254) (xy 371.526152 -194.309814) (xy 371.507574 -194.302072) (xy 371.500146 -194.295268)
			(xy 361.835954 -184.631076) (xy 361.81538 -184.623456) (xy 361.80395 -184.624472) (xy 361.727242 -184.630568)
			(xy 361.718098 -184.632092) (xy 361.709725 -184.634732) (xy 361.695312 -184.644734) (xy 361.689904 -184.65165)
			(xy 361.674463 -184.672332) (xy 361.63891 -184.709746) (xy 361.59864 -184.74203) (xy 361.554389 -184.768595)
			(xy 361.506962 -184.788958) (xy 361.457225 -184.802746) (xy 361.406084 -184.809709) (xy 361.380278 -184.810146)
			(xy 361.353027 -184.809659) (xy 361.299079 -184.8019) (xy 361.246785 -184.786543) (xy 361.197208 -184.763901)
			(xy 361.151358 -184.734435) (xy 361.110167 -184.698744) (xy 361.074475 -184.657555) (xy 361.045006 -184.611706)
			(xy 361.022362 -184.56213) (xy 361.007004 -184.509836) (xy 360.999242 -184.455889) (xy 360.99877 -184.428638)
			(xy 360.999246 -184.40127) (xy 361.007079 -184.347097) (xy 361.022575 -184.2946) (xy 361.045416 -184.244857)
			(xy 361.075133 -184.19889) (xy 361.09275 -184.17794) (xy 361.098846 -184.170828) (xy 361.105196 -184.154064)
			(xy 361.105196 -184.068212) (xy 361.098846 -184.051448) (xy 361.09275 -184.044336) (xy 361.076356 -184.024888)
			(xy 361.048324 -183.982445) (xy 361.026179 -183.936654) (xy 361.010313 -183.888326) (xy 361.001009 -183.838319)
			(xy 360.999278 -183.812942) (xy 360.99877 -183.80329) (xy 360.99115 -183.786272) (xy 353.29749 -176.092612)
			(xy 353.29039 -176.086052) (xy 353.272676 -176.078354) (xy 353.25337 -176.077769) (xy 353.24415 -176.080674)
			(xy 353.143566 -176.117504) (xy 353.125532 -176.140872) (xy 353.124262 -176.155604) (xy 353.121305 -176.183781)
			(xy 353.108128 -176.238881) (xy 353.086949 -176.291428) (xy 353.058233 -176.340265) (xy 353.022613 -176.38432)
			(xy 352.98087 -176.422624) (xy 352.933922 -176.454335) (xy 352.882801 -176.478757) (xy 352.828632 -176.495351)
			(xy 352.772605 -176.503754) (xy 352.744278 -176.504346) (xy 352.717027 -176.503859) (xy 352.663079 -176.4961)
			(xy 352.610785 -176.480743) (xy 352.561208 -176.458101) (xy 352.515358 -176.428635) (xy 352.474167 -176.392944)
			(xy 352.438475 -176.351755) (xy 352.409006 -176.305906) (xy 352.386362 -176.25633) (xy 352.371004 -176.204036)
			(xy 352.363242 -176.150089) (xy 352.36277 -176.122838) (xy 352.363246 -176.09547) (xy 352.371079 -176.041297)
			(xy 352.386575 -175.9888) (xy 352.409416 -175.939057) (xy 352.439133 -175.89309) (xy 352.45675 -175.87214)
			(xy 352.462846 -175.865028) (xy 352.469196 -175.848264) (xy 352.469196 -175.762412) (xy 352.462846 -175.745648)
			(xy 352.45675 -175.738536) (xy 352.43911 -175.717604) (xy 352.409387 -175.671638) (xy 352.38655 -175.62189)
			(xy 352.371066 -175.569387) (xy 352.363255 -175.515208) (xy 352.36277 -175.487838) (xy 352.36277 -175.481488)
			(xy 352.363612 -175.455385) (xy 352.371561 -175.403767) (xy 352.386487 -175.353719) (xy 352.408109 -175.306179)
			(xy 352.421698 -175.283876) (xy 352.425508 -175.278034) (xy 352.43389 -175.24984) (xy 352.427794 -175.223424)
			(xy 352.420174 -175.215296) (xy 352.418904 -175.214026) (xy 349.846392 -172.641514) (xy 349.838994 -172.634667)
			(xy 349.820396 -172.626934) (xy 349.810324 -172.626528) (xy 342.405208 -172.626528) (xy 342.386412 -172.634148)
			(xy 342.3793 -172.641514) (xy 342.14943 -172.871638) (xy 342.142031 -172.87848) (xy 342.123432 -172.886199)
			(xy 342.113362 -172.886624) (xy 340.631018 -172.886624) (xy 340.62416 -172.888402) (xy 340.591685 -172.896799)
			(xy 340.52564 -172.908544) (xy 340.458819 -172.914452) (xy 340.425278 -172.914818) (xy 340.391737 -172.914456)
			(xy 340.324914 -172.90856) (xy 340.258869 -172.896808) (xy 340.226396 -172.888402) (xy 340.219538 -172.886624)
			(xy 333.549498 -172.886624) (xy 333.530702 -172.894244) (xy 333.52359 -172.90161) (xy 333.042006 -173.383194)
			(xy 333.035158 -173.390592) (xy 333.02742 -173.40919) (xy 333.02702 -173.419262) (xy 333.02702 -188.082174)
			(xy 333.027457 -188.092238) (xy 333.035193 -188.110821) (xy 333.042006 -188.118242) (xy 340.36 -195.436236)
			(xy 340.361778 -195.438268) (xy 349.80521 -203.218753) (xy 380.872994 -203.218753) (xy 380.872994 -203.154831)
			(xy 380.881005 -203.091413) (xy 380.896902 -203.029499) (xy 380.920434 -202.970066) (xy 380.951228 -202.914051)
			(xy 380.988801 -202.862336) (xy 381.032558 -202.815739) (xy 381.081811 -202.774994) (xy 381.135782 -202.740743)
			(xy 381.193621 -202.713526) (xy 381.254414 -202.693773) (xy 381.317204 -202.681795) (xy 381.381 -202.677782)
			(xy 381.444796 -202.681795) (xy 381.507586 -202.693773) (xy 381.568379 -202.713526) (xy 381.626218 -202.740743)
			(xy 381.680189 -202.774994) (xy 381.729442 -202.815739) (xy 381.773199 -202.862336) (xy 381.810772 -202.914051)
			(xy 381.841566 -202.970066) (xy 381.865098 -203.029499) (xy 381.880995 -203.091413) (xy 381.889006 -203.154831)
			(xy 381.889508 -203.186792) (xy 381.889006 -203.218753) (xy 381.880995 -203.282171) (xy 381.865098 -203.344085)
			(xy 381.841566 -203.403518) (xy 381.810772 -203.459533) (xy 381.773199 -203.511248) (xy 381.729442 -203.557845)
			(xy 381.680189 -203.59859) (xy 381.626218 -203.632841) (xy 381.568379 -203.660058) (xy 381.507586 -203.679811)
			(xy 381.444796 -203.691789) (xy 381.381 -203.695803) (xy 381.317204 -203.691789) (xy 381.254414 -203.679811)
			(xy 381.193621 -203.660058) (xy 381.135782 -203.632841) (xy 381.081811 -203.59859) (xy 381.032558 -203.557845)
			(xy 380.988801 -203.511248) (xy 380.951228 -203.459533) (xy 380.920434 -203.403518) (xy 380.896902 -203.344085)
			(xy 380.881005 -203.282171) (xy 380.872994 -203.218753) (xy 349.80521 -203.218753) (xy 350.857758 -204.085952)
			(xy 374.82094 -204.085952) (xy 374.825011 -204.03033) (xy 374.837137 -203.975893) (xy 374.85706 -203.923802)
			(xy 374.884356 -203.875167) (xy 374.918442 -203.831024) (xy 374.958591 -203.792315) (xy 375.003949 -203.759864)
			(xy 375.053549 -203.734363) (xy 375.106333 -203.716356) (xy 375.161176 -203.706226) (xy 375.21691 -203.704189)
			(xy 375.272347 -203.710289) (xy 375.326304 -203.724395) (xy 375.377633 -203.746207) (xy 375.425239 -203.775261)
			(xy 375.468107 -203.810936) (xy 375.505324 -203.852473) (xy 375.536097 -203.898986) (xy 375.559769 -203.949483)
			(xy 375.575837 -204.00289) (xy 375.583957 -204.058066) (xy 375.584466 -204.085952) (xy 375.584465 -204.086)
			(xy 375.709941 -204.086) (xy 375.713955 -204.022201) (xy 375.725932 -203.959409) (xy 375.745685 -203.898612)
			(xy 375.772902 -203.840771) (xy 375.807153 -203.786796) (xy 375.847898 -203.73754) (xy 375.894495 -203.693778)
			(xy 375.94621 -203.656202) (xy 376.002226 -203.625403) (xy 376.06166 -203.601867) (xy 376.123576 -203.585965)
			(xy 376.186996 -203.577948) (xy 376.218958 -203.577444) (xy 376.250236 -203.577916) (xy 376.312322 -203.585575)
			(xy 376.372999 -203.600794) (xy 376.431349 -203.623344) (xy 376.486492 -203.652883) (xy 376.537593 -203.688966)
			(xy 376.583881 -203.731046) (xy 376.624655 -203.778488) (xy 376.642376 -203.804266) (xy 376.649859 -203.814399)
			(xy 376.671966 -203.8264) (xy 376.68454 -203.827126) (xy 376.769376 -203.827126) (xy 376.781952 -203.8264)
			(xy 376.80407 -203.814409) (xy 376.81154 -203.804266) (xy 376.829249 -203.778481) (xy 376.870038 -203.731055)
			(xy 376.916334 -203.688988) (xy 376.967439 -203.652915) (xy 377.022581 -203.623379) (xy 377.080928 -203.600827)
			(xy 377.1416 -203.585599) (xy 377.203681 -203.577924) (xy 377.234958 -203.577444) (xy 377.266919 -203.578018)
			(xy 377.330338 -203.586025) (xy 377.392253 -203.601918) (xy 377.451687 -203.625445) (xy 377.507704 -203.656237)
			(xy 377.55942 -203.693806) (xy 377.606019 -203.737562) (xy 377.646766 -203.786813) (xy 377.681019 -203.840784)
			(xy 377.708237 -203.898621) (xy 377.727991 -203.959414) (xy 377.73997 -204.022204) (xy 377.743981 -204.085952)
			(xy 377.86894 -204.085952) (xy 377.873011 -204.03033) (xy 377.885137 -203.975893) (xy 377.90506 -203.923802)
			(xy 377.932356 -203.875167) (xy 377.966442 -203.831024) (xy 378.006591 -203.792315) (xy 378.051949 -203.759864)
			(xy 378.101549 -203.734363) (xy 378.154333 -203.716356) (xy 378.209176 -203.706226) (xy 378.26491 -203.704189)
			(xy 378.320347 -203.710289) (xy 378.374304 -203.724395) (xy 378.425633 -203.746207) (xy 378.473239 -203.775261)
			(xy 378.516107 -203.810936) (xy 378.553324 -203.852473) (xy 378.584097 -203.898986) (xy 378.607769 -203.949483)
			(xy 378.623837 -204.00289) (xy 378.631957 -204.058066) (xy 378.632466 -204.085952) (xy 378.63235 -204.0923)
			(xy 379.61007 -204.0923) (xy 379.614085 -204.028499) (xy 379.626064 -203.965705) (xy 379.645819 -203.904907)
			(xy 379.673038 -203.847065) (xy 379.707293 -203.793091) (xy 379.748043 -203.743836) (xy 379.794644 -203.700076)
			(xy 379.846364 -203.662503) (xy 379.902384 -203.631708) (xy 379.961823 -203.608177) (xy 380.023742 -203.592282)
			(xy 380.087165 -203.584273) (xy 380.119128 -203.583794) (xy 380.150231 -203.584273) (xy 380.211972 -203.591875)
			(xy 380.272326 -203.606948) (xy 380.33039 -203.629268) (xy 380.3853 -203.658502) (xy 380.436235 -203.694214)
			(xy 380.482435 -203.735871) (xy 380.503176 -203.759054) (xy 380.509565 -203.765729) (xy 380.525829 -203.774463)
			(xy 380.534926 -203.776072) (xy 380.565152 -203.780136) (xy 380.574178 -203.780993) (xy 380.591873 -203.777099)
			(xy 380.599696 -203.772516) (xy 380.623025 -203.757917) (xy 380.672985 -203.734839) (xy 380.725744 -203.719184)
			(xy 380.780206 -203.711275) (xy 380.807722 -203.710794) (xy 380.834972 -203.711277) (xy 380.888918 -203.719036)
			(xy 380.94121 -203.734393) (xy 380.990785 -203.757036) (xy 381.036633 -203.786503) (xy 381.077821 -203.822195)
			(xy 381.11351 -203.863385) (xy 381.142975 -203.909234) (xy 381.165614 -203.95881) (xy 381.180968 -204.011104)
			(xy 381.188724 -204.06505) (xy 381.188724 -204.117913) (xy 382.568952 -204.117913) (xy 382.568952 -204.053991)
			(xy 382.576963 -203.990573) (xy 382.59286 -203.928659) (xy 382.616392 -203.869226) (xy 382.647186 -203.813211)
			(xy 382.684759 -203.761496) (xy 382.728516 -203.714899) (xy 382.777769 -203.674154) (xy 382.83174 -203.639903)
			(xy 382.889579 -203.612686) (xy 382.950372 -203.592933) (xy 383.013162 -203.580955) (xy 383.076958 -203.576942)
			(xy 383.140754 -203.580955) (xy 383.203544 -203.592933) (xy 383.264337 -203.612686) (xy 383.322176 -203.639903)
			(xy 383.376147 -203.674154) (xy 383.4254 -203.714899) (xy 383.469157 -203.761496) (xy 383.50673 -203.813211)
			(xy 383.537524 -203.869226) (xy 383.561056 -203.928659) (xy 383.576953 -203.990573) (xy 383.584964 -204.053991)
			(xy 383.585466 -204.085952) (xy 383.584964 -204.117913) (xy 383.576953 -204.181331) (xy 383.561056 -204.243245)
			(xy 383.537524 -204.302678) (xy 383.50673 -204.358693) (xy 383.469157 -204.410408) (xy 383.4254 -204.457005)
			(xy 383.376147 -204.49775) (xy 383.322176 -204.532001) (xy 383.264337 -204.559218) (xy 383.203544 -204.578971)
			(xy 383.140754 -204.590949) (xy 383.076958 -204.594963) (xy 383.013162 -204.590949) (xy 382.950372 -204.578971)
			(xy 382.889579 -204.559218) (xy 382.83174 -204.532001) (xy 382.777769 -204.49775) (xy 382.728516 -204.457005)
			(xy 382.684759 -204.410408) (xy 382.647186 -204.358693) (xy 382.616392 -204.302678) (xy 382.59286 -204.243245)
			(xy 382.576963 -204.181331) (xy 382.568952 -204.117913) (xy 381.188724 -204.117913) (xy 381.188724 -204.11955)
			(xy 381.180968 -204.173496) (xy 381.165614 -204.22579) (xy 381.142975 -204.275366) (xy 381.11351 -204.321215)
			(xy 381.077821 -204.362405) (xy 381.036633 -204.398097) (xy 380.990785 -204.427564) (xy 380.94121 -204.450207)
			(xy 380.888918 -204.465564) (xy 380.834972 -204.473323) (xy 380.807722 -204.47381) (xy 380.780206 -204.473335)
			(xy 380.725745 -204.465419) (xy 380.672986 -204.449762) (xy 380.623024 -204.42669) (xy 380.599696 -204.412088)
			(xy 380.591893 -204.407454) (xy 380.574182 -204.403557) (xy 380.565152 -204.404468) (xy 380.534926 -204.408532)
			(xy 380.525811 -204.410091) (xy 380.509528 -204.418828) (xy 380.503176 -204.42555) (xy 380.482455 -204.448753)
			(xy 380.43626 -204.490423) (xy 380.385326 -204.526144) (xy 380.330413 -204.555382) (xy 380.272342 -204.577699)
			(xy 380.211982 -204.592762) (xy 380.150234 -204.600346) (xy 380.119128 -204.60081) (xy 380.087165 -204.600327)
			(xy 380.023742 -204.592318) (xy 379.961823 -204.576423) (xy 379.902384 -204.552892) (xy 379.846364 -204.522097)
			(xy 379.794644 -204.484524) (xy 379.748043 -204.440764) (xy 379.707293 -204.391509) (xy 379.673038 -204.337535)
			(xy 379.645819 -204.279693) (xy 379.626064 -204.218895) (xy 379.614085 -204.156101) (xy 379.61007 -204.0923)
			(xy 378.63235 -204.0923) (xy 378.631957 -204.113838) (xy 378.623837 -204.169014) (xy 378.607769 -204.222421)
			(xy 378.584097 -204.272918) (xy 378.553324 -204.319431) (xy 378.516107 -204.360968) (xy 378.473239 -204.396643)
			(xy 378.425633 -204.425697) (xy 378.374304 -204.447509) (xy 378.320347 -204.461615) (xy 378.26491 -204.467715)
			(xy 378.209176 -204.465678) (xy 378.154333 -204.455548) (xy 378.101549 -204.437541) (xy 378.051949 -204.41204)
			(xy 378.006591 -204.379589) (xy 377.966442 -204.34088) (xy 377.932356 -204.296737) (xy 377.90506 -204.248102)
			(xy 377.885137 -204.196011) (xy 377.873011 -204.141574) (xy 377.86894 -204.085952) (xy 377.743981 -204.085952)
			(xy 377.743984 -204.086) (xy 377.73997 -204.149796) (xy 377.727991 -204.212586) (xy 377.708237 -204.273379)
			(xy 377.681019 -204.331216) (xy 377.646766 -204.385187) (xy 377.606019 -204.434438) (xy 377.55942 -204.478194)
			(xy 377.507704 -204.515763) (xy 377.451687 -204.546555) (xy 377.392253 -204.570082) (xy 377.330338 -204.585975)
			(xy 377.266919 -204.593982) (xy 377.234958 -204.59446) (xy 377.20368 -204.593974) (xy 377.141595 -204.586317)
			(xy 377.080919 -204.5711) (xy 377.022569 -204.548552) (xy 376.967426 -204.519015) (xy 376.916324 -204.482934)
			(xy 376.870036 -204.440856) (xy 376.829262 -204.393415) (xy 376.81154 -204.367638) (xy 376.804048 -204.357513)
			(xy 376.781948 -204.345507) (xy 376.769376 -204.344778) (xy 376.68454 -204.344778) (xy 376.671965 -204.345512)
			(xy 376.649847 -204.357497) (xy 376.642376 -204.367638) (xy 376.624658 -204.393416) (xy 376.58387 -204.440842)
			(xy 376.537575 -204.482909) (xy 376.486472 -204.518983) (xy 376.431331 -204.54852) (xy 376.372985 -204.571073)
			(xy 376.312315 -204.586302) (xy 376.250234 -204.593979) (xy 376.218958 -204.59446) (xy 376.186996 -204.594052)
			(xy 376.123576 -204.586035) (xy 376.06166 -204.570133) (xy 376.002226 -204.546597) (xy 375.94621 -204.515798)
			(xy 375.894495 -204.478222) (xy 375.847898 -204.43446) (xy 375.807153 -204.385204) (xy 375.772902 -204.331229)
			(xy 375.745685 -204.273388) (xy 375.725932 -204.212591) (xy 375.713955 -204.149799) (xy 375.709941 -204.086)
			(xy 375.584465 -204.086) (xy 375.583957 -204.113838) (xy 375.575837 -204.169014) (xy 375.559769 -204.222421)
			(xy 375.536097 -204.272918) (xy 375.505324 -204.319431) (xy 375.468107 -204.360968) (xy 375.425239 -204.396643)
			(xy 375.377633 -204.425697) (xy 375.326304 -204.447509) (xy 375.272347 -204.461615) (xy 375.21691 -204.467715)
			(xy 375.161176 -204.465678) (xy 375.106333 -204.455548) (xy 375.053549 -204.437541) (xy 375.003949 -204.41204)
			(xy 374.958591 -204.379589) (xy 374.918442 -204.34088) (xy 374.884356 -204.296737) (xy 374.85706 -204.248102)
			(xy 374.837137 -204.196011) (xy 374.825011 -204.141574) (xy 374.82094 -204.085952) (xy 350.857758 -204.085952)
			(xy 353.861684 -206.5609) (xy 372.858318 -206.5609) (xy 372.862331 -206.497108) (xy 372.874308 -206.434321)
			(xy 372.89406 -206.373531) (xy 372.921275 -206.315696) (xy 372.955525 -206.261728) (xy 372.996268 -206.212478)
			(xy 373.042862 -206.168722) (xy 373.094574 -206.131152) (xy 373.150586 -206.100359) (xy 373.210016 -206.076829)
			(xy 373.271926 -206.060933) (xy 373.335341 -206.052922) (xy 373.3673 -206.05242) (xy 373.398899 -206.052877)
			(xy 373.46161 -206.060709) (xy 373.522867 -206.076251) (xy 373.581726 -206.099265) (xy 373.63728 -206.129395)
			(xy 373.688671 -206.166177) (xy 373.735109 -206.209045) (xy 373.775876 -206.257336) (xy 373.793512 -206.28356)
			(xy 373.800116 -206.29372) (xy 373.819928 -206.305658) (xy 373.92356 -206.314294) (xy 373.945404 -206.305912)
			(xy 373.953278 -206.297276) (xy 373.973935 -206.275535) (xy 374.019517 -206.236561) (xy 374.069368 -206.203219)
			(xy 374.122794 -206.175972) (xy 374.179055 -206.1552) (xy 374.237369 -206.141189) (xy 374.296925 -206.134136)
			(xy 374.326912 -206.1337) (xy 374.357644 -206.134145) (xy 374.418658 -206.141555) (xy 374.478335 -206.156265)
			(xy 374.535804 -206.178062) (xy 374.590226 -206.206626) (xy 374.640808 -206.241542) (xy 374.686813 -206.282301)
			(xy 374.72757 -206.328307) (xy 374.762484 -206.378891) (xy 374.791047 -206.433315) (xy 374.812841 -206.490784)
			(xy 374.827549 -206.550461) (xy 374.834956 -206.611476) (xy 374.835175 -206.626) (xy 375.582941 -206.626)
			(xy 375.586955 -206.562201) (xy 375.598932 -206.499409) (xy 375.618685 -206.438612) (xy 375.645902 -206.380771)
			(xy 375.680153 -206.326796) (xy 375.720898 -206.27754) (xy 375.767495 -206.233778) (xy 375.81921 -206.196202)
			(xy 375.875226 -206.165403) (xy 375.93466 -206.141867) (xy 375.996576 -206.125965) (xy 376.059996 -206.117948)
			(xy 376.091958 -206.117444) (xy 376.12682 -206.11801) (xy 376.195888 -206.127542) (xy 376.263007 -206.146421)
			(xy 376.326918 -206.174292) (xy 376.386422 -206.210632) (xy 376.413776 -206.232252) (xy 376.422158 -206.23911)
			(xy 376.442224 -206.244698) (xy 376.537728 -206.230982) (xy 376.555762 -206.22006) (xy 376.561858 -206.21117)
			(xy 376.57968 -206.186038) (xy 376.620419 -206.139817) (xy 376.666447 -206.098861) (xy 376.717088 -206.063768)
			(xy 376.7716 -206.035055) (xy 376.829183 -206.013142) (xy 376.888993 -205.99835) (xy 376.950152 -205.990897)
			(xy 376.980958 -205.990444) (xy 377.012919 -205.991018) (xy 377.076338 -205.999025) (xy 377.138253 -206.014918)
			(xy 377.197687 -206.038445) (xy 377.253704 -206.069237) (xy 377.30542 -206.106806) (xy 377.352019 -206.150562)
			(xy 377.392766 -206.199813) (xy 377.427019 -206.253784) (xy 377.454237 -206.311621) (xy 377.473991 -206.372414)
			(xy 377.48597 -206.435204) (xy 377.489984 -206.499) (xy 377.48597 -206.562796) (xy 377.473991 -206.625586)
			(xy 377.454237 -206.686379) (xy 377.427019 -206.744216) (xy 377.392766 -206.798187) (xy 377.352019 -206.847438)
			(xy 377.30542 -206.891194) (xy 377.253704 -206.928763) (xy 377.197687 -206.959555) (xy 377.138253 -206.983082)
			(xy 377.076338 -206.998975) (xy 377.012919 -207.006982) (xy 376.980958 -207.00746) (xy 376.946097 -207.006885)
			(xy 376.877029 -206.997354) (xy 376.80991 -206.978478) (xy 376.745999 -206.950609) (xy 376.686494 -206.914271)
			(xy 376.65914 -206.892652) (xy 376.650758 -206.885794) (xy 376.630692 -206.880206) (xy 376.535188 -206.893922)
			(xy 376.517154 -206.904844) (xy 376.511058 -206.913734) (xy 376.493291 -206.938906) (xy 376.452544 -206.985126)
			(xy 376.406508 -207.02608) (xy 376.355858 -207.061169) (xy 376.301339 -207.089877) (xy 376.243748 -207.111784)
			(xy 376.183931 -207.126568) (xy 376.122766 -207.134012) (xy 376.091958 -207.13446) (xy 376.059996 -207.134052)
			(xy 375.996576 -207.126035) (xy 375.93466 -207.110133) (xy 375.875226 -207.086597) (xy 375.81921 -207.055798)
			(xy 375.767495 -207.018222) (xy 375.720898 -206.97446) (xy 375.680153 -206.925204) (xy 375.645902 -206.871229)
			(xy 375.618685 -206.813388) (xy 375.598932 -206.752591) (xy 375.586955 -206.689799) (xy 375.582941 -206.626)
			(xy 374.835175 -206.626) (xy 374.83542 -206.642208) (xy 374.834896 -206.674621) (xy 374.826662 -206.738921)
			(xy 374.810316 -206.801652) (xy 374.786125 -206.861795) (xy 374.75448 -206.918372) (xy 374.735598 -206.944722)
			(xy 374.729756 -206.95285) (xy 374.724676 -206.9719) (xy 374.736868 -207.061816) (xy 374.746774 -207.079088)
			(xy 374.754648 -207.085184) (xy 374.780258 -207.105886) (xy 374.826407 -207.152866) (xy 374.866105 -207.205409)
			(xy 374.89869 -207.262637) (xy 374.923614 -207.323593) (xy 374.940462 -207.387256) (xy 374.948951 -207.452561)
			(xy 374.949466 -207.485488) (xy 374.948964 -207.517449) (xy 374.948477 -207.521302) (xy 375.07494 -207.521302)
			(xy 375.079011 -207.46568) (xy 375.091137 -207.411243) (xy 375.11106 -207.359152) (xy 375.138356 -207.310517)
			(xy 375.172442 -207.266374) (xy 375.212591 -207.227665) (xy 375.257949 -207.195214) (xy 375.307549 -207.169713)
			(xy 375.360333 -207.151706) (xy 375.415176 -207.141576) (xy 375.47091 -207.139539) (xy 375.526347 -207.145639)
			(xy 375.580304 -207.159745) (xy 375.631633 -207.181557) (xy 375.679239 -207.210611) (xy 375.722107 -207.246286)
			(xy 375.759324 -207.287823) (xy 375.790097 -207.334336) (xy 375.813769 -207.384833) (xy 375.829837 -207.43824)
			(xy 375.832978 -207.45958) (xy 377.423934 -207.45958) (xy 377.424504 -207.426563) (xy 377.433054 -207.361086)
			(xy 377.450007 -207.297266) (xy 377.475079 -207.236177) (xy 377.507848 -207.178847) (xy 377.547761 -207.126242)
			(xy 377.594148 -207.079245) (xy 377.646228 -207.038649) (xy 377.703125 -207.005135) (xy 377.763881 -206.979267)
			(xy 377.795536 -206.969868) (xy 377.807982 -206.966312) (xy 377.826016 -206.94904) (xy 377.86056 -206.8449)
			(xy 377.856496 -206.820008) (xy 377.848622 -206.809848) (xy 377.8286 -206.783027) (xy 377.794958 -206.725166)
			(xy 377.769202 -206.66339) (xy 377.751778 -206.598767) (xy 377.742986 -206.532417) (xy 377.74245 -206.498952)
			(xy 377.742952 -206.466991) (xy 377.750963 -206.403573) (xy 377.76686 -206.341659) (xy 377.790392 -206.282226)
			(xy 377.821186 -206.226211) (xy 377.858759 -206.174496) (xy 377.902516 -206.127899) (xy 377.951769 -206.087154)
			(xy 378.00574 -206.052903) (xy 378.063579 -206.025686) (xy 378.124372 -206.005933) (xy 378.187162 -205.993955)
			(xy 378.250958 -205.989942) (xy 378.314754 -205.993955) (xy 378.377544 -206.005933) (xy 378.438337 -206.025686)
			(xy 378.496176 -206.052903) (xy 378.550147 -206.087154) (xy 378.5994 -206.127899) (xy 378.643157 -206.174496)
			(xy 378.68073 -206.226211) (xy 378.711524 -206.282226) (xy 378.735056 -206.341659) (xy 378.750953 -206.403573)
			(xy 378.758964 -206.466991) (xy 378.759466 -206.498952) (xy 378.758925 -206.53197) (xy 378.750371 -206.597448)
			(xy 378.733414 -206.661269) (xy 378.708338 -206.722358) (xy 378.675566 -206.779688) (xy 378.63565 -206.832293)
			(xy 378.58926 -206.879289) (xy 378.537177 -206.919885) (xy 378.480278 -206.953398) (xy 378.41952 -206.979265)
			(xy 378.387864 -206.988664) (xy 378.375418 -206.99222) (xy 378.357384 -207.009492) (xy 378.32284 -207.113632)
			(xy 378.326904 -207.138524) (xy 378.334778 -207.148684) (xy 378.354815 -207.175494) (xy 378.388454 -207.233358)
			(xy 378.414207 -207.295137) (xy 378.431628 -207.359762) (xy 378.440416 -207.426114) (xy 378.44095 -207.45958)
			(xy 378.440448 -207.491541) (xy 378.432437 -207.554959) (xy 378.41654 -207.616873) (xy 378.393008 -207.676306)
			(xy 378.362214 -207.732321) (xy 378.324641 -207.784036) (xy 378.280884 -207.830633) (xy 378.231631 -207.871378)
			(xy 378.17766 -207.905629) (xy 378.119821 -207.932846) (xy 378.059028 -207.952599) (xy 377.996238 -207.964577)
			(xy 377.932442 -207.968591) (xy 377.868646 -207.964577) (xy 377.805856 -207.952599) (xy 377.745063 -207.932846)
			(xy 377.687224 -207.905629) (xy 377.633253 -207.871378) (xy 377.584 -207.830633) (xy 377.540243 -207.784036)
			(xy 377.50267 -207.732321) (xy 377.471876 -207.676306) (xy 377.448344 -207.616873) (xy 377.432447 -207.554959)
			(xy 377.424436 -207.491541) (xy 377.423934 -207.45958) (xy 375.832978 -207.45958) (xy 375.837957 -207.493416)
			(xy 375.838466 -207.521302) (xy 375.837957 -207.549188) (xy 375.829837 -207.604364) (xy 375.813769 -207.657771)
			(xy 375.790097 -207.708268) (xy 375.759324 -207.754781) (xy 375.722107 -207.796318) (xy 375.679239 -207.831993)
			(xy 375.631633 -207.861047) (xy 375.580304 -207.882859) (xy 375.526347 -207.896965) (xy 375.47091 -207.903065)
			(xy 375.415176 -207.901028) (xy 375.360333 -207.890898) (xy 375.307549 -207.872891) (xy 375.257949 -207.84739)
			(xy 375.212591 -207.814939) (xy 375.172442 -207.77623) (xy 375.138356 -207.732087) (xy 375.11106 -207.683452)
			(xy 375.091137 -207.631361) (xy 375.079011 -207.576924) (xy 375.07494 -207.521302) (xy 374.948477 -207.521302)
			(xy 374.940953 -207.580867) (xy 374.925056 -207.642781) (xy 374.901524 -207.702214) (xy 374.87073 -207.758229)
			(xy 374.833157 -207.809944) (xy 374.7894 -207.856541) (xy 374.740147 -207.897286) (xy 374.686176 -207.931537)
			(xy 374.628337 -207.958754) (xy 374.567544 -207.978507) (xy 374.504754 -207.990485) (xy 374.440958 -207.994499)
			(xy 374.377162 -207.990485) (xy 374.314372 -207.978507) (xy 374.253579 -207.958754) (xy 374.19574 -207.931537)
			(xy 374.141769 -207.897286) (xy 374.092516 -207.856541) (xy 374.048759 -207.809944) (xy 374.011186 -207.758229)
			(xy 373.980392 -207.702214) (xy 373.95686 -207.642781) (xy 373.940963 -207.580867) (xy 373.932952 -207.517449)
			(xy 373.93245 -207.485488) (xy 373.932978 -207.453075) (xy 373.941212 -207.388775) (xy 373.957557 -207.326044)
			(xy 373.981748 -207.265902) (xy 374.013391 -207.209325) (xy 374.032272 -207.182974) (xy 374.038114 -207.174846)
			(xy 374.043194 -207.155796) (xy 374.031002 -207.06588) (xy 374.021096 -207.048608) (xy 374.013222 -207.042512)
			(xy 373.991495 -207.02499) (xy 373.951604 -206.985947) (xy 373.916232 -206.942767) (xy 373.9007 -206.919576)
			(xy 373.894096 -206.909416) (xy 373.874284 -206.897478) (xy 373.770652 -206.888842) (xy 373.748808 -206.897224)
			(xy 373.740934 -206.90586) (xy 373.720278 -206.927602) (xy 373.674695 -206.966575) (xy 373.624844 -206.999916)
			(xy 373.571417 -207.027162) (xy 373.515157 -207.047935) (xy 373.456843 -207.061945) (xy 373.397286 -207.068999)
			(xy 373.3673 -207.069436) (xy 373.335341 -207.068878) (xy 373.271926 -207.060867) (xy 373.210016 -207.044971)
			(xy 373.150586 -207.021441) (xy 373.094574 -206.990648) (xy 373.042862 -206.953078) (xy 372.996268 -206.909322)
			(xy 372.955525 -206.860072) (xy 372.921275 -206.806104) (xy 372.89406 -206.748269) (xy 372.874308 -206.687479)
			(xy 372.862331 -206.624692) (xy 372.858318 -206.5609) (xy 353.861684 -206.5609) (xy 357.494586 -209.554064)
			(xy 357.498151 -209.557163) (xy 357.504154 -209.564455) (xy 357.506524 -209.568542) (xy 360.83113 -215.55964)
			(xy 360.834094 -215.565363) (xy 360.837321 -215.577836) (xy 360.83748 -215.584278) (xy 360.83748 -221.80423)
			(xy 363.168958 -221.80423) (xy 363.172918 -221.755176) (xy 363.184695 -221.707392) (xy 363.203986 -221.662116)
			(xy 363.230289 -221.62052) (xy 363.262924 -221.583683) (xy 363.301045 -221.552558) (xy 363.343666 -221.527951)
			(xy 363.389682 -221.510499) (xy 363.437901 -221.500655) (xy 363.487076 -221.498674) (xy 363.535931 -221.504606)
			(xy 363.583202 -221.518298) (xy 363.627664 -221.539396) (xy 363.668167 -221.567352) (xy 363.70366 -221.601444)
			(xy 363.733225 -221.640788) (xy 363.756096 -221.684365) (xy 363.77168 -221.731046) (xy 363.779575 -221.779623)
			(xy 363.78007 -221.80423) (xy 364.109012 -221.80423) (xy 364.112972 -221.755176) (xy 364.124749 -221.707392)
			(xy 364.14404 -221.662116) (xy 364.170343 -221.62052) (xy 364.202978 -221.583683) (xy 364.241099 -221.552558)
			(xy 364.28372 -221.527951) (xy 364.329736 -221.510499) (xy 364.377955 -221.500655) (xy 364.42713 -221.498674)
			(xy 364.475985 -221.504606) (xy 364.523256 -221.518298) (xy 364.567718 -221.539396) (xy 364.608221 -221.567352)
			(xy 364.643714 -221.601444) (xy 364.673279 -221.640788) (xy 364.69615 -221.684365) (xy 364.711734 -221.731046)
			(xy 364.719629 -221.779623) (xy 364.720124 -221.80423) (xy 365.049066 -221.80423) (xy 365.053026 -221.755176)
			(xy 365.064803 -221.707392) (xy 365.084094 -221.662116) (xy 365.110397 -221.62052) (xy 365.143032 -221.583683)
			(xy 365.181153 -221.552558) (xy 365.223774 -221.527951) (xy 365.26979 -221.510499) (xy 365.318009 -221.500655)
			(xy 365.367184 -221.498674) (xy 365.416039 -221.504606) (xy 365.46331 -221.518298) (xy 365.507772 -221.539396)
			(xy 365.548275 -221.567352) (xy 365.583768 -221.601444) (xy 365.613333 -221.640788) (xy 365.636204 -221.684365)
			(xy 365.651788 -221.731046) (xy 365.659683 -221.779623) (xy 365.660178 -221.80423) (xy 367.868974 -221.80423)
			(xy 367.872934 -221.755176) (xy 367.884711 -221.707392) (xy 367.904002 -221.662116) (xy 367.930305 -221.62052)
			(xy 367.96294 -221.583683) (xy 368.001061 -221.552558) (xy 368.043682 -221.527951) (xy 368.089698 -221.510499)
			(xy 368.137917 -221.500655) (xy 368.187092 -221.498674) (xy 368.235947 -221.504606) (xy 368.283218 -221.518298)
			(xy 368.32768 -221.539396) (xy 368.368183 -221.567352) (xy 368.403676 -221.601444) (xy 368.433241 -221.640788)
			(xy 368.456112 -221.684365) (xy 368.471696 -221.731046) (xy 368.479591 -221.779623) (xy 368.480086 -221.80423)
			(xy 368.809028 -221.80423) (xy 368.812988 -221.755176) (xy 368.824765 -221.707392) (xy 368.844056 -221.662116)
			(xy 368.870359 -221.62052) (xy 368.902994 -221.583683) (xy 368.941115 -221.552558) (xy 368.983736 -221.527951)
			(xy 369.029752 -221.510499) (xy 369.077971 -221.500655) (xy 369.127146 -221.498674) (xy 369.176001 -221.504606)
			(xy 369.223272 -221.518298) (xy 369.267734 -221.539396) (xy 369.308237 -221.567352) (xy 369.34373 -221.601444)
			(xy 369.373295 -221.640788) (xy 369.396166 -221.684365) (xy 369.41175 -221.731046) (xy 369.419645 -221.779623)
			(xy 369.42014 -221.80423) (xy 369.749082 -221.80423) (xy 369.753042 -221.755176) (xy 369.764819 -221.707392)
			(xy 369.78411 -221.662116) (xy 369.810413 -221.62052) (xy 369.843048 -221.583683) (xy 369.881169 -221.552558)
			(xy 369.92379 -221.527951) (xy 369.969806 -221.510499) (xy 370.018025 -221.500655) (xy 370.0672 -221.498674)
			(xy 370.116055 -221.504606) (xy 370.163326 -221.518298) (xy 370.207788 -221.539396) (xy 370.248291 -221.567352)
			(xy 370.283784 -221.601444) (xy 370.313349 -221.640788) (xy 370.33622 -221.684365) (xy 370.351804 -221.731046)
			(xy 370.359699 -221.779623) (xy 370.360194 -221.80423) (xy 370.688882 -221.80423) (xy 370.692842 -221.755176)
			(xy 370.704619 -221.707392) (xy 370.72391 -221.662116) (xy 370.750213 -221.62052) (xy 370.782848 -221.583683)
			(xy 370.820969 -221.552558) (xy 370.86359 -221.527951) (xy 370.909606 -221.510499) (xy 370.957825 -221.500655)
			(xy 371.007 -221.498674) (xy 371.055855 -221.504606) (xy 371.103126 -221.518298) (xy 371.147588 -221.539396)
			(xy 371.188091 -221.567352) (xy 371.223584 -221.601444) (xy 371.253149 -221.640788) (xy 371.27602 -221.684365)
			(xy 371.291604 -221.731046) (xy 371.299499 -221.779623) (xy 371.299994 -221.80423) (xy 371.628936 -221.80423)
			(xy 371.632896 -221.755176) (xy 371.644673 -221.707392) (xy 371.663964 -221.662116) (xy 371.690267 -221.62052)
			(xy 371.722902 -221.583683) (xy 371.761023 -221.552558) (xy 371.803644 -221.527951) (xy 371.84966 -221.510499)
			(xy 371.897879 -221.500655) (xy 371.947054 -221.498674) (xy 371.995909 -221.504606) (xy 372.04318 -221.518298)
			(xy 372.087642 -221.539396) (xy 372.128145 -221.567352) (xy 372.163638 -221.601444) (xy 372.193203 -221.640788)
			(xy 372.216074 -221.684365) (xy 372.231658 -221.731046) (xy 372.239553 -221.779623) (xy 372.240048 -221.80423)
			(xy 373.509044 -221.80423) (xy 373.513004 -221.755176) (xy 373.524781 -221.707392) (xy 373.544072 -221.662116)
			(xy 373.570375 -221.62052) (xy 373.60301 -221.583683) (xy 373.641131 -221.552558) (xy 373.683752 -221.527951)
			(xy 373.729768 -221.510499) (xy 373.777987 -221.500655) (xy 373.827162 -221.498674) (xy 373.876017 -221.504606)
			(xy 373.923288 -221.518298) (xy 373.96775 -221.539396) (xy 374.008253 -221.567352) (xy 374.043746 -221.601444)
			(xy 374.073311 -221.640788) (xy 374.096182 -221.684365) (xy 374.111766 -221.731046) (xy 374.119661 -221.779623)
			(xy 374.120156 -221.80423) (xy 374.119661 -221.828837) (xy 374.111766 -221.877414) (xy 374.096182 -221.924095)
			(xy 374.073311 -221.967672) (xy 374.043746 -222.007016) (xy 374.008253 -222.041108) (xy 373.96775 -222.069064)
			(xy 373.923288 -222.090162) (xy 373.876017 -222.103854) (xy 373.827162 -222.109786) (xy 373.777987 -222.107805)
			(xy 373.729768 -222.097961) (xy 373.683752 -222.080509) (xy 373.641131 -222.055902) (xy 373.60301 -222.024777)
			(xy 373.570375 -221.98794) (xy 373.544072 -221.946344) (xy 373.524781 -221.901068) (xy 373.513004 -221.853284)
			(xy 373.509044 -221.80423) (xy 372.240048 -221.80423) (xy 372.239553 -221.828837) (xy 372.231658 -221.877414)
			(xy 372.216074 -221.924095) (xy 372.193203 -221.967672) (xy 372.163638 -222.007016) (xy 372.128145 -222.041108)
			(xy 372.087642 -222.069064) (xy 372.04318 -222.090162) (xy 371.995909 -222.103854) (xy 371.947054 -222.109786)
			(xy 371.897879 -222.107805) (xy 371.84966 -222.097961) (xy 371.803644 -222.080509) (xy 371.761023 -222.055902)
			(xy 371.722902 -222.024777) (xy 371.690267 -221.98794) (xy 371.663964 -221.946344) (xy 371.644673 -221.901068)
			(xy 371.632896 -221.853284) (xy 371.628936 -221.80423) (xy 371.299994 -221.80423) (xy 371.299499 -221.828837)
			(xy 371.291604 -221.877414) (xy 371.27602 -221.924095) (xy 371.253149 -221.967672) (xy 371.223584 -222.007016)
			(xy 371.188091 -222.041108) (xy 371.147588 -222.069064) (xy 371.103126 -222.090162) (xy 371.055855 -222.103854)
			(xy 371.007 -222.109786) (xy 370.957825 -222.107805) (xy 370.909606 -222.097961) (xy 370.86359 -222.080509)
			(xy 370.820969 -222.055902) (xy 370.782848 -222.024777) (xy 370.750213 -221.98794) (xy 370.72391 -221.946344)
			(xy 370.704619 -221.901068) (xy 370.692842 -221.853284) (xy 370.688882 -221.80423) (xy 370.360194 -221.80423)
			(xy 370.359699 -221.828837) (xy 370.351804 -221.877414) (xy 370.33622 -221.924095) (xy 370.313349 -221.967672)
			(xy 370.283784 -222.007016) (xy 370.248291 -222.041108) (xy 370.207788 -222.069064) (xy 370.163326 -222.090162)
			(xy 370.116055 -222.103854) (xy 370.0672 -222.109786) (xy 370.018025 -222.107805) (xy 369.969806 -222.097961)
			(xy 369.92379 -222.080509) (xy 369.881169 -222.055902) (xy 369.843048 -222.024777) (xy 369.810413 -221.98794)
			(xy 369.78411 -221.946344) (xy 369.764819 -221.901068) (xy 369.753042 -221.853284) (xy 369.749082 -221.80423)
			(xy 369.42014 -221.80423) (xy 369.419645 -221.828837) (xy 369.41175 -221.877414) (xy 369.396166 -221.924095)
			(xy 369.373295 -221.967672) (xy 369.34373 -222.007016) (xy 369.308237 -222.041108) (xy 369.267734 -222.069064)
			(xy 369.223272 -222.090162) (xy 369.176001 -222.103854) (xy 369.127146 -222.109786) (xy 369.077971 -222.107805)
			(xy 369.029752 -222.097961) (xy 368.983736 -222.080509) (xy 368.941115 -222.055902) (xy 368.902994 -222.024777)
			(xy 368.870359 -221.98794) (xy 368.844056 -221.946344) (xy 368.824765 -221.901068) (xy 368.812988 -221.853284)
			(xy 368.809028 -221.80423) (xy 368.480086 -221.80423) (xy 368.479591 -221.828837) (xy 368.471696 -221.877414)
			(xy 368.456112 -221.924095) (xy 368.433241 -221.967672) (xy 368.403676 -222.007016) (xy 368.368183 -222.041108)
			(xy 368.32768 -222.069064) (xy 368.283218 -222.090162) (xy 368.235947 -222.103854) (xy 368.187092 -222.109786)
			(xy 368.137917 -222.107805) (xy 368.089698 -222.097961) (xy 368.043682 -222.080509) (xy 368.001061 -222.055902)
			(xy 367.96294 -222.024777) (xy 367.930305 -221.98794) (xy 367.904002 -221.946344) (xy 367.884711 -221.901068)
			(xy 367.872934 -221.853284) (xy 367.868974 -221.80423) (xy 365.660178 -221.80423) (xy 365.659683 -221.828837)
			(xy 365.651788 -221.877414) (xy 365.636204 -221.924095) (xy 365.613333 -221.967672) (xy 365.583768 -222.007016)
			(xy 365.548275 -222.041108) (xy 365.507772 -222.069064) (xy 365.46331 -222.090162) (xy 365.416039 -222.103854)
			(xy 365.367184 -222.109786) (xy 365.318009 -222.107805) (xy 365.26979 -222.097961) (xy 365.223774 -222.080509)
			(xy 365.181153 -222.055902) (xy 365.143032 -222.024777) (xy 365.110397 -221.98794) (xy 365.084094 -221.946344)
			(xy 365.064803 -221.901068) (xy 365.053026 -221.853284) (xy 365.049066 -221.80423) (xy 364.720124 -221.80423)
			(xy 364.719629 -221.828837) (xy 364.711734 -221.877414) (xy 364.69615 -221.924095) (xy 364.673279 -221.967672)
			(xy 364.643714 -222.007016) (xy 364.608221 -222.041108) (xy 364.567718 -222.069064) (xy 364.523256 -222.090162)
			(xy 364.475985 -222.103854) (xy 364.42713 -222.109786) (xy 364.377955 -222.107805) (xy 364.329736 -222.097961)
			(xy 364.28372 -222.080509) (xy 364.241099 -222.055902) (xy 364.202978 -222.024777) (xy 364.170343 -221.98794)
			(xy 364.14404 -221.946344) (xy 364.124749 -221.901068) (xy 364.112972 -221.853284) (xy 364.109012 -221.80423)
			(xy 363.78007 -221.80423) (xy 363.779575 -221.828837) (xy 363.77168 -221.877414) (xy 363.756096 -221.924095)
			(xy 363.733225 -221.967672) (xy 363.70366 -222.007016) (xy 363.668167 -222.041108) (xy 363.627664 -222.069064)
			(xy 363.583202 -222.090162) (xy 363.535931 -222.103854) (xy 363.487076 -222.109786) (xy 363.437901 -222.107805)
			(xy 363.389682 -222.097961) (xy 363.343666 -222.080509) (xy 363.301045 -222.055902) (xy 363.262924 -222.024777)
			(xy 363.230289 -221.98794) (xy 363.203986 -221.946344) (xy 363.184695 -221.901068) (xy 363.172918 -221.853284)
			(xy 363.168958 -221.80423) (xy 360.83748 -221.80423) (xy 360.83748 -222.246444) (xy 360.83875 -222.25762)
			(xy 360.841036 -222.268542) (xy 360.844846 -222.27921) (xy 360.84891 -222.287592) (xy 360.93527 -222.340678)
			(xy 360.940933 -222.343897) (xy 360.953407 -222.347636) (xy 360.959908 -222.348044) (xy 360.97337 -222.348552)
			(xy 360.985308 -222.342456) (xy 361.006888 -222.331905) (xy 361.052543 -222.316981) (xy 361.099976 -222.309409)
			(xy 361.123992 -222.308928) (xy 361.124754 -222.308928) (xy 361.150011 -222.309417) (xy 361.199838 -222.317725)
			(xy 361.247617 -222.334121) (xy 361.292046 -222.358158) (xy 361.331911 -222.389182) (xy 361.366126 -222.426344)
			(xy 361.393757 -222.468631) (xy 361.41405 -222.51489) (xy 361.426452 -222.563858) (xy 361.430624 -222.6142)
			(xy 361.430621 -222.614236) (xy 364.578912 -222.614236) (xy 364.582872 -222.565182) (xy 364.594649 -222.517398)
			(xy 364.61394 -222.472122) (xy 364.640243 -222.430526) (xy 364.672878 -222.393689) (xy 364.710999 -222.362564)
			(xy 364.75362 -222.337957) (xy 364.799636 -222.320505) (xy 364.847855 -222.310661) (xy 364.89703 -222.30868)
			(xy 364.945885 -222.314612) (xy 364.993156 -222.328304) (xy 365.037618 -222.349402) (xy 365.078121 -222.377358)
			(xy 365.113614 -222.41145) (xy 365.143179 -222.450794) (xy 365.16605 -222.494371) (xy 365.181634 -222.541052)
			(xy 365.189529 -222.589629) (xy 365.190024 -222.614236) (xy 367.399074 -222.614236) (xy 367.403034 -222.565182)
			(xy 367.414811 -222.517398) (xy 367.434102 -222.472122) (xy 367.460405 -222.430526) (xy 367.49304 -222.393689)
			(xy 367.531161 -222.362564) (xy 367.573782 -222.337957) (xy 367.619798 -222.320505) (xy 367.668017 -222.310661)
			(xy 367.717192 -222.30868) (xy 367.766047 -222.314612) (xy 367.813318 -222.328304) (xy 367.85778 -222.349402)
			(xy 367.898283 -222.377358) (xy 367.933776 -222.41145) (xy 367.963341 -222.450794) (xy 367.986212 -222.494371)
			(xy 368.001796 -222.541052) (xy 368.009691 -222.589629) (xy 368.010186 -222.614236) (xy 370.218982 -222.614236)
			(xy 370.222942 -222.565182) (xy 370.234719 -222.517398) (xy 370.25401 -222.472122) (xy 370.280313 -222.430526)
			(xy 370.312948 -222.393689) (xy 370.351069 -222.362564) (xy 370.39369 -222.337957) (xy 370.439706 -222.320505)
			(xy 370.487925 -222.310661) (xy 370.5371 -222.30868) (xy 370.585955 -222.314612) (xy 370.633226 -222.328304)
			(xy 370.677688 -222.349402) (xy 370.718191 -222.377358) (xy 370.753684 -222.41145) (xy 370.783249 -222.450794)
			(xy 370.80612 -222.494371) (xy 370.821704 -222.541052) (xy 370.829599 -222.589629) (xy 370.830094 -222.614236)
			(xy 373.03889 -222.614236) (xy 373.04285 -222.565182) (xy 373.054627 -222.517398) (xy 373.073918 -222.472122)
			(xy 373.100221 -222.430526) (xy 373.132856 -222.393689) (xy 373.170977 -222.362564) (xy 373.213598 -222.337957)
			(xy 373.259614 -222.320505) (xy 373.307833 -222.310661) (xy 373.357008 -222.30868) (xy 373.405863 -222.314612)
			(xy 373.453134 -222.328304) (xy 373.497596 -222.349402) (xy 373.538099 -222.377358) (xy 373.573592 -222.41145)
			(xy 373.603157 -222.450794) (xy 373.626028 -222.494371) (xy 373.641612 -222.541052) (xy 373.649507 -222.589629)
			(xy 373.650002 -222.614236) (xy 373.649507 -222.638843) (xy 373.641612 -222.68742) (xy 373.626028 -222.734101)
			(xy 373.603157 -222.777678) (xy 373.573592 -222.817022) (xy 373.538099 -222.851114) (xy 373.497596 -222.87907)
			(xy 373.453134 -222.900168) (xy 373.405863 -222.91386) (xy 373.357008 -222.919792) (xy 373.307833 -222.917811)
			(xy 373.259614 -222.907967) (xy 373.213598 -222.890515) (xy 373.170977 -222.865908) (xy 373.132856 -222.834783)
			(xy 373.100221 -222.797946) (xy 373.073918 -222.75635) (xy 373.054627 -222.711074) (xy 373.04285 -222.66329)
			(xy 373.03889 -222.614236) (xy 370.830094 -222.614236) (xy 370.829599 -222.638843) (xy 370.821704 -222.68742)
			(xy 370.80612 -222.734101) (xy 370.783249 -222.777678) (xy 370.753684 -222.817022) (xy 370.718191 -222.851114)
			(xy 370.677688 -222.87907) (xy 370.633226 -222.900168) (xy 370.585955 -222.91386) (xy 370.5371 -222.919792)
			(xy 370.487925 -222.917811) (xy 370.439706 -222.907967) (xy 370.39369 -222.890515) (xy 370.351069 -222.865908)
			(xy 370.312948 -222.834783) (xy 370.280313 -222.797946) (xy 370.25401 -222.75635) (xy 370.234719 -222.711074)
			(xy 370.222942 -222.66329) (xy 370.218982 -222.614236) (xy 368.010186 -222.614236) (xy 368.009691 -222.638843)
			(xy 368.001796 -222.68742) (xy 367.986212 -222.734101) (xy 367.963341 -222.777678) (xy 367.933776 -222.817022)
			(xy 367.898283 -222.851114) (xy 367.85778 -222.87907) (xy 367.813318 -222.900168) (xy 367.766047 -222.91386)
			(xy 367.717192 -222.919792) (xy 367.668017 -222.917811) (xy 367.619798 -222.907967) (xy 367.573782 -222.890515)
			(xy 367.531161 -222.865908) (xy 367.49304 -222.834783) (xy 367.460405 -222.797946) (xy 367.434102 -222.75635)
			(xy 367.414811 -222.711074) (xy 367.403034 -222.66329) (xy 367.399074 -222.614236) (xy 365.190024 -222.614236)
			(xy 365.189529 -222.638843) (xy 365.181634 -222.68742) (xy 365.16605 -222.734101) (xy 365.143179 -222.777678)
			(xy 365.113614 -222.817022) (xy 365.078121 -222.851114) (xy 365.037618 -222.87907) (xy 364.993156 -222.900168)
			(xy 364.945885 -222.91386) (xy 364.89703 -222.919792) (xy 364.847855 -222.917811) (xy 364.799636 -222.907967)
			(xy 364.75362 -222.890515) (xy 364.710999 -222.865908) (xy 364.672878 -222.834783) (xy 364.640243 -222.797946)
			(xy 364.61394 -222.75635) (xy 364.594649 -222.711074) (xy 364.582872 -222.66329) (xy 364.578912 -222.614236)
			(xy 361.430621 -222.614236) (xy 361.426452 -222.664542) (xy 361.41405 -222.71351) (xy 361.393757 -222.759769)
			(xy 361.366126 -222.802056) (xy 361.331911 -222.839218) (xy 361.292046 -222.870242) (xy 361.247617 -222.894279)
			(xy 361.199838 -222.910675) (xy 361.150011 -222.918983) (xy 361.124754 -222.919544) (xy 361.123992 -222.919544)
			(xy 361.09998 -222.919027) (xy 361.052559 -222.911431) (xy 361.006906 -222.896522) (xy 360.985308 -222.886016)
			(xy 360.985054 -222.886016) (xy 360.979211 -222.883271) (xy 360.966618 -222.880454) (xy 360.960162 -222.880428)
			(xy 360.9467 -222.880936) (xy 360.861864 -222.933006) (xy 360.85568 -222.936993) (xy 360.845743 -222.947836)
			(xy 360.842306 -222.954342) (xy 360.83748 -222.96501) (xy 360.83748 -223.424242) (xy 361.289104 -223.424242)
			(xy 361.293064 -223.375188) (xy 361.304841 -223.327404) (xy 361.324132 -223.282128) (xy 361.350435 -223.240532)
			(xy 361.38307 -223.203695) (xy 361.421191 -223.17257) (xy 361.463812 -223.147963) (xy 361.509828 -223.130511)
			(xy 361.558047 -223.120667) (xy 361.607222 -223.118686) (xy 361.656077 -223.124618) (xy 361.703348 -223.13831)
			(xy 361.74781 -223.159408) (xy 361.788313 -223.187364) (xy 361.823806 -223.221456) (xy 361.853371 -223.2608)
			(xy 361.876242 -223.304377) (xy 361.891826 -223.351058) (xy 361.899721 -223.399635) (xy 361.900216 -223.424242)
			(xy 364.109012 -223.424242) (xy 364.112972 -223.375188) (xy 364.124749 -223.327404) (xy 364.14404 -223.282128)
			(xy 364.170343 -223.240532) (xy 364.202978 -223.203695) (xy 364.241099 -223.17257) (xy 364.28372 -223.147963)
			(xy 364.329736 -223.130511) (xy 364.377955 -223.120667) (xy 364.42713 -223.118686) (xy 364.475985 -223.124618)
			(xy 364.523256 -223.13831) (xy 364.567718 -223.159408) (xy 364.608221 -223.187364) (xy 364.643714 -223.221456)
			(xy 364.673279 -223.2608) (xy 364.69615 -223.304377) (xy 364.711734 -223.351058) (xy 364.719629 -223.399635)
			(xy 364.720124 -223.424242) (xy 365.049066 -223.424242) (xy 365.053026 -223.375188) (xy 365.064803 -223.327404)
			(xy 365.084094 -223.282128) (xy 365.110397 -223.240532) (xy 365.143032 -223.203695) (xy 365.181153 -223.17257)
			(xy 365.223774 -223.147963) (xy 365.26979 -223.130511) (xy 365.318009 -223.120667) (xy 365.367184 -223.118686)
			(xy 365.416039 -223.124618) (xy 365.46331 -223.13831) (xy 365.507772 -223.159408) (xy 365.548275 -223.187364)
			(xy 365.583768 -223.221456) (xy 365.613333 -223.2608) (xy 365.636204 -223.304377) (xy 365.651788 -223.351058)
			(xy 365.659683 -223.399635) (xy 365.660178 -223.424242) (xy 366.92892 -223.424242) (xy 366.93288 -223.375188)
			(xy 366.944657 -223.327404) (xy 366.963948 -223.282128) (xy 366.990251 -223.240532) (xy 367.022886 -223.203695)
			(xy 367.061007 -223.17257) (xy 367.103628 -223.147963) (xy 367.149644 -223.130511) (xy 367.197863 -223.120667)
			(xy 367.247038 -223.118686) (xy 367.295893 -223.124618) (xy 367.343164 -223.13831) (xy 367.387626 -223.159408)
			(xy 367.428129 -223.187364) (xy 367.463622 -223.221456) (xy 367.493187 -223.2608) (xy 367.516058 -223.304377)
			(xy 367.531642 -223.351058) (xy 367.539537 -223.399635) (xy 367.540032 -223.424242) (xy 369.749082 -223.424242)
			(xy 369.753042 -223.375188) (xy 369.764819 -223.327404) (xy 369.78411 -223.282128) (xy 369.810413 -223.240532)
			(xy 369.843048 -223.203695) (xy 369.881169 -223.17257) (xy 369.92379 -223.147963) (xy 369.969806 -223.130511)
			(xy 370.018025 -223.120667) (xy 370.0672 -223.118686) (xy 370.116055 -223.124618) (xy 370.163326 -223.13831)
			(xy 370.207788 -223.159408) (xy 370.248291 -223.187364) (xy 370.283784 -223.221456) (xy 370.313349 -223.2608)
			(xy 370.33622 -223.304377) (xy 370.351804 -223.351058) (xy 370.359699 -223.399635) (xy 370.360194 -223.424242)
			(xy 370.688882 -223.424242) (xy 370.692842 -223.375188) (xy 370.704619 -223.327404) (xy 370.72391 -223.282128)
			(xy 370.750213 -223.240532) (xy 370.782848 -223.203695) (xy 370.820969 -223.17257) (xy 370.86359 -223.147963)
			(xy 370.909606 -223.130511) (xy 370.957825 -223.120667) (xy 371.007 -223.118686) (xy 371.055855 -223.124618)
			(xy 371.103126 -223.13831) (xy 371.147588 -223.159408) (xy 371.188091 -223.187364) (xy 371.223584 -223.221456)
			(xy 371.253149 -223.2608) (xy 371.27602 -223.304377) (xy 371.291604 -223.351058) (xy 371.299499 -223.399635)
			(xy 371.299994 -223.424242) (xy 371.628936 -223.424242) (xy 371.632896 -223.375188) (xy 371.644673 -223.327404)
			(xy 371.663964 -223.282128) (xy 371.690267 -223.240532) (xy 371.722902 -223.203695) (xy 371.761023 -223.17257)
			(xy 371.803644 -223.147963) (xy 371.84966 -223.130511) (xy 371.897879 -223.120667) (xy 371.947054 -223.118686)
			(xy 371.995909 -223.124618) (xy 372.04318 -223.13831) (xy 372.087642 -223.159408) (xy 372.128145 -223.187364)
			(xy 372.163638 -223.221456) (xy 372.193203 -223.2608) (xy 372.216074 -223.304377) (xy 372.231658 -223.351058)
			(xy 372.239553 -223.399635) (xy 372.240048 -223.424242) (xy 372.56899 -223.424242) (xy 372.57295 -223.375188)
			(xy 372.584727 -223.327404) (xy 372.604018 -223.282128) (xy 372.630321 -223.240532) (xy 372.662956 -223.203695)
			(xy 372.701077 -223.17257) (xy 372.743698 -223.147963) (xy 372.789714 -223.130511) (xy 372.837933 -223.120667)
			(xy 372.887108 -223.118686) (xy 372.935963 -223.124618) (xy 372.983234 -223.13831) (xy 373.027696 -223.159408)
			(xy 373.068199 -223.187364) (xy 373.103692 -223.221456) (xy 373.133257 -223.2608) (xy 373.156128 -223.304377)
			(xy 373.171712 -223.351058) (xy 373.179607 -223.399635) (xy 373.180102 -223.424242) (xy 373.179607 -223.448849)
			(xy 373.171712 -223.497426) (xy 373.156128 -223.544107) (xy 373.133257 -223.587684) (xy 373.103692 -223.627028)
			(xy 373.068199 -223.66112) (xy 373.027696 -223.689076) (xy 372.983234 -223.710174) (xy 372.935963 -223.723866)
			(xy 372.887108 -223.729798) (xy 372.837933 -223.727817) (xy 372.789714 -223.717973) (xy 372.743698 -223.700521)
			(xy 372.701077 -223.675914) (xy 372.662956 -223.644789) (xy 372.630321 -223.607952) (xy 372.604018 -223.566356)
			(xy 372.584727 -223.52108) (xy 372.57295 -223.473296) (xy 372.56899 -223.424242) (xy 372.240048 -223.424242)
			(xy 372.239553 -223.448849) (xy 372.231658 -223.497426) (xy 372.216074 -223.544107) (xy 372.193203 -223.587684)
			(xy 372.163638 -223.627028) (xy 372.128145 -223.66112) (xy 372.087642 -223.689076) (xy 372.04318 -223.710174)
			(xy 371.995909 -223.723866) (xy 371.947054 -223.729798) (xy 371.897879 -223.727817) (xy 371.84966 -223.717973)
			(xy 371.803644 -223.700521) (xy 371.761023 -223.675914) (xy 371.722902 -223.644789) (xy 371.690267 -223.607952)
			(xy 371.663964 -223.566356) (xy 371.644673 -223.52108) (xy 371.632896 -223.473296) (xy 371.628936 -223.424242)
			(xy 371.299994 -223.424242) (xy 371.299499 -223.448849) (xy 371.291604 -223.497426) (xy 371.27602 -223.544107)
			(xy 371.253149 -223.587684) (xy 371.223584 -223.627028) (xy 371.188091 -223.66112) (xy 371.147588 -223.689076)
			(xy 371.103126 -223.710174) (xy 371.055855 -223.723866) (xy 371.007 -223.729798) (xy 370.957825 -223.727817)
			(xy 370.909606 -223.717973) (xy 370.86359 -223.700521) (xy 370.820969 -223.675914) (xy 370.782848 -223.644789)
			(xy 370.750213 -223.607952) (xy 370.72391 -223.566356) (xy 370.704619 -223.52108) (xy 370.692842 -223.473296)
			(xy 370.688882 -223.424242) (xy 370.360194 -223.424242) (xy 370.359699 -223.448849) (xy 370.351804 -223.497426)
			(xy 370.33622 -223.544107) (xy 370.313349 -223.587684) (xy 370.283784 -223.627028) (xy 370.248291 -223.66112)
			(xy 370.207788 -223.689076) (xy 370.163326 -223.710174) (xy 370.116055 -223.723866) (xy 370.0672 -223.729798)
			(xy 370.018025 -223.727817) (xy 369.969806 -223.717973) (xy 369.92379 -223.700521) (xy 369.881169 -223.675914)
			(xy 369.843048 -223.644789) (xy 369.810413 -223.607952) (xy 369.78411 -223.566356) (xy 369.764819 -223.52108)
			(xy 369.753042 -223.473296) (xy 369.749082 -223.424242) (xy 367.540032 -223.424242) (xy 367.539537 -223.448849)
			(xy 367.531642 -223.497426) (xy 367.516058 -223.544107) (xy 367.493187 -223.587684) (xy 367.463622 -223.627028)
			(xy 367.428129 -223.66112) (xy 367.387626 -223.689076) (xy 367.343164 -223.710174) (xy 367.295893 -223.723866)
			(xy 367.247038 -223.729798) (xy 367.197863 -223.727817) (xy 367.149644 -223.717973) (xy 367.103628 -223.700521)
			(xy 367.061007 -223.675914) (xy 367.022886 -223.644789) (xy 366.990251 -223.607952) (xy 366.963948 -223.566356)
			(xy 366.944657 -223.52108) (xy 366.93288 -223.473296) (xy 366.92892 -223.424242) (xy 365.660178 -223.424242)
			(xy 365.659683 -223.448849) (xy 365.651788 -223.497426) (xy 365.636204 -223.544107) (xy 365.613333 -223.587684)
			(xy 365.583768 -223.627028) (xy 365.548275 -223.66112) (xy 365.507772 -223.689076) (xy 365.46331 -223.710174)
			(xy 365.416039 -223.723866) (xy 365.367184 -223.729798) (xy 365.318009 -223.727817) (xy 365.26979 -223.717973)
			(xy 365.223774 -223.700521) (xy 365.181153 -223.675914) (xy 365.143032 -223.644789) (xy 365.110397 -223.607952)
			(xy 365.084094 -223.566356) (xy 365.064803 -223.52108) (xy 365.053026 -223.473296) (xy 365.049066 -223.424242)
			(xy 364.720124 -223.424242) (xy 364.719629 -223.448849) (xy 364.711734 -223.497426) (xy 364.69615 -223.544107)
			(xy 364.673279 -223.587684) (xy 364.643714 -223.627028) (xy 364.608221 -223.66112) (xy 364.567718 -223.689076)
			(xy 364.523256 -223.710174) (xy 364.475985 -223.723866) (xy 364.42713 -223.729798) (xy 364.377955 -223.727817)
			(xy 364.329736 -223.717973) (xy 364.28372 -223.700521) (xy 364.241099 -223.675914) (xy 364.202978 -223.644789)
			(xy 364.170343 -223.607952) (xy 364.14404 -223.566356) (xy 364.124749 -223.52108) (xy 364.112972 -223.473296)
			(xy 364.109012 -223.424242) (xy 361.900216 -223.424242) (xy 361.899721 -223.448849) (xy 361.891826 -223.497426)
			(xy 361.876242 -223.544107) (xy 361.853371 -223.587684) (xy 361.823806 -223.627028) (xy 361.788313 -223.66112)
			(xy 361.74781 -223.689076) (xy 361.703348 -223.710174) (xy 361.656077 -223.723866) (xy 361.607222 -223.729798)
			(xy 361.558047 -223.727817) (xy 361.509828 -223.717973) (xy 361.463812 -223.700521) (xy 361.421191 -223.675914)
			(xy 361.38307 -223.644789) (xy 361.350435 -223.607952) (xy 361.324132 -223.566356) (xy 361.304841 -223.52108)
			(xy 361.293064 -223.473296) (xy 361.289104 -223.424242) (xy 360.83748 -223.424242) (xy 360.83748 -223.866456)
			(xy 360.83875 -223.877632) (xy 360.841036 -223.888554) (xy 360.844846 -223.899222) (xy 360.84891 -223.907604)
			(xy 360.93527 -223.96069) (xy 360.940934 -223.963908) (xy 360.953407 -223.967647) (xy 360.959908 -223.968056)
			(xy 360.97337 -223.968564) (xy 360.985308 -223.962468) (xy 361.006888 -223.95192) (xy 361.052545 -223.937001)
			(xy 361.099976 -223.929431) (xy 361.123992 -223.92894) (xy 361.124754 -223.92894) (xy 361.15001 -223.929429)
			(xy 361.199835 -223.937736) (xy 361.247612 -223.954132) (xy 361.292039 -223.978169) (xy 361.331903 -224.00919)
			(xy 361.366117 -224.046351) (xy 361.393747 -224.088637) (xy 361.414039 -224.134894) (xy 361.42644 -224.18386)
			(xy 361.430612 -224.2342) (xy 361.430608 -224.234248) (xy 362.699058 -224.234248) (xy 362.703018 -224.185194)
			(xy 362.714795 -224.13741) (xy 362.734086 -224.092134) (xy 362.760389 -224.050538) (xy 362.793024 -224.013701)
			(xy 362.831145 -223.982576) (xy 362.873766 -223.957969) (xy 362.919782 -223.940517) (xy 362.968001 -223.930673)
			(xy 363.017176 -223.928692) (xy 363.066031 -223.934624) (xy 363.113302 -223.948316) (xy 363.157764 -223.969414)
			(xy 363.198267 -223.99737) (xy 363.23376 -224.031462) (xy 363.263325 -224.070806) (xy 363.286196 -224.114383)
			(xy 363.30178 -224.161064) (xy 363.309675 -224.209641) (xy 363.31017 -224.234248) (xy 364.578912 -224.234248)
			(xy 364.582872 -224.185194) (xy 364.594649 -224.13741) (xy 364.61394 -224.092134) (xy 364.640243 -224.050538)
			(xy 364.672878 -224.013701) (xy 364.710999 -223.982576) (xy 364.75362 -223.957969) (xy 364.799636 -223.940517)
			(xy 364.847855 -223.930673) (xy 364.89703 -223.928692) (xy 364.945885 -223.934624) (xy 364.993156 -223.948316)
			(xy 365.037618 -223.969414) (xy 365.078121 -223.99737) (xy 365.113614 -224.031462) (xy 365.143179 -224.070806)
			(xy 365.16605 -224.114383) (xy 365.181634 -224.161064) (xy 365.189529 -224.209641) (xy 365.190024 -224.234248)
			(xy 365.518966 -224.234248) (xy 365.522926 -224.185194) (xy 365.534703 -224.13741) (xy 365.553994 -224.092134)
			(xy 365.580297 -224.050538) (xy 365.612932 -224.013701) (xy 365.651053 -223.982576) (xy 365.693674 -223.957969)
			(xy 365.73969 -223.940517) (xy 365.787909 -223.930673) (xy 365.837084 -223.928692) (xy 365.885939 -223.934624)
			(xy 365.93321 -223.948316) (xy 365.977672 -223.969414) (xy 366.018175 -223.99737) (xy 366.053668 -224.031462)
			(xy 366.083233 -224.070806) (xy 366.106104 -224.114383) (xy 366.121688 -224.161064) (xy 366.129583 -224.209641)
			(xy 366.130078 -224.234248) (xy 366.45902 -224.234248) (xy 366.46298 -224.185194) (xy 366.474757 -224.13741)
			(xy 366.494048 -224.092134) (xy 366.520351 -224.050538) (xy 366.552986 -224.013701) (xy 366.591107 -223.982576)
			(xy 366.633728 -223.957969) (xy 366.679744 -223.940517) (xy 366.727963 -223.930673) (xy 366.777138 -223.928692)
			(xy 366.825993 -223.934624) (xy 366.873264 -223.948316) (xy 366.917726 -223.969414) (xy 366.958229 -223.99737)
			(xy 366.993722 -224.031462) (xy 367.023287 -224.070806) (xy 367.046158 -224.114383) (xy 367.061742 -224.161064)
			(xy 367.069637 -224.209641) (xy 367.070132 -224.234248) (xy 367.399074 -224.234248) (xy 367.403034 -224.185194)
			(xy 367.414811 -224.13741) (xy 367.434102 -224.092134) (xy 367.460405 -224.050538) (xy 367.49304 -224.013701)
			(xy 367.531161 -223.982576) (xy 367.573782 -223.957969) (xy 367.619798 -223.940517) (xy 367.668017 -223.930673)
			(xy 367.717192 -223.928692) (xy 367.766047 -223.934624) (xy 367.813318 -223.948316) (xy 367.85778 -223.969414)
			(xy 367.898283 -223.99737) (xy 367.933776 -224.031462) (xy 367.963341 -224.070806) (xy 367.986212 -224.114383)
			(xy 368.001796 -224.161064) (xy 368.009691 -224.209641) (xy 368.010186 -224.234248) (xy 368.338874 -224.234248)
			(xy 368.342834 -224.185194) (xy 368.354611 -224.13741) (xy 368.373902 -224.092134) (xy 368.400205 -224.050538)
			(xy 368.43284 -224.013701) (xy 368.470961 -223.982576) (xy 368.513582 -223.957969) (xy 368.559598 -223.940517)
			(xy 368.607817 -223.930673) (xy 368.656992 -223.928692) (xy 368.705847 -223.934624) (xy 368.753118 -223.948316)
			(xy 368.79758 -223.969414) (xy 368.838083 -223.99737) (xy 368.873576 -224.031462) (xy 368.903141 -224.070806)
			(xy 368.926012 -224.114383) (xy 368.941596 -224.161064) (xy 368.949491 -224.209641) (xy 368.949986 -224.234248)
			(xy 369.278928 -224.234248) (xy 369.282888 -224.185194) (xy 369.294665 -224.13741) (xy 369.313956 -224.092134)
			(xy 369.340259 -224.050538) (xy 369.372894 -224.013701) (xy 369.411015 -223.982576) (xy 369.453636 -223.957969)
			(xy 369.499652 -223.940517) (xy 369.547871 -223.930673) (xy 369.597046 -223.928692) (xy 369.645901 -223.934624)
			(xy 369.693172 -223.948316) (xy 369.737634 -223.969414) (xy 369.778137 -223.99737) (xy 369.81363 -224.031462)
			(xy 369.843195 -224.070806) (xy 369.866066 -224.114383) (xy 369.88165 -224.161064) (xy 369.889545 -224.209641)
			(xy 369.89004 -224.234248) (xy 370.218982 -224.234248) (xy 370.222942 -224.185194) (xy 370.234719 -224.13741)
			(xy 370.25401 -224.092134) (xy 370.280313 -224.050538) (xy 370.312948 -224.013701) (xy 370.351069 -223.982576)
			(xy 370.39369 -223.957969) (xy 370.439706 -223.940517) (xy 370.487925 -223.930673) (xy 370.5371 -223.928692)
			(xy 370.585955 -223.934624) (xy 370.633226 -223.948316) (xy 370.677688 -223.969414) (xy 370.718191 -223.99737)
			(xy 370.753684 -224.031462) (xy 370.783249 -224.070806) (xy 370.80612 -224.114383) (xy 370.821704 -224.161064)
			(xy 370.829599 -224.209641) (xy 370.830094 -224.234248) (xy 371.159036 -224.234248) (xy 371.162996 -224.185194)
			(xy 371.174773 -224.13741) (xy 371.194064 -224.092134) (xy 371.220367 -224.050538) (xy 371.253002 -224.013701)
			(xy 371.291123 -223.982576) (xy 371.333744 -223.957969) (xy 371.37976 -223.940517) (xy 371.427979 -223.930673)
			(xy 371.477154 -223.928692) (xy 371.526009 -223.934624) (xy 371.57328 -223.948316) (xy 371.617742 -223.969414)
			(xy 371.658245 -223.99737) (xy 371.693738 -224.031462) (xy 371.723303 -224.070806) (xy 371.746174 -224.114383)
			(xy 371.761758 -224.161064) (xy 371.769653 -224.209641) (xy 371.770148 -224.234248) (xy 372.09909 -224.234248)
			(xy 372.10305 -224.185194) (xy 372.114827 -224.13741) (xy 372.134118 -224.092134) (xy 372.160421 -224.050538)
			(xy 372.193056 -224.013701) (xy 372.231177 -223.982576) (xy 372.273798 -223.957969) (xy 372.319814 -223.940517)
			(xy 372.368033 -223.930673) (xy 372.417208 -223.928692) (xy 372.466063 -223.934624) (xy 372.513334 -223.948316)
			(xy 372.557796 -223.969414) (xy 372.598299 -223.99737) (xy 372.633792 -224.031462) (xy 372.663357 -224.070806)
			(xy 372.686228 -224.114383) (xy 372.701812 -224.161064) (xy 372.709707 -224.209641) (xy 372.710202 -224.234248)
			(xy 373.03889 -224.234248) (xy 373.04285 -224.185194) (xy 373.054627 -224.13741) (xy 373.073918 -224.092134)
			(xy 373.100221 -224.050538) (xy 373.132856 -224.013701) (xy 373.170977 -223.982576) (xy 373.213598 -223.957969)
			(xy 373.259614 -223.940517) (xy 373.307833 -223.930673) (xy 373.357008 -223.928692) (xy 373.405863 -223.934624)
			(xy 373.453134 -223.948316) (xy 373.497596 -223.969414) (xy 373.538099 -223.99737) (xy 373.573592 -224.031462)
			(xy 373.603157 -224.070806) (xy 373.626028 -224.114383) (xy 373.641612 -224.161064) (xy 373.649507 -224.209641)
			(xy 373.650002 -224.234248) (xy 373.649507 -224.258855) (xy 373.641612 -224.307432) (xy 373.626028 -224.354113)
			(xy 373.603157 -224.39769) (xy 373.573592 -224.437034) (xy 373.538099 -224.471126) (xy 373.497596 -224.499082)
			(xy 373.453134 -224.52018) (xy 373.405863 -224.533872) (xy 373.357008 -224.539804) (xy 373.307833 -224.537823)
			(xy 373.259614 -224.527979) (xy 373.213598 -224.510527) (xy 373.170977 -224.48592) (xy 373.132856 -224.454795)
			(xy 373.100221 -224.417958) (xy 373.073918 -224.376362) (xy 373.054627 -224.331086) (xy 373.04285 -224.283302)
			(xy 373.03889 -224.234248) (xy 372.710202 -224.234248) (xy 372.709707 -224.258855) (xy 372.701812 -224.307432)
			(xy 372.686228 -224.354113) (xy 372.663357 -224.39769) (xy 372.633792 -224.437034) (xy 372.598299 -224.471126)
			(xy 372.557796 -224.499082) (xy 372.513334 -224.52018) (xy 372.466063 -224.533872) (xy 372.417208 -224.539804)
			(xy 372.368033 -224.537823) (xy 372.319814 -224.527979) (xy 372.273798 -224.510527) (xy 372.231177 -224.48592)
			(xy 372.193056 -224.454795) (xy 372.160421 -224.417958) (xy 372.134118 -224.376362) (xy 372.114827 -224.331086)
			(xy 372.10305 -224.283302) (xy 372.09909 -224.234248) (xy 371.770148 -224.234248) (xy 371.769653 -224.258855)
			(xy 371.761758 -224.307432) (xy 371.746174 -224.354113) (xy 371.723303 -224.39769) (xy 371.693738 -224.437034)
			(xy 371.658245 -224.471126) (xy 371.617742 -224.499082) (xy 371.57328 -224.52018) (xy 371.526009 -224.533872)
			(xy 371.477154 -224.539804) (xy 371.427979 -224.537823) (xy 371.37976 -224.527979) (xy 371.333744 -224.510527)
			(xy 371.291123 -224.48592) (xy 371.253002 -224.454795) (xy 371.220367 -224.417958) (xy 371.194064 -224.376362)
			(xy 371.174773 -224.331086) (xy 371.162996 -224.283302) (xy 371.159036 -224.234248) (xy 370.830094 -224.234248)
			(xy 370.829599 -224.258855) (xy 370.821704 -224.307432) (xy 370.80612 -224.354113) (xy 370.783249 -224.39769)
			(xy 370.753684 -224.437034) (xy 370.718191 -224.471126) (xy 370.677688 -224.499082) (xy 370.633226 -224.52018)
			(xy 370.585955 -224.533872) (xy 370.5371 -224.539804) (xy 370.487925 -224.537823) (xy 370.439706 -224.527979)
			(xy 370.39369 -224.510527) (xy 370.351069 -224.48592) (xy 370.312948 -224.454795) (xy 370.280313 -224.417958)
			(xy 370.25401 -224.376362) (xy 370.234719 -224.331086) (xy 370.222942 -224.283302) (xy 370.218982 -224.234248)
			(xy 369.89004 -224.234248) (xy 369.889545 -224.258855) (xy 369.88165 -224.307432) (xy 369.866066 -224.354113)
			(xy 369.843195 -224.39769) (xy 369.81363 -224.437034) (xy 369.778137 -224.471126) (xy 369.737634 -224.499082)
			(xy 369.693172 -224.52018) (xy 369.645901 -224.533872) (xy 369.597046 -224.539804) (xy 369.547871 -224.537823)
			(xy 369.499652 -224.527979) (xy 369.453636 -224.510527) (xy 369.411015 -224.48592) (xy 369.372894 -224.454795)
			(xy 369.340259 -224.417958) (xy 369.313956 -224.376362) (xy 369.294665 -224.331086) (xy 369.282888 -224.283302)
			(xy 369.278928 -224.234248) (xy 368.949986 -224.234248) (xy 368.949491 -224.258855) (xy 368.941596 -224.307432)
			(xy 368.926012 -224.354113) (xy 368.903141 -224.39769) (xy 368.873576 -224.437034) (xy 368.838083 -224.471126)
			(xy 368.79758 -224.499082) (xy 368.753118 -224.52018) (xy 368.705847 -224.533872) (xy 368.656992 -224.539804)
			(xy 368.607817 -224.537823) (xy 368.559598 -224.527979) (xy 368.513582 -224.510527) (xy 368.470961 -224.48592)
			(xy 368.43284 -224.454795) (xy 368.400205 -224.417958) (xy 368.373902 -224.376362) (xy 368.354611 -224.331086)
			(xy 368.342834 -224.283302) (xy 368.338874 -224.234248) (xy 368.010186 -224.234248) (xy 368.009691 -224.258855)
			(xy 368.001796 -224.307432) (xy 367.986212 -224.354113) (xy 367.963341 -224.39769) (xy 367.933776 -224.437034)
			(xy 367.898283 -224.471126) (xy 367.85778 -224.499082) (xy 367.813318 -224.52018) (xy 367.766047 -224.533872)
			(xy 367.717192 -224.539804) (xy 367.668017 -224.537823) (xy 367.619798 -224.527979) (xy 367.573782 -224.510527)
			(xy 367.531161 -224.48592) (xy 367.49304 -224.454795) (xy 367.460405 -224.417958) (xy 367.434102 -224.376362)
			(xy 367.414811 -224.331086) (xy 367.403034 -224.283302) (xy 367.399074 -224.234248) (xy 367.070132 -224.234248)
			(xy 367.069637 -224.258855) (xy 367.061742 -224.307432) (xy 367.046158 -224.354113) (xy 367.023287 -224.39769)
			(xy 366.993722 -224.437034) (xy 366.958229 -224.471126) (xy 366.917726 -224.499082) (xy 366.873264 -224.52018)
			(xy 366.825993 -224.533872) (xy 366.777138 -224.539804) (xy 366.727963 -224.537823) (xy 366.679744 -224.527979)
			(xy 366.633728 -224.510527) (xy 366.591107 -224.48592) (xy 366.552986 -224.454795) (xy 366.520351 -224.417958)
			(xy 366.494048 -224.376362) (xy 366.474757 -224.331086) (xy 366.46298 -224.283302) (xy 366.45902 -224.234248)
			(xy 366.130078 -224.234248) (xy 366.129583 -224.258855) (xy 366.121688 -224.307432) (xy 366.106104 -224.354113)
			(xy 366.083233 -224.39769) (xy 366.053668 -224.437034) (xy 366.018175 -224.471126) (xy 365.977672 -224.499082)
			(xy 365.93321 -224.52018) (xy 365.885939 -224.533872) (xy 365.837084 -224.539804) (xy 365.787909 -224.537823)
			(xy 365.73969 -224.527979) (xy 365.693674 -224.510527) (xy 365.651053 -224.48592) (xy 365.612932 -224.454795)
			(xy 365.580297 -224.417958) (xy 365.553994 -224.376362) (xy 365.534703 -224.331086) (xy 365.522926 -224.283302)
			(xy 365.518966 -224.234248) (xy 365.190024 -224.234248) (xy 365.189529 -224.258855) (xy 365.181634 -224.307432)
			(xy 365.16605 -224.354113) (xy 365.143179 -224.39769) (xy 365.113614 -224.437034) (xy 365.078121 -224.471126)
			(xy 365.037618 -224.499082) (xy 364.993156 -224.52018) (xy 364.945885 -224.533872) (xy 364.89703 -224.539804)
			(xy 364.847855 -224.537823) (xy 364.799636 -224.527979) (xy 364.75362 -224.510527) (xy 364.710999 -224.48592)
			(xy 364.672878 -224.454795) (xy 364.640243 -224.417958) (xy 364.61394 -224.376362) (xy 364.594649 -224.331086)
			(xy 364.582872 -224.283302) (xy 364.578912 -224.234248) (xy 363.31017 -224.234248) (xy 363.309675 -224.258855)
			(xy 363.30178 -224.307432) (xy 363.286196 -224.354113) (xy 363.263325 -224.39769) (xy 363.23376 -224.437034)
			(xy 363.198267 -224.471126) (xy 363.157764 -224.499082) (xy 363.113302 -224.52018) (xy 363.066031 -224.533872)
			(xy 363.017176 -224.539804) (xy 362.968001 -224.537823) (xy 362.919782 -224.527979) (xy 362.873766 -224.510527)
			(xy 362.831145 -224.48592) (xy 362.793024 -224.454795) (xy 362.760389 -224.417958) (xy 362.734086 -224.376362)
			(xy 362.714795 -224.331086) (xy 362.703018 -224.283302) (xy 362.699058 -224.234248) (xy 361.430608 -224.234248)
			(xy 361.42644 -224.28454) (xy 361.414039 -224.333506) (xy 361.393747 -224.379763) (xy 361.366117 -224.422049)
			(xy 361.331903 -224.45921) (xy 361.292039 -224.490231) (xy 361.247612 -224.514268) (xy 361.199835 -224.530664)
			(xy 361.15001 -224.538971) (xy 361.124754 -224.539556) (xy 361.123992 -224.539556) (xy 361.09998 -224.539039)
			(xy 361.052559 -224.531444) (xy 361.006906 -224.516534) (xy 360.985308 -224.506028) (xy 360.985054 -224.506028)
			(xy 360.979211 -224.503283) (xy 360.966618 -224.500465) (xy 360.960162 -224.50044) (xy 360.9467 -224.500948)
			(xy 360.861864 -224.553018) (xy 360.85568 -224.557005) (xy 360.845746 -224.56785) (xy 360.842306 -224.574354)
			(xy 360.83748 -224.585022) (xy 360.83748 -225.044254) (xy 365.049066 -225.044254) (xy 365.053026 -224.9952)
			(xy 365.064803 -224.947416) (xy 365.084094 -224.90214) (xy 365.110397 -224.860544) (xy 365.143032 -224.823707)
			(xy 365.181153 -224.792582) (xy 365.223774 -224.767975) (xy 365.26979 -224.750523) (xy 365.318009 -224.740679)
			(xy 365.367184 -224.738698) (xy 365.416039 -224.74463) (xy 365.46331 -224.758322) (xy 365.507772 -224.77942)
			(xy 365.548275 -224.807376) (xy 365.583768 -224.841468) (xy 365.613333 -224.880812) (xy 365.636204 -224.924389)
			(xy 365.651788 -224.97107) (xy 365.659683 -225.019647) (xy 365.660178 -225.044254) (xy 369.749082 -225.044254)
			(xy 369.753042 -224.9952) (xy 369.764819 -224.947416) (xy 369.78411 -224.90214) (xy 369.810413 -224.860544)
			(xy 369.843048 -224.823707) (xy 369.881169 -224.792582) (xy 369.92379 -224.767975) (xy 369.969806 -224.750523)
			(xy 370.018025 -224.740679) (xy 370.0672 -224.738698) (xy 370.116055 -224.74463) (xy 370.163326 -224.758322)
			(xy 370.207788 -224.77942) (xy 370.248291 -224.807376) (xy 370.283784 -224.841468) (xy 370.313349 -224.880812)
			(xy 370.33622 -224.924389) (xy 370.351804 -224.97107) (xy 370.359699 -225.019647) (xy 370.360194 -225.044254)
			(xy 370.688882 -225.044254) (xy 370.692842 -224.9952) (xy 370.704619 -224.947416) (xy 370.72391 -224.90214)
			(xy 370.750213 -224.860544) (xy 370.782848 -224.823707) (xy 370.820969 -224.792582) (xy 370.86359 -224.767975)
			(xy 370.909606 -224.750523) (xy 370.957825 -224.740679) (xy 371.007 -224.738698) (xy 371.055855 -224.74463)
			(xy 371.103126 -224.758322) (xy 371.147588 -224.77942) (xy 371.188091 -224.807376) (xy 371.223584 -224.841468)
			(xy 371.253149 -224.880812) (xy 371.27602 -224.924389) (xy 371.291604 -224.97107) (xy 371.299499 -225.019647)
			(xy 371.299994 -225.044254) (xy 372.56899 -225.044254) (xy 372.57295 -224.9952) (xy 372.584727 -224.947416)
			(xy 372.604018 -224.90214) (xy 372.630321 -224.860544) (xy 372.662956 -224.823707) (xy 372.701077 -224.792582)
			(xy 372.743698 -224.767975) (xy 372.789714 -224.750523) (xy 372.837933 -224.740679) (xy 372.887108 -224.738698)
			(xy 372.935963 -224.74463) (xy 372.983234 -224.758322) (xy 373.027696 -224.77942) (xy 373.068199 -224.807376)
			(xy 373.103692 -224.841468) (xy 373.133257 -224.880812) (xy 373.156128 -224.924389) (xy 373.171712 -224.97107)
			(xy 373.179607 -225.019647) (xy 373.180102 -225.044254) (xy 373.509044 -225.044254) (xy 373.513004 -224.9952)
			(xy 373.524781 -224.947416) (xy 373.544072 -224.90214) (xy 373.570375 -224.860544) (xy 373.60301 -224.823707)
			(xy 373.641131 -224.792582) (xy 373.683752 -224.767975) (xy 373.729768 -224.750523) (xy 373.777987 -224.740679)
			(xy 373.827162 -224.738698) (xy 373.876017 -224.74463) (xy 373.923288 -224.758322) (xy 373.96775 -224.77942)
			(xy 374.008253 -224.807376) (xy 374.043746 -224.841468) (xy 374.073311 -224.880812) (xy 374.096182 -224.924389)
			(xy 374.111766 -224.97107) (xy 374.119661 -225.019647) (xy 374.120156 -225.044254) (xy 374.119661 -225.068861)
			(xy 374.111766 -225.117438) (xy 374.096182 -225.164119) (xy 374.073311 -225.207696) (xy 374.043746 -225.24704)
			(xy 374.008253 -225.281132) (xy 373.96775 -225.309088) (xy 373.923288 -225.330186) (xy 373.876017 -225.343878)
			(xy 373.827162 -225.34981) (xy 373.777987 -225.347829) (xy 373.729768 -225.337985) (xy 373.683752 -225.320533)
			(xy 373.641131 -225.295926) (xy 373.60301 -225.264801) (xy 373.570375 -225.227964) (xy 373.544072 -225.186368)
			(xy 373.524781 -225.141092) (xy 373.513004 -225.093308) (xy 373.509044 -225.044254) (xy 373.180102 -225.044254)
			(xy 373.179607 -225.068861) (xy 373.171712 -225.117438) (xy 373.156128 -225.164119) (xy 373.133257 -225.207696)
			(xy 373.103692 -225.24704) (xy 373.068199 -225.281132) (xy 373.027696 -225.309088) (xy 372.983234 -225.330186)
			(xy 372.935963 -225.343878) (xy 372.887108 -225.34981) (xy 372.837933 -225.347829) (xy 372.789714 -225.337985)
			(xy 372.743698 -225.320533) (xy 372.701077 -225.295926) (xy 372.662956 -225.264801) (xy 372.630321 -225.227964)
			(xy 372.604018 -225.186368) (xy 372.584727 -225.141092) (xy 372.57295 -225.093308) (xy 372.56899 -225.044254)
			(xy 371.299994 -225.044254) (xy 371.299499 -225.068861) (xy 371.291604 -225.117438) (xy 371.27602 -225.164119)
			(xy 371.253149 -225.207696) (xy 371.223584 -225.24704) (xy 371.188091 -225.281132) (xy 371.147588 -225.309088)
			(xy 371.103126 -225.330186) (xy 371.055855 -225.343878) (xy 371.007 -225.34981) (xy 370.957825 -225.347829)
			(xy 370.909606 -225.337985) (xy 370.86359 -225.320533) (xy 370.820969 -225.295926) (xy 370.782848 -225.264801)
			(xy 370.750213 -225.227964) (xy 370.72391 -225.186368) (xy 370.704619 -225.141092) (xy 370.692842 -225.093308)
			(xy 370.688882 -225.044254) (xy 370.360194 -225.044254) (xy 370.359699 -225.068861) (xy 370.351804 -225.117438)
			(xy 370.33622 -225.164119) (xy 370.313349 -225.207696) (xy 370.283784 -225.24704) (xy 370.248291 -225.281132)
			(xy 370.207788 -225.309088) (xy 370.163326 -225.330186) (xy 370.116055 -225.343878) (xy 370.0672 -225.34981)
			(xy 370.018025 -225.347829) (xy 369.969806 -225.337985) (xy 369.92379 -225.320533) (xy 369.881169 -225.295926)
			(xy 369.843048 -225.264801) (xy 369.810413 -225.227964) (xy 369.78411 -225.186368) (xy 369.764819 -225.141092)
			(xy 369.753042 -225.093308) (xy 369.749082 -225.044254) (xy 365.660178 -225.044254) (xy 365.659683 -225.068861)
			(xy 365.651788 -225.117438) (xy 365.636204 -225.164119) (xy 365.613333 -225.207696) (xy 365.583768 -225.24704)
			(xy 365.548275 -225.281132) (xy 365.507772 -225.309088) (xy 365.46331 -225.330186) (xy 365.416039 -225.343878)
			(xy 365.367184 -225.34981) (xy 365.318009 -225.347829) (xy 365.26979 -225.337985) (xy 365.223774 -225.320533)
			(xy 365.181153 -225.295926) (xy 365.143032 -225.264801) (xy 365.110397 -225.227964) (xy 365.084094 -225.186368)
			(xy 365.064803 -225.141092) (xy 365.053026 -225.093308) (xy 365.049066 -225.044254) (xy 360.83748 -225.044254)
			(xy 360.83748 -225.486468) (xy 360.83875 -225.497644) (xy 360.841036 -225.508566) (xy 360.844846 -225.519234)
			(xy 360.84891 -225.527616) (xy 360.93527 -225.580702) (xy 360.940934 -225.583919) (xy 360.953408 -225.587657)
			(xy 360.959908 -225.588068) (xy 360.97337 -225.588576) (xy 360.985308 -225.58248) (xy 361.006888 -225.571932)
			(xy 361.052544 -225.557012) (xy 361.099976 -225.549442) (xy 361.123992 -225.548952) (xy 361.124754 -225.548952)
			(xy 361.150018 -225.549441) (xy 361.199856 -225.557751) (xy 361.247648 -225.574151) (xy 361.292087 -225.598195)
			(xy 361.331963 -225.629226) (xy 361.366186 -225.666397) (xy 361.393824 -225.708695) (xy 361.414122 -225.754965)
			(xy 361.426527 -225.803946) (xy 361.430697 -225.85426) (xy 361.759004 -225.85426) (xy 361.762964 -225.805206)
			(xy 361.774741 -225.757422) (xy 361.794032 -225.712146) (xy 361.820335 -225.67055) (xy 361.85297 -225.633713)
			(xy 361.891091 -225.602588) (xy 361.933712 -225.577981) (xy 361.979728 -225.560529) (xy 362.027947 -225.550685)
			(xy 362.077122 -225.548704) (xy 362.125977 -225.554636) (xy 362.173248 -225.568328) (xy 362.21771 -225.589426)
			(xy 362.258213 -225.617382) (xy 362.293706 -225.651474) (xy 362.323271 -225.690818) (xy 362.346142 -225.734395)
			(xy 362.361726 -225.781076) (xy 362.369621 -225.829653) (xy 362.370116 -225.85426) (xy 362.699058 -225.85426)
			(xy 362.703018 -225.805206) (xy 362.714795 -225.757422) (xy 362.734086 -225.712146) (xy 362.760389 -225.67055)
			(xy 362.793024 -225.633713) (xy 362.831145 -225.602588) (xy 362.873766 -225.577981) (xy 362.919782 -225.560529)
			(xy 362.968001 -225.550685) (xy 363.017176 -225.548704) (xy 363.066031 -225.554636) (xy 363.113302 -225.568328)
			(xy 363.157764 -225.589426) (xy 363.198267 -225.617382) (xy 363.23376 -225.651474) (xy 363.263325 -225.690818)
			(xy 363.286196 -225.734395) (xy 363.30178 -225.781076) (xy 363.309675 -225.829653) (xy 363.31017 -225.85426)
			(xy 364.578912 -225.85426) (xy 364.582872 -225.805206) (xy 364.594649 -225.757422) (xy 364.61394 -225.712146)
			(xy 364.640243 -225.67055) (xy 364.672878 -225.633713) (xy 364.710999 -225.602588) (xy 364.75362 -225.577981)
			(xy 364.799636 -225.560529) (xy 364.847855 -225.550685) (xy 364.89703 -225.548704) (xy 364.945885 -225.554636)
			(xy 364.993156 -225.568328) (xy 365.037618 -225.589426) (xy 365.078121 -225.617382) (xy 365.113614 -225.651474)
			(xy 365.143179 -225.690818) (xy 365.16605 -225.734395) (xy 365.181634 -225.781076) (xy 365.189529 -225.829653)
			(xy 365.190024 -225.85426) (xy 365.518966 -225.85426) (xy 365.522926 -225.805206) (xy 365.534703 -225.757422)
			(xy 365.553994 -225.712146) (xy 365.580297 -225.67055) (xy 365.612932 -225.633713) (xy 365.651053 -225.602588)
			(xy 365.693674 -225.577981) (xy 365.73969 -225.560529) (xy 365.787909 -225.550685) (xy 365.837084 -225.548704)
			(xy 365.885939 -225.554636) (xy 365.93321 -225.568328) (xy 365.977672 -225.589426) (xy 366.018175 -225.617382)
			(xy 366.053668 -225.651474) (xy 366.083233 -225.690818) (xy 366.106104 -225.734395) (xy 366.121688 -225.781076)
			(xy 366.129583 -225.829653) (xy 366.130078 -225.85426) (xy 367.399074 -225.85426) (xy 367.403034 -225.805206)
			(xy 367.414811 -225.757422) (xy 367.434102 -225.712146) (xy 367.460405 -225.67055) (xy 367.49304 -225.633713)
			(xy 367.531161 -225.602588) (xy 367.573782 -225.577981) (xy 367.619798 -225.560529) (xy 367.668017 -225.550685)
			(xy 367.717192 -225.548704) (xy 367.766047 -225.554636) (xy 367.813318 -225.568328) (xy 367.85778 -225.589426)
			(xy 367.898283 -225.617382) (xy 367.933776 -225.651474) (xy 367.963341 -225.690818) (xy 367.986212 -225.734395)
			(xy 368.001796 -225.781076) (xy 368.009691 -225.829653) (xy 368.010186 -225.85426) (xy 368.339128 -225.85426)
			(xy 368.343088 -225.805206) (xy 368.354865 -225.757422) (xy 368.374156 -225.712146) (xy 368.400459 -225.67055)
			(xy 368.433094 -225.633713) (xy 368.471215 -225.602588) (xy 368.513836 -225.577981) (xy 368.559852 -225.560529)
			(xy 368.608071 -225.550685) (xy 368.657246 -225.548704) (xy 368.706101 -225.554636) (xy 368.753372 -225.568328)
			(xy 368.797834 -225.589426) (xy 368.838337 -225.617382) (xy 368.87383 -225.651474) (xy 368.903395 -225.690818)
			(xy 368.926266 -225.734395) (xy 368.94185 -225.781076) (xy 368.949745 -225.829653) (xy 368.95024 -225.85426)
			(xy 370.218982 -225.85426) (xy 370.222942 -225.805206) (xy 370.234719 -225.757422) (xy 370.25401 -225.712146)
			(xy 370.280313 -225.67055) (xy 370.312948 -225.633713) (xy 370.351069 -225.602588) (xy 370.39369 -225.577981)
			(xy 370.439706 -225.560529) (xy 370.487925 -225.550685) (xy 370.5371 -225.548704) (xy 370.585955 -225.554636)
			(xy 370.633226 -225.568328) (xy 370.677688 -225.589426) (xy 370.718191 -225.617382) (xy 370.753684 -225.651474)
			(xy 370.783249 -225.690818) (xy 370.80612 -225.734395) (xy 370.821704 -225.781076) (xy 370.829599 -225.829653)
			(xy 370.830094 -225.85426) (xy 371.159036 -225.85426) (xy 371.162996 -225.805206) (xy 371.174773 -225.757422)
			(xy 371.194064 -225.712146) (xy 371.220367 -225.67055) (xy 371.253002 -225.633713) (xy 371.291123 -225.602588)
			(xy 371.333744 -225.577981) (xy 371.37976 -225.560529) (xy 371.427979 -225.550685) (xy 371.477154 -225.548704)
			(xy 371.526009 -225.554636) (xy 371.57328 -225.568328) (xy 371.617742 -225.589426) (xy 371.658245 -225.617382)
			(xy 371.693738 -225.651474) (xy 371.723303 -225.690818) (xy 371.746174 -225.734395) (xy 371.761758 -225.781076)
			(xy 371.769653 -225.829653) (xy 371.770148 -225.85426) (xy 373.03889 -225.85426) (xy 373.04285 -225.805206)
			(xy 373.054627 -225.757422) (xy 373.073918 -225.712146) (xy 373.100221 -225.67055) (xy 373.132856 -225.633713)
			(xy 373.170977 -225.602588) (xy 373.213598 -225.577981) (xy 373.259614 -225.560529) (xy 373.307833 -225.550685)
			(xy 373.357008 -225.548704) (xy 373.405863 -225.554636) (xy 373.453134 -225.568328) (xy 373.497596 -225.589426)
			(xy 373.538099 -225.617382) (xy 373.573592 -225.651474) (xy 373.603157 -225.690818) (xy 373.626028 -225.734395)
			(xy 373.641612 -225.781076) (xy 373.649507 -225.829653) (xy 373.650002 -225.85426) (xy 373.649507 -225.878867)
			(xy 373.641612 -225.927444) (xy 373.626028 -225.974125) (xy 373.603157 -226.017702) (xy 373.573592 -226.057046)
			(xy 373.538099 -226.091138) (xy 373.497596 -226.119094) (xy 373.453134 -226.140192) (xy 373.405863 -226.153884)
			(xy 373.357008 -226.159816) (xy 373.307833 -226.157835) (xy 373.259614 -226.147991) (xy 373.213598 -226.130539)
			(xy 373.170977 -226.105932) (xy 373.132856 -226.074807) (xy 373.100221 -226.03797) (xy 373.073918 -225.996374)
			(xy 373.054627 -225.951098) (xy 373.04285 -225.903314) (xy 373.03889 -225.85426) (xy 371.770148 -225.85426)
			(xy 371.769653 -225.878867) (xy 371.761758 -225.927444) (xy 371.746174 -225.974125) (xy 371.723303 -226.017702)
			(xy 371.693738 -226.057046) (xy 371.658245 -226.091138) (xy 371.617742 -226.119094) (xy 371.57328 -226.140192)
			(xy 371.526009 -226.153884) (xy 371.477154 -226.159816) (xy 371.427979 -226.157835) (xy 371.37976 -226.147991)
			(xy 371.333744 -226.130539) (xy 371.291123 -226.105932) (xy 371.253002 -226.074807) (xy 371.220367 -226.03797)
			(xy 371.194064 -225.996374) (xy 371.174773 -225.951098) (xy 371.162996 -225.903314) (xy 371.159036 -225.85426)
			(xy 370.830094 -225.85426) (xy 370.829599 -225.878867) (xy 370.821704 -225.927444) (xy 370.80612 -225.974125)
			(xy 370.783249 -226.017702) (xy 370.753684 -226.057046) (xy 370.718191 -226.091138) (xy 370.677688 -226.119094)
			(xy 370.633226 -226.140192) (xy 370.585955 -226.153884) (xy 370.5371 -226.159816) (xy 370.487925 -226.157835)
			(xy 370.439706 -226.147991) (xy 370.39369 -226.130539) (xy 370.351069 -226.105932) (xy 370.312948 -226.074807)
			(xy 370.280313 -226.03797) (xy 370.25401 -225.996374) (xy 370.234719 -225.951098) (xy 370.222942 -225.903314)
			(xy 370.218982 -225.85426) (xy 368.95024 -225.85426) (xy 368.949745 -225.878867) (xy 368.94185 -225.927444)
			(xy 368.926266 -225.974125) (xy 368.903395 -226.017702) (xy 368.87383 -226.057046) (xy 368.838337 -226.091138)
			(xy 368.797834 -226.119094) (xy 368.753372 -226.140192) (xy 368.706101 -226.153884) (xy 368.657246 -226.159816)
			(xy 368.608071 -226.157835) (xy 368.559852 -226.147991) (xy 368.513836 -226.130539) (xy 368.471215 -226.105932)
			(xy 368.433094 -226.074807) (xy 368.400459 -226.03797) (xy 368.374156 -225.996374) (xy 368.354865 -225.951098)
			(xy 368.343088 -225.903314) (xy 368.339128 -225.85426) (xy 368.010186 -225.85426) (xy 368.009691 -225.878867)
			(xy 368.001796 -225.927444) (xy 367.986212 -225.974125) (xy 367.963341 -226.017702) (xy 367.933776 -226.057046)
			(xy 367.898283 -226.091138) (xy 367.85778 -226.119094) (xy 367.813318 -226.140192) (xy 367.766047 -226.153884)
			(xy 367.717192 -226.159816) (xy 367.668017 -226.157835) (xy 367.619798 -226.147991) (xy 367.573782 -226.130539)
			(xy 367.531161 -226.105932) (xy 367.49304 -226.074807) (xy 367.460405 -226.03797) (xy 367.434102 -225.996374)
			(xy 367.414811 -225.951098) (xy 367.403034 -225.903314) (xy 367.399074 -225.85426) (xy 366.130078 -225.85426)
			(xy 366.129583 -225.878867) (xy 366.121688 -225.927444) (xy 366.106104 -225.974125) (xy 366.083233 -226.017702)
			(xy 366.053668 -226.057046) (xy 366.018175 -226.091138) (xy 365.977672 -226.119094) (xy 365.93321 -226.140192)
			(xy 365.885939 -226.153884) (xy 365.837084 -226.159816) (xy 365.787909 -226.157835) (xy 365.73969 -226.147991)
			(xy 365.693674 -226.130539) (xy 365.651053 -226.105932) (xy 365.612932 -226.074807) (xy 365.580297 -226.03797)
			(xy 365.553994 -225.996374) (xy 365.534703 -225.951098) (xy 365.522926 -225.903314) (xy 365.518966 -225.85426)
			(xy 365.190024 -225.85426) (xy 365.189529 -225.878867) (xy 365.181634 -225.927444) (xy 365.16605 -225.974125)
			(xy 365.143179 -226.017702) (xy 365.113614 -226.057046) (xy 365.078121 -226.091138) (xy 365.037618 -226.119094)
			(xy 364.993156 -226.140192) (xy 364.945885 -226.153884) (xy 364.89703 -226.159816) (xy 364.847855 -226.157835)
			(xy 364.799636 -226.147991) (xy 364.75362 -226.130539) (xy 364.710999 -226.105932) (xy 364.672878 -226.074807)
			(xy 364.640243 -226.03797) (xy 364.61394 -225.996374) (xy 364.594649 -225.951098) (xy 364.582872 -225.903314)
			(xy 364.578912 -225.85426) (xy 363.31017 -225.85426) (xy 363.309675 -225.878867) (xy 363.30178 -225.927444)
			(xy 363.286196 -225.974125) (xy 363.263325 -226.017702) (xy 363.23376 -226.057046) (xy 363.198267 -226.091138)
			(xy 363.157764 -226.119094) (xy 363.113302 -226.140192) (xy 363.066031 -226.153884) (xy 363.017176 -226.159816)
			(xy 362.968001 -226.157835) (xy 362.919782 -226.147991) (xy 362.873766 -226.130539) (xy 362.831145 -226.105932)
			(xy 362.793024 -226.074807) (xy 362.760389 -226.03797) (xy 362.734086 -225.996374) (xy 362.714795 -225.951098)
			(xy 362.703018 -225.903314) (xy 362.699058 -225.85426) (xy 362.370116 -225.85426) (xy 362.369621 -225.878867)
			(xy 362.361726 -225.927444) (xy 362.346142 -225.974125) (xy 362.323271 -226.017702) (xy 362.293706 -226.057046)
			(xy 362.258213 -226.091138) (xy 362.21771 -226.119094) (xy 362.173248 -226.140192) (xy 362.125977 -226.153884)
			(xy 362.077122 -226.159816) (xy 362.027947 -226.157835) (xy 361.979728 -226.147991) (xy 361.933712 -226.130539)
			(xy 361.891091 -226.105932) (xy 361.85297 -226.074807) (xy 361.820335 -226.03797) (xy 361.794032 -225.996374)
			(xy 361.774741 -225.951098) (xy 361.762964 -225.903314) (xy 361.759004 -225.85426) (xy 361.430697 -225.85426)
			(xy 361.4307 -225.8543) (xy 361.426527 -225.904654) (xy 361.414122 -225.953635) (xy 361.393824 -225.999905)
			(xy 361.366186 -226.042203) (xy 361.331963 -226.079374) (xy 361.292087 -226.110405) (xy 361.247648 -226.134449)
			(xy 361.199856 -226.150849) (xy 361.150018 -226.159159) (xy 361.124754 -226.159568) (xy 361.123992 -226.159568)
			(xy 361.09998 -226.159051) (xy 361.052559 -226.151456) (xy 361.006905 -226.136547) (xy 360.985308 -226.12604)
			(xy 360.985054 -226.12604) (xy 360.97921 -226.123299) (xy 360.966617 -226.120486) (xy 360.960162 -226.120452)
			(xy 360.9467 -226.12096) (xy 360.861864 -226.17303) (xy 360.855681 -226.177018) (xy 360.845749 -226.187864)
			(xy 360.842306 -226.194366) (xy 360.83748 -226.205034) (xy 360.83748 -226.664266) (xy 363.168958 -226.664266)
			(xy 363.172918 -226.615212) (xy 363.184695 -226.567428) (xy 363.203986 -226.522152) (xy 363.230289 -226.480556)
			(xy 363.262924 -226.443719) (xy 363.301045 -226.412594) (xy 363.343666 -226.387987) (xy 363.389682 -226.370535)
			(xy 363.437901 -226.360691) (xy 363.487076 -226.35871) (xy 363.535931 -226.364642) (xy 363.583202 -226.378334)
			(xy 363.627664 -226.399432) (xy 363.668167 -226.427388) (xy 363.70366 -226.46148) (xy 363.733225 -226.500824)
			(xy 363.756096 -226.544401) (xy 363.77168 -226.591082) (xy 363.779575 -226.639659) (xy 363.78007 -226.664266)
			(xy 364.098581 -226.664266) (xy 364.102676 -226.613538) (xy 364.114855 -226.564124) (xy 364.134803 -226.517304)
			(xy 364.162004 -226.47429) (xy 364.195752 -226.436196) (xy 364.235174 -226.404009) (xy 364.279248 -226.378563)
			(xy 364.326834 -226.360516) (xy 364.376698 -226.350336) (xy 364.42755 -226.348287) (xy 364.478071 -226.354421)
			(xy 364.526955 -226.368581) (xy 364.572934 -226.390398) (xy 364.614818 -226.419308) (xy 364.651522 -226.454563)
			(xy 364.682095 -226.495249) (xy 364.705746 -226.540312) (xy 364.721862 -226.588586) (xy 364.730026 -226.63882)
			(xy 364.730538 -226.664266) (xy 365.038635 -226.664266) (xy 365.04273 -226.613538) (xy 365.054909 -226.564124)
			(xy 365.074857 -226.517304) (xy 365.102058 -226.47429) (xy 365.135806 -226.436196) (xy 365.175228 -226.404009)
			(xy 365.219302 -226.378563) (xy 365.266888 -226.360516) (xy 365.316752 -226.350336) (xy 365.367604 -226.348287)
			(xy 365.418125 -226.354421) (xy 365.467009 -226.368581) (xy 365.512988 -226.390398) (xy 365.554872 -226.419308)
			(xy 365.591576 -226.454563) (xy 365.622149 -226.495249) (xy 365.6458 -226.540312) (xy 365.661916 -226.588586)
			(xy 365.67008 -226.63882) (xy 365.670592 -226.664266) (xy 365.98912 -226.664266) (xy 365.99308 -226.615212)
			(xy 366.004857 -226.567428) (xy 366.024148 -226.522152) (xy 366.050451 -226.480556) (xy 366.083086 -226.443719)
			(xy 366.121207 -226.412594) (xy 366.163828 -226.387987) (xy 366.209844 -226.370535) (xy 366.258063 -226.360691)
			(xy 366.307238 -226.35871) (xy 366.356093 -226.364642) (xy 366.403364 -226.378334) (xy 366.447826 -226.399432)
			(xy 366.488329 -226.427388) (xy 366.523822 -226.46148) (xy 366.553387 -226.500824) (xy 366.576258 -226.544401)
			(xy 366.591842 -226.591082) (xy 366.599737 -226.639659) (xy 366.600232 -226.664266) (xy 366.918489 -226.664266)
			(xy 366.922584 -226.613538) (xy 366.934763 -226.564124) (xy 366.954711 -226.517304) (xy 366.981912 -226.47429)
			(xy 367.01566 -226.436196) (xy 367.055082 -226.404009) (xy 367.099156 -226.378563) (xy 367.146742 -226.360516)
			(xy 367.196606 -226.350336) (xy 367.247458 -226.348287) (xy 367.297979 -226.354421) (xy 367.346863 -226.368581)
			(xy 367.392842 -226.390398) (xy 367.434726 -226.419308) (xy 367.47143 -226.454563) (xy 367.502003 -226.495249)
			(xy 367.525654 -226.540312) (xy 367.54177 -226.588586) (xy 367.549934 -226.63882) (xy 367.550446 -226.664266)
			(xy 367.858543 -226.664266) (xy 367.862638 -226.613538) (xy 367.874817 -226.564124) (xy 367.894765 -226.517304)
			(xy 367.921966 -226.47429) (xy 367.955714 -226.436196) (xy 367.995136 -226.404009) (xy 368.03921 -226.378563)
			(xy 368.086796 -226.360516) (xy 368.13666 -226.350336) (xy 368.187512 -226.348287) (xy 368.238033 -226.354421)
			(xy 368.286917 -226.368581) (xy 368.332896 -226.390398) (xy 368.37478 -226.419308) (xy 368.411484 -226.454563)
			(xy 368.442057 -226.495249) (xy 368.465708 -226.540312) (xy 368.481824 -226.588586) (xy 368.489988 -226.63882)
			(xy 368.4905 -226.664266) (xy 368.809028 -226.664266) (xy 368.812988 -226.615212) (xy 368.824765 -226.567428)
			(xy 368.844056 -226.522152) (xy 368.870359 -226.480556) (xy 368.902994 -226.443719) (xy 368.941115 -226.412594)
			(xy 368.983736 -226.387987) (xy 369.029752 -226.370535) (xy 369.077971 -226.360691) (xy 369.127146 -226.35871)
			(xy 369.176001 -226.364642) (xy 369.223272 -226.378334) (xy 369.267734 -226.399432) (xy 369.308237 -226.427388)
			(xy 369.34373 -226.46148) (xy 369.373295 -226.500824) (xy 369.396166 -226.544401) (xy 369.41175 -226.591082)
			(xy 369.419645 -226.639659) (xy 369.42014 -226.664266) (xy 369.738651 -226.664266) (xy 369.742746 -226.613538)
			(xy 369.754925 -226.564124) (xy 369.774873 -226.517304) (xy 369.802074 -226.47429) (xy 369.835822 -226.436196)
			(xy 369.875244 -226.404009) (xy 369.919318 -226.378563) (xy 369.966904 -226.360516) (xy 370.016768 -226.350336)
			(xy 370.06762 -226.348287) (xy 370.118141 -226.354421) (xy 370.167025 -226.368581) (xy 370.213004 -226.390398)
			(xy 370.254888 -226.419308) (xy 370.291592 -226.454563) (xy 370.322165 -226.495249) (xy 370.345816 -226.540312)
			(xy 370.361932 -226.588586) (xy 370.370096 -226.63882) (xy 370.370608 -226.664266) (xy 370.678451 -226.664266)
			(xy 370.682546 -226.613538) (xy 370.694725 -226.564124) (xy 370.714673 -226.517304) (xy 370.741874 -226.47429)
			(xy 370.775622 -226.436196) (xy 370.815044 -226.404009) (xy 370.859118 -226.378563) (xy 370.906704 -226.360516)
			(xy 370.956568 -226.350336) (xy 371.00742 -226.348287) (xy 371.057941 -226.354421) (xy 371.106825 -226.368581)
			(xy 371.152804 -226.390398) (xy 371.194688 -226.419308) (xy 371.231392 -226.454563) (xy 371.261965 -226.495249)
			(xy 371.285616 -226.540312) (xy 371.301732 -226.588586) (xy 371.309896 -226.63882) (xy 371.310408 -226.664266)
			(xy 371.628936 -226.664266) (xy 371.632896 -226.615212) (xy 371.644673 -226.567428) (xy 371.663964 -226.522152)
			(xy 371.690267 -226.480556) (xy 371.722902 -226.443719) (xy 371.761023 -226.412594) (xy 371.803644 -226.387987)
			(xy 371.84966 -226.370535) (xy 371.897879 -226.360691) (xy 371.947054 -226.35871) (xy 371.995909 -226.364642)
			(xy 372.04318 -226.378334) (xy 372.087642 -226.399432) (xy 372.128145 -226.427388) (xy 372.163638 -226.46148)
			(xy 372.193203 -226.500824) (xy 372.216074 -226.544401) (xy 372.231658 -226.591082) (xy 372.239553 -226.639659)
			(xy 372.240048 -226.664266) (xy 372.558559 -226.664266) (xy 372.562654 -226.613538) (xy 372.574833 -226.564124)
			(xy 372.594781 -226.517304) (xy 372.621982 -226.47429) (xy 372.65573 -226.436196) (xy 372.695152 -226.404009)
			(xy 372.739226 -226.378563) (xy 372.786812 -226.360516) (xy 372.836676 -226.350336) (xy 372.887528 -226.348287)
			(xy 372.938049 -226.354421) (xy 372.986933 -226.368581) (xy 373.032912 -226.390398) (xy 373.074796 -226.419308)
			(xy 373.1115 -226.454563) (xy 373.142073 -226.495249) (xy 373.165724 -226.540312) (xy 373.18184 -226.588586)
			(xy 373.190004 -226.63882) (xy 373.190516 -226.664266) (xy 373.498613 -226.664266) (xy 373.502708 -226.613538)
			(xy 373.514887 -226.564124) (xy 373.534835 -226.517304) (xy 373.562036 -226.47429) (xy 373.595784 -226.436196)
			(xy 373.635206 -226.404009) (xy 373.67928 -226.378563) (xy 373.726866 -226.360516) (xy 373.77673 -226.350336)
			(xy 373.827582 -226.348287) (xy 373.878103 -226.354421) (xy 373.926987 -226.368581) (xy 373.972966 -226.390398)
			(xy 374.01485 -226.419308) (xy 374.051554 -226.454563) (xy 374.082127 -226.495249) (xy 374.105778 -226.540312)
			(xy 374.121894 -226.588586) (xy 374.130058 -226.63882) (xy 374.13057 -226.664266) (xy 374.130058 -226.689712)
			(xy 374.121894 -226.739946) (xy 374.105778 -226.78822) (xy 374.082127 -226.833283) (xy 374.051554 -226.873969)
			(xy 374.01485 -226.909224) (xy 373.972966 -226.938134) (xy 373.926987 -226.959951) (xy 373.878103 -226.974111)
			(xy 373.827582 -226.980245) (xy 373.77673 -226.978196) (xy 373.726866 -226.968016) (xy 373.67928 -226.949969)
			(xy 373.635206 -226.924523) (xy 373.595784 -226.892336) (xy 373.562036 -226.854242) (xy 373.534835 -226.811228)
			(xy 373.514887 -226.764408) (xy 373.502708 -226.714994) (xy 373.498613 -226.664266) (xy 373.190516 -226.664266)
			(xy 373.190004 -226.689712) (xy 373.18184 -226.739946) (xy 373.165724 -226.78822) (xy 373.142073 -226.833283)
			(xy 373.1115 -226.873969) (xy 373.074796 -226.909224) (xy 373.032912 -226.938134) (xy 372.986933 -226.959951)
			(xy 372.938049 -226.974111) (xy 372.887528 -226.980245) (xy 372.836676 -226.978196) (xy 372.786812 -226.968016)
			(xy 372.739226 -226.949969) (xy 372.695152 -226.924523) (xy 372.65573 -226.892336) (xy 372.621982 -226.854242)
			(xy 372.594781 -226.811228) (xy 372.574833 -226.764408) (xy 372.562654 -226.714994) (xy 372.558559 -226.664266)
			(xy 372.240048 -226.664266) (xy 372.239553 -226.688873) (xy 372.231658 -226.73745) (xy 372.216074 -226.784131)
			(xy 372.193203 -226.827708) (xy 372.163638 -226.867052) (xy 372.128145 -226.901144) (xy 372.087642 -226.9291)
			(xy 372.04318 -226.950198) (xy 371.995909 -226.96389) (xy 371.947054 -226.969822) (xy 371.897879 -226.967841)
			(xy 371.84966 -226.957997) (xy 371.803644 -226.940545) (xy 371.761023 -226.915938) (xy 371.722902 -226.884813)
			(xy 371.690267 -226.847976) (xy 371.663964 -226.80638) (xy 371.644673 -226.761104) (xy 371.632896 -226.71332)
			(xy 371.628936 -226.664266) (xy 371.310408 -226.664266) (xy 371.309896 -226.689712) (xy 371.301732 -226.739946)
			(xy 371.285616 -226.78822) (xy 371.261965 -226.833283) (xy 371.231392 -226.873969) (xy 371.194688 -226.909224)
			(xy 371.152804 -226.938134) (xy 371.106825 -226.959951) (xy 371.057941 -226.974111) (xy 371.00742 -226.980245)
			(xy 370.956568 -226.978196) (xy 370.906704 -226.968016) (xy 370.859118 -226.949969) (xy 370.815044 -226.924523)
			(xy 370.775622 -226.892336) (xy 370.741874 -226.854242) (xy 370.714673 -226.811228) (xy 370.694725 -226.764408)
			(xy 370.682546 -226.714994) (xy 370.678451 -226.664266) (xy 370.370608 -226.664266) (xy 370.370096 -226.689712)
			(xy 370.361932 -226.739946) (xy 370.345816 -226.78822) (xy 370.322165 -226.833283) (xy 370.291592 -226.873969)
			(xy 370.254888 -226.909224) (xy 370.213004 -226.938134) (xy 370.167025 -226.959951) (xy 370.118141 -226.974111)
			(xy 370.06762 -226.980245) (xy 370.016768 -226.978196) (xy 369.966904 -226.968016) (xy 369.919318 -226.949969)
			(xy 369.875244 -226.924523) (xy 369.835822 -226.892336) (xy 369.802074 -226.854242) (xy 369.774873 -226.811228)
			(xy 369.754925 -226.764408) (xy 369.742746 -226.714994) (xy 369.738651 -226.664266) (xy 369.42014 -226.664266)
			(xy 369.419645 -226.688873) (xy 369.41175 -226.73745) (xy 369.396166 -226.784131) (xy 369.373295 -226.827708)
			(xy 369.34373 -226.867052) (xy 369.308237 -226.901144) (xy 369.267734 -226.9291) (xy 369.223272 -226.950198)
			(xy 369.176001 -226.96389) (xy 369.127146 -226.969822) (xy 369.077971 -226.967841) (xy 369.029752 -226.957997)
			(xy 368.983736 -226.940545) (xy 368.941115 -226.915938) (xy 368.902994 -226.884813) (xy 368.870359 -226.847976)
			(xy 368.844056 -226.80638) (xy 368.824765 -226.761104) (xy 368.812988 -226.71332) (xy 368.809028 -226.664266)
			(xy 368.4905 -226.664266) (xy 368.489988 -226.689712) (xy 368.481824 -226.739946) (xy 368.465708 -226.78822)
			(xy 368.442057 -226.833283) (xy 368.411484 -226.873969) (xy 368.37478 -226.909224) (xy 368.332896 -226.938134)
			(xy 368.286917 -226.959951) (xy 368.238033 -226.974111) (xy 368.187512 -226.980245) (xy 368.13666 -226.978196)
			(xy 368.086796 -226.968016) (xy 368.03921 -226.949969) (xy 367.995136 -226.924523) (xy 367.955714 -226.892336)
			(xy 367.921966 -226.854242) (xy 367.894765 -226.811228) (xy 367.874817 -226.764408) (xy 367.862638 -226.714994)
			(xy 367.858543 -226.664266) (xy 367.550446 -226.664266) (xy 367.549934 -226.689712) (xy 367.54177 -226.739946)
			(xy 367.525654 -226.78822) (xy 367.502003 -226.833283) (xy 367.47143 -226.873969) (xy 367.434726 -226.909224)
			(xy 367.392842 -226.938134) (xy 367.346863 -226.959951) (xy 367.297979 -226.974111) (xy 367.247458 -226.980245)
			(xy 367.196606 -226.978196) (xy 367.146742 -226.968016) (xy 367.099156 -226.949969) (xy 367.055082 -226.924523)
			(xy 367.01566 -226.892336) (xy 366.981912 -226.854242) (xy 366.954711 -226.811228) (xy 366.934763 -226.764408)
			(xy 366.922584 -226.714994) (xy 366.918489 -226.664266) (xy 366.600232 -226.664266) (xy 366.599737 -226.688873)
			(xy 366.591842 -226.73745) (xy 366.576258 -226.784131) (xy 366.553387 -226.827708) (xy 366.523822 -226.867052)
			(xy 366.488329 -226.901144) (xy 366.447826 -226.9291) (xy 366.403364 -226.950198) (xy 366.356093 -226.96389)
			(xy 366.307238 -226.969822) (xy 366.258063 -226.967841) (xy 366.209844 -226.957997) (xy 366.163828 -226.940545)
			(xy 366.121207 -226.915938) (xy 366.083086 -226.884813) (xy 366.050451 -226.847976) (xy 366.024148 -226.80638)
			(xy 366.004857 -226.761104) (xy 365.99308 -226.71332) (xy 365.98912 -226.664266) (xy 365.670592 -226.664266)
			(xy 365.67008 -226.689712) (xy 365.661916 -226.739946) (xy 365.6458 -226.78822) (xy 365.622149 -226.833283)
			(xy 365.591576 -226.873969) (xy 365.554872 -226.909224) (xy 365.512988 -226.938134) (xy 365.467009 -226.959951)
			(xy 365.418125 -226.974111) (xy 365.367604 -226.980245) (xy 365.316752 -226.978196) (xy 365.266888 -226.968016)
			(xy 365.219302 -226.949969) (xy 365.175228 -226.924523) (xy 365.135806 -226.892336) (xy 365.102058 -226.854242)
			(xy 365.074857 -226.811228) (xy 365.054909 -226.764408) (xy 365.04273 -226.714994) (xy 365.038635 -226.664266)
			(xy 364.730538 -226.664266) (xy 364.730026 -226.689712) (xy 364.721862 -226.739946) (xy 364.705746 -226.78822)
			(xy 364.682095 -226.833283) (xy 364.651522 -226.873969) (xy 364.614818 -226.909224) (xy 364.572934 -226.938134)
			(xy 364.526955 -226.959951) (xy 364.478071 -226.974111) (xy 364.42755 -226.980245) (xy 364.376698 -226.978196)
			(xy 364.326834 -226.968016) (xy 364.279248 -226.949969) (xy 364.235174 -226.924523) (xy 364.195752 -226.892336)
			(xy 364.162004 -226.854242) (xy 364.134803 -226.811228) (xy 364.114855 -226.764408) (xy 364.102676 -226.714994)
			(xy 364.098581 -226.664266) (xy 363.78007 -226.664266) (xy 363.779575 -226.688873) (xy 363.77168 -226.73745)
			(xy 363.756096 -226.784131) (xy 363.733225 -226.827708) (xy 363.70366 -226.867052) (xy 363.668167 -226.901144)
			(xy 363.627664 -226.9291) (xy 363.583202 -226.950198) (xy 363.535931 -226.96389) (xy 363.487076 -226.969822)
			(xy 363.437901 -226.967841) (xy 363.389682 -226.957997) (xy 363.343666 -226.940545) (xy 363.301045 -226.915938)
			(xy 363.262924 -226.884813) (xy 363.230289 -226.847976) (xy 363.203986 -226.80638) (xy 363.184695 -226.761104)
			(xy 363.172918 -226.71332) (xy 363.168958 -226.664266) (xy 360.83748 -226.664266) (xy 360.83748 -227.10648)
			(xy 360.83875 -227.117656) (xy 360.841036 -227.128578) (xy 360.844846 -227.139246) (xy 360.84891 -227.147628)
			(xy 360.93527 -227.200714) (xy 360.940934 -227.203931) (xy 360.953408 -227.207668) (xy 360.959908 -227.20808)
			(xy 360.97337 -227.208588) (xy 360.985308 -227.202492) (xy 361.006888 -227.191943) (xy 361.052544 -227.177023)
			(xy 361.099976 -227.169452) (xy 361.123992 -227.168964) (xy 361.124754 -227.168964) (xy 361.150017 -227.169453)
			(xy 361.199853 -227.177763) (xy 361.247643 -227.194162) (xy 361.292081 -227.218205) (xy 361.331954 -227.249234)
			(xy 361.366177 -227.286404) (xy 361.393814 -227.328701) (xy 361.414111 -227.374969) (xy 361.426515 -227.423948)
			(xy 361.430686 -227.474272) (xy 361.748573 -227.474272) (xy 361.752668 -227.423544) (xy 361.764847 -227.37413)
			(xy 361.784795 -227.32731) (xy 361.811996 -227.284296) (xy 361.845744 -227.246202) (xy 361.885166 -227.214015)
			(xy 361.92924 -227.188569) (xy 361.976826 -227.170522) (xy 362.02669 -227.160342) (xy 362.077542 -227.158293)
			(xy 362.128063 -227.164427) (xy 362.176947 -227.178587) (xy 362.222926 -227.200404) (xy 362.26481 -227.229314)
			(xy 362.301514 -227.264569) (xy 362.332087 -227.305255) (xy 362.355738 -227.350318) (xy 362.371854 -227.398592)
			(xy 362.380018 -227.448826) (xy 362.38053 -227.474272) (xy 362.688627 -227.474272) (xy 362.692722 -227.423544)
			(xy 362.704901 -227.37413) (xy 362.724849 -227.32731) (xy 362.75205 -227.284296) (xy 362.785798 -227.246202)
			(xy 362.82522 -227.214015) (xy 362.869294 -227.188569) (xy 362.91688 -227.170522) (xy 362.966744 -227.160342)
			(xy 363.017596 -227.158293) (xy 363.068117 -227.164427) (xy 363.117001 -227.178587) (xy 363.16298 -227.200404)
			(xy 363.204864 -227.229314) (xy 363.241568 -227.264569) (xy 363.272141 -227.305255) (xy 363.295792 -227.350318)
			(xy 363.311908 -227.398592) (xy 363.320072 -227.448826) (xy 363.320584 -227.474272) (xy 363.639112 -227.474272)
			(xy 363.643072 -227.425218) (xy 363.654849 -227.377434) (xy 363.67414 -227.332158) (xy 363.700443 -227.290562)
			(xy 363.733078 -227.253725) (xy 363.771199 -227.2226) (xy 363.81382 -227.197993) (xy 363.859836 -227.180541)
			(xy 363.908055 -227.170697) (xy 363.95723 -227.168716) (xy 364.006085 -227.174648) (xy 364.053356 -227.18834)
			(xy 364.097818 -227.209438) (xy 364.138321 -227.237394) (xy 364.173814 -227.271486) (xy 364.203379 -227.31083)
			(xy 364.22625 -227.354407) (xy 364.241834 -227.401088) (xy 364.249729 -227.449665) (xy 364.250224 -227.474272)
			(xy 366.45902 -227.474272) (xy 366.46298 -227.425218) (xy 366.474757 -227.377434) (xy 366.494048 -227.332158)
			(xy 366.520351 -227.290562) (xy 366.552986 -227.253725) (xy 366.591107 -227.2226) (xy 366.633728 -227.197993)
			(xy 366.679744 -227.180541) (xy 366.727963 -227.170697) (xy 366.777138 -227.168716) (xy 366.825993 -227.174648)
			(xy 366.873264 -227.18834) (xy 366.917726 -227.209438) (xy 366.958229 -227.237394) (xy 366.993722 -227.271486)
			(xy 367.023287 -227.31083) (xy 367.046158 -227.354407) (xy 367.061742 -227.401088) (xy 367.069637 -227.449665)
			(xy 367.070132 -227.474272) (xy 369.278928 -227.474272) (xy 369.282888 -227.425218) (xy 369.294665 -227.377434)
			(xy 369.313956 -227.332158) (xy 369.340259 -227.290562) (xy 369.372894 -227.253725) (xy 369.411015 -227.2226)
			(xy 369.453636 -227.197993) (xy 369.499652 -227.180541) (xy 369.547871 -227.170697) (xy 369.597046 -227.168716)
			(xy 369.645901 -227.174648) (xy 369.693172 -227.18834) (xy 369.737634 -227.209438) (xy 369.778137 -227.237394)
			(xy 369.81363 -227.271486) (xy 369.843195 -227.31083) (xy 369.866066 -227.354407) (xy 369.88165 -227.401088)
			(xy 369.889545 -227.449665) (xy 369.89004 -227.474272) (xy 372.09909 -227.474272) (xy 372.10305 -227.425218)
			(xy 372.114827 -227.377434) (xy 372.134118 -227.332158) (xy 372.160421 -227.290562) (xy 372.193056 -227.253725)
			(xy 372.231177 -227.2226) (xy 372.273798 -227.197993) (xy 372.319814 -227.180541) (xy 372.368033 -227.170697)
			(xy 372.417208 -227.168716) (xy 372.466063 -227.174648) (xy 372.513334 -227.18834) (xy 372.557796 -227.209438)
			(xy 372.598299 -227.237394) (xy 372.633792 -227.271486) (xy 372.663357 -227.31083) (xy 372.686228 -227.354407)
			(xy 372.701812 -227.401088) (xy 372.709707 -227.449665) (xy 372.710202 -227.474272) (xy 372.709707 -227.498879)
			(xy 372.701812 -227.547456) (xy 372.686228 -227.594137) (xy 372.663357 -227.637714) (xy 372.633792 -227.677058)
			(xy 372.598299 -227.71115) (xy 372.557796 -227.739106) (xy 372.513334 -227.760204) (xy 372.466063 -227.773896)
			(xy 372.417208 -227.779828) (xy 372.368033 -227.777847) (xy 372.319814 -227.768003) (xy 372.273798 -227.750551)
			(xy 372.231177 -227.725944) (xy 372.193056 -227.694819) (xy 372.160421 -227.657982) (xy 372.134118 -227.616386)
			(xy 372.114827 -227.57111) (xy 372.10305 -227.523326) (xy 372.09909 -227.474272) (xy 369.89004 -227.474272)
			(xy 369.889545 -227.498879) (xy 369.88165 -227.547456) (xy 369.866066 -227.594137) (xy 369.843195 -227.637714)
			(xy 369.81363 -227.677058) (xy 369.778137 -227.71115) (xy 369.737634 -227.739106) (xy 369.693172 -227.760204)
			(xy 369.645901 -227.773896) (xy 369.597046 -227.779828) (xy 369.547871 -227.777847) (xy 369.499652 -227.768003)
			(xy 369.453636 -227.750551) (xy 369.411015 -227.725944) (xy 369.372894 -227.694819) (xy 369.340259 -227.657982)
			(xy 369.313956 -227.616386) (xy 369.294665 -227.57111) (xy 369.282888 -227.523326) (xy 369.278928 -227.474272)
			(xy 367.070132 -227.474272) (xy 367.069637 -227.498879) (xy 367.061742 -227.547456) (xy 367.046158 -227.594137)
			(xy 367.023287 -227.637714) (xy 366.993722 -227.677058) (xy 366.958229 -227.71115) (xy 366.917726 -227.739106)
			(xy 366.873264 -227.760204) (xy 366.825993 -227.773896) (xy 366.777138 -227.779828) (xy 366.727963 -227.777847)
			(xy 366.679744 -227.768003) (xy 366.633728 -227.750551) (xy 366.591107 -227.725944) (xy 366.552986 -227.694819)
			(xy 366.520351 -227.657982) (xy 366.494048 -227.616386) (xy 366.474757 -227.57111) (xy 366.46298 -227.523326)
			(xy 366.45902 -227.474272) (xy 364.250224 -227.474272) (xy 364.249729 -227.498879) (xy 364.241834 -227.547456)
			(xy 364.22625 -227.594137) (xy 364.203379 -227.637714) (xy 364.173814 -227.677058) (xy 364.138321 -227.71115)
			(xy 364.097818 -227.739106) (xy 364.053356 -227.760204) (xy 364.006085 -227.773896) (xy 363.95723 -227.779828)
			(xy 363.908055 -227.777847) (xy 363.859836 -227.768003) (xy 363.81382 -227.750551) (xy 363.771199 -227.725944)
			(xy 363.733078 -227.694819) (xy 363.700443 -227.657982) (xy 363.67414 -227.616386) (xy 363.654849 -227.57111)
			(xy 363.643072 -227.523326) (xy 363.639112 -227.474272) (xy 363.320584 -227.474272) (xy 363.320072 -227.499718)
			(xy 363.311908 -227.549952) (xy 363.295792 -227.598226) (xy 363.272141 -227.643289) (xy 363.241568 -227.683975)
			(xy 363.204864 -227.71923) (xy 363.16298 -227.74814) (xy 363.117001 -227.769957) (xy 363.068117 -227.784117)
			(xy 363.017596 -227.790251) (xy 362.966744 -227.788202) (xy 362.91688 -227.778022) (xy 362.869294 -227.759975)
			(xy 362.82522 -227.734529) (xy 362.785798 -227.702342) (xy 362.75205 -227.664248) (xy 362.724849 -227.621234)
			(xy 362.704901 -227.574414) (xy 362.692722 -227.525) (xy 362.688627 -227.474272) (xy 362.38053 -227.474272)
			(xy 362.380018 -227.499718) (xy 362.371854 -227.549952) (xy 362.355738 -227.598226) (xy 362.332087 -227.643289)
			(xy 362.301514 -227.683975) (xy 362.26481 -227.71923) (xy 362.222926 -227.74814) (xy 362.176947 -227.769957)
			(xy 362.128063 -227.784117) (xy 362.077542 -227.790251) (xy 362.02669 -227.788202) (xy 361.976826 -227.778022)
			(xy 361.92924 -227.759975) (xy 361.885166 -227.734529) (xy 361.845744 -227.702342) (xy 361.811996 -227.664248)
			(xy 361.784795 -227.621234) (xy 361.764847 -227.574414) (xy 361.752668 -227.525) (xy 361.748573 -227.474272)
			(xy 361.430686 -227.474272) (xy 361.430688 -227.4743) (xy 361.426515 -227.524652) (xy 361.414111 -227.573631)
			(xy 361.393814 -227.619899) (xy 361.366177 -227.662196) (xy 361.331954 -227.699366) (xy 361.292081 -227.730395)
			(xy 361.247643 -227.754438) (xy 361.199853 -227.770837) (xy 361.150017 -227.779147) (xy 361.124754 -227.77958)
			(xy 361.123992 -227.77958) (xy 361.09998 -227.779063) (xy 361.052558 -227.771468) (xy 361.006905 -227.75656)
			(xy 360.985308 -227.746052) (xy 360.985054 -227.746052) (xy 360.97921 -227.74331) (xy 360.966618 -227.740497)
			(xy 360.960162 -227.740464) (xy 360.9467 -227.740972) (xy 360.861864 -227.793042) (xy 360.855682 -227.79703)
			(xy 360.845753 -227.807877) (xy 360.842306 -227.814378) (xy 360.83748 -227.825046) (xy 360.83748 -228.284278)
			(xy 363.168958 -228.284278) (xy 363.172918 -228.235224) (xy 363.184695 -228.18744) (xy 363.203986 -228.142164)
			(xy 363.230289 -228.100568) (xy 363.262924 -228.063731) (xy 363.301045 -228.032606) (xy 363.343666 -228.007999)
			(xy 363.389682 -227.990547) (xy 363.437901 -227.980703) (xy 363.487076 -227.978722) (xy 363.535931 -227.984654)
			(xy 363.583202 -227.998346) (xy 363.627664 -228.019444) (xy 363.668167 -228.0474) (xy 363.70366 -228.081492)
			(xy 363.733225 -228.120836) (xy 363.756096 -228.164413) (xy 363.77168 -228.211094) (xy 363.779575 -228.259671)
			(xy 363.78007 -228.284278) (xy 364.098581 -228.284278) (xy 364.102676 -228.23355) (xy 364.114855 -228.184136)
			(xy 364.134803 -228.137316) (xy 364.162004 -228.094302) (xy 364.195752 -228.056208) (xy 364.235174 -228.024021)
			(xy 364.279248 -227.998575) (xy 364.326834 -227.980528) (xy 364.376698 -227.970348) (xy 364.42755 -227.968299)
			(xy 364.478071 -227.974433) (xy 364.526955 -227.988593) (xy 364.572934 -228.01041) (xy 364.614818 -228.03932)
			(xy 364.651522 -228.074575) (xy 364.682095 -228.115261) (xy 364.705746 -228.160324) (xy 364.721862 -228.208598)
			(xy 364.730026 -228.258832) (xy 364.730538 -228.284278) (xy 365.038635 -228.284278) (xy 365.04273 -228.23355)
			(xy 365.054909 -228.184136) (xy 365.074857 -228.137316) (xy 365.102058 -228.094302) (xy 365.135806 -228.056208)
			(xy 365.175228 -228.024021) (xy 365.219302 -227.998575) (xy 365.266888 -227.980528) (xy 365.316752 -227.970348)
			(xy 365.367604 -227.968299) (xy 365.418125 -227.974433) (xy 365.467009 -227.988593) (xy 365.512988 -228.01041)
			(xy 365.554872 -228.03932) (xy 365.591576 -228.074575) (xy 365.622149 -228.115261) (xy 365.6458 -228.160324)
			(xy 365.661916 -228.208598) (xy 365.67008 -228.258832) (xy 365.670592 -228.284278) (xy 365.98912 -228.284278)
			(xy 365.99308 -228.235224) (xy 366.004857 -228.18744) (xy 366.024148 -228.142164) (xy 366.050451 -228.100568)
			(xy 366.083086 -228.063731) (xy 366.121207 -228.032606) (xy 366.163828 -228.007999) (xy 366.209844 -227.990547)
			(xy 366.258063 -227.980703) (xy 366.307238 -227.978722) (xy 366.356093 -227.984654) (xy 366.403364 -227.998346)
			(xy 366.447826 -228.019444) (xy 366.488329 -228.0474) (xy 366.523822 -228.081492) (xy 366.553387 -228.120836)
			(xy 366.576258 -228.164413) (xy 366.591842 -228.211094) (xy 366.599737 -228.259671) (xy 366.600232 -228.284278)
			(xy 366.918489 -228.284278) (xy 366.922584 -228.23355) (xy 366.934763 -228.184136) (xy 366.954711 -228.137316)
			(xy 366.981912 -228.094302) (xy 367.01566 -228.056208) (xy 367.055082 -228.024021) (xy 367.099156 -227.998575)
			(xy 367.146742 -227.980528) (xy 367.196606 -227.970348) (xy 367.247458 -227.968299) (xy 367.297979 -227.974433)
			(xy 367.346863 -227.988593) (xy 367.392842 -228.01041) (xy 367.434726 -228.03932) (xy 367.47143 -228.074575)
			(xy 367.502003 -228.115261) (xy 367.525654 -228.160324) (xy 367.54177 -228.208598) (xy 367.549934 -228.258832)
			(xy 367.550446 -228.284278) (xy 367.858543 -228.284278) (xy 367.862638 -228.23355) (xy 367.874817 -228.184136)
			(xy 367.894765 -228.137316) (xy 367.921966 -228.094302) (xy 367.955714 -228.056208) (xy 367.995136 -228.024021)
			(xy 368.03921 -227.998575) (xy 368.086796 -227.980528) (xy 368.13666 -227.970348) (xy 368.187512 -227.968299)
			(xy 368.238033 -227.974433) (xy 368.286917 -227.988593) (xy 368.332896 -228.01041) (xy 368.37478 -228.03932)
			(xy 368.411484 -228.074575) (xy 368.442057 -228.115261) (xy 368.465708 -228.160324) (xy 368.481824 -228.208598)
			(xy 368.489988 -228.258832) (xy 368.4905 -228.284278) (xy 368.809028 -228.284278) (xy 368.812988 -228.235224)
			(xy 368.824765 -228.18744) (xy 368.844056 -228.142164) (xy 368.870359 -228.100568) (xy 368.902994 -228.063731)
			(xy 368.941115 -228.032606) (xy 368.983736 -228.007999) (xy 369.029752 -227.990547) (xy 369.077971 -227.980703)
			(xy 369.127146 -227.978722) (xy 369.176001 -227.984654) (xy 369.223272 -227.998346) (xy 369.267734 -228.019444)
			(xy 369.308237 -228.0474) (xy 369.34373 -228.081492) (xy 369.373295 -228.120836) (xy 369.396166 -228.164413)
			(xy 369.41175 -228.211094) (xy 369.419645 -228.259671) (xy 369.42014 -228.284278) (xy 369.738651 -228.284278)
			(xy 369.742746 -228.23355) (xy 369.754925 -228.184136) (xy 369.774873 -228.137316) (xy 369.802074 -228.094302)
			(xy 369.835822 -228.056208) (xy 369.875244 -228.024021) (xy 369.919318 -227.998575) (xy 369.966904 -227.980528)
			(xy 370.016768 -227.970348) (xy 370.06762 -227.968299) (xy 370.118141 -227.974433) (xy 370.167025 -227.988593)
			(xy 370.213004 -228.01041) (xy 370.254888 -228.03932) (xy 370.291592 -228.074575) (xy 370.322165 -228.115261)
			(xy 370.345816 -228.160324) (xy 370.361932 -228.208598) (xy 370.370096 -228.258832) (xy 370.370608 -228.284278)
			(xy 370.678451 -228.284278) (xy 370.682546 -228.23355) (xy 370.694725 -228.184136) (xy 370.714673 -228.137316)
			(xy 370.741874 -228.094302) (xy 370.775622 -228.056208) (xy 370.815044 -228.024021) (xy 370.859118 -227.998575)
			(xy 370.906704 -227.980528) (xy 370.956568 -227.970348) (xy 371.00742 -227.968299) (xy 371.057941 -227.974433)
			(xy 371.106825 -227.988593) (xy 371.152804 -228.01041) (xy 371.194688 -228.03932) (xy 371.231392 -228.074575)
			(xy 371.261965 -228.115261) (xy 371.285616 -228.160324) (xy 371.301732 -228.208598) (xy 371.309896 -228.258832)
			(xy 371.310408 -228.284278) (xy 371.628936 -228.284278) (xy 371.632896 -228.235224) (xy 371.644673 -228.18744)
			(xy 371.663964 -228.142164) (xy 371.690267 -228.100568) (xy 371.722902 -228.063731) (xy 371.761023 -228.032606)
			(xy 371.803644 -228.007999) (xy 371.84966 -227.990547) (xy 371.897879 -227.980703) (xy 371.947054 -227.978722)
			(xy 371.995909 -227.984654) (xy 372.04318 -227.998346) (xy 372.087642 -228.019444) (xy 372.128145 -228.0474)
			(xy 372.163638 -228.081492) (xy 372.193203 -228.120836) (xy 372.216074 -228.164413) (xy 372.231658 -228.211094)
			(xy 372.239553 -228.259671) (xy 372.240048 -228.284278) (xy 372.558559 -228.284278) (xy 372.562654 -228.23355)
			(xy 372.574833 -228.184136) (xy 372.594781 -228.137316) (xy 372.621982 -228.094302) (xy 372.65573 -228.056208)
			(xy 372.695152 -228.024021) (xy 372.739226 -227.998575) (xy 372.786812 -227.980528) (xy 372.836676 -227.970348)
			(xy 372.887528 -227.968299) (xy 372.938049 -227.974433) (xy 372.986933 -227.988593) (xy 373.032912 -228.01041)
			(xy 373.074796 -228.03932) (xy 373.1115 -228.074575) (xy 373.142073 -228.115261) (xy 373.165724 -228.160324)
			(xy 373.18184 -228.208598) (xy 373.190004 -228.258832) (xy 373.190516 -228.284278) (xy 373.498613 -228.284278)
			(xy 373.502708 -228.23355) (xy 373.514887 -228.184136) (xy 373.534835 -228.137316) (xy 373.562036 -228.094302)
			(xy 373.595784 -228.056208) (xy 373.635206 -228.024021) (xy 373.67928 -227.998575) (xy 373.726866 -227.980528)
			(xy 373.77673 -227.970348) (xy 373.827582 -227.968299) (xy 373.878103 -227.974433) (xy 373.926987 -227.988593)
			(xy 373.972966 -228.01041) (xy 374.01485 -228.03932) (xy 374.051554 -228.074575) (xy 374.082127 -228.115261)
			(xy 374.105778 -228.160324) (xy 374.121894 -228.208598) (xy 374.130058 -228.258832) (xy 374.13057 -228.284278)
			(xy 374.130058 -228.309724) (xy 374.121894 -228.359958) (xy 374.105778 -228.408232) (xy 374.082127 -228.453295)
			(xy 374.051554 -228.493981) (xy 374.01485 -228.529236) (xy 373.972966 -228.558146) (xy 373.926987 -228.579963)
			(xy 373.878103 -228.594123) (xy 373.827582 -228.600257) (xy 373.77673 -228.598208) (xy 373.726866 -228.588028)
			(xy 373.67928 -228.569981) (xy 373.635206 -228.544535) (xy 373.595784 -228.512348) (xy 373.562036 -228.474254)
			(xy 373.534835 -228.43124) (xy 373.514887 -228.38442) (xy 373.502708 -228.335006) (xy 373.498613 -228.284278)
			(xy 373.190516 -228.284278) (xy 373.190004 -228.309724) (xy 373.18184 -228.359958) (xy 373.165724 -228.408232)
			(xy 373.142073 -228.453295) (xy 373.1115 -228.493981) (xy 373.074796 -228.529236) (xy 373.032912 -228.558146)
			(xy 372.986933 -228.579963) (xy 372.938049 -228.594123) (xy 372.887528 -228.600257) (xy 372.836676 -228.598208)
			(xy 372.786812 -228.588028) (xy 372.739226 -228.569981) (xy 372.695152 -228.544535) (xy 372.65573 -228.512348)
			(xy 372.621982 -228.474254) (xy 372.594781 -228.43124) (xy 372.574833 -228.38442) (xy 372.562654 -228.335006)
			(xy 372.558559 -228.284278) (xy 372.240048 -228.284278) (xy 372.239553 -228.308885) (xy 372.231658 -228.357462)
			(xy 372.216074 -228.404143) (xy 372.193203 -228.44772) (xy 372.163638 -228.487064) (xy 372.128145 -228.521156)
			(xy 372.087642 -228.549112) (xy 372.04318 -228.57021) (xy 371.995909 -228.583902) (xy 371.947054 -228.589834)
			(xy 371.897879 -228.587853) (xy 371.84966 -228.578009) (xy 371.803644 -228.560557) (xy 371.761023 -228.53595)
			(xy 371.722902 -228.504825) (xy 371.690267 -228.467988) (xy 371.663964 -228.426392) (xy 371.644673 -228.381116)
			(xy 371.632896 -228.333332) (xy 371.628936 -228.284278) (xy 371.310408 -228.284278) (xy 371.309896 -228.309724)
			(xy 371.301732 -228.359958) (xy 371.285616 -228.408232) (xy 371.261965 -228.453295) (xy 371.231392 -228.493981)
			(xy 371.194688 -228.529236) (xy 371.152804 -228.558146) (xy 371.106825 -228.579963) (xy 371.057941 -228.594123)
			(xy 371.00742 -228.600257) (xy 370.956568 -228.598208) (xy 370.906704 -228.588028) (xy 370.859118 -228.569981)
			(xy 370.815044 -228.544535) (xy 370.775622 -228.512348) (xy 370.741874 -228.474254) (xy 370.714673 -228.43124)
			(xy 370.694725 -228.38442) (xy 370.682546 -228.335006) (xy 370.678451 -228.284278) (xy 370.370608 -228.284278)
			(xy 370.370096 -228.309724) (xy 370.361932 -228.359958) (xy 370.345816 -228.408232) (xy 370.322165 -228.453295)
			(xy 370.291592 -228.493981) (xy 370.254888 -228.529236) (xy 370.213004 -228.558146) (xy 370.167025 -228.579963)
			(xy 370.118141 -228.594123) (xy 370.06762 -228.600257) (xy 370.016768 -228.598208) (xy 369.966904 -228.588028)
			(xy 369.919318 -228.569981) (xy 369.875244 -228.544535) (xy 369.835822 -228.512348) (xy 369.802074 -228.474254)
			(xy 369.774873 -228.43124) (xy 369.754925 -228.38442) (xy 369.742746 -228.335006) (xy 369.738651 -228.284278)
			(xy 369.42014 -228.284278) (xy 369.419645 -228.308885) (xy 369.41175 -228.357462) (xy 369.396166 -228.404143)
			(xy 369.373295 -228.44772) (xy 369.34373 -228.487064) (xy 369.308237 -228.521156) (xy 369.267734 -228.549112)
			(xy 369.223272 -228.57021) (xy 369.176001 -228.583902) (xy 369.127146 -228.589834) (xy 369.077971 -228.587853)
			(xy 369.029752 -228.578009) (xy 368.983736 -228.560557) (xy 368.941115 -228.53595) (xy 368.902994 -228.504825)
			(xy 368.870359 -228.467988) (xy 368.844056 -228.426392) (xy 368.824765 -228.381116) (xy 368.812988 -228.333332)
			(xy 368.809028 -228.284278) (xy 368.4905 -228.284278) (xy 368.489988 -228.309724) (xy 368.481824 -228.359958)
			(xy 368.465708 -228.408232) (xy 368.442057 -228.453295) (xy 368.411484 -228.493981) (xy 368.37478 -228.529236)
			(xy 368.332896 -228.558146) (xy 368.286917 -228.579963) (xy 368.238033 -228.594123) (xy 368.187512 -228.600257)
			(xy 368.13666 -228.598208) (xy 368.086796 -228.588028) (xy 368.03921 -228.569981) (xy 367.995136 -228.544535)
			(xy 367.955714 -228.512348) (xy 367.921966 -228.474254) (xy 367.894765 -228.43124) (xy 367.874817 -228.38442)
			(xy 367.862638 -228.335006) (xy 367.858543 -228.284278) (xy 367.550446 -228.284278) (xy 367.549934 -228.309724)
			(xy 367.54177 -228.359958) (xy 367.525654 -228.408232) (xy 367.502003 -228.453295) (xy 367.47143 -228.493981)
			(xy 367.434726 -228.529236) (xy 367.392842 -228.558146) (xy 367.346863 -228.579963) (xy 367.297979 -228.594123)
			(xy 367.247458 -228.600257) (xy 367.196606 -228.598208) (xy 367.146742 -228.588028) (xy 367.099156 -228.569981)
			(xy 367.055082 -228.544535) (xy 367.01566 -228.512348) (xy 366.981912 -228.474254) (xy 366.954711 -228.43124)
			(xy 366.934763 -228.38442) (xy 366.922584 -228.335006) (xy 366.918489 -228.284278) (xy 366.600232 -228.284278)
			(xy 366.599737 -228.308885) (xy 366.591842 -228.357462) (xy 366.576258 -228.404143) (xy 366.553387 -228.44772)
			(xy 366.523822 -228.487064) (xy 366.488329 -228.521156) (xy 366.447826 -228.549112) (xy 366.403364 -228.57021)
			(xy 366.356093 -228.583902) (xy 366.307238 -228.589834) (xy 366.258063 -228.587853) (xy 366.209844 -228.578009)
			(xy 366.163828 -228.560557) (xy 366.121207 -228.53595) (xy 366.083086 -228.504825) (xy 366.050451 -228.467988)
			(xy 366.024148 -228.426392) (xy 366.004857 -228.381116) (xy 365.99308 -228.333332) (xy 365.98912 -228.284278)
			(xy 365.670592 -228.284278) (xy 365.67008 -228.309724) (xy 365.661916 -228.359958) (xy 365.6458 -228.408232)
			(xy 365.622149 -228.453295) (xy 365.591576 -228.493981) (xy 365.554872 -228.529236) (xy 365.512988 -228.558146)
			(xy 365.467009 -228.579963) (xy 365.418125 -228.594123) (xy 365.367604 -228.600257) (xy 365.316752 -228.598208)
			(xy 365.266888 -228.588028) (xy 365.219302 -228.569981) (xy 365.175228 -228.544535) (xy 365.135806 -228.512348)
			(xy 365.102058 -228.474254) (xy 365.074857 -228.43124) (xy 365.054909 -228.38442) (xy 365.04273 -228.335006)
			(xy 365.038635 -228.284278) (xy 364.730538 -228.284278) (xy 364.730026 -228.309724) (xy 364.721862 -228.359958)
			(xy 364.705746 -228.408232) (xy 364.682095 -228.453295) (xy 364.651522 -228.493981) (xy 364.614818 -228.529236)
			(xy 364.572934 -228.558146) (xy 364.526955 -228.579963) (xy 364.478071 -228.594123) (xy 364.42755 -228.600257)
			(xy 364.376698 -228.598208) (xy 364.326834 -228.588028) (xy 364.279248 -228.569981) (xy 364.235174 -228.544535)
			(xy 364.195752 -228.512348) (xy 364.162004 -228.474254) (xy 364.134803 -228.43124) (xy 364.114855 -228.38442)
			(xy 364.102676 -228.335006) (xy 364.098581 -228.284278) (xy 363.78007 -228.284278) (xy 363.779575 -228.308885)
			(xy 363.77168 -228.357462) (xy 363.756096 -228.404143) (xy 363.733225 -228.44772) (xy 363.70366 -228.487064)
			(xy 363.668167 -228.521156) (xy 363.627664 -228.549112) (xy 363.583202 -228.57021) (xy 363.535931 -228.583902)
			(xy 363.487076 -228.589834) (xy 363.437901 -228.587853) (xy 363.389682 -228.578009) (xy 363.343666 -228.560557)
			(xy 363.301045 -228.53595) (xy 363.262924 -228.504825) (xy 363.230289 -228.467988) (xy 363.203986 -228.426392)
			(xy 363.184695 -228.381116) (xy 363.172918 -228.333332) (xy 363.168958 -228.284278) (xy 360.83748 -228.284278)
			(xy 360.83748 -228.726492) (xy 360.83875 -228.737668) (xy 360.841036 -228.74859) (xy 360.844846 -228.759258)
			(xy 360.84891 -228.76764) (xy 360.93527 -228.820726) (xy 360.940932 -228.823948) (xy 360.953406 -228.827691)
			(xy 360.959908 -228.828092) (xy 360.97337 -228.8286) (xy 360.985308 -228.822504) (xy 361.006888 -228.811955)
			(xy 361.052544 -228.797034) (xy 361.099976 -228.789463) (xy 361.123992 -228.788976) (xy 361.124754 -228.788976)
			(xy 361.150016 -228.789465) (xy 361.199851 -228.797774) (xy 361.247638 -228.814173) (xy 361.292074 -228.838215)
			(xy 361.331946 -228.869243) (xy 361.366167 -228.906412) (xy 361.393803 -228.948706) (xy 361.4141 -228.994973)
			(xy 361.426503 -229.04395) (xy 361.430675 -229.094284) (xy 361.748573 -229.094284) (xy 361.752668 -229.043556)
			(xy 361.764847 -228.994142) (xy 361.784795 -228.947322) (xy 361.811996 -228.904308) (xy 361.845744 -228.866214)
			(xy 361.885166 -228.834027) (xy 361.92924 -228.808581) (xy 361.976826 -228.790534) (xy 362.02669 -228.780354)
			(xy 362.077542 -228.778305) (xy 362.128063 -228.784439) (xy 362.176947 -228.798599) (xy 362.222926 -228.820416)
			(xy 362.26481 -228.849326) (xy 362.301514 -228.884581) (xy 362.332087 -228.925267) (xy 362.355738 -228.97033)
			(xy 362.371854 -229.018604) (xy 362.380018 -229.068838) (xy 362.38053 -229.094284) (xy 362.688627 -229.094284)
			(xy 362.692722 -229.043556) (xy 362.704901 -228.994142) (xy 362.724849 -228.947322) (xy 362.75205 -228.904308)
			(xy 362.785798 -228.866214) (xy 362.82522 -228.834027) (xy 362.869294 -228.808581) (xy 362.91688 -228.790534)
			(xy 362.966744 -228.780354) (xy 363.017596 -228.778305) (xy 363.068117 -228.784439) (xy 363.117001 -228.798599)
			(xy 363.16298 -228.820416) (xy 363.204864 -228.849326) (xy 363.241568 -228.884581) (xy 363.272141 -228.925267)
			(xy 363.295792 -228.97033) (xy 363.311908 -229.018604) (xy 363.320072 -229.068838) (xy 363.320584 -229.094284)
			(xy 363.639112 -229.094284) (xy 363.643072 -229.04523) (xy 363.654849 -228.997446) (xy 363.67414 -228.95217)
			(xy 363.700443 -228.910574) (xy 363.733078 -228.873737) (xy 363.771199 -228.842612) (xy 363.81382 -228.818005)
			(xy 363.859836 -228.800553) (xy 363.908055 -228.790709) (xy 363.95723 -228.788728) (xy 364.006085 -228.79466)
			(xy 364.053356 -228.808352) (xy 364.097818 -228.82945) (xy 364.138321 -228.857406) (xy 364.173814 -228.891498)
			(xy 364.203379 -228.930842) (xy 364.22625 -228.974419) (xy 364.241834 -229.0211) (xy 364.249729 -229.069677)
			(xy 364.250224 -229.094284) (xy 364.578912 -229.094284) (xy 364.582872 -229.04523) (xy 364.594649 -228.997446)
			(xy 364.61394 -228.95217) (xy 364.640243 -228.910574) (xy 364.672878 -228.873737) (xy 364.710999 -228.842612)
			(xy 364.75362 -228.818005) (xy 364.799636 -228.800553) (xy 364.847855 -228.790709) (xy 364.89703 -228.788728)
			(xy 364.945885 -228.79466) (xy 364.993156 -228.808352) (xy 365.037618 -228.82945) (xy 365.078121 -228.857406)
			(xy 365.113614 -228.891498) (xy 365.143179 -228.930842) (xy 365.16605 -228.974419) (xy 365.181634 -229.0211)
			(xy 365.189529 -229.069677) (xy 365.190024 -229.094284) (xy 365.518966 -229.094284) (xy 365.522926 -229.04523)
			(xy 365.534703 -228.997446) (xy 365.553994 -228.95217) (xy 365.580297 -228.910574) (xy 365.612932 -228.873737)
			(xy 365.651053 -228.842612) (xy 365.693674 -228.818005) (xy 365.73969 -228.800553) (xy 365.787909 -228.790709)
			(xy 365.837084 -228.788728) (xy 365.885939 -228.79466) (xy 365.93321 -228.808352) (xy 365.977672 -228.82945)
			(xy 366.018175 -228.857406) (xy 366.053668 -228.891498) (xy 366.083233 -228.930842) (xy 366.106104 -228.974419)
			(xy 366.121688 -229.0211) (xy 366.129583 -229.069677) (xy 366.130078 -229.094284) (xy 366.45902 -229.094284)
			(xy 366.46298 -229.04523) (xy 366.474757 -228.997446) (xy 366.494048 -228.95217) (xy 366.520351 -228.910574)
			(xy 366.552986 -228.873737) (xy 366.591107 -228.842612) (xy 366.633728 -228.818005) (xy 366.679744 -228.800553)
			(xy 366.727963 -228.790709) (xy 366.777138 -228.788728) (xy 366.825993 -228.79466) (xy 366.873264 -228.808352)
			(xy 366.917726 -228.82945) (xy 366.958229 -228.857406) (xy 366.993722 -228.891498) (xy 367.023287 -228.930842)
			(xy 367.046158 -228.974419) (xy 367.061742 -229.0211) (xy 367.069637 -229.069677) (xy 367.070132 -229.094284)
			(xy 367.399074 -229.094284) (xy 367.403034 -229.04523) (xy 367.414811 -228.997446) (xy 367.434102 -228.95217)
			(xy 367.460405 -228.910574) (xy 367.49304 -228.873737) (xy 367.531161 -228.842612) (xy 367.573782 -228.818005)
			(xy 367.619798 -228.800553) (xy 367.668017 -228.790709) (xy 367.717192 -228.788728) (xy 367.766047 -228.79466)
			(xy 367.813318 -228.808352) (xy 367.85778 -228.82945) (xy 367.898283 -228.857406) (xy 367.933776 -228.891498)
			(xy 367.963341 -228.930842) (xy 367.986212 -228.974419) (xy 368.001796 -229.0211) (xy 368.009691 -229.069677)
			(xy 368.010186 -229.094284) (xy 368.339128 -229.094284) (xy 368.343088 -229.04523) (xy 368.354865 -228.997446)
			(xy 368.374156 -228.95217) (xy 368.400459 -228.910574) (xy 368.433094 -228.873737) (xy 368.471215 -228.842612)
			(xy 368.513836 -228.818005) (xy 368.559852 -228.800553) (xy 368.608071 -228.790709) (xy 368.657246 -228.788728)
			(xy 368.706101 -228.79466) (xy 368.753372 -228.808352) (xy 368.797834 -228.82945) (xy 368.838337 -228.857406)
			(xy 368.87383 -228.891498) (xy 368.903395 -228.930842) (xy 368.926266 -228.974419) (xy 368.94185 -229.0211)
			(xy 368.949745 -229.069677) (xy 368.95024 -229.094284) (xy 369.278928 -229.094284) (xy 369.282888 -229.04523)
			(xy 369.294665 -228.997446) (xy 369.313956 -228.95217) (xy 369.340259 -228.910574) (xy 369.372894 -228.873737)
			(xy 369.411015 -228.842612) (xy 369.453636 -228.818005) (xy 369.499652 -228.800553) (xy 369.547871 -228.790709)
			(xy 369.597046 -228.788728) (xy 369.645901 -228.79466) (xy 369.693172 -228.808352) (xy 369.737634 -228.82945)
			(xy 369.778137 -228.857406) (xy 369.81363 -228.891498) (xy 369.843195 -228.930842) (xy 369.866066 -228.974419)
			(xy 369.88165 -229.0211) (xy 369.889545 -229.069677) (xy 369.89004 -229.094284) (xy 370.218982 -229.094284)
			(xy 370.222942 -229.04523) (xy 370.234719 -228.997446) (xy 370.25401 -228.95217) (xy 370.280313 -228.910574)
			(xy 370.312948 -228.873737) (xy 370.351069 -228.842612) (xy 370.39369 -228.818005) (xy 370.439706 -228.800553)
			(xy 370.487925 -228.790709) (xy 370.5371 -228.788728) (xy 370.585955 -228.79466) (xy 370.633226 -228.808352)
			(xy 370.677688 -228.82945) (xy 370.718191 -228.857406) (xy 370.753684 -228.891498) (xy 370.783249 -228.930842)
			(xy 370.80612 -228.974419) (xy 370.821704 -229.0211) (xy 370.829599 -229.069677) (xy 370.830094 -229.094284)
			(xy 371.159036 -229.094284) (xy 371.162996 -229.04523) (xy 371.174773 -228.997446) (xy 371.194064 -228.95217)
			(xy 371.220367 -228.910574) (xy 371.253002 -228.873737) (xy 371.291123 -228.842612) (xy 371.333744 -228.818005)
			(xy 371.37976 -228.800553) (xy 371.427979 -228.790709) (xy 371.477154 -228.788728) (xy 371.526009 -228.79466)
			(xy 371.57328 -228.808352) (xy 371.617742 -228.82945) (xy 371.658245 -228.857406) (xy 371.693738 -228.891498)
			(xy 371.723303 -228.930842) (xy 371.746174 -228.974419) (xy 371.761758 -229.0211) (xy 371.769653 -229.069677)
			(xy 371.770148 -229.094284) (xy 372.09909 -229.094284) (xy 372.10305 -229.04523) (xy 372.114827 -228.997446)
			(xy 372.134118 -228.95217) (xy 372.160421 -228.910574) (xy 372.193056 -228.873737) (xy 372.231177 -228.842612)
			(xy 372.273798 -228.818005) (xy 372.319814 -228.800553) (xy 372.368033 -228.790709) (xy 372.417208 -228.788728)
			(xy 372.466063 -228.79466) (xy 372.513334 -228.808352) (xy 372.557796 -228.82945) (xy 372.598299 -228.857406)
			(xy 372.633792 -228.891498) (xy 372.663357 -228.930842) (xy 372.686228 -228.974419) (xy 372.701812 -229.0211)
			(xy 372.709707 -229.069677) (xy 372.710202 -229.094284) (xy 373.03889 -229.094284) (xy 373.04285 -229.04523)
			(xy 373.054627 -228.997446) (xy 373.073918 -228.95217) (xy 373.100221 -228.910574) (xy 373.132856 -228.873737)
			(xy 373.170977 -228.842612) (xy 373.213598 -228.818005) (xy 373.259614 -228.800553) (xy 373.307833 -228.790709)
			(xy 373.357008 -228.788728) (xy 373.405863 -228.79466) (xy 373.453134 -228.808352) (xy 373.497596 -228.82945)
			(xy 373.538099 -228.857406) (xy 373.573592 -228.891498) (xy 373.603157 -228.930842) (xy 373.626028 -228.974419)
			(xy 373.641612 -229.0211) (xy 373.649507 -229.069677) (xy 373.650002 -229.094284) (xy 373.649507 -229.118891)
			(xy 373.641612 -229.167468) (xy 373.626028 -229.214149) (xy 373.603157 -229.257726) (xy 373.573592 -229.29707)
			(xy 373.538099 -229.331162) (xy 373.497596 -229.359118) (xy 373.453134 -229.380216) (xy 373.405863 -229.393908)
			(xy 373.357008 -229.39984) (xy 373.307833 -229.397859) (xy 373.259614 -229.388015) (xy 373.213598 -229.370563)
			(xy 373.170977 -229.345956) (xy 373.132856 -229.314831) (xy 373.100221 -229.277994) (xy 373.073918 -229.236398)
			(xy 373.054627 -229.191122) (xy 373.04285 -229.143338) (xy 373.03889 -229.094284) (xy 372.710202 -229.094284)
			(xy 372.709707 -229.118891) (xy 372.701812 -229.167468) (xy 372.686228 -229.214149) (xy 372.663357 -229.257726)
			(xy 372.633792 -229.29707) (xy 372.598299 -229.331162) (xy 372.557796 -229.359118) (xy 372.513334 -229.380216)
			(xy 372.466063 -229.393908) (xy 372.417208 -229.39984) (xy 372.368033 -229.397859) (xy 372.319814 -229.388015)
			(xy 372.273798 -229.370563) (xy 372.231177 -229.345956) (xy 372.193056 -229.314831) (xy 372.160421 -229.277994)
			(xy 372.134118 -229.236398) (xy 372.114827 -229.191122) (xy 372.10305 -229.143338) (xy 372.09909 -229.094284)
			(xy 371.770148 -229.094284) (xy 371.769653 -229.118891) (xy 371.761758 -229.167468) (xy 371.746174 -229.214149)
			(xy 371.723303 -229.257726) (xy 371.693738 -229.29707) (xy 371.658245 -229.331162) (xy 371.617742 -229.359118)
			(xy 371.57328 -229.380216) (xy 371.526009 -229.393908) (xy 371.477154 -229.39984) (xy 371.427979 -229.397859)
			(xy 371.37976 -229.388015) (xy 371.333744 -229.370563) (xy 371.291123 -229.345956) (xy 371.253002 -229.314831)
			(xy 371.220367 -229.277994) (xy 371.194064 -229.236398) (xy 371.174773 -229.191122) (xy 371.162996 -229.143338)
			(xy 371.159036 -229.094284) (xy 370.830094 -229.094284) (xy 370.829599 -229.118891) (xy 370.821704 -229.167468)
			(xy 370.80612 -229.214149) (xy 370.783249 -229.257726) (xy 370.753684 -229.29707) (xy 370.718191 -229.331162)
			(xy 370.677688 -229.359118) (xy 370.633226 -229.380216) (xy 370.585955 -229.393908) (xy 370.5371 -229.39984)
			(xy 370.487925 -229.397859) (xy 370.439706 -229.388015) (xy 370.39369 -229.370563) (xy 370.351069 -229.345956)
			(xy 370.312948 -229.314831) (xy 370.280313 -229.277994) (xy 370.25401 -229.236398) (xy 370.234719 -229.191122)
			(xy 370.222942 -229.143338) (xy 370.218982 -229.094284) (xy 369.89004 -229.094284) (xy 369.889545 -229.118891)
			(xy 369.88165 -229.167468) (xy 369.866066 -229.214149) (xy 369.843195 -229.257726) (xy 369.81363 -229.29707)
			(xy 369.778137 -229.331162) (xy 369.737634 -229.359118) (xy 369.693172 -229.380216) (xy 369.645901 -229.393908)
			(xy 369.597046 -229.39984) (xy 369.547871 -229.397859) (xy 369.499652 -229.388015) (xy 369.453636 -229.370563)
			(xy 369.411015 -229.345956) (xy 369.372894 -229.314831) (xy 369.340259 -229.277994) (xy 369.313956 -229.236398)
			(xy 369.294665 -229.191122) (xy 369.282888 -229.143338) (xy 369.278928 -229.094284) (xy 368.95024 -229.094284)
			(xy 368.949745 -229.118891) (xy 368.94185 -229.167468) (xy 368.926266 -229.214149) (xy 368.903395 -229.257726)
			(xy 368.87383 -229.29707) (xy 368.838337 -229.331162) (xy 368.797834 -229.359118) (xy 368.753372 -229.380216)
			(xy 368.706101 -229.393908) (xy 368.657246 -229.39984) (xy 368.608071 -229.397859) (xy 368.559852 -229.388015)
			(xy 368.513836 -229.370563) (xy 368.471215 -229.345956) (xy 368.433094 -229.314831) (xy 368.400459 -229.277994)
			(xy 368.374156 -229.236398) (xy 368.354865 -229.191122) (xy 368.343088 -229.143338) (xy 368.339128 -229.094284)
			(xy 368.010186 -229.094284) (xy 368.009691 -229.118891) (xy 368.001796 -229.167468) (xy 367.986212 -229.214149)
			(xy 367.963341 -229.257726) (xy 367.933776 -229.29707) (xy 367.898283 -229.331162) (xy 367.85778 -229.359118)
			(xy 367.813318 -229.380216) (xy 367.766047 -229.393908) (xy 367.717192 -229.39984) (xy 367.668017 -229.397859)
			(xy 367.619798 -229.388015) (xy 367.573782 -229.370563) (xy 367.531161 -229.345956) (xy 367.49304 -229.314831)
			(xy 367.460405 -229.277994) (xy 367.434102 -229.236398) (xy 367.414811 -229.191122) (xy 367.403034 -229.143338)
			(xy 367.399074 -229.094284) (xy 367.070132 -229.094284) (xy 367.069637 -229.118891) (xy 367.061742 -229.167468)
			(xy 367.046158 -229.214149) (xy 367.023287 -229.257726) (xy 366.993722 -229.29707) (xy 366.958229 -229.331162)
			(xy 366.917726 -229.359118) (xy 366.873264 -229.380216) (xy 366.825993 -229.393908) (xy 366.777138 -229.39984)
			(xy 366.727963 -229.397859) (xy 366.679744 -229.388015) (xy 366.633728 -229.370563) (xy 366.591107 -229.345956)
			(xy 366.552986 -229.314831) (xy 366.520351 -229.277994) (xy 366.494048 -229.236398) (xy 366.474757 -229.191122)
			(xy 366.46298 -229.143338) (xy 366.45902 -229.094284) (xy 366.130078 -229.094284) (xy 366.129583 -229.118891)
			(xy 366.121688 -229.167468) (xy 366.106104 -229.214149) (xy 366.083233 -229.257726) (xy 366.053668 -229.29707)
			(xy 366.018175 -229.331162) (xy 365.977672 -229.359118) (xy 365.93321 -229.380216) (xy 365.885939 -229.393908)
			(xy 365.837084 -229.39984) (xy 365.787909 -229.397859) (xy 365.73969 -229.388015) (xy 365.693674 -229.370563)
			(xy 365.651053 -229.345956) (xy 365.612932 -229.314831) (xy 365.580297 -229.277994) (xy 365.553994 -229.236398)
			(xy 365.534703 -229.191122) (xy 365.522926 -229.143338) (xy 365.518966 -229.094284) (xy 365.190024 -229.094284)
			(xy 365.189529 -229.118891) (xy 365.181634 -229.167468) (xy 365.16605 -229.214149) (xy 365.143179 -229.257726)
			(xy 365.113614 -229.29707) (xy 365.078121 -229.331162) (xy 365.037618 -229.359118) (xy 364.993156 -229.380216)
			(xy 364.945885 -229.393908) (xy 364.89703 -229.39984) (xy 364.847855 -229.397859) (xy 364.799636 -229.388015)
			(xy 364.75362 -229.370563) (xy 364.710999 -229.345956) (xy 364.672878 -229.314831) (xy 364.640243 -229.277994)
			(xy 364.61394 -229.236398) (xy 364.594649 -229.191122) (xy 364.582872 -229.143338) (xy 364.578912 -229.094284)
			(xy 364.250224 -229.094284) (xy 364.249729 -229.118891) (xy 364.241834 -229.167468) (xy 364.22625 -229.214149)
			(xy 364.203379 -229.257726) (xy 364.173814 -229.29707) (xy 364.138321 -229.331162) (xy 364.097818 -229.359118)
			(xy 364.053356 -229.380216) (xy 364.006085 -229.393908) (xy 363.95723 -229.39984) (xy 363.908055 -229.397859)
			(xy 363.859836 -229.388015) (xy 363.81382 -229.370563) (xy 363.771199 -229.345956) (xy 363.733078 -229.314831)
			(xy 363.700443 -229.277994) (xy 363.67414 -229.236398) (xy 363.654849 -229.191122) (xy 363.643072 -229.143338)
			(xy 363.639112 -229.094284) (xy 363.320584 -229.094284) (xy 363.320072 -229.11973) (xy 363.311908 -229.169964)
			(xy 363.295792 -229.218238) (xy 363.272141 -229.263301) (xy 363.241568 -229.303987) (xy 363.204864 -229.339242)
			(xy 363.16298 -229.368152) (xy 363.117001 -229.389969) (xy 363.068117 -229.404129) (xy 363.017596 -229.410263)
			(xy 362.966744 -229.408214) (xy 362.91688 -229.398034) (xy 362.869294 -229.379987) (xy 362.82522 -229.354541)
			(xy 362.785798 -229.322354) (xy 362.75205 -229.28426) (xy 362.724849 -229.241246) (xy 362.704901 -229.194426)
			(xy 362.692722 -229.145012) (xy 362.688627 -229.094284) (xy 362.38053 -229.094284) (xy 362.380018 -229.11973)
			(xy 362.371854 -229.169964) (xy 362.355738 -229.218238) (xy 362.332087 -229.263301) (xy 362.301514 -229.303987)
			(xy 362.26481 -229.339242) (xy 362.222926 -229.368152) (xy 362.176947 -229.389969) (xy 362.128063 -229.404129)
			(xy 362.077542 -229.410263) (xy 362.02669 -229.408214) (xy 361.976826 -229.398034) (xy 361.92924 -229.379987)
			(xy 361.885166 -229.354541) (xy 361.845744 -229.322354) (xy 361.811996 -229.28426) (xy 361.784795 -229.241246)
			(xy 361.764847 -229.194426) (xy 361.752668 -229.145012) (xy 361.748573 -229.094284) (xy 361.430675 -229.094284)
			(xy 361.430676 -229.0943) (xy 361.426503 -229.14465) (xy 361.4141 -229.193627) (xy 361.393803 -229.239894)
			(xy 361.366167 -229.282188) (xy 361.331946 -229.319357) (xy 361.292074 -229.350385) (xy 361.247638 -229.374427)
			(xy 361.19985 -229.390826) (xy 361.150016 -229.399135) (xy 361.124754 -229.399592) (xy 361.123992 -229.399592)
			(xy 361.09998 -229.399075) (xy 361.052558 -229.391481) (xy 361.006905 -229.376573) (xy 360.985308 -229.366064)
			(xy 360.985054 -229.366064) (xy 360.979211 -229.363322) (xy 360.966618 -229.360508) (xy 360.960162 -229.360476)
			(xy 360.9467 -229.360984) (xy 360.861864 -229.413054) (xy 360.855676 -229.417037) (xy 360.84573 -229.427876)
			(xy 360.842306 -229.43439) (xy 360.83748 -229.445058) (xy 360.83748 -229.904036) (xy 361.289104 -229.904036)
			(xy 361.293064 -229.854982) (xy 361.304841 -229.807198) (xy 361.324132 -229.761922) (xy 361.350435 -229.720326)
			(xy 361.38307 -229.683489) (xy 361.421191 -229.652364) (xy 361.463812 -229.627757) (xy 361.509828 -229.610305)
			(xy 361.558047 -229.600461) (xy 361.607222 -229.59848) (xy 361.656077 -229.604412) (xy 361.703348 -229.618104)
			(xy 361.74781 -229.639202) (xy 361.788313 -229.667158) (xy 361.823806 -229.70125) (xy 361.853371 -229.740594)
			(xy 361.876242 -229.784171) (xy 361.891826 -229.830852) (xy 361.899721 -229.879429) (xy 361.900216 -229.904036)
			(xy 362.228904 -229.904036) (xy 362.232864 -229.854982) (xy 362.244641 -229.807198) (xy 362.263932 -229.761922)
			(xy 362.290235 -229.720326) (xy 362.32287 -229.683489) (xy 362.360991 -229.652364) (xy 362.403612 -229.627757)
			(xy 362.449628 -229.610305) (xy 362.497847 -229.600461) (xy 362.547022 -229.59848) (xy 362.595877 -229.604412)
			(xy 362.643148 -229.618104) (xy 362.68761 -229.639202) (xy 362.728113 -229.667158) (xy 362.763606 -229.70125)
			(xy 362.793171 -229.740594) (xy 362.816042 -229.784171) (xy 362.831626 -229.830852) (xy 362.839521 -229.879429)
			(xy 362.840016 -229.904036) (xy 363.168958 -229.904036) (xy 363.172918 -229.854982) (xy 363.184695 -229.807198)
			(xy 363.203986 -229.761922) (xy 363.230289 -229.720326) (xy 363.262924 -229.683489) (xy 363.301045 -229.652364)
			(xy 363.343666 -229.627757) (xy 363.389682 -229.610305) (xy 363.437901 -229.600461) (xy 363.487076 -229.59848)
			(xy 363.535931 -229.604412) (xy 363.583202 -229.618104) (xy 363.627664 -229.639202) (xy 363.668167 -229.667158)
			(xy 363.70366 -229.70125) (xy 363.733225 -229.740594) (xy 363.756096 -229.784171) (xy 363.77168 -229.830852)
			(xy 363.779575 -229.879429) (xy 363.78007 -229.904036) (xy 364.098581 -229.904036) (xy 364.102676 -229.853308)
			(xy 364.114855 -229.803894) (xy 364.134803 -229.757074) (xy 364.162004 -229.71406) (xy 364.195752 -229.675966)
			(xy 364.235174 -229.643779) (xy 364.279248 -229.618333) (xy 364.326834 -229.600286) (xy 364.376698 -229.590106)
			(xy 364.42755 -229.588057) (xy 364.478071 -229.594191) (xy 364.526955 -229.608351) (xy 364.572934 -229.630168)
			(xy 364.614818 -229.659078) (xy 364.651522 -229.694333) (xy 364.682095 -229.735019) (xy 364.705746 -229.780082)
			(xy 364.721862 -229.828356) (xy 364.730026 -229.87859) (xy 364.730538 -229.904036) (xy 365.038635 -229.904036)
			(xy 365.04273 -229.853308) (xy 365.054909 -229.803894) (xy 365.074857 -229.757074) (xy 365.102058 -229.71406)
			(xy 365.135806 -229.675966) (xy 365.175228 -229.643779) (xy 365.219302 -229.618333) (xy 365.266888 -229.600286)
			(xy 365.316752 -229.590106) (xy 365.367604 -229.588057) (xy 365.418125 -229.594191) (xy 365.467009 -229.608351)
			(xy 365.512988 -229.630168) (xy 365.554872 -229.659078) (xy 365.591576 -229.694333) (xy 365.622149 -229.735019)
			(xy 365.6458 -229.780082) (xy 365.661916 -229.828356) (xy 365.67008 -229.87859) (xy 365.670592 -229.904036)
			(xy 365.98912 -229.904036) (xy 365.99308 -229.854982) (xy 366.004857 -229.807198) (xy 366.024148 -229.761922)
			(xy 366.050451 -229.720326) (xy 366.083086 -229.683489) (xy 366.121207 -229.652364) (xy 366.163828 -229.627757)
			(xy 366.209844 -229.610305) (xy 366.258063 -229.600461) (xy 366.307238 -229.59848) (xy 366.356093 -229.604412)
			(xy 366.403364 -229.618104) (xy 366.447826 -229.639202) (xy 366.488329 -229.667158) (xy 366.523822 -229.70125)
			(xy 366.553387 -229.740594) (xy 366.576258 -229.784171) (xy 366.591842 -229.830852) (xy 366.599737 -229.879429)
			(xy 366.600232 -229.904036) (xy 366.918489 -229.904036) (xy 366.922584 -229.853308) (xy 366.934763 -229.803894)
			(xy 366.954711 -229.757074) (xy 366.981912 -229.71406) (xy 367.01566 -229.675966) (xy 367.055082 -229.643779)
			(xy 367.099156 -229.618333) (xy 367.146742 -229.600286) (xy 367.196606 -229.590106) (xy 367.247458 -229.588057)
			(xy 367.297979 -229.594191) (xy 367.346863 -229.608351) (xy 367.392842 -229.630168) (xy 367.434726 -229.659078)
			(xy 367.47143 -229.694333) (xy 367.502003 -229.735019) (xy 367.525654 -229.780082) (xy 367.54177 -229.828356)
			(xy 367.549934 -229.87859) (xy 367.550446 -229.904036) (xy 367.858543 -229.904036) (xy 367.862638 -229.853308)
			(xy 367.874817 -229.803894) (xy 367.894765 -229.757074) (xy 367.921966 -229.71406) (xy 367.955714 -229.675966)
			(xy 367.995136 -229.643779) (xy 368.03921 -229.618333) (xy 368.086796 -229.600286) (xy 368.13666 -229.590106)
			(xy 368.187512 -229.588057) (xy 368.238033 -229.594191) (xy 368.286917 -229.608351) (xy 368.332896 -229.630168)
			(xy 368.37478 -229.659078) (xy 368.411484 -229.694333) (xy 368.442057 -229.735019) (xy 368.465708 -229.780082)
			(xy 368.481824 -229.828356) (xy 368.489988 -229.87859) (xy 368.4905 -229.904036) (xy 368.809028 -229.904036)
			(xy 368.812988 -229.854982) (xy 368.824765 -229.807198) (xy 368.844056 -229.761922) (xy 368.870359 -229.720326)
			(xy 368.902994 -229.683489) (xy 368.941115 -229.652364) (xy 368.983736 -229.627757) (xy 369.029752 -229.610305)
			(xy 369.077971 -229.600461) (xy 369.127146 -229.59848) (xy 369.176001 -229.604412) (xy 369.223272 -229.618104)
			(xy 369.267734 -229.639202) (xy 369.308237 -229.667158) (xy 369.34373 -229.70125) (xy 369.373295 -229.740594)
			(xy 369.396166 -229.784171) (xy 369.41175 -229.830852) (xy 369.419645 -229.879429) (xy 369.42014 -229.904036)
			(xy 369.738651 -229.904036) (xy 369.742746 -229.853308) (xy 369.754925 -229.803894) (xy 369.774873 -229.757074)
			(xy 369.802074 -229.71406) (xy 369.835822 -229.675966) (xy 369.875244 -229.643779) (xy 369.919318 -229.618333)
			(xy 369.966904 -229.600286) (xy 370.016768 -229.590106) (xy 370.06762 -229.588057) (xy 370.118141 -229.594191)
			(xy 370.167025 -229.608351) (xy 370.213004 -229.630168) (xy 370.254888 -229.659078) (xy 370.291592 -229.694333)
			(xy 370.322165 -229.735019) (xy 370.345816 -229.780082) (xy 370.361932 -229.828356) (xy 370.370096 -229.87859)
			(xy 370.370608 -229.904036) (xy 370.678451 -229.904036) (xy 370.682546 -229.853308) (xy 370.694725 -229.803894)
			(xy 370.714673 -229.757074) (xy 370.741874 -229.71406) (xy 370.775622 -229.675966) (xy 370.815044 -229.643779)
			(xy 370.859118 -229.618333) (xy 370.906704 -229.600286) (xy 370.956568 -229.590106) (xy 371.00742 -229.588057)
			(xy 371.057941 -229.594191) (xy 371.106825 -229.608351) (xy 371.152804 -229.630168) (xy 371.194688 -229.659078)
			(xy 371.231392 -229.694333) (xy 371.261965 -229.735019) (xy 371.285616 -229.780082) (xy 371.301732 -229.828356)
			(xy 371.309896 -229.87859) (xy 371.310408 -229.904036) (xy 371.628936 -229.904036) (xy 371.632896 -229.854982)
			(xy 371.644673 -229.807198) (xy 371.663964 -229.761922) (xy 371.690267 -229.720326) (xy 371.722902 -229.683489)
			(xy 371.761023 -229.652364) (xy 371.803644 -229.627757) (xy 371.84966 -229.610305) (xy 371.897879 -229.600461)
			(xy 371.947054 -229.59848) (xy 371.995909 -229.604412) (xy 372.04318 -229.618104) (xy 372.087642 -229.639202)
			(xy 372.128145 -229.667158) (xy 372.163638 -229.70125) (xy 372.193203 -229.740594) (xy 372.216074 -229.784171)
			(xy 372.231658 -229.830852) (xy 372.239553 -229.879429) (xy 372.240048 -229.904036) (xy 372.558559 -229.904036)
			(xy 372.562654 -229.853308) (xy 372.574833 -229.803894) (xy 372.594781 -229.757074) (xy 372.621982 -229.71406)
			(xy 372.65573 -229.675966) (xy 372.695152 -229.643779) (xy 372.739226 -229.618333) (xy 372.786812 -229.600286)
			(xy 372.836676 -229.590106) (xy 372.887528 -229.588057) (xy 372.938049 -229.594191) (xy 372.986933 -229.608351)
			(xy 373.032912 -229.630168) (xy 373.074796 -229.659078) (xy 373.1115 -229.694333) (xy 373.142073 -229.735019)
			(xy 373.165724 -229.780082) (xy 373.18184 -229.828356) (xy 373.190004 -229.87859) (xy 373.190516 -229.904036)
			(xy 373.498613 -229.904036) (xy 373.502708 -229.853308) (xy 373.514887 -229.803894) (xy 373.534835 -229.757074)
			(xy 373.562036 -229.71406) (xy 373.595784 -229.675966) (xy 373.635206 -229.643779) (xy 373.67928 -229.618333)
			(xy 373.726866 -229.600286) (xy 373.77673 -229.590106) (xy 373.827582 -229.588057) (xy 373.878103 -229.594191)
			(xy 373.926987 -229.608351) (xy 373.972966 -229.630168) (xy 374.01485 -229.659078) (xy 374.051554 -229.694333)
			(xy 374.082127 -229.735019) (xy 374.105778 -229.780082) (xy 374.121894 -229.828356) (xy 374.130058 -229.87859)
			(xy 374.13057 -229.904036) (xy 374.130058 -229.929482) (xy 374.121894 -229.979716) (xy 374.105778 -230.02799)
			(xy 374.082127 -230.073053) (xy 374.051554 -230.113739) (xy 374.01485 -230.148994) (xy 373.972966 -230.177904)
			(xy 373.926987 -230.199721) (xy 373.878103 -230.213881) (xy 373.827582 -230.220015) (xy 373.77673 -230.217966)
			(xy 373.726866 -230.207786) (xy 373.67928 -230.189739) (xy 373.635206 -230.164293) (xy 373.595784 -230.132106)
			(xy 373.562036 -230.094012) (xy 373.534835 -230.050998) (xy 373.514887 -230.004178) (xy 373.502708 -229.954764)
			(xy 373.498613 -229.904036) (xy 373.190516 -229.904036) (xy 373.190004 -229.929482) (xy 373.18184 -229.979716)
			(xy 373.165724 -230.02799) (xy 373.142073 -230.073053) (xy 373.1115 -230.113739) (xy 373.074796 -230.148994)
			(xy 373.032912 -230.177904) (xy 372.986933 -230.199721) (xy 372.938049 -230.213881) (xy 372.887528 -230.220015)
			(xy 372.836676 -230.217966) (xy 372.786812 -230.207786) (xy 372.739226 -230.189739) (xy 372.695152 -230.164293)
			(xy 372.65573 -230.132106) (xy 372.621982 -230.094012) (xy 372.594781 -230.050998) (xy 372.574833 -230.004178)
			(xy 372.562654 -229.954764) (xy 372.558559 -229.904036) (xy 372.240048 -229.904036) (xy 372.239553 -229.928643)
			(xy 372.231658 -229.97722) (xy 372.216074 -230.023901) (xy 372.193203 -230.067478) (xy 372.163638 -230.106822)
			(xy 372.128145 -230.140914) (xy 372.087642 -230.16887) (xy 372.04318 -230.189968) (xy 371.995909 -230.20366)
			(xy 371.947054 -230.209592) (xy 371.897879 -230.207611) (xy 371.84966 -230.197767) (xy 371.803644 -230.180315)
			(xy 371.761023 -230.155708) (xy 371.722902 -230.124583) (xy 371.690267 -230.087746) (xy 371.663964 -230.04615)
			(xy 371.644673 -230.000874) (xy 371.632896 -229.95309) (xy 371.628936 -229.904036) (xy 371.310408 -229.904036)
			(xy 371.309896 -229.929482) (xy 371.301732 -229.979716) (xy 371.285616 -230.02799) (xy 371.261965 -230.073053)
			(xy 371.231392 -230.113739) (xy 371.194688 -230.148994) (xy 371.152804 -230.177904) (xy 371.106825 -230.199721)
			(xy 371.057941 -230.213881) (xy 371.00742 -230.220015) (xy 370.956568 -230.217966) (xy 370.906704 -230.207786)
			(xy 370.859118 -230.189739) (xy 370.815044 -230.164293) (xy 370.775622 -230.132106) (xy 370.741874 -230.094012)
			(xy 370.714673 -230.050998) (xy 370.694725 -230.004178) (xy 370.682546 -229.954764) (xy 370.678451 -229.904036)
			(xy 370.370608 -229.904036) (xy 370.370096 -229.929482) (xy 370.361932 -229.979716) (xy 370.345816 -230.02799)
			(xy 370.322165 -230.073053) (xy 370.291592 -230.113739) (xy 370.254888 -230.148994) (xy 370.213004 -230.177904)
			(xy 370.167025 -230.199721) (xy 370.118141 -230.213881) (xy 370.06762 -230.220015) (xy 370.016768 -230.217966)
			(xy 369.966904 -230.207786) (xy 369.919318 -230.189739) (xy 369.875244 -230.164293) (xy 369.835822 -230.132106)
			(xy 369.802074 -230.094012) (xy 369.774873 -230.050998) (xy 369.754925 -230.004178) (xy 369.742746 -229.954764)
			(xy 369.738651 -229.904036) (xy 369.42014 -229.904036) (xy 369.419645 -229.928643) (xy 369.41175 -229.97722)
			(xy 369.396166 -230.023901) (xy 369.373295 -230.067478) (xy 369.34373 -230.106822) (xy 369.308237 -230.140914)
			(xy 369.267734 -230.16887) (xy 369.223272 -230.189968) (xy 369.176001 -230.20366) (xy 369.127146 -230.209592)
			(xy 369.077971 -230.207611) (xy 369.029752 -230.197767) (xy 368.983736 -230.180315) (xy 368.941115 -230.155708)
			(xy 368.902994 -230.124583) (xy 368.870359 -230.087746) (xy 368.844056 -230.04615) (xy 368.824765 -230.000874)
			(xy 368.812988 -229.95309) (xy 368.809028 -229.904036) (xy 368.4905 -229.904036) (xy 368.489988 -229.929482)
			(xy 368.481824 -229.979716) (xy 368.465708 -230.02799) (xy 368.442057 -230.073053) (xy 368.411484 -230.113739)
			(xy 368.37478 -230.148994) (xy 368.332896 -230.177904) (xy 368.286917 -230.199721) (xy 368.238033 -230.213881)
			(xy 368.187512 -230.220015) (xy 368.13666 -230.217966) (xy 368.086796 -230.207786) (xy 368.03921 -230.189739)
			(xy 367.995136 -230.164293) (xy 367.955714 -230.132106) (xy 367.921966 -230.094012) (xy 367.894765 -230.050998)
			(xy 367.874817 -230.004178) (xy 367.862638 -229.954764) (xy 367.858543 -229.904036) (xy 367.550446 -229.904036)
			(xy 367.549934 -229.929482) (xy 367.54177 -229.979716) (xy 367.525654 -230.02799) (xy 367.502003 -230.073053)
			(xy 367.47143 -230.113739) (xy 367.434726 -230.148994) (xy 367.392842 -230.177904) (xy 367.346863 -230.199721)
			(xy 367.297979 -230.213881) (xy 367.247458 -230.220015) (xy 367.196606 -230.217966) (xy 367.146742 -230.207786)
			(xy 367.099156 -230.189739) (xy 367.055082 -230.164293) (xy 367.01566 -230.132106) (xy 366.981912 -230.094012)
			(xy 366.954711 -230.050998) (xy 366.934763 -230.004178) (xy 366.922584 -229.954764) (xy 366.918489 -229.904036)
			(xy 366.600232 -229.904036) (xy 366.599737 -229.928643) (xy 366.591842 -229.97722) (xy 366.576258 -230.023901)
			(xy 366.553387 -230.067478) (xy 366.523822 -230.106822) (xy 366.488329 -230.140914) (xy 366.447826 -230.16887)
			(xy 366.403364 -230.189968) (xy 366.356093 -230.20366) (xy 366.307238 -230.209592) (xy 366.258063 -230.207611)
			(xy 366.209844 -230.197767) (xy 366.163828 -230.180315) (xy 366.121207 -230.155708) (xy 366.083086 -230.124583)
			(xy 366.050451 -230.087746) (xy 366.024148 -230.04615) (xy 366.004857 -230.000874) (xy 365.99308 -229.95309)
			(xy 365.98912 -229.904036) (xy 365.670592 -229.904036) (xy 365.67008 -229.929482) (xy 365.661916 -229.979716)
			(xy 365.6458 -230.02799) (xy 365.622149 -230.073053) (xy 365.591576 -230.113739) (xy 365.554872 -230.148994)
			(xy 365.512988 -230.177904) (xy 365.467009 -230.199721) (xy 365.418125 -230.213881) (xy 365.367604 -230.220015)
			(xy 365.316752 -230.217966) (xy 365.266888 -230.207786) (xy 365.219302 -230.189739) (xy 365.175228 -230.164293)
			(xy 365.135806 -230.132106) (xy 365.102058 -230.094012) (xy 365.074857 -230.050998) (xy 365.054909 -230.004178)
			(xy 365.04273 -229.954764) (xy 365.038635 -229.904036) (xy 364.730538 -229.904036) (xy 364.730026 -229.929482)
			(xy 364.721862 -229.979716) (xy 364.705746 -230.02799) (xy 364.682095 -230.073053) (xy 364.651522 -230.113739)
			(xy 364.614818 -230.148994) (xy 364.572934 -230.177904) (xy 364.526955 -230.199721) (xy 364.478071 -230.213881)
			(xy 364.42755 -230.220015) (xy 364.376698 -230.217966) (xy 364.326834 -230.207786) (xy 364.279248 -230.189739)
			(xy 364.235174 -230.164293) (xy 364.195752 -230.132106) (xy 364.162004 -230.094012) (xy 364.134803 -230.050998)
			(xy 364.114855 -230.004178) (xy 364.102676 -229.954764) (xy 364.098581 -229.904036) (xy 363.78007 -229.904036)
			(xy 363.779575 -229.928643) (xy 363.77168 -229.97722) (xy 363.756096 -230.023901) (xy 363.733225 -230.067478)
			(xy 363.70366 -230.106822) (xy 363.668167 -230.140914) (xy 363.627664 -230.16887) (xy 363.583202 -230.189968)
			(xy 363.535931 -230.20366) (xy 363.487076 -230.209592) (xy 363.437901 -230.207611) (xy 363.389682 -230.197767)
			(xy 363.343666 -230.180315) (xy 363.301045 -230.155708) (xy 363.262924 -230.124583) (xy 363.230289 -230.087746)
			(xy 363.203986 -230.04615) (xy 363.184695 -230.000874) (xy 363.172918 -229.95309) (xy 363.168958 -229.904036)
			(xy 362.840016 -229.904036) (xy 362.839521 -229.928643) (xy 362.831626 -229.97722) (xy 362.816042 -230.023901)
			(xy 362.793171 -230.067478) (xy 362.763606 -230.106822) (xy 362.728113 -230.140914) (xy 362.68761 -230.16887)
			(xy 362.643148 -230.189968) (xy 362.595877 -230.20366) (xy 362.547022 -230.209592) (xy 362.497847 -230.207611)
			(xy 362.449628 -230.197767) (xy 362.403612 -230.180315) (xy 362.360991 -230.155708) (xy 362.32287 -230.124583)
			(xy 362.290235 -230.087746) (xy 362.263932 -230.04615) (xy 362.244641 -230.000874) (xy 362.232864 -229.95309)
			(xy 362.228904 -229.904036) (xy 361.900216 -229.904036) (xy 361.899721 -229.928643) (xy 361.891826 -229.97722)
			(xy 361.876242 -230.023901) (xy 361.853371 -230.067478) (xy 361.823806 -230.106822) (xy 361.788313 -230.140914)
			(xy 361.74781 -230.16887) (xy 361.703348 -230.189968) (xy 361.656077 -230.20366) (xy 361.607222 -230.209592)
			(xy 361.558047 -230.207611) (xy 361.509828 -230.197767) (xy 361.463812 -230.180315) (xy 361.421191 -230.155708)
			(xy 361.38307 -230.124583) (xy 361.350435 -230.087746) (xy 361.324132 -230.04615) (xy 361.304841 -230.000874)
			(xy 361.293064 -229.95309) (xy 361.289104 -229.904036) (xy 360.83748 -229.904036) (xy 360.83748 -230.346504)
			(xy 360.83875 -230.35768) (xy 360.841036 -230.368602) (xy 360.844846 -230.37927) (xy 360.84891 -230.387652)
			(xy 360.93527 -230.440738) (xy 360.940933 -230.443959) (xy 360.953407 -230.447701) (xy 360.959908 -230.448104)
			(xy 360.97337 -230.448612) (xy 360.985308 -230.442516) (xy 361.006888 -230.431966) (xy 361.052544 -230.417045)
			(xy 361.099976 -230.409474) (xy 361.123992 -230.408988) (xy 361.124754 -230.408988) (xy 361.150015 -230.409477)
			(xy 361.199848 -230.417786) (xy 361.247633 -230.434184) (xy 361.292067 -230.458225) (xy 361.331938 -230.489252)
			(xy 361.366158 -230.526419) (xy 361.393792 -230.568712) (xy 361.414088 -230.614977) (xy 361.426492 -230.663952)
			(xy 361.430664 -230.714296) (xy 361.748573 -230.714296) (xy 361.752668 -230.663568) (xy 361.764847 -230.614154)
			(xy 361.784795 -230.567334) (xy 361.811996 -230.52432) (xy 361.845744 -230.486226) (xy 361.885166 -230.454039)
			(xy 361.92924 -230.428593) (xy 361.976826 -230.410546) (xy 362.02669 -230.400366) (xy 362.077542 -230.398317)
			(xy 362.128063 -230.404451) (xy 362.176947 -230.418611) (xy 362.222926 -230.440428) (xy 362.26481 -230.469338)
			(xy 362.301514 -230.504593) (xy 362.332087 -230.545279) (xy 362.355738 -230.590342) (xy 362.371854 -230.638616)
			(xy 362.380018 -230.68885) (xy 362.38053 -230.714296) (xy 362.688627 -230.714296) (xy 362.692722 -230.663568)
			(xy 362.704901 -230.614154) (xy 362.724849 -230.567334) (xy 362.75205 -230.52432) (xy 362.785798 -230.486226)
			(xy 362.82522 -230.454039) (xy 362.869294 -230.428593) (xy 362.91688 -230.410546) (xy 362.966744 -230.400366)
			(xy 363.017596 -230.398317) (xy 363.068117 -230.404451) (xy 363.117001 -230.418611) (xy 363.16298 -230.440428)
			(xy 363.204864 -230.469338) (xy 363.241568 -230.504593) (xy 363.272141 -230.545279) (xy 363.295792 -230.590342)
			(xy 363.311908 -230.638616) (xy 363.320072 -230.68885) (xy 363.320579 -230.714042) (xy 363.639112 -230.714042)
			(xy 363.643072 -230.664988) (xy 363.654849 -230.617204) (xy 363.67414 -230.571928) (xy 363.700443 -230.530332)
			(xy 363.733078 -230.493495) (xy 363.771199 -230.46237) (xy 363.81382 -230.437763) (xy 363.859836 -230.420311)
			(xy 363.908055 -230.410467) (xy 363.95723 -230.408486) (xy 364.006085 -230.414418) (xy 364.053356 -230.42811)
			(xy 364.097818 -230.449208) (xy 364.138321 -230.477164) (xy 364.173814 -230.511256) (xy 364.203379 -230.5506)
			(xy 364.22625 -230.594177) (xy 364.241834 -230.640858) (xy 364.249729 -230.689435) (xy 364.250224 -230.714042)
			(xy 364.250219 -230.714296) (xy 366.45902 -230.714296) (xy 366.46298 -230.665242) (xy 366.474757 -230.617458)
			(xy 366.494048 -230.572182) (xy 366.520351 -230.530586) (xy 366.552986 -230.493749) (xy 366.591107 -230.462624)
			(xy 366.633728 -230.438017) (xy 366.679744 -230.420565) (xy 366.727963 -230.410721) (xy 366.777138 -230.40874)
			(xy 366.825993 -230.414672) (xy 366.873264 -230.428364) (xy 366.917726 -230.449462) (xy 366.958229 -230.477418)
			(xy 366.993722 -230.51151) (xy 367.023287 -230.550854) (xy 367.046158 -230.594431) (xy 367.061742 -230.641112)
			(xy 367.069637 -230.689689) (xy 367.070132 -230.714296) (xy 369.278928 -230.714296) (xy 369.282888 -230.665242)
			(xy 369.294665 -230.617458) (xy 369.313956 -230.572182) (xy 369.340259 -230.530586) (xy 369.372894 -230.493749)
			(xy 369.411015 -230.462624) (xy 369.453636 -230.438017) (xy 369.499652 -230.420565) (xy 369.547871 -230.410721)
			(xy 369.597046 -230.40874) (xy 369.645901 -230.414672) (xy 369.693172 -230.428364) (xy 369.737634 -230.449462)
			(xy 369.778137 -230.477418) (xy 369.81363 -230.51151) (xy 369.843195 -230.550854) (xy 369.866066 -230.594431)
			(xy 369.88165 -230.641112) (xy 369.889545 -230.689689) (xy 369.890035 -230.714042) (xy 372.09909 -230.714042)
			(xy 372.10305 -230.664988) (xy 372.114827 -230.617204) (xy 372.134118 -230.571928) (xy 372.160421 -230.530332)
			(xy 372.193056 -230.493495) (xy 372.231177 -230.46237) (xy 372.273798 -230.437763) (xy 372.319814 -230.420311)
			(xy 372.368033 -230.410467) (xy 372.417208 -230.408486) (xy 372.466063 -230.414418) (xy 372.513334 -230.42811)
			(xy 372.557796 -230.449208) (xy 372.598299 -230.477164) (xy 372.633792 -230.511256) (xy 372.663357 -230.5506)
			(xy 372.686228 -230.594177) (xy 372.701812 -230.640858) (xy 372.709707 -230.689435) (xy 372.710202 -230.714042)
			(xy 372.709707 -230.738649) (xy 372.701812 -230.787226) (xy 372.686228 -230.833907) (xy 372.663357 -230.877484)
			(xy 372.633792 -230.916828) (xy 372.598299 -230.95092) (xy 372.557796 -230.978876) (xy 372.513334 -230.999974)
			(xy 372.466063 -231.013666) (xy 372.417208 -231.019598) (xy 372.368033 -231.017617) (xy 372.319814 -231.007773)
			(xy 372.273798 -230.990321) (xy 372.231177 -230.965714) (xy 372.193056 -230.934589) (xy 372.160421 -230.897752)
			(xy 372.134118 -230.856156) (xy 372.114827 -230.81088) (xy 372.10305 -230.763096) (xy 372.09909 -230.714042)
			(xy 369.890035 -230.714042) (xy 369.89004 -230.714296) (xy 369.889545 -230.738903) (xy 369.88165 -230.78748)
			(xy 369.866066 -230.834161) (xy 369.843195 -230.877738) (xy 369.81363 -230.917082) (xy 369.778137 -230.951174)
			(xy 369.737634 -230.97913) (xy 369.693172 -231.000228) (xy 369.645901 -231.01392) (xy 369.597046 -231.019852)
			(xy 369.547871 -231.017871) (xy 369.499652 -231.008027) (xy 369.453636 -230.990575) (xy 369.411015 -230.965968)
			(xy 369.372894 -230.934843) (xy 369.340259 -230.898006) (xy 369.313956 -230.85641) (xy 369.294665 -230.811134)
			(xy 369.282888 -230.76335) (xy 369.278928 -230.714296) (xy 367.070132 -230.714296) (xy 367.069637 -230.738903)
			(xy 367.061742 -230.78748) (xy 367.046158 -230.834161) (xy 367.023287 -230.877738) (xy 366.993722 -230.917082)
			(xy 366.958229 -230.951174) (xy 366.917726 -230.97913) (xy 366.873264 -231.000228) (xy 366.825993 -231.01392)
			(xy 366.777138 -231.019852) (xy 366.727963 -231.017871) (xy 366.679744 -231.008027) (xy 366.633728 -230.990575)
			(xy 366.591107 -230.965968) (xy 366.552986 -230.934843) (xy 366.520351 -230.898006) (xy 366.494048 -230.85641)
			(xy 366.474757 -230.811134) (xy 366.46298 -230.76335) (xy 366.45902 -230.714296) (xy 364.250219 -230.714296)
			(xy 364.249729 -230.738649) (xy 364.241834 -230.787226) (xy 364.22625 -230.833907) (xy 364.203379 -230.877484)
			(xy 364.173814 -230.916828) (xy 364.138321 -230.95092) (xy 364.097818 -230.978876) (xy 364.053356 -230.999974)
			(xy 364.006085 -231.013666) (xy 363.95723 -231.019598) (xy 363.908055 -231.017617) (xy 363.859836 -231.007773)
			(xy 363.81382 -230.990321) (xy 363.771199 -230.965714) (xy 363.733078 -230.934589) (xy 363.700443 -230.897752)
			(xy 363.67414 -230.856156) (xy 363.654849 -230.81088) (xy 363.643072 -230.763096) (xy 363.639112 -230.714042)
			(xy 363.320579 -230.714042) (xy 363.320584 -230.714296) (xy 363.320072 -230.739742) (xy 363.311908 -230.789976)
			(xy 363.295792 -230.83825) (xy 363.272141 -230.883313) (xy 363.241568 -230.923999) (xy 363.204864 -230.959254)
			(xy 363.16298 -230.988164) (xy 363.117001 -231.009981) (xy 363.068117 -231.024141) (xy 363.017596 -231.030275)
			(xy 362.966744 -231.028226) (xy 362.91688 -231.018046) (xy 362.869294 -230.999999) (xy 362.82522 -230.974553)
			(xy 362.785798 -230.942366) (xy 362.75205 -230.904272) (xy 362.724849 -230.861258) (xy 362.704901 -230.814438)
			(xy 362.692722 -230.765024) (xy 362.688627 -230.714296) (xy 362.38053 -230.714296) (xy 362.380018 -230.739742)
			(xy 362.371854 -230.789976) (xy 362.355738 -230.83825) (xy 362.332087 -230.883313) (xy 362.301514 -230.923999)
			(xy 362.26481 -230.959254) (xy 362.222926 -230.988164) (xy 362.176947 -231.009981) (xy 362.128063 -231.024141)
			(xy 362.077542 -231.030275) (xy 362.02669 -231.028226) (xy 361.976826 -231.018046) (xy 361.92924 -230.999999)
			(xy 361.885166 -230.974553) (xy 361.845744 -230.942366) (xy 361.811996 -230.904272) (xy 361.784795 -230.861258)
			(xy 361.764847 -230.814438) (xy 361.752668 -230.765024) (xy 361.748573 -230.714296) (xy 361.430664 -230.714296)
			(xy 361.430664 -230.7143) (xy 361.426492 -230.764648) (xy 361.414088 -230.813623) (xy 361.393792 -230.859888)
			(xy 361.366158 -230.902181) (xy 361.331938 -230.939348) (xy 361.292067 -230.970375) (xy 361.247633 -230.994416)
			(xy 361.199848 -231.010814) (xy 361.150015 -231.019123) (xy 361.124754 -231.019604) (xy 361.123992 -231.019604)
			(xy 361.09998 -231.019087) (xy 361.052559 -231.01149) (xy 361.006907 -230.996579) (xy 360.985308 -230.986076)
			(xy 360.985054 -230.986076) (xy 360.979211 -230.983333) (xy 360.966618 -230.980519) (xy 360.960162 -230.980488)
			(xy 360.9467 -230.980996) (xy 360.861864 -231.033066) (xy 360.855677 -231.03705) (xy 360.845733 -231.04789)
			(xy 360.842306 -231.054402) (xy 360.83748 -231.06507) (xy 360.83748 -231.524048) (xy 363.168958 -231.524048)
			(xy 363.172918 -231.474994) (xy 363.184695 -231.42721) (xy 363.203986 -231.381934) (xy 363.230289 -231.340338)
			(xy 363.262924 -231.303501) (xy 363.301045 -231.272376) (xy 363.343666 -231.247769) (xy 363.389682 -231.230317)
			(xy 363.437901 -231.220473) (xy 363.487076 -231.218492) (xy 363.535931 -231.224424) (xy 363.583202 -231.238116)
			(xy 363.627664 -231.259214) (xy 363.668167 -231.28717) (xy 363.70366 -231.321262) (xy 363.733225 -231.360606)
			(xy 363.756096 -231.404183) (xy 363.77168 -231.450864) (xy 363.779575 -231.499441) (xy 363.78007 -231.524048)
			(xy 364.098581 -231.524048) (xy 364.102676 -231.47332) (xy 364.114855 -231.423906) (xy 364.134803 -231.377086)
			(xy 364.162004 -231.334072) (xy 364.195752 -231.295978) (xy 364.235174 -231.263791) (xy 364.279248 -231.238345)
			(xy 364.326834 -231.220298) (xy 364.376698 -231.210118) (xy 364.42755 -231.208069) (xy 364.478071 -231.214203)
			(xy 364.526955 -231.228363) (xy 364.572934 -231.25018) (xy 364.614818 -231.27909) (xy 364.651522 -231.314345)
			(xy 364.682095 -231.355031) (xy 364.705746 -231.400094) (xy 364.721862 -231.448368) (xy 364.730026 -231.498602)
			(xy 364.730538 -231.524048) (xy 365.038635 -231.524048) (xy 365.04273 -231.47332) (xy 365.054909 -231.423906)
			(xy 365.074857 -231.377086) (xy 365.102058 -231.334072) (xy 365.135806 -231.295978) (xy 365.175228 -231.263791)
			(xy 365.219302 -231.238345) (xy 365.266888 -231.220298) (xy 365.316752 -231.210118) (xy 365.367604 -231.208069)
			(xy 365.418125 -231.214203) (xy 365.467009 -231.228363) (xy 365.512988 -231.25018) (xy 365.554872 -231.27909)
			(xy 365.591576 -231.314345) (xy 365.622149 -231.355031) (xy 365.6458 -231.400094) (xy 365.661916 -231.448368)
			(xy 365.67008 -231.498602) (xy 365.670592 -231.524048) (xy 365.98912 -231.524048) (xy 365.99308 -231.474994)
			(xy 366.004857 -231.42721) (xy 366.024148 -231.381934) (xy 366.050451 -231.340338) (xy 366.083086 -231.303501)
			(xy 366.121207 -231.272376) (xy 366.163828 -231.247769) (xy 366.209844 -231.230317) (xy 366.258063 -231.220473)
			(xy 366.307238 -231.218492) (xy 366.356093 -231.224424) (xy 366.403364 -231.238116) (xy 366.447826 -231.259214)
			(xy 366.488329 -231.28717) (xy 366.523822 -231.321262) (xy 366.553387 -231.360606) (xy 366.576258 -231.404183)
			(xy 366.591842 -231.450864) (xy 366.599737 -231.499441) (xy 366.600232 -231.524048) (xy 366.918489 -231.524048)
			(xy 366.922584 -231.47332) (xy 366.934763 -231.423906) (xy 366.954711 -231.377086) (xy 366.981912 -231.334072)
			(xy 367.01566 -231.295978) (xy 367.055082 -231.263791) (xy 367.099156 -231.238345) (xy 367.146742 -231.220298)
			(xy 367.196606 -231.210118) (xy 367.247458 -231.208069) (xy 367.297979 -231.214203) (xy 367.346863 -231.228363)
			(xy 367.392842 -231.25018) (xy 367.434726 -231.27909) (xy 367.47143 -231.314345) (xy 367.502003 -231.355031)
			(xy 367.525654 -231.400094) (xy 367.54177 -231.448368) (xy 367.549934 -231.498602) (xy 367.550446 -231.524048)
			(xy 367.858543 -231.524048) (xy 367.862638 -231.47332) (xy 367.874817 -231.423906) (xy 367.894765 -231.377086)
			(xy 367.921966 -231.334072) (xy 367.955714 -231.295978) (xy 367.995136 -231.263791) (xy 368.03921 -231.238345)
			(xy 368.086796 -231.220298) (xy 368.13666 -231.210118) (xy 368.187512 -231.208069) (xy 368.238033 -231.214203)
			(xy 368.286917 -231.228363) (xy 368.332896 -231.25018) (xy 368.37478 -231.27909) (xy 368.411484 -231.314345)
			(xy 368.442057 -231.355031) (xy 368.465708 -231.400094) (xy 368.481824 -231.448368) (xy 368.489988 -231.498602)
			(xy 368.4905 -231.524048) (xy 368.809028 -231.524048) (xy 368.812988 -231.474994) (xy 368.824765 -231.42721)
			(xy 368.844056 -231.381934) (xy 368.870359 -231.340338) (xy 368.902994 -231.303501) (xy 368.941115 -231.272376)
			(xy 368.983736 -231.247769) (xy 369.029752 -231.230317) (xy 369.077971 -231.220473) (xy 369.127146 -231.218492)
			(xy 369.176001 -231.224424) (xy 369.223272 -231.238116) (xy 369.267734 -231.259214) (xy 369.308237 -231.28717)
			(xy 369.34373 -231.321262) (xy 369.373295 -231.360606) (xy 369.396166 -231.404183) (xy 369.41175 -231.450864)
			(xy 369.419645 -231.499441) (xy 369.42014 -231.524048) (xy 369.738651 -231.524048) (xy 369.742746 -231.47332)
			(xy 369.754925 -231.423906) (xy 369.774873 -231.377086) (xy 369.802074 -231.334072) (xy 369.835822 -231.295978)
			(xy 369.875244 -231.263791) (xy 369.919318 -231.238345) (xy 369.966904 -231.220298) (xy 370.016768 -231.210118)
			(xy 370.06762 -231.208069) (xy 370.118141 -231.214203) (xy 370.167025 -231.228363) (xy 370.213004 -231.25018)
			(xy 370.254888 -231.27909) (xy 370.291592 -231.314345) (xy 370.322165 -231.355031) (xy 370.345816 -231.400094)
			(xy 370.361932 -231.448368) (xy 370.370096 -231.498602) (xy 370.370608 -231.524048) (xy 370.678451 -231.524048)
			(xy 370.682546 -231.47332) (xy 370.694725 -231.423906) (xy 370.714673 -231.377086) (xy 370.741874 -231.334072)
			(xy 370.775622 -231.295978) (xy 370.815044 -231.263791) (xy 370.859118 -231.238345) (xy 370.906704 -231.220298)
			(xy 370.956568 -231.210118) (xy 371.00742 -231.208069) (xy 371.057941 -231.214203) (xy 371.106825 -231.228363)
			(xy 371.152804 -231.25018) (xy 371.194688 -231.27909) (xy 371.231392 -231.314345) (xy 371.261965 -231.355031)
			(xy 371.285616 -231.400094) (xy 371.301732 -231.448368) (xy 371.309896 -231.498602) (xy 371.310408 -231.524048)
			(xy 371.628936 -231.524048) (xy 371.632896 -231.474994) (xy 371.644673 -231.42721) (xy 371.663964 -231.381934)
			(xy 371.690267 -231.340338) (xy 371.722902 -231.303501) (xy 371.761023 -231.272376) (xy 371.803644 -231.247769)
			(xy 371.84966 -231.230317) (xy 371.897879 -231.220473) (xy 371.947054 -231.218492) (xy 371.995909 -231.224424)
			(xy 372.04318 -231.238116) (xy 372.087642 -231.259214) (xy 372.128145 -231.28717) (xy 372.163638 -231.321262)
			(xy 372.193203 -231.360606) (xy 372.216074 -231.404183) (xy 372.231658 -231.450864) (xy 372.239553 -231.499441)
			(xy 372.240048 -231.524048) (xy 372.558559 -231.524048) (xy 372.562654 -231.47332) (xy 372.574833 -231.423906)
			(xy 372.594781 -231.377086) (xy 372.621982 -231.334072) (xy 372.65573 -231.295978) (xy 372.695152 -231.263791)
			(xy 372.739226 -231.238345) (xy 372.786812 -231.220298) (xy 372.836676 -231.210118) (xy 372.887528 -231.208069)
			(xy 372.938049 -231.214203) (xy 372.986933 -231.228363) (xy 373.032912 -231.25018) (xy 373.074796 -231.27909)
			(xy 373.1115 -231.314345) (xy 373.142073 -231.355031) (xy 373.165724 -231.400094) (xy 373.18184 -231.448368)
			(xy 373.190004 -231.498602) (xy 373.190516 -231.524048) (xy 373.498613 -231.524048) (xy 373.502708 -231.47332)
			(xy 373.514887 -231.423906) (xy 373.534835 -231.377086) (xy 373.562036 -231.334072) (xy 373.595784 -231.295978)
			(xy 373.635206 -231.263791) (xy 373.67928 -231.238345) (xy 373.726866 -231.220298) (xy 373.77673 -231.210118)
			(xy 373.827582 -231.208069) (xy 373.878103 -231.214203) (xy 373.926987 -231.228363) (xy 373.972966 -231.25018)
			(xy 374.01485 -231.27909) (xy 374.051554 -231.314345) (xy 374.082127 -231.355031) (xy 374.105778 -231.400094)
			(xy 374.121894 -231.448368) (xy 374.130058 -231.498602) (xy 374.13057 -231.524048) (xy 374.130058 -231.549494)
			(xy 374.121894 -231.599728) (xy 374.105778 -231.648002) (xy 374.082127 -231.693065) (xy 374.051554 -231.733751)
			(xy 374.01485 -231.769006) (xy 373.972966 -231.797916) (xy 373.926987 -231.819733) (xy 373.878103 -231.833893)
			(xy 373.827582 -231.840027) (xy 373.77673 -231.837978) (xy 373.726866 -231.827798) (xy 373.67928 -231.809751)
			(xy 373.635206 -231.784305) (xy 373.595784 -231.752118) (xy 373.562036 -231.714024) (xy 373.534835 -231.67101)
			(xy 373.514887 -231.62419) (xy 373.502708 -231.574776) (xy 373.498613 -231.524048) (xy 373.190516 -231.524048)
			(xy 373.190004 -231.549494) (xy 373.18184 -231.599728) (xy 373.165724 -231.648002) (xy 373.142073 -231.693065)
			(xy 373.1115 -231.733751) (xy 373.074796 -231.769006) (xy 373.032912 -231.797916) (xy 372.986933 -231.819733)
			(xy 372.938049 -231.833893) (xy 372.887528 -231.840027) (xy 372.836676 -231.837978) (xy 372.786812 -231.827798)
			(xy 372.739226 -231.809751) (xy 372.695152 -231.784305) (xy 372.65573 -231.752118) (xy 372.621982 -231.714024)
			(xy 372.594781 -231.67101) (xy 372.574833 -231.62419) (xy 372.562654 -231.574776) (xy 372.558559 -231.524048)
			(xy 372.240048 -231.524048) (xy 372.239553 -231.548655) (xy 372.231658 -231.597232) (xy 372.216074 -231.643913)
			(xy 372.193203 -231.68749) (xy 372.163638 -231.726834) (xy 372.128145 -231.760926) (xy 372.087642 -231.788882)
			(xy 372.04318 -231.80998) (xy 371.995909 -231.823672) (xy 371.947054 -231.829604) (xy 371.897879 -231.827623)
			(xy 371.84966 -231.817779) (xy 371.803644 -231.800327) (xy 371.761023 -231.77572) (xy 371.722902 -231.744595)
			(xy 371.690267 -231.707758) (xy 371.663964 -231.666162) (xy 371.644673 -231.620886) (xy 371.632896 -231.573102)
			(xy 371.628936 -231.524048) (xy 371.310408 -231.524048) (xy 371.309896 -231.549494) (xy 371.301732 -231.599728)
			(xy 371.285616 -231.648002) (xy 371.261965 -231.693065) (xy 371.231392 -231.733751) (xy 371.194688 -231.769006)
			(xy 371.152804 -231.797916) (xy 371.106825 -231.819733) (xy 371.057941 -231.833893) (xy 371.00742 -231.840027)
			(xy 370.956568 -231.837978) (xy 370.906704 -231.827798) (xy 370.859118 -231.809751) (xy 370.815044 -231.784305)
			(xy 370.775622 -231.752118) (xy 370.741874 -231.714024) (xy 370.714673 -231.67101) (xy 370.694725 -231.62419)
			(xy 370.682546 -231.574776) (xy 370.678451 -231.524048) (xy 370.370608 -231.524048) (xy 370.370096 -231.549494)
			(xy 370.361932 -231.599728) (xy 370.345816 -231.648002) (xy 370.322165 -231.693065) (xy 370.291592 -231.733751)
			(xy 370.254888 -231.769006) (xy 370.213004 -231.797916) (xy 370.167025 -231.819733) (xy 370.118141 -231.833893)
			(xy 370.06762 -231.840027) (xy 370.016768 -231.837978) (xy 369.966904 -231.827798) (xy 369.919318 -231.809751)
			(xy 369.875244 -231.784305) (xy 369.835822 -231.752118) (xy 369.802074 -231.714024) (xy 369.774873 -231.67101)
			(xy 369.754925 -231.62419) (xy 369.742746 -231.574776) (xy 369.738651 -231.524048) (xy 369.42014 -231.524048)
			(xy 369.419645 -231.548655) (xy 369.41175 -231.597232) (xy 369.396166 -231.643913) (xy 369.373295 -231.68749)
			(xy 369.34373 -231.726834) (xy 369.308237 -231.760926) (xy 369.267734 -231.788882) (xy 369.223272 -231.80998)
			(xy 369.176001 -231.823672) (xy 369.127146 -231.829604) (xy 369.077971 -231.827623) (xy 369.029752 -231.817779)
			(xy 368.983736 -231.800327) (xy 368.941115 -231.77572) (xy 368.902994 -231.744595) (xy 368.870359 -231.707758)
			(xy 368.844056 -231.666162) (xy 368.824765 -231.620886) (xy 368.812988 -231.573102) (xy 368.809028 -231.524048)
			(xy 368.4905 -231.524048) (xy 368.489988 -231.549494) (xy 368.481824 -231.599728) (xy 368.465708 -231.648002)
			(xy 368.442057 -231.693065) (xy 368.411484 -231.733751) (xy 368.37478 -231.769006) (xy 368.332896 -231.797916)
			(xy 368.286917 -231.819733) (xy 368.238033 -231.833893) (xy 368.187512 -231.840027) (xy 368.13666 -231.837978)
			(xy 368.086796 -231.827798) (xy 368.03921 -231.809751) (xy 367.995136 -231.784305) (xy 367.955714 -231.752118)
			(xy 367.921966 -231.714024) (xy 367.894765 -231.67101) (xy 367.874817 -231.62419) (xy 367.862638 -231.574776)
			(xy 367.858543 -231.524048) (xy 367.550446 -231.524048) (xy 367.549934 -231.549494) (xy 367.54177 -231.599728)
			(xy 367.525654 -231.648002) (xy 367.502003 -231.693065) (xy 367.47143 -231.733751) (xy 367.434726 -231.769006)
			(xy 367.392842 -231.797916) (xy 367.346863 -231.819733) (xy 367.297979 -231.833893) (xy 367.247458 -231.840027)
			(xy 367.196606 -231.837978) (xy 367.146742 -231.827798) (xy 367.099156 -231.809751) (xy 367.055082 -231.784305)
			(xy 367.01566 -231.752118) (xy 366.981912 -231.714024) (xy 366.954711 -231.67101) (xy 366.934763 -231.62419)
			(xy 366.922584 -231.574776) (xy 366.918489 -231.524048) (xy 366.600232 -231.524048) (xy 366.599737 -231.548655)
			(xy 366.591842 -231.597232) (xy 366.576258 -231.643913) (xy 366.553387 -231.68749) (xy 366.523822 -231.726834)
			(xy 366.488329 -231.760926) (xy 366.447826 -231.788882) (xy 366.403364 -231.80998) (xy 366.356093 -231.823672)
			(xy 366.307238 -231.829604) (xy 366.258063 -231.827623) (xy 366.209844 -231.817779) (xy 366.163828 -231.800327)
			(xy 366.121207 -231.77572) (xy 366.083086 -231.744595) (xy 366.050451 -231.707758) (xy 366.024148 -231.666162)
			(xy 366.004857 -231.620886) (xy 365.99308 -231.573102) (xy 365.98912 -231.524048) (xy 365.670592 -231.524048)
			(xy 365.67008 -231.549494) (xy 365.661916 -231.599728) (xy 365.6458 -231.648002) (xy 365.622149 -231.693065)
			(xy 365.591576 -231.733751) (xy 365.554872 -231.769006) (xy 365.512988 -231.797916) (xy 365.467009 -231.819733)
			(xy 365.418125 -231.833893) (xy 365.367604 -231.840027) (xy 365.316752 -231.837978) (xy 365.266888 -231.827798)
			(xy 365.219302 -231.809751) (xy 365.175228 -231.784305) (xy 365.135806 -231.752118) (xy 365.102058 -231.714024)
			(xy 365.074857 -231.67101) (xy 365.054909 -231.62419) (xy 365.04273 -231.574776) (xy 365.038635 -231.524048)
			(xy 364.730538 -231.524048) (xy 364.730026 -231.549494) (xy 364.721862 -231.599728) (xy 364.705746 -231.648002)
			(xy 364.682095 -231.693065) (xy 364.651522 -231.733751) (xy 364.614818 -231.769006) (xy 364.572934 -231.797916)
			(xy 364.526955 -231.819733) (xy 364.478071 -231.833893) (xy 364.42755 -231.840027) (xy 364.376698 -231.837978)
			(xy 364.326834 -231.827798) (xy 364.279248 -231.809751) (xy 364.235174 -231.784305) (xy 364.195752 -231.752118)
			(xy 364.162004 -231.714024) (xy 364.134803 -231.67101) (xy 364.114855 -231.62419) (xy 364.102676 -231.574776)
			(xy 364.098581 -231.524048) (xy 363.78007 -231.524048) (xy 363.779575 -231.548655) (xy 363.77168 -231.597232)
			(xy 363.756096 -231.643913) (xy 363.733225 -231.68749) (xy 363.70366 -231.726834) (xy 363.668167 -231.760926)
			(xy 363.627664 -231.788882) (xy 363.583202 -231.80998) (xy 363.535931 -231.823672) (xy 363.487076 -231.829604)
			(xy 363.437901 -231.827623) (xy 363.389682 -231.817779) (xy 363.343666 -231.800327) (xy 363.301045 -231.77572)
			(xy 363.262924 -231.744595) (xy 363.230289 -231.707758) (xy 363.203986 -231.666162) (xy 363.184695 -231.620886)
			(xy 363.172918 -231.573102) (xy 363.168958 -231.524048) (xy 360.83748 -231.524048) (xy 360.83748 -231.966262)
			(xy 360.83875 -231.977438) (xy 360.841036 -231.98836) (xy 360.844846 -231.999028) (xy 360.84891 -232.00741)
			(xy 360.93527 -232.060496) (xy 360.940934 -232.063714) (xy 360.953408 -232.067452) (xy 360.959908 -232.067862)
			(xy 360.97337 -232.06837) (xy 360.985308 -232.062274) (xy 361.006888 -232.051726) (xy 361.052544 -232.036806)
			(xy 361.099976 -232.029236) (xy 361.123992 -232.028746) (xy 361.124754 -232.028746) (xy 361.150018 -232.029235)
			(xy 361.199858 -232.037545) (xy 361.24765 -232.053946) (xy 361.29209 -232.07799) (xy 361.331967 -232.109021)
			(xy 361.366191 -232.146193) (xy 361.393829 -232.188492) (xy 361.414128 -232.234763) (xy 361.426533 -232.283745)
			(xy 361.430702 -232.334054) (xy 361.748573 -232.334054) (xy 361.752668 -232.283326) (xy 361.764847 -232.233912)
			(xy 361.784795 -232.187092) (xy 361.811996 -232.144078) (xy 361.845744 -232.105984) (xy 361.885166 -232.073797)
			(xy 361.92924 -232.048351) (xy 361.976826 -232.030304) (xy 362.02669 -232.020124) (xy 362.077542 -232.018075)
			(xy 362.128063 -232.024209) (xy 362.176947 -232.038369) (xy 362.222926 -232.060186) (xy 362.26481 -232.089096)
			(xy 362.301514 -232.124351) (xy 362.332087 -232.165037) (xy 362.355738 -232.2101) (xy 362.371854 -232.258374)
			(xy 362.380018 -232.308608) (xy 362.38053 -232.334054) (xy 362.688627 -232.334054) (xy 362.692722 -232.283326)
			(xy 362.704901 -232.233912) (xy 362.724849 -232.187092) (xy 362.75205 -232.144078) (xy 362.785798 -232.105984)
			(xy 362.82522 -232.073797) (xy 362.869294 -232.048351) (xy 362.91688 -232.030304) (xy 362.966744 -232.020124)
			(xy 363.017596 -232.018075) (xy 363.068117 -232.024209) (xy 363.117001 -232.038369) (xy 363.16298 -232.060186)
			(xy 363.204864 -232.089096) (xy 363.241568 -232.124351) (xy 363.272141 -232.165037) (xy 363.295792 -232.2101)
			(xy 363.311908 -232.258374) (xy 363.320072 -232.308608) (xy 363.320584 -232.334054) (xy 363.639112 -232.334054)
			(xy 363.643072 -232.285) (xy 363.654849 -232.237216) (xy 363.67414 -232.19194) (xy 363.700443 -232.150344)
			(xy 363.733078 -232.113507) (xy 363.771199 -232.082382) (xy 363.81382 -232.057775) (xy 363.859836 -232.040323)
			(xy 363.908055 -232.030479) (xy 363.95723 -232.028498) (xy 364.006085 -232.03443) (xy 364.053356 -232.048122)
			(xy 364.097818 -232.06922) (xy 364.138321 -232.097176) (xy 364.173814 -232.131268) (xy 364.203379 -232.170612)
			(xy 364.22625 -232.214189) (xy 364.241834 -232.26087) (xy 364.249729 -232.309447) (xy 364.250224 -232.334054)
			(xy 364.578912 -232.334054) (xy 364.582872 -232.285) (xy 364.594649 -232.237216) (xy 364.61394 -232.19194)
			(xy 364.640243 -232.150344) (xy 364.672878 -232.113507) (xy 364.710999 -232.082382) (xy 364.75362 -232.057775)
			(xy 364.799636 -232.040323) (xy 364.847855 -232.030479) (xy 364.89703 -232.028498) (xy 364.945885 -232.03443)
			(xy 364.993156 -232.048122) (xy 365.037618 -232.06922) (xy 365.078121 -232.097176) (xy 365.113614 -232.131268)
			(xy 365.143179 -232.170612) (xy 365.16605 -232.214189) (xy 365.181634 -232.26087) (xy 365.189529 -232.309447)
			(xy 365.190024 -232.334054) (xy 365.518966 -232.334054) (xy 365.522926 -232.285) (xy 365.534703 -232.237216)
			(xy 365.553994 -232.19194) (xy 365.580297 -232.150344) (xy 365.612932 -232.113507) (xy 365.651053 -232.082382)
			(xy 365.693674 -232.057775) (xy 365.73969 -232.040323) (xy 365.787909 -232.030479) (xy 365.837084 -232.028498)
			(xy 365.885939 -232.03443) (xy 365.93321 -232.048122) (xy 365.977672 -232.06922) (xy 366.018175 -232.097176)
			(xy 366.053668 -232.131268) (xy 366.083233 -232.170612) (xy 366.106104 -232.214189) (xy 366.121688 -232.26087)
			(xy 366.129583 -232.309447) (xy 366.130078 -232.334054) (xy 366.45902 -232.334054) (xy 366.46298 -232.285)
			(xy 366.474757 -232.237216) (xy 366.494048 -232.19194) (xy 366.520351 -232.150344) (xy 366.552986 -232.113507)
			(xy 366.591107 -232.082382) (xy 366.633728 -232.057775) (xy 366.679744 -232.040323) (xy 366.727963 -232.030479)
			(xy 366.777138 -232.028498) (xy 366.825993 -232.03443) (xy 366.873264 -232.048122) (xy 366.917726 -232.06922)
			(xy 366.958229 -232.097176) (xy 366.993722 -232.131268) (xy 367.023287 -232.170612) (xy 367.046158 -232.214189)
			(xy 367.061742 -232.26087) (xy 367.069637 -232.309447) (xy 367.070132 -232.334054) (xy 367.399074 -232.334054)
			(xy 367.403034 -232.285) (xy 367.414811 -232.237216) (xy 367.434102 -232.19194) (xy 367.460405 -232.150344)
			(xy 367.49304 -232.113507) (xy 367.531161 -232.082382) (xy 367.573782 -232.057775) (xy 367.619798 -232.040323)
			(xy 367.668017 -232.030479) (xy 367.717192 -232.028498) (xy 367.766047 -232.03443) (xy 367.813318 -232.048122)
			(xy 367.85778 -232.06922) (xy 367.898283 -232.097176) (xy 367.933776 -232.131268) (xy 367.963341 -232.170612)
			(xy 367.986212 -232.214189) (xy 368.001796 -232.26087) (xy 368.009691 -232.309447) (xy 368.010186 -232.334054)
			(xy 368.338874 -232.334054) (xy 368.342834 -232.285) (xy 368.354611 -232.237216) (xy 368.373902 -232.19194)
			(xy 368.400205 -232.150344) (xy 368.43284 -232.113507) (xy 368.470961 -232.082382) (xy 368.513582 -232.057775)
			(xy 368.559598 -232.040323) (xy 368.607817 -232.030479) (xy 368.656992 -232.028498) (xy 368.705847 -232.03443)
			(xy 368.753118 -232.048122) (xy 368.79758 -232.06922) (xy 368.838083 -232.097176) (xy 368.873576 -232.131268)
			(xy 368.903141 -232.170612) (xy 368.926012 -232.214189) (xy 368.941596 -232.26087) (xy 368.949491 -232.309447)
			(xy 368.949986 -232.334054) (xy 369.278928 -232.334054) (xy 369.282888 -232.285) (xy 369.294665 -232.237216)
			(xy 369.313956 -232.19194) (xy 369.340259 -232.150344) (xy 369.372894 -232.113507) (xy 369.411015 -232.082382)
			(xy 369.453636 -232.057775) (xy 369.499652 -232.040323) (xy 369.547871 -232.030479) (xy 369.597046 -232.028498)
			(xy 369.645901 -232.03443) (xy 369.693172 -232.048122) (xy 369.737634 -232.06922) (xy 369.778137 -232.097176)
			(xy 369.81363 -232.131268) (xy 369.843195 -232.170612) (xy 369.866066 -232.214189) (xy 369.88165 -232.26087)
			(xy 369.889545 -232.309447) (xy 369.89004 -232.334054) (xy 370.218982 -232.334054) (xy 370.222942 -232.285)
			(xy 370.234719 -232.237216) (xy 370.25401 -232.19194) (xy 370.280313 -232.150344) (xy 370.312948 -232.113507)
			(xy 370.351069 -232.082382) (xy 370.39369 -232.057775) (xy 370.439706 -232.040323) (xy 370.487925 -232.030479)
			(xy 370.5371 -232.028498) (xy 370.585955 -232.03443) (xy 370.633226 -232.048122) (xy 370.677688 -232.06922)
			(xy 370.718191 -232.097176) (xy 370.753684 -232.131268) (xy 370.783249 -232.170612) (xy 370.80612 -232.214189)
			(xy 370.821704 -232.26087) (xy 370.829599 -232.309447) (xy 370.830094 -232.334054) (xy 371.159036 -232.334054)
			(xy 371.162996 -232.285) (xy 371.174773 -232.237216) (xy 371.194064 -232.19194) (xy 371.220367 -232.150344)
			(xy 371.253002 -232.113507) (xy 371.291123 -232.082382) (xy 371.333744 -232.057775) (xy 371.37976 -232.040323)
			(xy 371.427979 -232.030479) (xy 371.477154 -232.028498) (xy 371.526009 -232.03443) (xy 371.57328 -232.048122)
			(xy 371.617742 -232.06922) (xy 371.658245 -232.097176) (xy 371.693738 -232.131268) (xy 371.723303 -232.170612)
			(xy 371.746174 -232.214189) (xy 371.761758 -232.26087) (xy 371.769653 -232.309447) (xy 371.770148 -232.334054)
			(xy 372.09909 -232.334054) (xy 372.10305 -232.285) (xy 372.114827 -232.237216) (xy 372.134118 -232.19194)
			(xy 372.160421 -232.150344) (xy 372.193056 -232.113507) (xy 372.231177 -232.082382) (xy 372.273798 -232.057775)
			(xy 372.319814 -232.040323) (xy 372.368033 -232.030479) (xy 372.417208 -232.028498) (xy 372.466063 -232.03443)
			(xy 372.513334 -232.048122) (xy 372.557796 -232.06922) (xy 372.598299 -232.097176) (xy 372.633792 -232.131268)
			(xy 372.663357 -232.170612) (xy 372.686228 -232.214189) (xy 372.701812 -232.26087) (xy 372.709707 -232.309447)
			(xy 372.710202 -232.334054) (xy 373.03889 -232.334054) (xy 373.04285 -232.285) (xy 373.054627 -232.237216)
			(xy 373.073918 -232.19194) (xy 373.100221 -232.150344) (xy 373.132856 -232.113507) (xy 373.170977 -232.082382)
			(xy 373.213598 -232.057775) (xy 373.259614 -232.040323) (xy 373.307833 -232.030479) (xy 373.357008 -232.028498)
			(xy 373.405863 -232.03443) (xy 373.453134 -232.048122) (xy 373.497596 -232.06922) (xy 373.538099 -232.097176)
			(xy 373.573592 -232.131268) (xy 373.603157 -232.170612) (xy 373.626028 -232.214189) (xy 373.641612 -232.26087)
			(xy 373.649507 -232.309447) (xy 373.650002 -232.334054) (xy 373.649507 -232.358661) (xy 373.641612 -232.407238)
			(xy 373.626028 -232.453919) (xy 373.603157 -232.497496) (xy 373.573592 -232.53684) (xy 373.538099 -232.570932)
			(xy 373.497596 -232.598888) (xy 373.453134 -232.619986) (xy 373.405863 -232.633678) (xy 373.357008 -232.63961)
			(xy 373.307833 -232.637629) (xy 373.259614 -232.627785) (xy 373.213598 -232.610333) (xy 373.170977 -232.585726)
			(xy 373.132856 -232.554601) (xy 373.100221 -232.517764) (xy 373.073918 -232.476168) (xy 373.054627 -232.430892)
			(xy 373.04285 -232.383108) (xy 373.03889 -232.334054) (xy 372.710202 -232.334054) (xy 372.709707 -232.358661)
			(xy 372.701812 -232.407238) (xy 372.686228 -232.453919) (xy 372.663357 -232.497496) (xy 372.633792 -232.53684)
			(xy 372.598299 -232.570932) (xy 372.557796 -232.598888) (xy 372.513334 -232.619986) (xy 372.466063 -232.633678)
			(xy 372.417208 -232.63961) (xy 372.368033 -232.637629) (xy 372.319814 -232.627785) (xy 372.273798 -232.610333)
			(xy 372.231177 -232.585726) (xy 372.193056 -232.554601) (xy 372.160421 -232.517764) (xy 372.134118 -232.476168)
			(xy 372.114827 -232.430892) (xy 372.10305 -232.383108) (xy 372.09909 -232.334054) (xy 371.770148 -232.334054)
			(xy 371.769653 -232.358661) (xy 371.761758 -232.407238) (xy 371.746174 -232.453919) (xy 371.723303 -232.497496)
			(xy 371.693738 -232.53684) (xy 371.658245 -232.570932) (xy 371.617742 -232.598888) (xy 371.57328 -232.619986)
			(xy 371.526009 -232.633678) (xy 371.477154 -232.63961) (xy 371.427979 -232.637629) (xy 371.37976 -232.627785)
			(xy 371.333744 -232.610333) (xy 371.291123 -232.585726) (xy 371.253002 -232.554601) (xy 371.220367 -232.517764)
			(xy 371.194064 -232.476168) (xy 371.174773 -232.430892) (xy 371.162996 -232.383108) (xy 371.159036 -232.334054)
			(xy 370.830094 -232.334054) (xy 370.829599 -232.358661) (xy 370.821704 -232.407238) (xy 370.80612 -232.453919)
			(xy 370.783249 -232.497496) (xy 370.753684 -232.53684) (xy 370.718191 -232.570932) (xy 370.677688 -232.598888)
			(xy 370.633226 -232.619986) (xy 370.585955 -232.633678) (xy 370.5371 -232.63961) (xy 370.487925 -232.637629)
			(xy 370.439706 -232.627785) (xy 370.39369 -232.610333) (xy 370.351069 -232.585726) (xy 370.312948 -232.554601)
			(xy 370.280313 -232.517764) (xy 370.25401 -232.476168) (xy 370.234719 -232.430892) (xy 370.222942 -232.383108)
			(xy 370.218982 -232.334054) (xy 369.89004 -232.334054) (xy 369.889545 -232.358661) (xy 369.88165 -232.407238)
			(xy 369.866066 -232.453919) (xy 369.843195 -232.497496) (xy 369.81363 -232.53684) (xy 369.778137 -232.570932)
			(xy 369.737634 -232.598888) (xy 369.693172 -232.619986) (xy 369.645901 -232.633678) (xy 369.597046 -232.63961)
			(xy 369.547871 -232.637629) (xy 369.499652 -232.627785) (xy 369.453636 -232.610333) (xy 369.411015 -232.585726)
			(xy 369.372894 -232.554601) (xy 369.340259 -232.517764) (xy 369.313956 -232.476168) (xy 369.294665 -232.430892)
			(xy 369.282888 -232.383108) (xy 369.278928 -232.334054) (xy 368.949986 -232.334054) (xy 368.949491 -232.358661)
			(xy 368.941596 -232.407238) (xy 368.926012 -232.453919) (xy 368.903141 -232.497496) (xy 368.873576 -232.53684)
			(xy 368.838083 -232.570932) (xy 368.79758 -232.598888) (xy 368.753118 -232.619986) (xy 368.705847 -232.633678)
			(xy 368.656992 -232.63961) (xy 368.607817 -232.637629) (xy 368.559598 -232.627785) (xy 368.513582 -232.610333)
			(xy 368.470961 -232.585726) (xy 368.43284 -232.554601) (xy 368.400205 -232.517764) (xy 368.373902 -232.476168)
			(xy 368.354611 -232.430892) (xy 368.342834 -232.383108) (xy 368.338874 -232.334054) (xy 368.010186 -232.334054)
			(xy 368.009691 -232.358661) (xy 368.001796 -232.407238) (xy 367.986212 -232.453919) (xy 367.963341 -232.497496)
			(xy 367.933776 -232.53684) (xy 367.898283 -232.570932) (xy 367.85778 -232.598888) (xy 367.813318 -232.619986)
			(xy 367.766047 -232.633678) (xy 367.717192 -232.63961) (xy 367.668017 -232.637629) (xy 367.619798 -232.627785)
			(xy 367.573782 -232.610333) (xy 367.531161 -232.585726) (xy 367.49304 -232.554601) (xy 367.460405 -232.517764)
			(xy 367.434102 -232.476168) (xy 367.414811 -232.430892) (xy 367.403034 -232.383108) (xy 367.399074 -232.334054)
			(xy 367.070132 -232.334054) (xy 367.069637 -232.358661) (xy 367.061742 -232.407238) (xy 367.046158 -232.453919)
			(xy 367.023287 -232.497496) (xy 366.993722 -232.53684) (xy 366.958229 -232.570932) (xy 366.917726 -232.598888)
			(xy 366.873264 -232.619986) (xy 366.825993 -232.633678) (xy 366.777138 -232.63961) (xy 366.727963 -232.637629)
			(xy 366.679744 -232.627785) (xy 366.633728 -232.610333) (xy 366.591107 -232.585726) (xy 366.552986 -232.554601)
			(xy 366.520351 -232.517764) (xy 366.494048 -232.476168) (xy 366.474757 -232.430892) (xy 366.46298 -232.383108)
			(xy 366.45902 -232.334054) (xy 366.130078 -232.334054) (xy 366.129583 -232.358661) (xy 366.121688 -232.407238)
			(xy 366.106104 -232.453919) (xy 366.083233 -232.497496) (xy 366.053668 -232.53684) (xy 366.018175 -232.570932)
			(xy 365.977672 -232.598888) (xy 365.93321 -232.619986) (xy 365.885939 -232.633678) (xy 365.837084 -232.63961)
			(xy 365.787909 -232.637629) (xy 365.73969 -232.627785) (xy 365.693674 -232.610333) (xy 365.651053 -232.585726)
			(xy 365.612932 -232.554601) (xy 365.580297 -232.517764) (xy 365.553994 -232.476168) (xy 365.534703 -232.430892)
			(xy 365.522926 -232.383108) (xy 365.518966 -232.334054) (xy 365.190024 -232.334054) (xy 365.189529 -232.358661)
			(xy 365.181634 -232.407238) (xy 365.16605 -232.453919) (xy 365.143179 -232.497496) (xy 365.113614 -232.53684)
			(xy 365.078121 -232.570932) (xy 365.037618 -232.598888) (xy 364.993156 -232.619986) (xy 364.945885 -232.633678)
			(xy 364.89703 -232.63961) (xy 364.847855 -232.637629) (xy 364.799636 -232.627785) (xy 364.75362 -232.610333)
			(xy 364.710999 -232.585726) (xy 364.672878 -232.554601) (xy 364.640243 -232.517764) (xy 364.61394 -232.476168)
			(xy 364.594649 -232.430892) (xy 364.582872 -232.383108) (xy 364.578912 -232.334054) (xy 364.250224 -232.334054)
			(xy 364.249729 -232.358661) (xy 364.241834 -232.407238) (xy 364.22625 -232.453919) (xy 364.203379 -232.497496)
			(xy 364.173814 -232.53684) (xy 364.138321 -232.570932) (xy 364.097818 -232.598888) (xy 364.053356 -232.619986)
			(xy 364.006085 -232.633678) (xy 363.95723 -232.63961) (xy 363.908055 -232.637629) (xy 363.859836 -232.627785)
			(xy 363.81382 -232.610333) (xy 363.771199 -232.585726) (xy 363.733078 -232.554601) (xy 363.700443 -232.517764)
			(xy 363.67414 -232.476168) (xy 363.654849 -232.430892) (xy 363.643072 -232.383108) (xy 363.639112 -232.334054)
			(xy 363.320584 -232.334054) (xy 363.320072 -232.3595) (xy 363.311908 -232.409734) (xy 363.295792 -232.458008)
			(xy 363.272141 -232.503071) (xy 363.241568 -232.543757) (xy 363.204864 -232.579012) (xy 363.16298 -232.607922)
			(xy 363.117001 -232.629739) (xy 363.068117 -232.643899) (xy 363.017596 -232.650033) (xy 362.966744 -232.647984)
			(xy 362.91688 -232.637804) (xy 362.869294 -232.619757) (xy 362.82522 -232.594311) (xy 362.785798 -232.562124)
			(xy 362.75205 -232.52403) (xy 362.724849 -232.481016) (xy 362.704901 -232.434196) (xy 362.692722 -232.384782)
			(xy 362.688627 -232.334054) (xy 362.38053 -232.334054) (xy 362.380018 -232.3595) (xy 362.371854 -232.409734)
			(xy 362.355738 -232.458008) (xy 362.332087 -232.503071) (xy 362.301514 -232.543757) (xy 362.26481 -232.579012)
			(xy 362.222926 -232.607922) (xy 362.176947 -232.629739) (xy 362.128063 -232.643899) (xy 362.077542 -232.650033)
			(xy 362.02669 -232.647984) (xy 361.976826 -232.637804) (xy 361.92924 -232.619757) (xy 361.885166 -232.594311)
			(xy 361.845744 -232.562124) (xy 361.811996 -232.52403) (xy 361.784795 -232.481016) (xy 361.764847 -232.434196)
			(xy 361.752668 -232.384782) (xy 361.748573 -232.334054) (xy 361.430702 -232.334054) (xy 361.430706 -232.3341)
			(xy 361.426533 -232.384455) (xy 361.414128 -232.433437) (xy 361.393829 -232.479708) (xy 361.366191 -232.522007)
			(xy 361.331967 -232.559179) (xy 361.29209 -232.59021) (xy 361.24765 -232.614254) (xy 361.199858 -232.630655)
			(xy 361.150018 -232.638965) (xy 361.124754 -232.639362) (xy 361.123992 -232.639362) (xy 361.09998 -232.638845)
			(xy 361.052559 -232.63125) (xy 361.006906 -232.616341) (xy 360.985308 -232.605834) (xy 360.985054 -232.605834)
			(xy 360.97921 -232.603093) (xy 360.966617 -232.600281) (xy 360.960162 -232.600246) (xy 360.9467 -232.600754)
			(xy 360.861864 -232.652824) (xy 360.855681 -232.656812) (xy 360.845748 -232.667657) (xy 360.842306 -232.67416)
			(xy 360.83748 -232.684828) (xy 360.83748 -233.14406) (xy 361.289104 -233.14406) (xy 361.293064 -233.095006)
			(xy 361.304841 -233.047222) (xy 361.324132 -233.001946) (xy 361.350435 -232.96035) (xy 361.38307 -232.923513)
			(xy 361.421191 -232.892388) (xy 361.463812 -232.867781) (xy 361.509828 -232.850329) (xy 361.558047 -232.840485)
			(xy 361.607222 -232.838504) (xy 361.656077 -232.844436) (xy 361.703348 -232.858128) (xy 361.74781 -232.879226)
			(xy 361.788313 -232.907182) (xy 361.823806 -232.941274) (xy 361.853371 -232.980618) (xy 361.876242 -233.024195)
			(xy 361.891826 -233.070876) (xy 361.899721 -233.119453) (xy 361.900216 -233.14406) (xy 362.228904 -233.14406)
			(xy 362.232864 -233.095006) (xy 362.244641 -233.047222) (xy 362.263932 -233.001946) (xy 362.290235 -232.96035)
			(xy 362.32287 -232.923513) (xy 362.360991 -232.892388) (xy 362.403612 -232.867781) (xy 362.449628 -232.850329)
			(xy 362.497847 -232.840485) (xy 362.547022 -232.838504) (xy 362.595877 -232.844436) (xy 362.643148 -232.858128)
			(xy 362.68761 -232.879226) (xy 362.728113 -232.907182) (xy 362.763606 -232.941274) (xy 362.793171 -232.980618)
			(xy 362.816042 -233.024195) (xy 362.831626 -233.070876) (xy 362.839521 -233.119453) (xy 362.840016 -233.14406)
			(xy 363.168958 -233.14406) (xy 363.172918 -233.095006) (xy 363.184695 -233.047222) (xy 363.203986 -233.001946)
			(xy 363.230289 -232.96035) (xy 363.262924 -232.923513) (xy 363.301045 -232.892388) (xy 363.343666 -232.867781)
			(xy 363.389682 -232.850329) (xy 363.437901 -232.840485) (xy 363.487076 -232.838504) (xy 363.535931 -232.844436)
			(xy 363.583202 -232.858128) (xy 363.627664 -232.879226) (xy 363.668167 -232.907182) (xy 363.70366 -232.941274)
			(xy 363.733225 -232.980618) (xy 363.756096 -233.024195) (xy 363.77168 -233.070876) (xy 363.779575 -233.119453)
			(xy 363.78007 -233.14406) (xy 364.098581 -233.14406) (xy 364.102676 -233.093332) (xy 364.114855 -233.043918)
			(xy 364.134803 -232.997098) (xy 364.162004 -232.954084) (xy 364.195752 -232.91599) (xy 364.235174 -232.883803)
			(xy 364.279248 -232.858357) (xy 364.326834 -232.84031) (xy 364.376698 -232.83013) (xy 364.42755 -232.828081)
			(xy 364.478071 -232.834215) (xy 364.526955 -232.848375) (xy 364.572934 -232.870192) (xy 364.614818 -232.899102)
			(xy 364.651522 -232.934357) (xy 364.682095 -232.975043) (xy 364.705746 -233.020106) (xy 364.721862 -233.06838)
			(xy 364.730026 -233.118614) (xy 364.730538 -233.14406) (xy 365.038635 -233.14406) (xy 365.04273 -233.093332)
			(xy 365.054909 -233.043918) (xy 365.074857 -232.997098) (xy 365.102058 -232.954084) (xy 365.135806 -232.91599)
			(xy 365.175228 -232.883803) (xy 365.219302 -232.858357) (xy 365.266888 -232.84031) (xy 365.316752 -232.83013)
			(xy 365.367604 -232.828081) (xy 365.418125 -232.834215) (xy 365.467009 -232.848375) (xy 365.512988 -232.870192)
			(xy 365.554872 -232.899102) (xy 365.591576 -232.934357) (xy 365.622149 -232.975043) (xy 365.6458 -233.020106)
			(xy 365.661916 -233.06838) (xy 365.67008 -233.118614) (xy 365.670592 -233.14406) (xy 365.98912 -233.14406)
			(xy 365.99308 -233.095006) (xy 366.004857 -233.047222) (xy 366.024148 -233.001946) (xy 366.050451 -232.96035)
			(xy 366.083086 -232.923513) (xy 366.121207 -232.892388) (xy 366.163828 -232.867781) (xy 366.209844 -232.850329)
			(xy 366.258063 -232.840485) (xy 366.307238 -232.838504) (xy 366.356093 -232.844436) (xy 366.403364 -232.858128)
			(xy 366.447826 -232.879226) (xy 366.488329 -232.907182) (xy 366.523822 -232.941274) (xy 366.553387 -232.980618)
			(xy 366.576258 -233.024195) (xy 366.591842 -233.070876) (xy 366.599737 -233.119453) (xy 366.600232 -233.14406)
			(xy 366.918489 -233.14406) (xy 366.922584 -233.093332) (xy 366.934763 -233.043918) (xy 366.954711 -232.997098)
			(xy 366.981912 -232.954084) (xy 367.01566 -232.91599) (xy 367.055082 -232.883803) (xy 367.099156 -232.858357)
			(xy 367.146742 -232.84031) (xy 367.196606 -232.83013) (xy 367.247458 -232.828081) (xy 367.297979 -232.834215)
			(xy 367.346863 -232.848375) (xy 367.392842 -232.870192) (xy 367.434726 -232.899102) (xy 367.47143 -232.934357)
			(xy 367.502003 -232.975043) (xy 367.525654 -233.020106) (xy 367.54177 -233.06838) (xy 367.549934 -233.118614)
			(xy 367.550446 -233.14406) (xy 367.858543 -233.14406) (xy 367.862638 -233.093332) (xy 367.874817 -233.043918)
			(xy 367.894765 -232.997098) (xy 367.921966 -232.954084) (xy 367.955714 -232.91599) (xy 367.995136 -232.883803)
			(xy 368.03921 -232.858357) (xy 368.086796 -232.84031) (xy 368.13666 -232.83013) (xy 368.187512 -232.828081)
			(xy 368.238033 -232.834215) (xy 368.286917 -232.848375) (xy 368.332896 -232.870192) (xy 368.37478 -232.899102)
			(xy 368.411484 -232.934357) (xy 368.442057 -232.975043) (xy 368.465708 -233.020106) (xy 368.481824 -233.06838)
			(xy 368.489988 -233.118614) (xy 368.4905 -233.14406) (xy 368.809028 -233.14406) (xy 368.812988 -233.095006)
			(xy 368.824765 -233.047222) (xy 368.844056 -233.001946) (xy 368.870359 -232.96035) (xy 368.902994 -232.923513)
			(xy 368.941115 -232.892388) (xy 368.983736 -232.867781) (xy 369.029752 -232.850329) (xy 369.077971 -232.840485)
			(xy 369.127146 -232.838504) (xy 369.176001 -232.844436) (xy 369.223272 -232.858128) (xy 369.267734 -232.879226)
			(xy 369.308237 -232.907182) (xy 369.34373 -232.941274) (xy 369.373295 -232.980618) (xy 369.396166 -233.024195)
			(xy 369.41175 -233.070876) (xy 369.419645 -233.119453) (xy 369.42014 -233.14406) (xy 369.738651 -233.14406)
			(xy 369.742746 -233.093332) (xy 369.754925 -233.043918) (xy 369.774873 -232.997098) (xy 369.802074 -232.954084)
			(xy 369.835822 -232.91599) (xy 369.875244 -232.883803) (xy 369.919318 -232.858357) (xy 369.966904 -232.84031)
			(xy 370.016768 -232.83013) (xy 370.06762 -232.828081) (xy 370.118141 -232.834215) (xy 370.167025 -232.848375)
			(xy 370.213004 -232.870192) (xy 370.254888 -232.899102) (xy 370.291592 -232.934357) (xy 370.322165 -232.975043)
			(xy 370.345816 -233.020106) (xy 370.361932 -233.06838) (xy 370.370096 -233.118614) (xy 370.370608 -233.14406)
			(xy 370.678451 -233.14406) (xy 370.682546 -233.093332) (xy 370.694725 -233.043918) (xy 370.714673 -232.997098)
			(xy 370.741874 -232.954084) (xy 370.775622 -232.91599) (xy 370.815044 -232.883803) (xy 370.859118 -232.858357)
			(xy 370.906704 -232.84031) (xy 370.956568 -232.83013) (xy 371.00742 -232.828081) (xy 371.057941 -232.834215)
			(xy 371.106825 -232.848375) (xy 371.152804 -232.870192) (xy 371.194688 -232.899102) (xy 371.231392 -232.934357)
			(xy 371.261965 -232.975043) (xy 371.285616 -233.020106) (xy 371.301732 -233.06838) (xy 371.309896 -233.118614)
			(xy 371.310408 -233.14406) (xy 371.628936 -233.14406) (xy 371.632896 -233.095006) (xy 371.644673 -233.047222)
			(xy 371.663964 -233.001946) (xy 371.690267 -232.96035) (xy 371.722902 -232.923513) (xy 371.761023 -232.892388)
			(xy 371.803644 -232.867781) (xy 371.84966 -232.850329) (xy 371.897879 -232.840485) (xy 371.947054 -232.838504)
			(xy 371.995909 -232.844436) (xy 372.04318 -232.858128) (xy 372.087642 -232.879226) (xy 372.128145 -232.907182)
			(xy 372.163638 -232.941274) (xy 372.193203 -232.980618) (xy 372.216074 -233.024195) (xy 372.231658 -233.070876)
			(xy 372.239553 -233.119453) (xy 372.240048 -233.14406) (xy 372.558559 -233.14406) (xy 372.562654 -233.093332)
			(xy 372.574833 -233.043918) (xy 372.594781 -232.997098) (xy 372.621982 -232.954084) (xy 372.65573 -232.91599)
			(xy 372.695152 -232.883803) (xy 372.739226 -232.858357) (xy 372.786812 -232.84031) (xy 372.836676 -232.83013)
			(xy 372.887528 -232.828081) (xy 372.938049 -232.834215) (xy 372.986933 -232.848375) (xy 373.032912 -232.870192)
			(xy 373.074796 -232.899102) (xy 373.1115 -232.934357) (xy 373.142073 -232.975043) (xy 373.165724 -233.020106)
			(xy 373.18184 -233.06838) (xy 373.190004 -233.118614) (xy 373.190516 -233.14406) (xy 373.498613 -233.14406)
			(xy 373.502708 -233.093332) (xy 373.514887 -233.043918) (xy 373.534835 -232.997098) (xy 373.562036 -232.954084)
			(xy 373.595784 -232.91599) (xy 373.635206 -232.883803) (xy 373.67928 -232.858357) (xy 373.726866 -232.84031)
			(xy 373.77673 -232.83013) (xy 373.827582 -232.828081) (xy 373.878103 -232.834215) (xy 373.926987 -232.848375)
			(xy 373.972966 -232.870192) (xy 374.01485 -232.899102) (xy 374.051554 -232.934357) (xy 374.082127 -232.975043)
			(xy 374.105778 -233.020106) (xy 374.121894 -233.06838) (xy 374.130058 -233.118614) (xy 374.13057 -233.14406)
			(xy 374.130058 -233.169506) (xy 374.121894 -233.21974) (xy 374.105778 -233.268014) (xy 374.082127 -233.313077)
			(xy 374.051554 -233.353763) (xy 374.01485 -233.389018) (xy 373.972966 -233.417928) (xy 373.926987 -233.439745)
			(xy 373.878103 -233.453905) (xy 373.827582 -233.460039) (xy 373.77673 -233.45799) (xy 373.726866 -233.44781)
			(xy 373.67928 -233.429763) (xy 373.635206 -233.404317) (xy 373.595784 -233.37213) (xy 373.562036 -233.334036)
			(xy 373.534835 -233.291022) (xy 373.514887 -233.244202) (xy 373.502708 -233.194788) (xy 373.498613 -233.14406)
			(xy 373.190516 -233.14406) (xy 373.190004 -233.169506) (xy 373.18184 -233.21974) (xy 373.165724 -233.268014)
			(xy 373.142073 -233.313077) (xy 373.1115 -233.353763) (xy 373.074796 -233.389018) (xy 373.032912 -233.417928)
			(xy 372.986933 -233.439745) (xy 372.938049 -233.453905) (xy 372.887528 -233.460039) (xy 372.836676 -233.45799)
			(xy 372.786812 -233.44781) (xy 372.739226 -233.429763) (xy 372.695152 -233.404317) (xy 372.65573 -233.37213)
			(xy 372.621982 -233.334036) (xy 372.594781 -233.291022) (xy 372.574833 -233.244202) (xy 372.562654 -233.194788)
			(xy 372.558559 -233.14406) (xy 372.240048 -233.14406) (xy 372.239553 -233.168667) (xy 372.231658 -233.217244)
			(xy 372.216074 -233.263925) (xy 372.193203 -233.307502) (xy 372.163638 -233.346846) (xy 372.128145 -233.380938)
			(xy 372.087642 -233.408894) (xy 372.04318 -233.429992) (xy 371.995909 -233.443684) (xy 371.947054 -233.449616)
			(xy 371.897879 -233.447635) (xy 371.84966 -233.437791) (xy 371.803644 -233.420339) (xy 371.761023 -233.395732)
			(xy 371.722902 -233.364607) (xy 371.690267 -233.32777) (xy 371.663964 -233.286174) (xy 371.644673 -233.240898)
			(xy 371.632896 -233.193114) (xy 371.628936 -233.14406) (xy 371.310408 -233.14406) (xy 371.309896 -233.169506)
			(xy 371.301732 -233.21974) (xy 371.285616 -233.268014) (xy 371.261965 -233.313077) (xy 371.231392 -233.353763)
			(xy 371.194688 -233.389018) (xy 371.152804 -233.417928) (xy 371.106825 -233.439745) (xy 371.057941 -233.453905)
			(xy 371.00742 -233.460039) (xy 370.956568 -233.45799) (xy 370.906704 -233.44781) (xy 370.859118 -233.429763)
			(xy 370.815044 -233.404317) (xy 370.775622 -233.37213) (xy 370.741874 -233.334036) (xy 370.714673 -233.291022)
			(xy 370.694725 -233.244202) (xy 370.682546 -233.194788) (xy 370.678451 -233.14406) (xy 370.370608 -233.14406)
			(xy 370.370096 -233.169506) (xy 370.361932 -233.21974) (xy 370.345816 -233.268014) (xy 370.322165 -233.313077)
			(xy 370.291592 -233.353763) (xy 370.254888 -233.389018) (xy 370.213004 -233.417928) (xy 370.167025 -233.439745)
			(xy 370.118141 -233.453905) (xy 370.06762 -233.460039) (xy 370.016768 -233.45799) (xy 369.966904 -233.44781)
			(xy 369.919318 -233.429763) (xy 369.875244 -233.404317) (xy 369.835822 -233.37213) (xy 369.802074 -233.334036)
			(xy 369.774873 -233.291022) (xy 369.754925 -233.244202) (xy 369.742746 -233.194788) (xy 369.738651 -233.14406)
			(xy 369.42014 -233.14406) (xy 369.419645 -233.168667) (xy 369.41175 -233.217244) (xy 369.396166 -233.263925)
			(xy 369.373295 -233.307502) (xy 369.34373 -233.346846) (xy 369.308237 -233.380938) (xy 369.267734 -233.408894)
			(xy 369.223272 -233.429992) (xy 369.176001 -233.443684) (xy 369.127146 -233.449616) (xy 369.077971 -233.447635)
			(xy 369.029752 -233.437791) (xy 368.983736 -233.420339) (xy 368.941115 -233.395732) (xy 368.902994 -233.364607)
			(xy 368.870359 -233.32777) (xy 368.844056 -233.286174) (xy 368.824765 -233.240898) (xy 368.812988 -233.193114)
			(xy 368.809028 -233.14406) (xy 368.4905 -233.14406) (xy 368.489988 -233.169506) (xy 368.481824 -233.21974)
			(xy 368.465708 -233.268014) (xy 368.442057 -233.313077) (xy 368.411484 -233.353763) (xy 368.37478 -233.389018)
			(xy 368.332896 -233.417928) (xy 368.286917 -233.439745) (xy 368.238033 -233.453905) (xy 368.187512 -233.460039)
			(xy 368.13666 -233.45799) (xy 368.086796 -233.44781) (xy 368.03921 -233.429763) (xy 367.995136 -233.404317)
			(xy 367.955714 -233.37213) (xy 367.921966 -233.334036) (xy 367.894765 -233.291022) (xy 367.874817 -233.244202)
			(xy 367.862638 -233.194788) (xy 367.858543 -233.14406) (xy 367.550446 -233.14406) (xy 367.549934 -233.169506)
			(xy 367.54177 -233.21974) (xy 367.525654 -233.268014) (xy 367.502003 -233.313077) (xy 367.47143 -233.353763)
			(xy 367.434726 -233.389018) (xy 367.392842 -233.417928) (xy 367.346863 -233.439745) (xy 367.297979 -233.453905)
			(xy 367.247458 -233.460039) (xy 367.196606 -233.45799) (xy 367.146742 -233.44781) (xy 367.099156 -233.429763)
			(xy 367.055082 -233.404317) (xy 367.01566 -233.37213) (xy 366.981912 -233.334036) (xy 366.954711 -233.291022)
			(xy 366.934763 -233.244202) (xy 366.922584 -233.194788) (xy 366.918489 -233.14406) (xy 366.600232 -233.14406)
			(xy 366.599737 -233.168667) (xy 366.591842 -233.217244) (xy 366.576258 -233.263925) (xy 366.553387 -233.307502)
			(xy 366.523822 -233.346846) (xy 366.488329 -233.380938) (xy 366.447826 -233.408894) (xy 366.403364 -233.429992)
			(xy 366.356093 -233.443684) (xy 366.307238 -233.449616) (xy 366.258063 -233.447635) (xy 366.209844 -233.437791)
			(xy 366.163828 -233.420339) (xy 366.121207 -233.395732) (xy 366.083086 -233.364607) (xy 366.050451 -233.32777)
			(xy 366.024148 -233.286174) (xy 366.004857 -233.240898) (xy 365.99308 -233.193114) (xy 365.98912 -233.14406)
			(xy 365.670592 -233.14406) (xy 365.67008 -233.169506) (xy 365.661916 -233.21974) (xy 365.6458 -233.268014)
			(xy 365.622149 -233.313077) (xy 365.591576 -233.353763) (xy 365.554872 -233.389018) (xy 365.512988 -233.417928)
			(xy 365.467009 -233.439745) (xy 365.418125 -233.453905) (xy 365.367604 -233.460039) (xy 365.316752 -233.45799)
			(xy 365.266888 -233.44781) (xy 365.219302 -233.429763) (xy 365.175228 -233.404317) (xy 365.135806 -233.37213)
			(xy 365.102058 -233.334036) (xy 365.074857 -233.291022) (xy 365.054909 -233.244202) (xy 365.04273 -233.194788)
			(xy 365.038635 -233.14406) (xy 364.730538 -233.14406) (xy 364.730026 -233.169506) (xy 364.721862 -233.21974)
			(xy 364.705746 -233.268014) (xy 364.682095 -233.313077) (xy 364.651522 -233.353763) (xy 364.614818 -233.389018)
			(xy 364.572934 -233.417928) (xy 364.526955 -233.439745) (xy 364.478071 -233.453905) (xy 364.42755 -233.460039)
			(xy 364.376698 -233.45799) (xy 364.326834 -233.44781) (xy 364.279248 -233.429763) (xy 364.235174 -233.404317)
			(xy 364.195752 -233.37213) (xy 364.162004 -233.334036) (xy 364.134803 -233.291022) (xy 364.114855 -233.244202)
			(xy 364.102676 -233.194788) (xy 364.098581 -233.14406) (xy 363.78007 -233.14406) (xy 363.779575 -233.168667)
			(xy 363.77168 -233.217244) (xy 363.756096 -233.263925) (xy 363.733225 -233.307502) (xy 363.70366 -233.346846)
			(xy 363.668167 -233.380938) (xy 363.627664 -233.408894) (xy 363.583202 -233.429992) (xy 363.535931 -233.443684)
			(xy 363.487076 -233.449616) (xy 363.437901 -233.447635) (xy 363.389682 -233.437791) (xy 363.343666 -233.420339)
			(xy 363.301045 -233.395732) (xy 363.262924 -233.364607) (xy 363.230289 -233.32777) (xy 363.203986 -233.286174)
			(xy 363.184695 -233.240898) (xy 363.172918 -233.193114) (xy 363.168958 -233.14406) (xy 362.840016 -233.14406)
			(xy 362.839521 -233.168667) (xy 362.831626 -233.217244) (xy 362.816042 -233.263925) (xy 362.793171 -233.307502)
			(xy 362.763606 -233.346846) (xy 362.728113 -233.380938) (xy 362.68761 -233.408894) (xy 362.643148 -233.429992)
			(xy 362.595877 -233.443684) (xy 362.547022 -233.449616) (xy 362.497847 -233.447635) (xy 362.449628 -233.437791)
			(xy 362.403612 -233.420339) (xy 362.360991 -233.395732) (xy 362.32287 -233.364607) (xy 362.290235 -233.32777)
			(xy 362.263932 -233.286174) (xy 362.244641 -233.240898) (xy 362.232864 -233.193114) (xy 362.228904 -233.14406)
			(xy 361.900216 -233.14406) (xy 361.899721 -233.168667) (xy 361.891826 -233.217244) (xy 361.876242 -233.263925)
			(xy 361.853371 -233.307502) (xy 361.823806 -233.346846) (xy 361.788313 -233.380938) (xy 361.74781 -233.408894)
			(xy 361.703348 -233.429992) (xy 361.656077 -233.443684) (xy 361.607222 -233.449616) (xy 361.558047 -233.447635)
			(xy 361.509828 -233.437791) (xy 361.463812 -233.420339) (xy 361.421191 -233.395732) (xy 361.38307 -233.364607)
			(xy 361.350435 -233.32777) (xy 361.324132 -233.286174) (xy 361.304841 -233.240898) (xy 361.293064 -233.193114)
			(xy 361.289104 -233.14406) (xy 360.83748 -233.14406) (xy 360.83748 -233.586274) (xy 360.83875 -233.59745)
			(xy 360.841036 -233.608372) (xy 360.844846 -233.61904) (xy 360.84891 -233.627422) (xy 360.93527 -233.680508)
			(xy 360.940934 -233.683725) (xy 360.953408 -233.687463) (xy 360.959908 -233.687874) (xy 360.97337 -233.688382)
			(xy 360.985308 -233.682286) (xy 361.006888 -233.671737) (xy 361.052544 -233.656817) (xy 361.099976 -233.649247)
			(xy 361.123992 -233.648758) (xy 361.124754 -233.648758) (xy 361.150017 -233.649247) (xy 361.199855 -233.657557)
			(xy 361.247645 -233.673957) (xy 361.292084 -233.698) (xy 361.331959 -233.72903) (xy 361.366181 -233.766201)
			(xy 361.393819 -233.808498) (xy 361.414117 -233.854767) (xy 361.426521 -233.903747) (xy 361.430691 -233.954066)
			(xy 361.748573 -233.954066) (xy 361.752668 -233.903338) (xy 361.764847 -233.853924) (xy 361.784795 -233.807104)
			(xy 361.811996 -233.76409) (xy 361.845744 -233.725996) (xy 361.885166 -233.693809) (xy 361.92924 -233.668363)
			(xy 361.976826 -233.650316) (xy 362.02669 -233.640136) (xy 362.077542 -233.638087) (xy 362.128063 -233.644221)
			(xy 362.176947 -233.658381) (xy 362.222926 -233.680198) (xy 362.26481 -233.709108) (xy 362.301514 -233.744363)
			(xy 362.332087 -233.785049) (xy 362.355738 -233.830112) (xy 362.371854 -233.878386) (xy 362.380018 -233.92862)
			(xy 362.38053 -233.954066) (xy 362.688627 -233.954066) (xy 362.692722 -233.903338) (xy 362.704901 -233.853924)
			(xy 362.724849 -233.807104) (xy 362.75205 -233.76409) (xy 362.785798 -233.725996) (xy 362.82522 -233.693809)
			(xy 362.869294 -233.668363) (xy 362.91688 -233.650316) (xy 362.966744 -233.640136) (xy 363.017596 -233.638087)
			(xy 363.068117 -233.644221) (xy 363.117001 -233.658381) (xy 363.16298 -233.680198) (xy 363.204864 -233.709108)
			(xy 363.241568 -233.744363) (xy 363.272141 -233.785049) (xy 363.295792 -233.830112) (xy 363.311908 -233.878386)
			(xy 363.320072 -233.92862) (xy 363.320584 -233.954066) (xy 363.639112 -233.954066) (xy 363.643072 -233.905012)
			(xy 363.654849 -233.857228) (xy 363.67414 -233.811952) (xy 363.700443 -233.770356) (xy 363.733078 -233.733519)
			(xy 363.771199 -233.702394) (xy 363.81382 -233.677787) (xy 363.859836 -233.660335) (xy 363.908055 -233.650491)
			(xy 363.95723 -233.64851) (xy 364.006085 -233.654442) (xy 364.053356 -233.668134) (xy 364.097818 -233.689232)
			(xy 364.138321 -233.717188) (xy 364.173814 -233.75128) (xy 364.203379 -233.790624) (xy 364.22625 -233.834201)
			(xy 364.241834 -233.880882) (xy 364.249729 -233.929459) (xy 364.250224 -233.954066) (xy 366.45902 -233.954066)
			(xy 366.46298 -233.905012) (xy 366.474757 -233.857228) (xy 366.494048 -233.811952) (xy 366.520351 -233.770356)
			(xy 366.552986 -233.733519) (xy 366.591107 -233.702394) (xy 366.633728 -233.677787) (xy 366.679744 -233.660335)
			(xy 366.727963 -233.650491) (xy 366.777138 -233.64851) (xy 366.825993 -233.654442) (xy 366.873264 -233.668134)
			(xy 366.917726 -233.689232) (xy 366.958229 -233.717188) (xy 366.993722 -233.75128) (xy 367.023287 -233.790624)
			(xy 367.046158 -233.834201) (xy 367.061742 -233.880882) (xy 367.069637 -233.929459) (xy 367.070132 -233.954066)
			(xy 369.278928 -233.954066) (xy 369.282888 -233.905012) (xy 369.294665 -233.857228) (xy 369.313956 -233.811952)
			(xy 369.340259 -233.770356) (xy 369.372894 -233.733519) (xy 369.411015 -233.702394) (xy 369.453636 -233.677787)
			(xy 369.499652 -233.660335) (xy 369.547871 -233.650491) (xy 369.597046 -233.64851) (xy 369.645901 -233.654442)
			(xy 369.693172 -233.668134) (xy 369.737634 -233.689232) (xy 369.778137 -233.717188) (xy 369.81363 -233.75128)
			(xy 369.843195 -233.790624) (xy 369.866066 -233.834201) (xy 369.88165 -233.880882) (xy 369.889545 -233.929459)
			(xy 369.89004 -233.954066) (xy 372.09909 -233.954066) (xy 372.10305 -233.905012) (xy 372.114827 -233.857228)
			(xy 372.134118 -233.811952) (xy 372.160421 -233.770356) (xy 372.193056 -233.733519) (xy 372.231177 -233.702394)
			(xy 372.273798 -233.677787) (xy 372.319814 -233.660335) (xy 372.368033 -233.650491) (xy 372.417208 -233.64851)
			(xy 372.466063 -233.654442) (xy 372.513334 -233.668134) (xy 372.557796 -233.689232) (xy 372.598299 -233.717188)
			(xy 372.633792 -233.75128) (xy 372.663357 -233.790624) (xy 372.686228 -233.834201) (xy 372.701812 -233.880882)
			(xy 372.709707 -233.929459) (xy 372.710202 -233.954066) (xy 372.709707 -233.978673) (xy 372.701812 -234.02725)
			(xy 372.686228 -234.073931) (xy 372.663357 -234.117508) (xy 372.633792 -234.156852) (xy 372.598299 -234.190944)
			(xy 372.557796 -234.2189) (xy 372.513334 -234.239998) (xy 372.466063 -234.25369) (xy 372.417208 -234.259622)
			(xy 372.368033 -234.257641) (xy 372.319814 -234.247797) (xy 372.273798 -234.230345) (xy 372.231177 -234.205738)
			(xy 372.193056 -234.174613) (xy 372.160421 -234.137776) (xy 372.134118 -234.09618) (xy 372.114827 -234.050904)
			(xy 372.10305 -234.00312) (xy 372.09909 -233.954066) (xy 369.89004 -233.954066) (xy 369.889545 -233.978673)
			(xy 369.88165 -234.02725) (xy 369.866066 -234.073931) (xy 369.843195 -234.117508) (xy 369.81363 -234.156852)
			(xy 369.778137 -234.190944) (xy 369.737634 -234.2189) (xy 369.693172 -234.239998) (xy 369.645901 -234.25369)
			(xy 369.597046 -234.259622) (xy 369.547871 -234.257641) (xy 369.499652 -234.247797) (xy 369.453636 -234.230345)
			(xy 369.411015 -234.205738) (xy 369.372894 -234.174613) (xy 369.340259 -234.137776) (xy 369.313956 -234.09618)
			(xy 369.294665 -234.050904) (xy 369.282888 -234.00312) (xy 369.278928 -233.954066) (xy 367.070132 -233.954066)
			(xy 367.069637 -233.978673) (xy 367.061742 -234.02725) (xy 367.046158 -234.073931) (xy 367.023287 -234.117508)
			(xy 366.993722 -234.156852) (xy 366.958229 -234.190944) (xy 366.917726 -234.2189) (xy 366.873264 -234.239998)
			(xy 366.825993 -234.25369) (xy 366.777138 -234.259622) (xy 366.727963 -234.257641) (xy 366.679744 -234.247797)
			(xy 366.633728 -234.230345) (xy 366.591107 -234.205738) (xy 366.552986 -234.174613) (xy 366.520351 -234.137776)
			(xy 366.494048 -234.09618) (xy 366.474757 -234.050904) (xy 366.46298 -234.00312) (xy 366.45902 -233.954066)
			(xy 364.250224 -233.954066) (xy 364.249729 -233.978673) (xy 364.241834 -234.02725) (xy 364.22625 -234.073931)
			(xy 364.203379 -234.117508) (xy 364.173814 -234.156852) (xy 364.138321 -234.190944) (xy 364.097818 -234.2189)
			(xy 364.053356 -234.239998) (xy 364.006085 -234.25369) (xy 363.95723 -234.259622) (xy 363.908055 -234.257641)
			(xy 363.859836 -234.247797) (xy 363.81382 -234.230345) (xy 363.771199 -234.205738) (xy 363.733078 -234.174613)
			(xy 363.700443 -234.137776) (xy 363.67414 -234.09618) (xy 363.654849 -234.050904) (xy 363.643072 -234.00312)
			(xy 363.639112 -233.954066) (xy 363.320584 -233.954066) (xy 363.320072 -233.979512) (xy 363.311908 -234.029746)
			(xy 363.295792 -234.07802) (xy 363.272141 -234.123083) (xy 363.241568 -234.163769) (xy 363.204864 -234.199024)
			(xy 363.16298 -234.227934) (xy 363.117001 -234.249751) (xy 363.068117 -234.263911) (xy 363.017596 -234.270045)
			(xy 362.966744 -234.267996) (xy 362.91688 -234.257816) (xy 362.869294 -234.239769) (xy 362.82522 -234.214323)
			(xy 362.785798 -234.182136) (xy 362.75205 -234.144042) (xy 362.724849 -234.101028) (xy 362.704901 -234.054208)
			(xy 362.692722 -234.004794) (xy 362.688627 -233.954066) (xy 362.38053 -233.954066) (xy 362.380018 -233.979512)
			(xy 362.371854 -234.029746) (xy 362.355738 -234.07802) (xy 362.332087 -234.123083) (xy 362.301514 -234.163769)
			(xy 362.26481 -234.199024) (xy 362.222926 -234.227934) (xy 362.176947 -234.249751) (xy 362.128063 -234.263911)
			(xy 362.077542 -234.270045) (xy 362.02669 -234.267996) (xy 361.976826 -234.257816) (xy 361.92924 -234.239769)
			(xy 361.885166 -234.214323) (xy 361.845744 -234.182136) (xy 361.811996 -234.144042) (xy 361.784795 -234.101028)
			(xy 361.764847 -234.054208) (xy 361.752668 -234.004794) (xy 361.748573 -233.954066) (xy 361.430691 -233.954066)
			(xy 361.430694 -233.9541) (xy 361.426521 -234.004453) (xy 361.414117 -234.053433) (xy 361.393819 -234.099702)
			(xy 361.366181 -234.141999) (xy 361.331959 -234.17917) (xy 361.292084 -234.2102) (xy 361.247645 -234.234243)
			(xy 361.199855 -234.250643) (xy 361.150017 -234.258953) (xy 361.124754 -234.259374) (xy 361.123992 -234.259374)
			(xy 361.09998 -234.258857) (xy 361.052558 -234.251262) (xy 361.006905 -234.236354) (xy 360.985308 -234.225846)
			(xy 360.985054 -234.225846) (xy 360.97921 -234.223105) (xy 360.966617 -234.220292) (xy 360.960162 -234.220258)
			(xy 360.9467 -234.220766) (xy 360.861864 -234.272836) (xy 360.855682 -234.276824) (xy 360.845751 -234.287671)
			(xy 360.842306 -234.294172) (xy 360.83748 -234.30484) (xy 360.83748 -234.764072) (xy 363.168958 -234.764072)
			(xy 363.172918 -234.715018) (xy 363.184695 -234.667234) (xy 363.203986 -234.621958) (xy 363.230289 -234.580362)
			(xy 363.262924 -234.543525) (xy 363.301045 -234.5124) (xy 363.343666 -234.487793) (xy 363.389682 -234.470341)
			(xy 363.437901 -234.460497) (xy 363.487076 -234.458516) (xy 363.535931 -234.464448) (xy 363.583202 -234.47814)
			(xy 363.627664 -234.499238) (xy 363.668167 -234.527194) (xy 363.70366 -234.561286) (xy 363.733225 -234.60063)
			(xy 363.756096 -234.644207) (xy 363.77168 -234.690888) (xy 363.779575 -234.739465) (xy 363.78007 -234.764072)
			(xy 364.098581 -234.764072) (xy 364.102676 -234.713344) (xy 364.114855 -234.66393) (xy 364.134803 -234.61711)
			(xy 364.162004 -234.574096) (xy 364.195752 -234.536002) (xy 364.235174 -234.503815) (xy 364.279248 -234.478369)
			(xy 364.326834 -234.460322) (xy 364.376698 -234.450142) (xy 364.42755 -234.448093) (xy 364.478071 -234.454227)
			(xy 364.526955 -234.468387) (xy 364.572934 -234.490204) (xy 364.614818 -234.519114) (xy 364.651522 -234.554369)
			(xy 364.682095 -234.595055) (xy 364.705746 -234.640118) (xy 364.721862 -234.688392) (xy 364.730026 -234.738626)
			(xy 364.730538 -234.764072) (xy 365.038635 -234.764072) (xy 365.04273 -234.713344) (xy 365.054909 -234.66393)
			(xy 365.074857 -234.61711) (xy 365.102058 -234.574096) (xy 365.135806 -234.536002) (xy 365.175228 -234.503815)
			(xy 365.219302 -234.478369) (xy 365.266888 -234.460322) (xy 365.316752 -234.450142) (xy 365.367604 -234.448093)
			(xy 365.418125 -234.454227) (xy 365.467009 -234.468387) (xy 365.512988 -234.490204) (xy 365.554872 -234.519114)
			(xy 365.591576 -234.554369) (xy 365.622149 -234.595055) (xy 365.6458 -234.640118) (xy 365.661916 -234.688392)
			(xy 365.67008 -234.738626) (xy 365.670592 -234.764072) (xy 365.98912 -234.764072) (xy 365.99308 -234.715018)
			(xy 366.004857 -234.667234) (xy 366.024148 -234.621958) (xy 366.050451 -234.580362) (xy 366.083086 -234.543525)
			(xy 366.121207 -234.5124) (xy 366.163828 -234.487793) (xy 366.209844 -234.470341) (xy 366.258063 -234.460497)
			(xy 366.307238 -234.458516) (xy 366.356093 -234.464448) (xy 366.403364 -234.47814) (xy 366.447826 -234.499238)
			(xy 366.488329 -234.527194) (xy 366.523822 -234.561286) (xy 366.553387 -234.60063) (xy 366.576258 -234.644207)
			(xy 366.591842 -234.690888) (xy 366.599737 -234.739465) (xy 366.600232 -234.764072) (xy 366.918489 -234.764072)
			(xy 366.922584 -234.713344) (xy 366.934763 -234.66393) (xy 366.954711 -234.61711) (xy 366.981912 -234.574096)
			(xy 367.01566 -234.536002) (xy 367.055082 -234.503815) (xy 367.099156 -234.478369) (xy 367.146742 -234.460322)
			(xy 367.196606 -234.450142) (xy 367.247458 -234.448093) (xy 367.297979 -234.454227) (xy 367.346863 -234.468387)
			(xy 367.392842 -234.490204) (xy 367.434726 -234.519114) (xy 367.47143 -234.554369) (xy 367.502003 -234.595055)
			(xy 367.525654 -234.640118) (xy 367.54177 -234.688392) (xy 367.549934 -234.738626) (xy 367.550446 -234.764072)
			(xy 367.858543 -234.764072) (xy 367.862638 -234.713344) (xy 367.874817 -234.66393) (xy 367.894765 -234.61711)
			(xy 367.921966 -234.574096) (xy 367.955714 -234.536002) (xy 367.995136 -234.503815) (xy 368.03921 -234.478369)
			(xy 368.086796 -234.460322) (xy 368.13666 -234.450142) (xy 368.187512 -234.448093) (xy 368.238033 -234.454227)
			(xy 368.286917 -234.468387) (xy 368.332896 -234.490204) (xy 368.37478 -234.519114) (xy 368.411484 -234.554369)
			(xy 368.442057 -234.595055) (xy 368.465708 -234.640118) (xy 368.481824 -234.688392) (xy 368.489988 -234.738626)
			(xy 368.4905 -234.764072) (xy 368.809028 -234.764072) (xy 368.812988 -234.715018) (xy 368.824765 -234.667234)
			(xy 368.844056 -234.621958) (xy 368.870359 -234.580362) (xy 368.902994 -234.543525) (xy 368.941115 -234.5124)
			(xy 368.983736 -234.487793) (xy 369.029752 -234.470341) (xy 369.077971 -234.460497) (xy 369.127146 -234.458516)
			(xy 369.176001 -234.464448) (xy 369.223272 -234.47814) (xy 369.267734 -234.499238) (xy 369.308237 -234.527194)
			(xy 369.34373 -234.561286) (xy 369.373295 -234.60063) (xy 369.396166 -234.644207) (xy 369.41175 -234.690888)
			(xy 369.419645 -234.739465) (xy 369.42014 -234.764072) (xy 369.738651 -234.764072) (xy 369.742746 -234.713344)
			(xy 369.754925 -234.66393) (xy 369.774873 -234.61711) (xy 369.802074 -234.574096) (xy 369.835822 -234.536002)
			(xy 369.875244 -234.503815) (xy 369.919318 -234.478369) (xy 369.966904 -234.460322) (xy 370.016768 -234.450142)
			(xy 370.06762 -234.448093) (xy 370.118141 -234.454227) (xy 370.167025 -234.468387) (xy 370.213004 -234.490204)
			(xy 370.254888 -234.519114) (xy 370.291592 -234.554369) (xy 370.322165 -234.595055) (xy 370.345816 -234.640118)
			(xy 370.361932 -234.688392) (xy 370.370096 -234.738626) (xy 370.370608 -234.764072) (xy 370.678451 -234.764072)
			(xy 370.682546 -234.713344) (xy 370.694725 -234.66393) (xy 370.714673 -234.61711) (xy 370.741874 -234.574096)
			(xy 370.775622 -234.536002) (xy 370.815044 -234.503815) (xy 370.859118 -234.478369) (xy 370.906704 -234.460322)
			(xy 370.956568 -234.450142) (xy 371.00742 -234.448093) (xy 371.057941 -234.454227) (xy 371.106825 -234.468387)
			(xy 371.152804 -234.490204) (xy 371.194688 -234.519114) (xy 371.231392 -234.554369) (xy 371.261965 -234.595055)
			(xy 371.285616 -234.640118) (xy 371.301732 -234.688392) (xy 371.309896 -234.738626) (xy 371.310408 -234.764072)
			(xy 371.628936 -234.764072) (xy 371.632896 -234.715018) (xy 371.644673 -234.667234) (xy 371.663964 -234.621958)
			(xy 371.690267 -234.580362) (xy 371.722902 -234.543525) (xy 371.761023 -234.5124) (xy 371.803644 -234.487793)
			(xy 371.84966 -234.470341) (xy 371.897879 -234.460497) (xy 371.947054 -234.458516) (xy 371.995909 -234.464448)
			(xy 372.04318 -234.47814) (xy 372.087642 -234.499238) (xy 372.128145 -234.527194) (xy 372.163638 -234.561286)
			(xy 372.193203 -234.60063) (xy 372.216074 -234.644207) (xy 372.231658 -234.690888) (xy 372.239553 -234.739465)
			(xy 372.240048 -234.764072) (xy 372.558559 -234.764072) (xy 372.562654 -234.713344) (xy 372.574833 -234.66393)
			(xy 372.594781 -234.61711) (xy 372.621982 -234.574096) (xy 372.65573 -234.536002) (xy 372.695152 -234.503815)
			(xy 372.739226 -234.478369) (xy 372.786812 -234.460322) (xy 372.836676 -234.450142) (xy 372.887528 -234.448093)
			(xy 372.938049 -234.454227) (xy 372.986933 -234.468387) (xy 373.032912 -234.490204) (xy 373.074796 -234.519114)
			(xy 373.1115 -234.554369) (xy 373.142073 -234.595055) (xy 373.165724 -234.640118) (xy 373.18184 -234.688392)
			(xy 373.190004 -234.738626) (xy 373.190516 -234.764072) (xy 373.498613 -234.764072) (xy 373.502708 -234.713344)
			(xy 373.514887 -234.66393) (xy 373.534835 -234.61711) (xy 373.562036 -234.574096) (xy 373.595784 -234.536002)
			(xy 373.635206 -234.503815) (xy 373.67928 -234.478369) (xy 373.726866 -234.460322) (xy 373.77673 -234.450142)
			(xy 373.827582 -234.448093) (xy 373.878103 -234.454227) (xy 373.926987 -234.468387) (xy 373.972966 -234.490204)
			(xy 374.01485 -234.519114) (xy 374.051554 -234.554369) (xy 374.082127 -234.595055) (xy 374.105778 -234.640118)
			(xy 374.121894 -234.688392) (xy 374.130058 -234.738626) (xy 374.13057 -234.764072) (xy 374.130058 -234.789518)
			(xy 374.121894 -234.839752) (xy 374.105778 -234.888026) (xy 374.082127 -234.933089) (xy 374.051554 -234.973775)
			(xy 374.01485 -235.00903) (xy 373.972966 -235.03794) (xy 373.926987 -235.059757) (xy 373.878103 -235.073917)
			(xy 373.827582 -235.080051) (xy 373.77673 -235.078002) (xy 373.726866 -235.067822) (xy 373.67928 -235.049775)
			(xy 373.635206 -235.024329) (xy 373.595784 -234.992142) (xy 373.562036 -234.954048) (xy 373.534835 -234.911034)
			(xy 373.514887 -234.864214) (xy 373.502708 -234.8148) (xy 373.498613 -234.764072) (xy 373.190516 -234.764072)
			(xy 373.190004 -234.789518) (xy 373.18184 -234.839752) (xy 373.165724 -234.888026) (xy 373.142073 -234.933089)
			(xy 373.1115 -234.973775) (xy 373.074796 -235.00903) (xy 373.032912 -235.03794) (xy 372.986933 -235.059757)
			(xy 372.938049 -235.073917) (xy 372.887528 -235.080051) (xy 372.836676 -235.078002) (xy 372.786812 -235.067822)
			(xy 372.739226 -235.049775) (xy 372.695152 -235.024329) (xy 372.65573 -234.992142) (xy 372.621982 -234.954048)
			(xy 372.594781 -234.911034) (xy 372.574833 -234.864214) (xy 372.562654 -234.8148) (xy 372.558559 -234.764072)
			(xy 372.240048 -234.764072) (xy 372.239553 -234.788679) (xy 372.231658 -234.837256) (xy 372.216074 -234.883937)
			(xy 372.193203 -234.927514) (xy 372.163638 -234.966858) (xy 372.128145 -235.00095) (xy 372.087642 -235.028906)
			(xy 372.04318 -235.050004) (xy 371.995909 -235.063696) (xy 371.947054 -235.069628) (xy 371.897879 -235.067647)
			(xy 371.84966 -235.057803) (xy 371.803644 -235.040351) (xy 371.761023 -235.015744) (xy 371.722902 -234.984619)
			(xy 371.690267 -234.947782) (xy 371.663964 -234.906186) (xy 371.644673 -234.86091) (xy 371.632896 -234.813126)
			(xy 371.628936 -234.764072) (xy 371.310408 -234.764072) (xy 371.309896 -234.789518) (xy 371.301732 -234.839752)
			(xy 371.285616 -234.888026) (xy 371.261965 -234.933089) (xy 371.231392 -234.973775) (xy 371.194688 -235.00903)
			(xy 371.152804 -235.03794) (xy 371.106825 -235.059757) (xy 371.057941 -235.073917) (xy 371.00742 -235.080051)
			(xy 370.956568 -235.078002) (xy 370.906704 -235.067822) (xy 370.859118 -235.049775) (xy 370.815044 -235.024329)
			(xy 370.775622 -234.992142) (xy 370.741874 -234.954048) (xy 370.714673 -234.911034) (xy 370.694725 -234.864214)
			(xy 370.682546 -234.8148) (xy 370.678451 -234.764072) (xy 370.370608 -234.764072) (xy 370.370096 -234.789518)
			(xy 370.361932 -234.839752) (xy 370.345816 -234.888026) (xy 370.322165 -234.933089) (xy 370.291592 -234.973775)
			(xy 370.254888 -235.00903) (xy 370.213004 -235.03794) (xy 370.167025 -235.059757) (xy 370.118141 -235.073917)
			(xy 370.06762 -235.080051) (xy 370.016768 -235.078002) (xy 369.966904 -235.067822) (xy 369.919318 -235.049775)
			(xy 369.875244 -235.024329) (xy 369.835822 -234.992142) (xy 369.802074 -234.954048) (xy 369.774873 -234.911034)
			(xy 369.754925 -234.864214) (xy 369.742746 -234.8148) (xy 369.738651 -234.764072) (xy 369.42014 -234.764072)
			(xy 369.419645 -234.788679) (xy 369.41175 -234.837256) (xy 369.396166 -234.883937) (xy 369.373295 -234.927514)
			(xy 369.34373 -234.966858) (xy 369.308237 -235.00095) (xy 369.267734 -235.028906) (xy 369.223272 -235.050004)
			(xy 369.176001 -235.063696) (xy 369.127146 -235.069628) (xy 369.077971 -235.067647) (xy 369.029752 -235.057803)
			(xy 368.983736 -235.040351) (xy 368.941115 -235.015744) (xy 368.902994 -234.984619) (xy 368.870359 -234.947782)
			(xy 368.844056 -234.906186) (xy 368.824765 -234.86091) (xy 368.812988 -234.813126) (xy 368.809028 -234.764072)
			(xy 368.4905 -234.764072) (xy 368.489988 -234.789518) (xy 368.481824 -234.839752) (xy 368.465708 -234.888026)
			(xy 368.442057 -234.933089) (xy 368.411484 -234.973775) (xy 368.37478 -235.00903) (xy 368.332896 -235.03794)
			(xy 368.286917 -235.059757) (xy 368.238033 -235.073917) (xy 368.187512 -235.080051) (xy 368.13666 -235.078002)
			(xy 368.086796 -235.067822) (xy 368.03921 -235.049775) (xy 367.995136 -235.024329) (xy 367.955714 -234.992142)
			(xy 367.921966 -234.954048) (xy 367.894765 -234.911034) (xy 367.874817 -234.864214) (xy 367.862638 -234.8148)
			(xy 367.858543 -234.764072) (xy 367.550446 -234.764072) (xy 367.549934 -234.789518) (xy 367.54177 -234.839752)
			(xy 367.525654 -234.888026) (xy 367.502003 -234.933089) (xy 367.47143 -234.973775) (xy 367.434726 -235.00903)
			(xy 367.392842 -235.03794) (xy 367.346863 -235.059757) (xy 367.297979 -235.073917) (xy 367.247458 -235.080051)
			(xy 367.196606 -235.078002) (xy 367.146742 -235.067822) (xy 367.099156 -235.049775) (xy 367.055082 -235.024329)
			(xy 367.01566 -234.992142) (xy 366.981912 -234.954048) (xy 366.954711 -234.911034) (xy 366.934763 -234.864214)
			(xy 366.922584 -234.8148) (xy 366.918489 -234.764072) (xy 366.600232 -234.764072) (xy 366.599737 -234.788679)
			(xy 366.591842 -234.837256) (xy 366.576258 -234.883937) (xy 366.553387 -234.927514) (xy 366.523822 -234.966858)
			(xy 366.488329 -235.00095) (xy 366.447826 -235.028906) (xy 366.403364 -235.050004) (xy 366.356093 -235.063696)
			(xy 366.307238 -235.069628) (xy 366.258063 -235.067647) (xy 366.209844 -235.057803) (xy 366.163828 -235.040351)
			(xy 366.121207 -235.015744) (xy 366.083086 -234.984619) (xy 366.050451 -234.947782) (xy 366.024148 -234.906186)
			(xy 366.004857 -234.86091) (xy 365.99308 -234.813126) (xy 365.98912 -234.764072) (xy 365.670592 -234.764072)
			(xy 365.67008 -234.789518) (xy 365.661916 -234.839752) (xy 365.6458 -234.888026) (xy 365.622149 -234.933089)
			(xy 365.591576 -234.973775) (xy 365.554872 -235.00903) (xy 365.512988 -235.03794) (xy 365.467009 -235.059757)
			(xy 365.418125 -235.073917) (xy 365.367604 -235.080051) (xy 365.316752 -235.078002) (xy 365.266888 -235.067822)
			(xy 365.219302 -235.049775) (xy 365.175228 -235.024329) (xy 365.135806 -234.992142) (xy 365.102058 -234.954048)
			(xy 365.074857 -234.911034) (xy 365.054909 -234.864214) (xy 365.04273 -234.8148) (xy 365.038635 -234.764072)
			(xy 364.730538 -234.764072) (xy 364.730026 -234.789518) (xy 364.721862 -234.839752) (xy 364.705746 -234.888026)
			(xy 364.682095 -234.933089) (xy 364.651522 -234.973775) (xy 364.614818 -235.00903) (xy 364.572934 -235.03794)
			(xy 364.526955 -235.059757) (xy 364.478071 -235.073917) (xy 364.42755 -235.080051) (xy 364.376698 -235.078002)
			(xy 364.326834 -235.067822) (xy 364.279248 -235.049775) (xy 364.235174 -235.024329) (xy 364.195752 -234.992142)
			(xy 364.162004 -234.954048) (xy 364.134803 -234.911034) (xy 364.114855 -234.864214) (xy 364.102676 -234.8148)
			(xy 364.098581 -234.764072) (xy 363.78007 -234.764072) (xy 363.779575 -234.788679) (xy 363.77168 -234.837256)
			(xy 363.756096 -234.883937) (xy 363.733225 -234.927514) (xy 363.70366 -234.966858) (xy 363.668167 -235.00095)
			(xy 363.627664 -235.028906) (xy 363.583202 -235.050004) (xy 363.535931 -235.063696) (xy 363.487076 -235.069628)
			(xy 363.437901 -235.067647) (xy 363.389682 -235.057803) (xy 363.343666 -235.040351) (xy 363.301045 -235.015744)
			(xy 363.262924 -234.984619) (xy 363.230289 -234.947782) (xy 363.203986 -234.906186) (xy 363.184695 -234.86091)
			(xy 363.172918 -234.813126) (xy 363.168958 -234.764072) (xy 360.83748 -234.764072) (xy 360.83748 -235.206286)
			(xy 360.83875 -235.217462) (xy 360.841036 -235.228384) (xy 360.844846 -235.239052) (xy 360.84891 -235.247434)
			(xy 360.93527 -235.30052) (xy 360.940932 -235.303742) (xy 360.953406 -235.307486) (xy 360.959908 -235.307886)
			(xy 360.97337 -235.308394) (xy 360.985308 -235.302298) (xy 361.006888 -235.291749) (xy 361.052544 -235.276828)
			(xy 361.099976 -235.269258) (xy 361.123992 -235.26877) (xy 361.124754 -235.26877) (xy 361.150016 -235.269259)
			(xy 361.199852 -235.277568) (xy 361.24764 -235.293968) (xy 361.292077 -235.31801) (xy 361.33195 -235.349039)
			(xy 361.366172 -235.386208) (xy 361.393808 -235.428503) (xy 361.414105 -235.474771) (xy 361.426509 -235.523749)
			(xy 361.43068 -235.574078) (xy 361.748573 -235.574078) (xy 361.752668 -235.52335) (xy 361.764847 -235.473936)
			(xy 361.784795 -235.427116) (xy 361.811996 -235.384102) (xy 361.845744 -235.346008) (xy 361.885166 -235.313821)
			(xy 361.92924 -235.288375) (xy 361.976826 -235.270328) (xy 362.02669 -235.260148) (xy 362.077542 -235.258099)
			(xy 362.128063 -235.264233) (xy 362.176947 -235.278393) (xy 362.222926 -235.30021) (xy 362.26481 -235.32912)
			(xy 362.301514 -235.364375) (xy 362.332087 -235.405061) (xy 362.355738 -235.450124) (xy 362.371854 -235.498398)
			(xy 362.380018 -235.548632) (xy 362.38053 -235.574078) (xy 362.688627 -235.574078) (xy 362.692722 -235.52335)
			(xy 362.704901 -235.473936) (xy 362.724849 -235.427116) (xy 362.75205 -235.384102) (xy 362.785798 -235.346008)
			(xy 362.82522 -235.313821) (xy 362.869294 -235.288375) (xy 362.91688 -235.270328) (xy 362.966744 -235.260148)
			(xy 363.017596 -235.258099) (xy 363.068117 -235.264233) (xy 363.117001 -235.278393) (xy 363.16298 -235.30021)
			(xy 363.204864 -235.32912) (xy 363.241568 -235.364375) (xy 363.272141 -235.405061) (xy 363.295792 -235.450124)
			(xy 363.311908 -235.498398) (xy 363.320072 -235.548632) (xy 363.320584 -235.574078) (xy 363.639112 -235.574078)
			(xy 363.643072 -235.525024) (xy 363.654849 -235.47724) (xy 363.67414 -235.431964) (xy 363.700443 -235.390368)
			(xy 363.733078 -235.353531) (xy 363.771199 -235.322406) (xy 363.81382 -235.297799) (xy 363.859836 -235.280347)
			(xy 363.908055 -235.270503) (xy 363.95723 -235.268522) (xy 364.006085 -235.274454) (xy 364.053356 -235.288146)
			(xy 364.097818 -235.309244) (xy 364.138321 -235.3372) (xy 364.173814 -235.371292) (xy 364.203379 -235.410636)
			(xy 364.22625 -235.454213) (xy 364.241834 -235.500894) (xy 364.249729 -235.549471) (xy 364.250224 -235.574078)
			(xy 364.578912 -235.574078) (xy 364.582872 -235.525024) (xy 364.594649 -235.47724) (xy 364.61394 -235.431964)
			(xy 364.640243 -235.390368) (xy 364.672878 -235.353531) (xy 364.710999 -235.322406) (xy 364.75362 -235.297799)
			(xy 364.799636 -235.280347) (xy 364.847855 -235.270503) (xy 364.89703 -235.268522) (xy 364.945885 -235.274454)
			(xy 364.993156 -235.288146) (xy 365.037618 -235.309244) (xy 365.078121 -235.3372) (xy 365.113614 -235.371292)
			(xy 365.143179 -235.410636) (xy 365.16605 -235.454213) (xy 365.181634 -235.500894) (xy 365.189529 -235.549471)
			(xy 365.190024 -235.574078) (xy 365.518966 -235.574078) (xy 365.522926 -235.525024) (xy 365.534703 -235.47724)
			(xy 365.553994 -235.431964) (xy 365.580297 -235.390368) (xy 365.612932 -235.353531) (xy 365.651053 -235.322406)
			(xy 365.693674 -235.297799) (xy 365.73969 -235.280347) (xy 365.787909 -235.270503) (xy 365.837084 -235.268522)
			(xy 365.885939 -235.274454) (xy 365.93321 -235.288146) (xy 365.977672 -235.309244) (xy 366.018175 -235.3372)
			(xy 366.053668 -235.371292) (xy 366.083233 -235.410636) (xy 366.106104 -235.454213) (xy 366.121688 -235.500894)
			(xy 366.129583 -235.549471) (xy 366.130078 -235.574078) (xy 366.45902 -235.574078) (xy 366.46298 -235.525024)
			(xy 366.474757 -235.47724) (xy 366.494048 -235.431964) (xy 366.520351 -235.390368) (xy 366.552986 -235.353531)
			(xy 366.591107 -235.322406) (xy 366.633728 -235.297799) (xy 366.679744 -235.280347) (xy 366.727963 -235.270503)
			(xy 366.777138 -235.268522) (xy 366.825993 -235.274454) (xy 366.873264 -235.288146) (xy 366.917726 -235.309244)
			(xy 366.958229 -235.3372) (xy 366.993722 -235.371292) (xy 367.023287 -235.410636) (xy 367.046158 -235.454213)
			(xy 367.061742 -235.500894) (xy 367.069637 -235.549471) (xy 367.070132 -235.574078) (xy 367.399074 -235.574078)
			(xy 367.403034 -235.525024) (xy 367.414811 -235.47724) (xy 367.434102 -235.431964) (xy 367.460405 -235.390368)
			(xy 367.49304 -235.353531) (xy 367.531161 -235.322406) (xy 367.573782 -235.297799) (xy 367.619798 -235.280347)
			(xy 367.668017 -235.270503) (xy 367.717192 -235.268522) (xy 367.766047 -235.274454) (xy 367.813318 -235.288146)
			(xy 367.85778 -235.309244) (xy 367.898283 -235.3372) (xy 367.933776 -235.371292) (xy 367.963341 -235.410636)
			(xy 367.986212 -235.454213) (xy 368.001796 -235.500894) (xy 368.009691 -235.549471) (xy 368.010186 -235.574078)
			(xy 368.338874 -235.574078) (xy 368.342834 -235.525024) (xy 368.354611 -235.47724) (xy 368.373902 -235.431964)
			(xy 368.400205 -235.390368) (xy 368.43284 -235.353531) (xy 368.470961 -235.322406) (xy 368.513582 -235.297799)
			(xy 368.559598 -235.280347) (xy 368.607817 -235.270503) (xy 368.656992 -235.268522) (xy 368.705847 -235.274454)
			(xy 368.753118 -235.288146) (xy 368.79758 -235.309244) (xy 368.838083 -235.3372) (xy 368.873576 -235.371292)
			(xy 368.903141 -235.410636) (xy 368.926012 -235.454213) (xy 368.941596 -235.500894) (xy 368.949491 -235.549471)
			(xy 368.949986 -235.574078) (xy 369.278928 -235.574078) (xy 369.282888 -235.525024) (xy 369.294665 -235.47724)
			(xy 369.313956 -235.431964) (xy 369.340259 -235.390368) (xy 369.372894 -235.353531) (xy 369.411015 -235.322406)
			(xy 369.453636 -235.297799) (xy 369.499652 -235.280347) (xy 369.547871 -235.270503) (xy 369.597046 -235.268522)
			(xy 369.645901 -235.274454) (xy 369.693172 -235.288146) (xy 369.737634 -235.309244) (xy 369.778137 -235.3372)
			(xy 369.81363 -235.371292) (xy 369.843195 -235.410636) (xy 369.866066 -235.454213) (xy 369.88165 -235.500894)
			(xy 369.889545 -235.549471) (xy 369.89004 -235.574078) (xy 370.218982 -235.574078) (xy 370.222942 -235.525024)
			(xy 370.234719 -235.47724) (xy 370.25401 -235.431964) (xy 370.280313 -235.390368) (xy 370.312948 -235.353531)
			(xy 370.351069 -235.322406) (xy 370.39369 -235.297799) (xy 370.439706 -235.280347) (xy 370.487925 -235.270503)
			(xy 370.5371 -235.268522) (xy 370.585955 -235.274454) (xy 370.633226 -235.288146) (xy 370.677688 -235.309244)
			(xy 370.718191 -235.3372) (xy 370.753684 -235.371292) (xy 370.783249 -235.410636) (xy 370.80612 -235.454213)
			(xy 370.821704 -235.500894) (xy 370.829599 -235.549471) (xy 370.830094 -235.574078) (xy 371.159036 -235.574078)
			(xy 371.162996 -235.525024) (xy 371.174773 -235.47724) (xy 371.194064 -235.431964) (xy 371.220367 -235.390368)
			(xy 371.253002 -235.353531) (xy 371.291123 -235.322406) (xy 371.333744 -235.297799) (xy 371.37976 -235.280347)
			(xy 371.427979 -235.270503) (xy 371.477154 -235.268522) (xy 371.526009 -235.274454) (xy 371.57328 -235.288146)
			(xy 371.617742 -235.309244) (xy 371.658245 -235.3372) (xy 371.693738 -235.371292) (xy 371.723303 -235.410636)
			(xy 371.746174 -235.454213) (xy 371.761758 -235.500894) (xy 371.769653 -235.549471) (xy 371.770148 -235.574078)
			(xy 372.09909 -235.574078) (xy 372.10305 -235.525024) (xy 372.114827 -235.47724) (xy 372.134118 -235.431964)
			(xy 372.160421 -235.390368) (xy 372.193056 -235.353531) (xy 372.231177 -235.322406) (xy 372.273798 -235.297799)
			(xy 372.319814 -235.280347) (xy 372.368033 -235.270503) (xy 372.417208 -235.268522) (xy 372.466063 -235.274454)
			(xy 372.513334 -235.288146) (xy 372.557796 -235.309244) (xy 372.598299 -235.3372) (xy 372.633792 -235.371292)
			(xy 372.663357 -235.410636) (xy 372.686228 -235.454213) (xy 372.701812 -235.500894) (xy 372.709707 -235.549471)
			(xy 372.710202 -235.574078) (xy 373.03889 -235.574078) (xy 373.04285 -235.525024) (xy 373.054627 -235.47724)
			(xy 373.073918 -235.431964) (xy 373.100221 -235.390368) (xy 373.132856 -235.353531) (xy 373.170977 -235.322406)
			(xy 373.213598 -235.297799) (xy 373.259614 -235.280347) (xy 373.307833 -235.270503) (xy 373.357008 -235.268522)
			(xy 373.405863 -235.274454) (xy 373.453134 -235.288146) (xy 373.497596 -235.309244) (xy 373.538099 -235.3372)
			(xy 373.573592 -235.371292) (xy 373.603157 -235.410636) (xy 373.626028 -235.454213) (xy 373.641612 -235.500894)
			(xy 373.649507 -235.549471) (xy 373.650002 -235.574078) (xy 373.649507 -235.598685) (xy 373.641612 -235.647262)
			(xy 373.626028 -235.693943) (xy 373.603157 -235.73752) (xy 373.573592 -235.776864) (xy 373.538099 -235.810956)
			(xy 373.497596 -235.838912) (xy 373.453134 -235.86001) (xy 373.405863 -235.873702) (xy 373.357008 -235.879634)
			(xy 373.307833 -235.877653) (xy 373.259614 -235.867809) (xy 373.213598 -235.850357) (xy 373.170977 -235.82575)
			(xy 373.132856 -235.794625) (xy 373.100221 -235.757788) (xy 373.073918 -235.716192) (xy 373.054627 -235.670916)
			(xy 373.04285 -235.623132) (xy 373.03889 -235.574078) (xy 372.710202 -235.574078) (xy 372.709707 -235.598685)
			(xy 372.701812 -235.647262) (xy 372.686228 -235.693943) (xy 372.663357 -235.73752) (xy 372.633792 -235.776864)
			(xy 372.598299 -235.810956) (xy 372.557796 -235.838912) (xy 372.513334 -235.86001) (xy 372.466063 -235.873702)
			(xy 372.417208 -235.879634) (xy 372.368033 -235.877653) (xy 372.319814 -235.867809) (xy 372.273798 -235.850357)
			(xy 372.231177 -235.82575) (xy 372.193056 -235.794625) (xy 372.160421 -235.757788) (xy 372.134118 -235.716192)
			(xy 372.114827 -235.670916) (xy 372.10305 -235.623132) (xy 372.09909 -235.574078) (xy 371.770148 -235.574078)
			(xy 371.769653 -235.598685) (xy 371.761758 -235.647262) (xy 371.746174 -235.693943) (xy 371.723303 -235.73752)
			(xy 371.693738 -235.776864) (xy 371.658245 -235.810956) (xy 371.617742 -235.838912) (xy 371.57328 -235.86001)
			(xy 371.526009 -235.873702) (xy 371.477154 -235.879634) (xy 371.427979 -235.877653) (xy 371.37976 -235.867809)
			(xy 371.333744 -235.850357) (xy 371.291123 -235.82575) (xy 371.253002 -235.794625) (xy 371.220367 -235.757788)
			(xy 371.194064 -235.716192) (xy 371.174773 -235.670916) (xy 371.162996 -235.623132) (xy 371.159036 -235.574078)
			(xy 370.830094 -235.574078) (xy 370.829599 -235.598685) (xy 370.821704 -235.647262) (xy 370.80612 -235.693943)
			(xy 370.783249 -235.73752) (xy 370.753684 -235.776864) (xy 370.718191 -235.810956) (xy 370.677688 -235.838912)
			(xy 370.633226 -235.86001) (xy 370.585955 -235.873702) (xy 370.5371 -235.879634) (xy 370.487925 -235.877653)
			(xy 370.439706 -235.867809) (xy 370.39369 -235.850357) (xy 370.351069 -235.82575) (xy 370.312948 -235.794625)
			(xy 370.280313 -235.757788) (xy 370.25401 -235.716192) (xy 370.234719 -235.670916) (xy 370.222942 -235.623132)
			(xy 370.218982 -235.574078) (xy 369.89004 -235.574078) (xy 369.889545 -235.598685) (xy 369.88165 -235.647262)
			(xy 369.866066 -235.693943) (xy 369.843195 -235.73752) (xy 369.81363 -235.776864) (xy 369.778137 -235.810956)
			(xy 369.737634 -235.838912) (xy 369.693172 -235.86001) (xy 369.645901 -235.873702) (xy 369.597046 -235.879634)
			(xy 369.547871 -235.877653) (xy 369.499652 -235.867809) (xy 369.453636 -235.850357) (xy 369.411015 -235.82575)
			(xy 369.372894 -235.794625) (xy 369.340259 -235.757788) (xy 369.313956 -235.716192) (xy 369.294665 -235.670916)
			(xy 369.282888 -235.623132) (xy 369.278928 -235.574078) (xy 368.949986 -235.574078) (xy 368.949491 -235.598685)
			(xy 368.941596 -235.647262) (xy 368.926012 -235.693943) (xy 368.903141 -235.73752) (xy 368.873576 -235.776864)
			(xy 368.838083 -235.810956) (xy 368.79758 -235.838912) (xy 368.753118 -235.86001) (xy 368.705847 -235.873702)
			(xy 368.656992 -235.879634) (xy 368.607817 -235.877653) (xy 368.559598 -235.867809) (xy 368.513582 -235.850357)
			(xy 368.470961 -235.82575) (xy 368.43284 -235.794625) (xy 368.400205 -235.757788) (xy 368.373902 -235.716192)
			(xy 368.354611 -235.670916) (xy 368.342834 -235.623132) (xy 368.338874 -235.574078) (xy 368.010186 -235.574078)
			(xy 368.009691 -235.598685) (xy 368.001796 -235.647262) (xy 367.986212 -235.693943) (xy 367.963341 -235.73752)
			(xy 367.933776 -235.776864) (xy 367.898283 -235.810956) (xy 367.85778 -235.838912) (xy 367.813318 -235.86001)
			(xy 367.766047 -235.873702) (xy 367.717192 -235.879634) (xy 367.668017 -235.877653) (xy 367.619798 -235.867809)
			(xy 367.573782 -235.850357) (xy 367.531161 -235.82575) (xy 367.49304 -235.794625) (xy 367.460405 -235.757788)
			(xy 367.434102 -235.716192) (xy 367.414811 -235.670916) (xy 367.403034 -235.623132) (xy 367.399074 -235.574078)
			(xy 367.070132 -235.574078) (xy 367.069637 -235.598685) (xy 367.061742 -235.647262) (xy 367.046158 -235.693943)
			(xy 367.023287 -235.73752) (xy 366.993722 -235.776864) (xy 366.958229 -235.810956) (xy 366.917726 -235.838912)
			(xy 366.873264 -235.86001) (xy 366.825993 -235.873702) (xy 366.777138 -235.879634) (xy 366.727963 -235.877653)
			(xy 366.679744 -235.867809) (xy 366.633728 -235.850357) (xy 366.591107 -235.82575) (xy 366.552986 -235.794625)
			(xy 366.520351 -235.757788) (xy 366.494048 -235.716192) (xy 366.474757 -235.670916) (xy 366.46298 -235.623132)
			(xy 366.45902 -235.574078) (xy 366.130078 -235.574078) (xy 366.129583 -235.598685) (xy 366.121688 -235.647262)
			(xy 366.106104 -235.693943) (xy 366.083233 -235.73752) (xy 366.053668 -235.776864) (xy 366.018175 -235.810956)
			(xy 365.977672 -235.838912) (xy 365.93321 -235.86001) (xy 365.885939 -235.873702) (xy 365.837084 -235.879634)
			(xy 365.787909 -235.877653) (xy 365.73969 -235.867809) (xy 365.693674 -235.850357) (xy 365.651053 -235.82575)
			(xy 365.612932 -235.794625) (xy 365.580297 -235.757788) (xy 365.553994 -235.716192) (xy 365.534703 -235.670916)
			(xy 365.522926 -235.623132) (xy 365.518966 -235.574078) (xy 365.190024 -235.574078) (xy 365.189529 -235.598685)
			(xy 365.181634 -235.647262) (xy 365.16605 -235.693943) (xy 365.143179 -235.73752) (xy 365.113614 -235.776864)
			(xy 365.078121 -235.810956) (xy 365.037618 -235.838912) (xy 364.993156 -235.86001) (xy 364.945885 -235.873702)
			(xy 364.89703 -235.879634) (xy 364.847855 -235.877653) (xy 364.799636 -235.867809) (xy 364.75362 -235.850357)
			(xy 364.710999 -235.82575) (xy 364.672878 -235.794625) (xy 364.640243 -235.757788) (xy 364.61394 -235.716192)
			(xy 364.594649 -235.670916) (xy 364.582872 -235.623132) (xy 364.578912 -235.574078) (xy 364.250224 -235.574078)
			(xy 364.249729 -235.598685) (xy 364.241834 -235.647262) (xy 364.22625 -235.693943) (xy 364.203379 -235.73752)
			(xy 364.173814 -235.776864) (xy 364.138321 -235.810956) (xy 364.097818 -235.838912) (xy 364.053356 -235.86001)
			(xy 364.006085 -235.873702) (xy 363.95723 -235.879634) (xy 363.908055 -235.877653) (xy 363.859836 -235.867809)
			(xy 363.81382 -235.850357) (xy 363.771199 -235.82575) (xy 363.733078 -235.794625) (xy 363.700443 -235.757788)
			(xy 363.67414 -235.716192) (xy 363.654849 -235.670916) (xy 363.643072 -235.623132) (xy 363.639112 -235.574078)
			(xy 363.320584 -235.574078) (xy 363.320072 -235.599524) (xy 363.311908 -235.649758) (xy 363.295792 -235.698032)
			(xy 363.272141 -235.743095) (xy 363.241568 -235.783781) (xy 363.204864 -235.819036) (xy 363.16298 -235.847946)
			(xy 363.117001 -235.869763) (xy 363.068117 -235.883923) (xy 363.017596 -235.890057) (xy 362.966744 -235.888008)
			(xy 362.91688 -235.877828) (xy 362.869294 -235.859781) (xy 362.82522 -235.834335) (xy 362.785798 -235.802148)
			(xy 362.75205 -235.764054) (xy 362.724849 -235.72104) (xy 362.704901 -235.67422) (xy 362.692722 -235.624806)
			(xy 362.688627 -235.574078) (xy 362.38053 -235.574078) (xy 362.380018 -235.599524) (xy 362.371854 -235.649758)
			(xy 362.355738 -235.698032) (xy 362.332087 -235.743095) (xy 362.301514 -235.783781) (xy 362.26481 -235.819036)
			(xy 362.222926 -235.847946) (xy 362.176947 -235.869763) (xy 362.128063 -235.883923) (xy 362.077542 -235.890057)
			(xy 362.02669 -235.888008) (xy 361.976826 -235.877828) (xy 361.92924 -235.859781) (xy 361.885166 -235.834335)
			(xy 361.845744 -235.802148) (xy 361.811996 -235.764054) (xy 361.784795 -235.72104) (xy 361.764847 -235.67422)
			(xy 361.752668 -235.624806) (xy 361.748573 -235.574078) (xy 361.43068 -235.574078) (xy 361.430682 -235.5741)
			(xy 361.426509 -235.624451) (xy 361.414105 -235.673429) (xy 361.393808 -235.719697) (xy 361.366172 -235.761992)
			(xy 361.33195 -235.799161) (xy 361.292077 -235.83019) (xy 361.24764 -235.854232) (xy 361.199852 -235.870632)
			(xy 361.150016 -235.878941) (xy 361.124754 -235.879386) (xy 361.123992 -235.879386) (xy 361.09998 -235.878869)
			(xy 361.052558 -235.871274) (xy 361.006905 -235.856366) (xy 360.985308 -235.845858) (xy 360.985054 -235.845858)
			(xy 360.979211 -235.843116) (xy 360.966618 -235.840303) (xy 360.960162 -235.84027) (xy 360.9467 -235.840778)
			(xy 360.861864 -235.892848) (xy 360.855682 -235.896837) (xy 360.845754 -235.907684) (xy 360.842306 -235.914184)
			(xy 360.83748 -235.924852) (xy 360.83748 -236.384084) (xy 361.289104 -236.384084) (xy 361.293064 -236.33503)
			(xy 361.304841 -236.287246) (xy 361.324132 -236.24197) (xy 361.350435 -236.200374) (xy 361.38307 -236.163537)
			(xy 361.421191 -236.132412) (xy 361.463812 -236.107805) (xy 361.509828 -236.090353) (xy 361.558047 -236.080509)
			(xy 361.607222 -236.078528) (xy 361.656077 -236.08446) (xy 361.703348 -236.098152) (xy 361.74781 -236.11925)
			(xy 361.788313 -236.147206) (xy 361.823806 -236.181298) (xy 361.853371 -236.220642) (xy 361.876242 -236.264219)
			(xy 361.891826 -236.3109) (xy 361.899721 -236.359477) (xy 361.900216 -236.384084) (xy 362.228904 -236.384084)
			(xy 362.232864 -236.33503) (xy 362.244641 -236.287246) (xy 362.263932 -236.24197) (xy 362.290235 -236.200374)
			(xy 362.32287 -236.163537) (xy 362.360991 -236.132412) (xy 362.403612 -236.107805) (xy 362.449628 -236.090353)
			(xy 362.497847 -236.080509) (xy 362.547022 -236.078528) (xy 362.595877 -236.08446) (xy 362.643148 -236.098152)
			(xy 362.68761 -236.11925) (xy 362.728113 -236.147206) (xy 362.763606 -236.181298) (xy 362.793171 -236.220642)
			(xy 362.816042 -236.264219) (xy 362.831626 -236.3109) (xy 362.839521 -236.359477) (xy 362.840016 -236.384084)
			(xy 363.168958 -236.384084) (xy 363.172918 -236.33503) (xy 363.184695 -236.287246) (xy 363.203986 -236.24197)
			(xy 363.230289 -236.200374) (xy 363.262924 -236.163537) (xy 363.301045 -236.132412) (xy 363.343666 -236.107805)
			(xy 363.389682 -236.090353) (xy 363.437901 -236.080509) (xy 363.487076 -236.078528) (xy 363.535931 -236.08446)
			(xy 363.583202 -236.098152) (xy 363.627664 -236.11925) (xy 363.668167 -236.147206) (xy 363.70366 -236.181298)
			(xy 363.733225 -236.220642) (xy 363.756096 -236.264219) (xy 363.77168 -236.3109) (xy 363.779575 -236.359477)
			(xy 363.78007 -236.384084) (xy 365.98912 -236.384084) (xy 365.99308 -236.33503) (xy 366.004857 -236.287246)
			(xy 366.024148 -236.24197) (xy 366.050451 -236.200374) (xy 366.083086 -236.163537) (xy 366.121207 -236.132412)
			(xy 366.163828 -236.107805) (xy 366.209844 -236.090353) (xy 366.258063 -236.080509) (xy 366.307238 -236.078528)
			(xy 366.356093 -236.08446) (xy 366.403364 -236.098152) (xy 366.447826 -236.11925) (xy 366.488329 -236.147206)
			(xy 366.523822 -236.181298) (xy 366.553387 -236.220642) (xy 366.576258 -236.264219) (xy 366.591842 -236.3109)
			(xy 366.599737 -236.359477) (xy 366.600232 -236.384084) (xy 368.809028 -236.384084) (xy 368.812988 -236.33503)
			(xy 368.824765 -236.287246) (xy 368.844056 -236.24197) (xy 368.870359 -236.200374) (xy 368.902994 -236.163537)
			(xy 368.941115 -236.132412) (xy 368.983736 -236.107805) (xy 369.029752 -236.090353) (xy 369.077971 -236.080509)
			(xy 369.127146 -236.078528) (xy 369.176001 -236.08446) (xy 369.223272 -236.098152) (xy 369.267734 -236.11925)
			(xy 369.308237 -236.147206) (xy 369.34373 -236.181298) (xy 369.373295 -236.220642) (xy 369.396166 -236.264219)
			(xy 369.41175 -236.3109) (xy 369.419645 -236.359477) (xy 369.42014 -236.384084) (xy 369.738651 -236.384084)
			(xy 369.742746 -236.333356) (xy 369.754925 -236.283942) (xy 369.774873 -236.237122) (xy 369.802074 -236.194108)
			(xy 369.835822 -236.156014) (xy 369.875244 -236.123827) (xy 369.919318 -236.098381) (xy 369.966904 -236.080334)
			(xy 370.016768 -236.070154) (xy 370.06762 -236.068105) (xy 370.118141 -236.074239) (xy 370.167025 -236.088399)
			(xy 370.213004 -236.110216) (xy 370.254888 -236.139126) (xy 370.291592 -236.174381) (xy 370.322165 -236.215067)
			(xy 370.345816 -236.26013) (xy 370.361932 -236.308404) (xy 370.370096 -236.358638) (xy 370.370608 -236.384084)
			(xy 370.678451 -236.384084) (xy 370.682546 -236.333356) (xy 370.694725 -236.283942) (xy 370.714673 -236.237122)
			(xy 370.741874 -236.194108) (xy 370.775622 -236.156014) (xy 370.815044 -236.123827) (xy 370.859118 -236.098381)
			(xy 370.906704 -236.080334) (xy 370.956568 -236.070154) (xy 371.00742 -236.068105) (xy 371.057941 -236.074239)
			(xy 371.106825 -236.088399) (xy 371.152804 -236.110216) (xy 371.194688 -236.139126) (xy 371.231392 -236.174381)
			(xy 371.261965 -236.215067) (xy 371.285616 -236.26013) (xy 371.301732 -236.308404) (xy 371.309896 -236.358638)
			(xy 371.310408 -236.384084) (xy 371.628936 -236.384084) (xy 371.632896 -236.33503) (xy 371.644673 -236.287246)
			(xy 371.663964 -236.24197) (xy 371.690267 -236.200374) (xy 371.722902 -236.163537) (xy 371.761023 -236.132412)
			(xy 371.803644 -236.107805) (xy 371.84966 -236.090353) (xy 371.897879 -236.080509) (xy 371.947054 -236.078528)
			(xy 371.995909 -236.08446) (xy 372.04318 -236.098152) (xy 372.087642 -236.11925) (xy 372.128145 -236.147206)
			(xy 372.163638 -236.181298) (xy 372.193203 -236.220642) (xy 372.216074 -236.264219) (xy 372.231658 -236.3109)
			(xy 372.239553 -236.359477) (xy 372.240048 -236.384084) (xy 372.558559 -236.384084) (xy 372.562654 -236.333356)
			(xy 372.574833 -236.283942) (xy 372.594781 -236.237122) (xy 372.621982 -236.194108) (xy 372.65573 -236.156014)
			(xy 372.695152 -236.123827) (xy 372.739226 -236.098381) (xy 372.786812 -236.080334) (xy 372.836676 -236.070154)
			(xy 372.887528 -236.068105) (xy 372.938049 -236.074239) (xy 372.986933 -236.088399) (xy 373.032912 -236.110216)
			(xy 373.074796 -236.139126) (xy 373.1115 -236.174381) (xy 373.142073 -236.215067) (xy 373.165724 -236.26013)
			(xy 373.18184 -236.308404) (xy 373.190004 -236.358638) (xy 373.190516 -236.384084) (xy 373.498613 -236.384084)
			(xy 373.502708 -236.333356) (xy 373.514887 -236.283942) (xy 373.534835 -236.237122) (xy 373.562036 -236.194108)
			(xy 373.595784 -236.156014) (xy 373.635206 -236.123827) (xy 373.67928 -236.098381) (xy 373.726866 -236.080334)
			(xy 373.77673 -236.070154) (xy 373.827582 -236.068105) (xy 373.878103 -236.074239) (xy 373.926987 -236.088399)
			(xy 373.972966 -236.110216) (xy 374.01485 -236.139126) (xy 374.051554 -236.174381) (xy 374.082127 -236.215067)
			(xy 374.105778 -236.26013) (xy 374.121894 -236.308404) (xy 374.130058 -236.358638) (xy 374.13057 -236.384084)
			(xy 374.130058 -236.40953) (xy 374.121894 -236.459764) (xy 374.105778 -236.508038) (xy 374.082127 -236.553101)
			(xy 374.051554 -236.593787) (xy 374.01485 -236.629042) (xy 373.972966 -236.657952) (xy 373.926987 -236.679769)
			(xy 373.878103 -236.693929) (xy 373.827582 -236.700063) (xy 373.77673 -236.698014) (xy 373.726866 -236.687834)
			(xy 373.67928 -236.669787) (xy 373.635206 -236.644341) (xy 373.595784 -236.612154) (xy 373.562036 -236.57406)
			(xy 373.534835 -236.531046) (xy 373.514887 -236.484226) (xy 373.502708 -236.434812) (xy 373.498613 -236.384084)
			(xy 373.190516 -236.384084) (xy 373.190004 -236.40953) (xy 373.18184 -236.459764) (xy 373.165724 -236.508038)
			(xy 373.142073 -236.553101) (xy 373.1115 -236.593787) (xy 373.074796 -236.629042) (xy 373.032912 -236.657952)
			(xy 372.986933 -236.679769) (xy 372.938049 -236.693929) (xy 372.887528 -236.700063) (xy 372.836676 -236.698014)
			(xy 372.786812 -236.687834) (xy 372.739226 -236.669787) (xy 372.695152 -236.644341) (xy 372.65573 -236.612154)
			(xy 372.621982 -236.57406) (xy 372.594781 -236.531046) (xy 372.574833 -236.484226) (xy 372.562654 -236.434812)
			(xy 372.558559 -236.384084) (xy 372.240048 -236.384084) (xy 372.239553 -236.408691) (xy 372.231658 -236.457268)
			(xy 372.216074 -236.503949) (xy 372.193203 -236.547526) (xy 372.163638 -236.58687) (xy 372.128145 -236.620962)
			(xy 372.087642 -236.648918) (xy 372.04318 -236.670016) (xy 371.995909 -236.683708) (xy 371.947054 -236.68964)
			(xy 371.897879 -236.687659) (xy 371.84966 -236.677815) (xy 371.803644 -236.660363) (xy 371.761023 -236.635756)
			(xy 371.722902 -236.604631) (xy 371.690267 -236.567794) (xy 371.663964 -236.526198) (xy 371.644673 -236.480922)
			(xy 371.632896 -236.433138) (xy 371.628936 -236.384084) (xy 371.310408 -236.384084) (xy 371.309896 -236.40953)
			(xy 371.301732 -236.459764) (xy 371.285616 -236.508038) (xy 371.261965 -236.553101) (xy 371.231392 -236.593787)
			(xy 371.194688 -236.629042) (xy 371.152804 -236.657952) (xy 371.106825 -236.679769) (xy 371.057941 -236.693929)
			(xy 371.00742 -236.700063) (xy 370.956568 -236.698014) (xy 370.906704 -236.687834) (xy 370.859118 -236.669787)
			(xy 370.815044 -236.644341) (xy 370.775622 -236.612154) (xy 370.741874 -236.57406) (xy 370.714673 -236.531046)
			(xy 370.694725 -236.484226) (xy 370.682546 -236.434812) (xy 370.678451 -236.384084) (xy 370.370608 -236.384084)
			(xy 370.370096 -236.40953) (xy 370.361932 -236.459764) (xy 370.345816 -236.508038) (xy 370.322165 -236.553101)
			(xy 370.291592 -236.593787) (xy 370.254888 -236.629042) (xy 370.213004 -236.657952) (xy 370.167025 -236.679769)
			(xy 370.118141 -236.693929) (xy 370.06762 -236.700063) (xy 370.016768 -236.698014) (xy 369.966904 -236.687834)
			(xy 369.919318 -236.669787) (xy 369.875244 -236.644341) (xy 369.835822 -236.612154) (xy 369.802074 -236.57406)
			(xy 369.774873 -236.531046) (xy 369.754925 -236.484226) (xy 369.742746 -236.434812) (xy 369.738651 -236.384084)
			(xy 369.42014 -236.384084) (xy 369.419645 -236.408691) (xy 369.41175 -236.457268) (xy 369.396166 -236.503949)
			(xy 369.373295 -236.547526) (xy 369.34373 -236.58687) (xy 369.308237 -236.620962) (xy 369.267734 -236.648918)
			(xy 369.223272 -236.670016) (xy 369.176001 -236.683708) (xy 369.127146 -236.68964) (xy 369.077971 -236.687659)
			(xy 369.029752 -236.677815) (xy 368.983736 -236.660363) (xy 368.941115 -236.635756) (xy 368.902994 -236.604631)
			(xy 368.870359 -236.567794) (xy 368.844056 -236.526198) (xy 368.824765 -236.480922) (xy 368.812988 -236.433138)
			(xy 368.809028 -236.384084) (xy 366.600232 -236.384084) (xy 366.599737 -236.408691) (xy 366.591842 -236.457268)
			(xy 366.576258 -236.503949) (xy 366.553387 -236.547526) (xy 366.523822 -236.58687) (xy 366.488329 -236.620962)
			(xy 366.447826 -236.648918) (xy 366.403364 -236.670016) (xy 366.356093 -236.683708) (xy 366.307238 -236.68964)
			(xy 366.258063 -236.687659) (xy 366.209844 -236.677815) (xy 366.163828 -236.660363) (xy 366.121207 -236.635756)
			(xy 366.083086 -236.604631) (xy 366.050451 -236.567794) (xy 366.024148 -236.526198) (xy 366.004857 -236.480922)
			(xy 365.99308 -236.433138) (xy 365.98912 -236.384084) (xy 363.78007 -236.384084) (xy 363.779575 -236.408691)
			(xy 363.77168 -236.457268) (xy 363.756096 -236.503949) (xy 363.733225 -236.547526) (xy 363.70366 -236.58687)
			(xy 363.668167 -236.620962) (xy 363.627664 -236.648918) (xy 363.583202 -236.670016) (xy 363.535931 -236.683708)
			(xy 363.487076 -236.68964) (xy 363.437901 -236.687659) (xy 363.389682 -236.677815) (xy 363.343666 -236.660363)
			(xy 363.301045 -236.635756) (xy 363.262924 -236.604631) (xy 363.230289 -236.567794) (xy 363.203986 -236.526198)
			(xy 363.184695 -236.480922) (xy 363.172918 -236.433138) (xy 363.168958 -236.384084) (xy 362.840016 -236.384084)
			(xy 362.839521 -236.408691) (xy 362.831626 -236.457268) (xy 362.816042 -236.503949) (xy 362.793171 -236.547526)
			(xy 362.763606 -236.58687) (xy 362.728113 -236.620962) (xy 362.68761 -236.648918) (xy 362.643148 -236.670016)
			(xy 362.595877 -236.683708) (xy 362.547022 -236.68964) (xy 362.497847 -236.687659) (xy 362.449628 -236.677815)
			(xy 362.403612 -236.660363) (xy 362.360991 -236.635756) (xy 362.32287 -236.604631) (xy 362.290235 -236.567794)
			(xy 362.263932 -236.526198) (xy 362.244641 -236.480922) (xy 362.232864 -236.433138) (xy 362.228904 -236.384084)
			(xy 361.900216 -236.384084) (xy 361.899721 -236.408691) (xy 361.891826 -236.457268) (xy 361.876242 -236.503949)
			(xy 361.853371 -236.547526) (xy 361.823806 -236.58687) (xy 361.788313 -236.620962) (xy 361.74781 -236.648918)
			(xy 361.703348 -236.670016) (xy 361.656077 -236.683708) (xy 361.607222 -236.68964) (xy 361.558047 -236.687659)
			(xy 361.509828 -236.677815) (xy 361.463812 -236.660363) (xy 361.421191 -236.635756) (xy 361.38307 -236.604631)
			(xy 361.350435 -236.567794) (xy 361.324132 -236.526198) (xy 361.304841 -236.480922) (xy 361.293064 -236.433138)
			(xy 361.289104 -236.384084) (xy 360.83748 -236.384084) (xy 360.83748 -236.826298) (xy 360.83875 -236.837474)
			(xy 360.841036 -236.848396) (xy 360.844846 -236.859064) (xy 360.84891 -236.867446) (xy 360.93527 -236.920532)
			(xy 360.940933 -236.923753) (xy 360.953406 -236.927496) (xy 360.959908 -236.927898) (xy 360.97337 -236.928406)
			(xy 360.985308 -236.92231) (xy 361.006888 -236.911761) (xy 361.052544 -236.896839) (xy 361.099976 -236.889268)
			(xy 361.123992 -236.888782) (xy 361.124754 -236.888782) (xy 361.150015 -236.889271) (xy 361.199849 -236.89758)
			(xy 361.247635 -236.913979) (xy 361.292071 -236.93802) (xy 361.331942 -236.969048) (xy 361.366162 -237.006215)
			(xy 361.393798 -237.048509) (xy 361.414094 -237.094775) (xy 361.426498 -237.143751) (xy 361.430669 -237.19409)
			(xy 363.639112 -237.19409) (xy 363.643072 -237.145036) (xy 363.654849 -237.097252) (xy 363.67414 -237.051976)
			(xy 363.700443 -237.01038) (xy 363.733078 -236.973543) (xy 363.771199 -236.942418) (xy 363.81382 -236.917811)
			(xy 363.859836 -236.900359) (xy 363.908055 -236.890515) (xy 363.95723 -236.888534) (xy 364.006085 -236.894466)
			(xy 364.053356 -236.908158) (xy 364.097818 -236.929256) (xy 364.138321 -236.957212) (xy 364.173814 -236.991304)
			(xy 364.203379 -237.030648) (xy 364.22625 -237.074225) (xy 364.241834 -237.120906) (xy 364.249729 -237.169483)
			(xy 364.250224 -237.19409) (xy 364.578912 -237.19409) (xy 364.582872 -237.145036) (xy 364.594649 -237.097252)
			(xy 364.61394 -237.051976) (xy 364.640243 -237.01038) (xy 364.672878 -236.973543) (xy 364.710999 -236.942418)
			(xy 364.75362 -236.917811) (xy 364.799636 -236.900359) (xy 364.847855 -236.890515) (xy 364.89703 -236.888534)
			(xy 364.945885 -236.894466) (xy 364.993156 -236.908158) (xy 365.037618 -236.929256) (xy 365.078121 -236.957212)
			(xy 365.113614 -236.991304) (xy 365.143179 -237.030648) (xy 365.16605 -237.074225) (xy 365.181634 -237.120906)
			(xy 365.189529 -237.169483) (xy 365.190024 -237.19409) (xy 365.518966 -237.19409) (xy 365.522926 -237.145036)
			(xy 365.534703 -237.097252) (xy 365.553994 -237.051976) (xy 365.580297 -237.01038) (xy 365.612932 -236.973543)
			(xy 365.651053 -236.942418) (xy 365.693674 -236.917811) (xy 365.73969 -236.900359) (xy 365.787909 -236.890515)
			(xy 365.837084 -236.888534) (xy 365.885939 -236.894466) (xy 365.93321 -236.908158) (xy 365.977672 -236.929256)
			(xy 366.018175 -236.957212) (xy 366.053668 -236.991304) (xy 366.083233 -237.030648) (xy 366.106104 -237.074225)
			(xy 366.121688 -237.120906) (xy 366.129583 -237.169483) (xy 366.130078 -237.19409) (xy 366.45902 -237.19409)
			(xy 366.46298 -237.145036) (xy 366.474757 -237.097252) (xy 366.494048 -237.051976) (xy 366.520351 -237.01038)
			(xy 366.552986 -236.973543) (xy 366.591107 -236.942418) (xy 366.633728 -236.917811) (xy 366.679744 -236.900359)
			(xy 366.727963 -236.890515) (xy 366.777138 -236.888534) (xy 366.825993 -236.894466) (xy 366.873264 -236.908158)
			(xy 366.917726 -236.929256) (xy 366.958229 -236.957212) (xy 366.993722 -236.991304) (xy 367.023287 -237.030648)
			(xy 367.046158 -237.074225) (xy 367.061742 -237.120906) (xy 367.069637 -237.169483) (xy 367.070132 -237.19409)
			(xy 367.399074 -237.19409) (xy 367.403034 -237.145036) (xy 367.414811 -237.097252) (xy 367.434102 -237.051976)
			(xy 367.460405 -237.01038) (xy 367.49304 -236.973543) (xy 367.531161 -236.942418) (xy 367.573782 -236.917811)
			(xy 367.619798 -236.900359) (xy 367.668017 -236.890515) (xy 367.717192 -236.888534) (xy 367.766047 -236.894466)
			(xy 367.813318 -236.908158) (xy 367.85778 -236.929256) (xy 367.898283 -236.957212) (xy 367.933776 -236.991304)
			(xy 367.963341 -237.030648) (xy 367.986212 -237.074225) (xy 368.001796 -237.120906) (xy 368.009691 -237.169483)
			(xy 368.010186 -237.19409) (xy 368.338874 -237.19409) (xy 368.342834 -237.145036) (xy 368.354611 -237.097252)
			(xy 368.373902 -237.051976) (xy 368.400205 -237.01038) (xy 368.43284 -236.973543) (xy 368.470961 -236.942418)
			(xy 368.513582 -236.917811) (xy 368.559598 -236.900359) (xy 368.607817 -236.890515) (xy 368.656992 -236.888534)
			(xy 368.705847 -236.894466) (xy 368.753118 -236.908158) (xy 368.79758 -236.929256) (xy 368.838083 -236.957212)
			(xy 368.873576 -236.991304) (xy 368.903141 -237.030648) (xy 368.926012 -237.074225) (xy 368.941596 -237.120906)
			(xy 368.949491 -237.169483) (xy 368.949986 -237.19409) (xy 369.278928 -237.19409) (xy 369.282888 -237.145036)
			(xy 369.294665 -237.097252) (xy 369.313956 -237.051976) (xy 369.340259 -237.01038) (xy 369.372894 -236.973543)
			(xy 369.411015 -236.942418) (xy 369.453636 -236.917811) (xy 369.499652 -236.900359) (xy 369.547871 -236.890515)
			(xy 369.597046 -236.888534) (xy 369.645901 -236.894466) (xy 369.693172 -236.908158) (xy 369.737634 -236.929256)
			(xy 369.778137 -236.957212) (xy 369.81363 -236.991304) (xy 369.843195 -237.030648) (xy 369.866066 -237.074225)
			(xy 369.88165 -237.120906) (xy 369.889545 -237.169483) (xy 369.89004 -237.19409) (xy 370.218982 -237.19409)
			(xy 370.222942 -237.145036) (xy 370.234719 -237.097252) (xy 370.25401 -237.051976) (xy 370.280313 -237.01038)
			(xy 370.312948 -236.973543) (xy 370.351069 -236.942418) (xy 370.39369 -236.917811) (xy 370.439706 -236.900359)
			(xy 370.487925 -236.890515) (xy 370.5371 -236.888534) (xy 370.585955 -236.894466) (xy 370.633226 -236.908158)
			(xy 370.677688 -236.929256) (xy 370.718191 -236.957212) (xy 370.753684 -236.991304) (xy 370.783249 -237.030648)
			(xy 370.80612 -237.074225) (xy 370.821704 -237.120906) (xy 370.829599 -237.169483) (xy 370.830094 -237.19409)
			(xy 371.159036 -237.19409) (xy 371.162996 -237.145036) (xy 371.174773 -237.097252) (xy 371.194064 -237.051976)
			(xy 371.220367 -237.01038) (xy 371.253002 -236.973543) (xy 371.291123 -236.942418) (xy 371.333744 -236.917811)
			(xy 371.37976 -236.900359) (xy 371.427979 -236.890515) (xy 371.477154 -236.888534) (xy 371.526009 -236.894466)
			(xy 371.57328 -236.908158) (xy 371.617742 -236.929256) (xy 371.658245 -236.957212) (xy 371.693738 -236.991304)
			(xy 371.723303 -237.030648) (xy 371.746174 -237.074225) (xy 371.761758 -237.120906) (xy 371.769653 -237.169483)
			(xy 371.770148 -237.19409) (xy 372.09909 -237.19409) (xy 372.10305 -237.145036) (xy 372.114827 -237.097252)
			(xy 372.134118 -237.051976) (xy 372.160421 -237.01038) (xy 372.193056 -236.973543) (xy 372.231177 -236.942418)
			(xy 372.273798 -236.917811) (xy 372.319814 -236.900359) (xy 372.368033 -236.890515) (xy 372.417208 -236.888534)
			(xy 372.466063 -236.894466) (xy 372.513334 -236.908158) (xy 372.557796 -236.929256) (xy 372.598299 -236.957212)
			(xy 372.633792 -236.991304) (xy 372.663357 -237.030648) (xy 372.686228 -237.074225) (xy 372.701812 -237.120906)
			(xy 372.709707 -237.169483) (xy 372.710202 -237.19409) (xy 373.03889 -237.19409) (xy 373.04285 -237.145036)
			(xy 373.054627 -237.097252) (xy 373.073918 -237.051976) (xy 373.100221 -237.01038) (xy 373.132856 -236.973543)
			(xy 373.170977 -236.942418) (xy 373.213598 -236.917811) (xy 373.259614 -236.900359) (xy 373.307833 -236.890515)
			(xy 373.357008 -236.888534) (xy 373.405863 -236.894466) (xy 373.453134 -236.908158) (xy 373.497596 -236.929256)
			(xy 373.538099 -236.957212) (xy 373.573592 -236.991304) (xy 373.603157 -237.030648) (xy 373.626028 -237.074225)
			(xy 373.641612 -237.120906) (xy 373.649507 -237.169483) (xy 373.650002 -237.19409) (xy 373.649507 -237.218697)
			(xy 373.641612 -237.267274) (xy 373.626028 -237.313955) (xy 373.603157 -237.357532) (xy 373.573592 -237.396876)
			(xy 373.538099 -237.430968) (xy 373.497596 -237.458924) (xy 373.453134 -237.480022) (xy 373.405863 -237.493714)
			(xy 373.357008 -237.499646) (xy 373.307833 -237.497665) (xy 373.259614 -237.487821) (xy 373.213598 -237.470369)
			(xy 373.170977 -237.445762) (xy 373.132856 -237.414637) (xy 373.100221 -237.3778) (xy 373.073918 -237.336204)
			(xy 373.054627 -237.290928) (xy 373.04285 -237.243144) (xy 373.03889 -237.19409) (xy 372.710202 -237.19409)
			(xy 372.709707 -237.218697) (xy 372.701812 -237.267274) (xy 372.686228 -237.313955) (xy 372.663357 -237.357532)
			(xy 372.633792 -237.396876) (xy 372.598299 -237.430968) (xy 372.557796 -237.458924) (xy 372.513334 -237.480022)
			(xy 372.466063 -237.493714) (xy 372.417208 -237.499646) (xy 372.368033 -237.497665) (xy 372.319814 -237.487821)
			(xy 372.273798 -237.470369) (xy 372.231177 -237.445762) (xy 372.193056 -237.414637) (xy 372.160421 -237.3778)
			(xy 372.134118 -237.336204) (xy 372.114827 -237.290928) (xy 372.10305 -237.243144) (xy 372.09909 -237.19409)
			(xy 371.770148 -237.19409) (xy 371.769653 -237.218697) (xy 371.761758 -237.267274) (xy 371.746174 -237.313955)
			(xy 371.723303 -237.357532) (xy 371.693738 -237.396876) (xy 371.658245 -237.430968) (xy 371.617742 -237.458924)
			(xy 371.57328 -237.480022) (xy 371.526009 -237.493714) (xy 371.477154 -237.499646) (xy 371.427979 -237.497665)
			(xy 371.37976 -237.487821) (xy 371.333744 -237.470369) (xy 371.291123 -237.445762) (xy 371.253002 -237.414637)
			(xy 371.220367 -237.3778) (xy 371.194064 -237.336204) (xy 371.174773 -237.290928) (xy 371.162996 -237.243144)
			(xy 371.159036 -237.19409) (xy 370.830094 -237.19409) (xy 370.829599 -237.218697) (xy 370.821704 -237.267274)
			(xy 370.80612 -237.313955) (xy 370.783249 -237.357532) (xy 370.753684 -237.396876) (xy 370.718191 -237.430968)
			(xy 370.677688 -237.458924) (xy 370.633226 -237.480022) (xy 370.585955 -237.493714) (xy 370.5371 -237.499646)
			(xy 370.487925 -237.497665) (xy 370.439706 -237.487821) (xy 370.39369 -237.470369) (xy 370.351069 -237.445762)
			(xy 370.312948 -237.414637) (xy 370.280313 -237.3778) (xy 370.25401 -237.336204) (xy 370.234719 -237.290928)
			(xy 370.222942 -237.243144) (xy 370.218982 -237.19409) (xy 369.89004 -237.19409) (xy 369.889545 -237.218697)
			(xy 369.88165 -237.267274) (xy 369.866066 -237.313955) (xy 369.843195 -237.357532) (xy 369.81363 -237.396876)
			(xy 369.778137 -237.430968) (xy 369.737634 -237.458924) (xy 369.693172 -237.480022) (xy 369.645901 -237.493714)
			(xy 369.597046 -237.499646) (xy 369.547871 -237.497665) (xy 369.499652 -237.487821) (xy 369.453636 -237.470369)
			(xy 369.411015 -237.445762) (xy 369.372894 -237.414637) (xy 369.340259 -237.3778) (xy 369.313956 -237.336204)
			(xy 369.294665 -237.290928) (xy 369.282888 -237.243144) (xy 369.278928 -237.19409) (xy 368.949986 -237.19409)
			(xy 368.949491 -237.218697) (xy 368.941596 -237.267274) (xy 368.926012 -237.313955) (xy 368.903141 -237.357532)
			(xy 368.873576 -237.396876) (xy 368.838083 -237.430968) (xy 368.79758 -237.458924) (xy 368.753118 -237.480022)
			(xy 368.705847 -237.493714) (xy 368.656992 -237.499646) (xy 368.607817 -237.497665) (xy 368.559598 -237.487821)
			(xy 368.513582 -237.470369) (xy 368.470961 -237.445762) (xy 368.43284 -237.414637) (xy 368.400205 -237.3778)
			(xy 368.373902 -237.336204) (xy 368.354611 -237.290928) (xy 368.342834 -237.243144) (xy 368.338874 -237.19409)
			(xy 368.010186 -237.19409) (xy 368.009691 -237.218697) (xy 368.001796 -237.267274) (xy 367.986212 -237.313955)
			(xy 367.963341 -237.357532) (xy 367.933776 -237.396876) (xy 367.898283 -237.430968) (xy 367.85778 -237.458924)
			(xy 367.813318 -237.480022) (xy 367.766047 -237.493714) (xy 367.717192 -237.499646) (xy 367.668017 -237.497665)
			(xy 367.619798 -237.487821) (xy 367.573782 -237.470369) (xy 367.531161 -237.445762) (xy 367.49304 -237.414637)
			(xy 367.460405 -237.3778) (xy 367.434102 -237.336204) (xy 367.414811 -237.290928) (xy 367.403034 -237.243144)
			(xy 367.399074 -237.19409) (xy 367.070132 -237.19409) (xy 367.069637 -237.218697) (xy 367.061742 -237.267274)
			(xy 367.046158 -237.313955) (xy 367.023287 -237.357532) (xy 366.993722 -237.396876) (xy 366.958229 -237.430968)
			(xy 366.917726 -237.458924) (xy 366.873264 -237.480022) (xy 366.825993 -237.493714) (xy 366.777138 -237.499646)
			(xy 366.727963 -237.497665) (xy 366.679744 -237.487821) (xy 366.633728 -237.470369) (xy 366.591107 -237.445762)
			(xy 366.552986 -237.414637) (xy 366.520351 -237.3778) (xy 366.494048 -237.336204) (xy 366.474757 -237.290928)
			(xy 366.46298 -237.243144) (xy 366.45902 -237.19409) (xy 366.130078 -237.19409) (xy 366.129583 -237.218697)
			(xy 366.121688 -237.267274) (xy 366.106104 -237.313955) (xy 366.083233 -237.357532) (xy 366.053668 -237.396876)
			(xy 366.018175 -237.430968) (xy 365.977672 -237.458924) (xy 365.93321 -237.480022) (xy 365.885939 -237.493714)
			(xy 365.837084 -237.499646) (xy 365.787909 -237.497665) (xy 365.73969 -237.487821) (xy 365.693674 -237.470369)
			(xy 365.651053 -237.445762) (xy 365.612932 -237.414637) (xy 365.580297 -237.3778) (xy 365.553994 -237.336204)
			(xy 365.534703 -237.290928) (xy 365.522926 -237.243144) (xy 365.518966 -237.19409) (xy 365.190024 -237.19409)
			(xy 365.189529 -237.218697) (xy 365.181634 -237.267274) (xy 365.16605 -237.313955) (xy 365.143179 -237.357532)
			(xy 365.113614 -237.396876) (xy 365.078121 -237.430968) (xy 365.037618 -237.458924) (xy 364.993156 -237.480022)
			(xy 364.945885 -237.493714) (xy 364.89703 -237.499646) (xy 364.847855 -237.497665) (xy 364.799636 -237.487821)
			(xy 364.75362 -237.470369) (xy 364.710999 -237.445762) (xy 364.672878 -237.414637) (xy 364.640243 -237.3778)
			(xy 364.61394 -237.336204) (xy 364.594649 -237.290928) (xy 364.582872 -237.243144) (xy 364.578912 -237.19409)
			(xy 364.250224 -237.19409) (xy 364.249729 -237.218697) (xy 364.241834 -237.267274) (xy 364.22625 -237.313955)
			(xy 364.203379 -237.357532) (xy 364.173814 -237.396876) (xy 364.138321 -237.430968) (xy 364.097818 -237.458924)
			(xy 364.053356 -237.480022) (xy 364.006085 -237.493714) (xy 363.95723 -237.499646) (xy 363.908055 -237.497665)
			(xy 363.859836 -237.487821) (xy 363.81382 -237.470369) (xy 363.771199 -237.445762) (xy 363.733078 -237.414637)
			(xy 363.700443 -237.3778) (xy 363.67414 -237.336204) (xy 363.654849 -237.290928) (xy 363.643072 -237.243144)
			(xy 363.639112 -237.19409) (xy 361.430669 -237.19409) (xy 361.43067 -237.1941) (xy 361.426498 -237.244449)
			(xy 361.414094 -237.293425) (xy 361.393798 -237.339691) (xy 361.366162 -237.381985) (xy 361.331942 -237.419152)
			(xy 361.292071 -237.45018) (xy 361.247635 -237.474221) (xy 361.199849 -237.49062) (xy 361.150015 -237.498929)
			(xy 361.124754 -237.499398) (xy 361.123992 -237.499398) (xy 361.09998 -237.498882) (xy 361.052558 -237.491287)
			(xy 361.006904 -237.47638) (xy 360.985308 -237.46587) (xy 360.985054 -237.46587) (xy 360.979211 -237.463128)
			(xy 360.966618 -237.460313) (xy 360.960162 -237.460282) (xy 360.9467 -237.46079) (xy 360.861864 -237.51286)
			(xy 360.855677 -237.516844) (xy 360.845732 -237.527683) (xy 360.842306 -237.534196) (xy 360.83748 -237.544864)
			(xy 360.83748 -238.004096) (xy 361.289104 -238.004096) (xy 361.293064 -237.955042) (xy 361.304841 -237.907258)
			(xy 361.324132 -237.861982) (xy 361.350435 -237.820386) (xy 361.38307 -237.783549) (xy 361.421191 -237.752424)
			(xy 361.463812 -237.727817) (xy 361.509828 -237.710365) (xy 361.558047 -237.700521) (xy 361.607222 -237.69854)
			(xy 361.656077 -237.704472) (xy 361.703348 -237.718164) (xy 361.74781 -237.739262) (xy 361.788313 -237.767218)
			(xy 361.823806 -237.80131) (xy 361.853371 -237.840654) (xy 361.876242 -237.884231) (xy 361.891826 -237.930912)
			(xy 361.899721 -237.979489) (xy 361.900216 -238.004096) (xy 362.228904 -238.004096) (xy 362.232864 -237.955042)
			(xy 362.244641 -237.907258) (xy 362.263932 -237.861982) (xy 362.290235 -237.820386) (xy 362.32287 -237.783549)
			(xy 362.360991 -237.752424) (xy 362.403612 -237.727817) (xy 362.449628 -237.710365) (xy 362.497847 -237.700521)
			(xy 362.547022 -237.69854) (xy 362.595877 -237.704472) (xy 362.643148 -237.718164) (xy 362.68761 -237.739262)
			(xy 362.728113 -237.767218) (xy 362.763606 -237.80131) (xy 362.793171 -237.840654) (xy 362.816042 -237.884231)
			(xy 362.831626 -237.930912) (xy 362.839521 -237.979489) (xy 362.840016 -238.004096) (xy 363.168958 -238.004096)
			(xy 363.172918 -237.955042) (xy 363.184695 -237.907258) (xy 363.203986 -237.861982) (xy 363.230289 -237.820386)
			(xy 363.262924 -237.783549) (xy 363.301045 -237.752424) (xy 363.343666 -237.727817) (xy 363.389682 -237.710365)
			(xy 363.437901 -237.700521) (xy 363.487076 -237.69854) (xy 363.535931 -237.704472) (xy 363.583202 -237.718164)
			(xy 363.627664 -237.739262) (xy 363.668167 -237.767218) (xy 363.70366 -237.80131) (xy 363.733225 -237.840654)
			(xy 363.756096 -237.884231) (xy 363.77168 -237.930912) (xy 363.779575 -237.979489) (xy 363.78007 -238.004096)
			(xy 364.098581 -238.004096) (xy 364.102676 -237.953368) (xy 364.114855 -237.903954) (xy 364.134803 -237.857134)
			(xy 364.162004 -237.81412) (xy 364.195752 -237.776026) (xy 364.235174 -237.743839) (xy 364.279248 -237.718393)
			(xy 364.326834 -237.700346) (xy 364.376698 -237.690166) (xy 364.42755 -237.688117) (xy 364.478071 -237.694251)
			(xy 364.526955 -237.708411) (xy 364.572934 -237.730228) (xy 364.614818 -237.759138) (xy 364.651522 -237.794393)
			(xy 364.682095 -237.835079) (xy 364.705746 -237.880142) (xy 364.721862 -237.928416) (xy 364.730026 -237.97865)
			(xy 364.730538 -238.004096) (xy 365.038635 -238.004096) (xy 365.04273 -237.953368) (xy 365.054909 -237.903954)
			(xy 365.074857 -237.857134) (xy 365.102058 -237.81412) (xy 365.135806 -237.776026) (xy 365.175228 -237.743839)
			(xy 365.219302 -237.718393) (xy 365.266888 -237.700346) (xy 365.316752 -237.690166) (xy 365.367604 -237.688117)
			(xy 365.418125 -237.694251) (xy 365.467009 -237.708411) (xy 365.512988 -237.730228) (xy 365.554872 -237.759138)
			(xy 365.591576 -237.794393) (xy 365.622149 -237.835079) (xy 365.6458 -237.880142) (xy 365.661916 -237.928416)
			(xy 365.67008 -237.97865) (xy 365.670592 -238.004096) (xy 365.98912 -238.004096) (xy 365.99308 -237.955042)
			(xy 366.004857 -237.907258) (xy 366.024148 -237.861982) (xy 366.050451 -237.820386) (xy 366.083086 -237.783549)
			(xy 366.121207 -237.752424) (xy 366.163828 -237.727817) (xy 366.209844 -237.710365) (xy 366.258063 -237.700521)
			(xy 366.307238 -237.69854) (xy 366.356093 -237.704472) (xy 366.403364 -237.718164) (xy 366.447826 -237.739262)
			(xy 366.488329 -237.767218) (xy 366.523822 -237.80131) (xy 366.553387 -237.840654) (xy 366.576258 -237.884231)
			(xy 366.591842 -237.930912) (xy 366.599737 -237.979489) (xy 366.600232 -238.004096) (xy 366.92892 -238.004096)
			(xy 366.93288 -237.955042) (xy 366.944657 -237.907258) (xy 366.963948 -237.861982) (xy 366.990251 -237.820386)
			(xy 367.022886 -237.783549) (xy 367.061007 -237.752424) (xy 367.103628 -237.727817) (xy 367.149644 -237.710365)
			(xy 367.197863 -237.700521) (xy 367.247038 -237.69854) (xy 367.295893 -237.704472) (xy 367.343164 -237.718164)
			(xy 367.387626 -237.739262) (xy 367.428129 -237.767218) (xy 367.463622 -237.80131) (xy 367.493187 -237.840654)
			(xy 367.516058 -237.884231) (xy 367.531642 -237.930912) (xy 367.539537 -237.979489) (xy 367.540032 -238.004096)
			(xy 367.868974 -238.004096) (xy 367.872934 -237.955042) (xy 367.884711 -237.907258) (xy 367.904002 -237.861982)
			(xy 367.930305 -237.820386) (xy 367.96294 -237.783549) (xy 368.001061 -237.752424) (xy 368.043682 -237.727817)
			(xy 368.089698 -237.710365) (xy 368.137917 -237.700521) (xy 368.187092 -237.69854) (xy 368.235947 -237.704472)
			(xy 368.283218 -237.718164) (xy 368.32768 -237.739262) (xy 368.368183 -237.767218) (xy 368.403676 -237.80131)
			(xy 368.433241 -237.840654) (xy 368.456112 -237.884231) (xy 368.471696 -237.930912) (xy 368.479591 -237.979489)
			(xy 368.480086 -238.004096) (xy 368.809028 -238.004096) (xy 368.812988 -237.955042) (xy 368.824765 -237.907258)
			(xy 368.844056 -237.861982) (xy 368.870359 -237.820386) (xy 368.902994 -237.783549) (xy 368.941115 -237.752424)
			(xy 368.983736 -237.727817) (xy 369.029752 -237.710365) (xy 369.077971 -237.700521) (xy 369.127146 -237.69854)
			(xy 369.176001 -237.704472) (xy 369.223272 -237.718164) (xy 369.267734 -237.739262) (xy 369.308237 -237.767218)
			(xy 369.34373 -237.80131) (xy 369.373295 -237.840654) (xy 369.396166 -237.884231) (xy 369.41175 -237.930912)
			(xy 369.419645 -237.979489) (xy 369.42014 -238.004096) (xy 369.749082 -238.004096) (xy 369.753042 -237.955042)
			(xy 369.764819 -237.907258) (xy 369.78411 -237.861982) (xy 369.810413 -237.820386) (xy 369.843048 -237.783549)
			(xy 369.881169 -237.752424) (xy 369.92379 -237.727817) (xy 369.969806 -237.710365) (xy 370.018025 -237.700521)
			(xy 370.0672 -237.69854) (xy 370.116055 -237.704472) (xy 370.163326 -237.718164) (xy 370.207788 -237.739262)
			(xy 370.248291 -237.767218) (xy 370.283784 -237.80131) (xy 370.313349 -237.840654) (xy 370.33622 -237.884231)
			(xy 370.351804 -237.930912) (xy 370.359699 -237.979489) (xy 370.360194 -238.004096) (xy 370.688882 -238.004096)
			(xy 370.692842 -237.955042) (xy 370.704619 -237.907258) (xy 370.72391 -237.861982) (xy 370.750213 -237.820386)
			(xy 370.782848 -237.783549) (xy 370.820969 -237.752424) (xy 370.86359 -237.727817) (xy 370.909606 -237.710365)
			(xy 370.957825 -237.700521) (xy 371.007 -237.69854) (xy 371.055855 -237.704472) (xy 371.103126 -237.718164)
			(xy 371.147588 -237.739262) (xy 371.188091 -237.767218) (xy 371.223584 -237.80131) (xy 371.253149 -237.840654)
			(xy 371.27602 -237.884231) (xy 371.291604 -237.930912) (xy 371.299499 -237.979489) (xy 371.299994 -238.004096)
			(xy 371.628936 -238.004096) (xy 371.632896 -237.955042) (xy 371.644673 -237.907258) (xy 371.663964 -237.861982)
			(xy 371.690267 -237.820386) (xy 371.722902 -237.783549) (xy 371.761023 -237.752424) (xy 371.803644 -237.727817)
			(xy 371.84966 -237.710365) (xy 371.897879 -237.700521) (xy 371.947054 -237.69854) (xy 371.995909 -237.704472)
			(xy 372.04318 -237.718164) (xy 372.087642 -237.739262) (xy 372.128145 -237.767218) (xy 372.163638 -237.80131)
			(xy 372.193203 -237.840654) (xy 372.216074 -237.884231) (xy 372.231658 -237.930912) (xy 372.239553 -237.979489)
			(xy 372.240048 -238.004096) (xy 372.56899 -238.004096) (xy 372.57295 -237.955042) (xy 372.584727 -237.907258)
			(xy 372.604018 -237.861982) (xy 372.630321 -237.820386) (xy 372.662956 -237.783549) (xy 372.701077 -237.752424)
			(xy 372.743698 -237.727817) (xy 372.789714 -237.710365) (xy 372.837933 -237.700521) (xy 372.887108 -237.69854)
			(xy 372.935963 -237.704472) (xy 372.983234 -237.718164) (xy 373.027696 -237.739262) (xy 373.068199 -237.767218)
			(xy 373.103692 -237.80131) (xy 373.133257 -237.840654) (xy 373.156128 -237.884231) (xy 373.171712 -237.930912)
			(xy 373.179607 -237.979489) (xy 373.180102 -238.004096) (xy 373.509044 -238.004096) (xy 373.513004 -237.955042)
			(xy 373.524781 -237.907258) (xy 373.544072 -237.861982) (xy 373.570375 -237.820386) (xy 373.60301 -237.783549)
			(xy 373.641131 -237.752424) (xy 373.683752 -237.727817) (xy 373.729768 -237.710365) (xy 373.777987 -237.700521)
			(xy 373.827162 -237.69854) (xy 373.876017 -237.704472) (xy 373.923288 -237.718164) (xy 373.96775 -237.739262)
			(xy 374.008253 -237.767218) (xy 374.043746 -237.80131) (xy 374.073311 -237.840654) (xy 374.096182 -237.884231)
			(xy 374.111766 -237.930912) (xy 374.119661 -237.979489) (xy 374.120156 -238.004096) (xy 374.119661 -238.028703)
			(xy 374.111766 -238.07728) (xy 374.096182 -238.123961) (xy 374.073311 -238.167538) (xy 374.043746 -238.206882)
			(xy 374.008253 -238.240974) (xy 373.96775 -238.26893) (xy 373.923288 -238.290028) (xy 373.876017 -238.30372)
			(xy 373.827162 -238.309652) (xy 373.777987 -238.307671) (xy 373.729768 -238.297827) (xy 373.683752 -238.280375)
			(xy 373.641131 -238.255768) (xy 373.60301 -238.224643) (xy 373.570375 -238.187806) (xy 373.544072 -238.14621)
			(xy 373.524781 -238.100934) (xy 373.513004 -238.05315) (xy 373.509044 -238.004096) (xy 373.180102 -238.004096)
			(xy 373.179607 -238.028703) (xy 373.171712 -238.07728) (xy 373.156128 -238.123961) (xy 373.133257 -238.167538)
			(xy 373.103692 -238.206882) (xy 373.068199 -238.240974) (xy 373.027696 -238.26893) (xy 372.983234 -238.290028)
			(xy 372.935963 -238.30372) (xy 372.887108 -238.309652) (xy 372.837933 -238.307671) (xy 372.789714 -238.297827)
			(xy 372.743698 -238.280375) (xy 372.701077 -238.255768) (xy 372.662956 -238.224643) (xy 372.630321 -238.187806)
			(xy 372.604018 -238.14621) (xy 372.584727 -238.100934) (xy 372.57295 -238.05315) (xy 372.56899 -238.004096)
			(xy 372.240048 -238.004096) (xy 372.239553 -238.028703) (xy 372.231658 -238.07728) (xy 372.216074 -238.123961)
			(xy 372.193203 -238.167538) (xy 372.163638 -238.206882) (xy 372.128145 -238.240974) (xy 372.087642 -238.26893)
			(xy 372.04318 -238.290028) (xy 371.995909 -238.30372) (xy 371.947054 -238.309652) (xy 371.897879 -238.307671)
			(xy 371.84966 -238.297827) (xy 371.803644 -238.280375) (xy 371.761023 -238.255768) (xy 371.722902 -238.224643)
			(xy 371.690267 -238.187806) (xy 371.663964 -238.14621) (xy 371.644673 -238.100934) (xy 371.632896 -238.05315)
			(xy 371.628936 -238.004096) (xy 371.299994 -238.004096) (xy 371.299499 -238.028703) (xy 371.291604 -238.07728)
			(xy 371.27602 -238.123961) (xy 371.253149 -238.167538) (xy 371.223584 -238.206882) (xy 371.188091 -238.240974)
			(xy 371.147588 -238.26893) (xy 371.103126 -238.290028) (xy 371.055855 -238.30372) (xy 371.007 -238.309652)
			(xy 370.957825 -238.307671) (xy 370.909606 -238.297827) (xy 370.86359 -238.280375) (xy 370.820969 -238.255768)
			(xy 370.782848 -238.224643) (xy 370.750213 -238.187806) (xy 370.72391 -238.14621) (xy 370.704619 -238.100934)
			(xy 370.692842 -238.05315) (xy 370.688882 -238.004096) (xy 370.360194 -238.004096) (xy 370.359699 -238.028703)
			(xy 370.351804 -238.07728) (xy 370.33622 -238.123961) (xy 370.313349 -238.167538) (xy 370.283784 -238.206882)
			(xy 370.248291 -238.240974) (xy 370.207788 -238.26893) (xy 370.163326 -238.290028) (xy 370.116055 -238.30372)
			(xy 370.0672 -238.309652) (xy 370.018025 -238.307671) (xy 369.969806 -238.297827) (xy 369.92379 -238.280375)
			(xy 369.881169 -238.255768) (xy 369.843048 -238.224643) (xy 369.810413 -238.187806) (xy 369.78411 -238.14621)
			(xy 369.764819 -238.100934) (xy 369.753042 -238.05315) (xy 369.749082 -238.004096) (xy 369.42014 -238.004096)
			(xy 369.419645 -238.028703) (xy 369.41175 -238.07728) (xy 369.396166 -238.123961) (xy 369.373295 -238.167538)
			(xy 369.34373 -238.206882) (xy 369.308237 -238.240974) (xy 369.267734 -238.26893) (xy 369.223272 -238.290028)
			(xy 369.176001 -238.30372) (xy 369.127146 -238.309652) (xy 369.077971 -238.307671) (xy 369.029752 -238.297827)
			(xy 368.983736 -238.280375) (xy 368.941115 -238.255768) (xy 368.902994 -238.224643) (xy 368.870359 -238.187806)
			(xy 368.844056 -238.14621) (xy 368.824765 -238.100934) (xy 368.812988 -238.05315) (xy 368.809028 -238.004096)
			(xy 368.480086 -238.004096) (xy 368.479591 -238.028703) (xy 368.471696 -238.07728) (xy 368.456112 -238.123961)
			(xy 368.433241 -238.167538) (xy 368.403676 -238.206882) (xy 368.368183 -238.240974) (xy 368.32768 -238.26893)
			(xy 368.283218 -238.290028) (xy 368.235947 -238.30372) (xy 368.187092 -238.309652) (xy 368.137917 -238.307671)
			(xy 368.089698 -238.297827) (xy 368.043682 -238.280375) (xy 368.001061 -238.255768) (xy 367.96294 -238.224643)
			(xy 367.930305 -238.187806) (xy 367.904002 -238.14621) (xy 367.884711 -238.100934) (xy 367.872934 -238.05315)
			(xy 367.868974 -238.004096) (xy 367.540032 -238.004096) (xy 367.539537 -238.028703) (xy 367.531642 -238.07728)
			(xy 367.516058 -238.123961) (xy 367.493187 -238.167538) (xy 367.463622 -238.206882) (xy 367.428129 -238.240974)
			(xy 367.387626 -238.26893) (xy 367.343164 -238.290028) (xy 367.295893 -238.30372) (xy 367.247038 -238.309652)
			(xy 367.197863 -238.307671) (xy 367.149644 -238.297827) (xy 367.103628 -238.280375) (xy 367.061007 -238.255768)
			(xy 367.022886 -238.224643) (xy 366.990251 -238.187806) (xy 366.963948 -238.14621) (xy 366.944657 -238.100934)
			(xy 366.93288 -238.05315) (xy 366.92892 -238.004096) (xy 366.600232 -238.004096) (xy 366.599737 -238.028703)
			(xy 366.591842 -238.07728) (xy 366.576258 -238.123961) (xy 366.553387 -238.167538) (xy 366.523822 -238.206882)
			(xy 366.488329 -238.240974) (xy 366.447826 -238.26893) (xy 366.403364 -238.290028) (xy 366.356093 -238.30372)
			(xy 366.307238 -238.309652) (xy 366.258063 -238.307671) (xy 366.209844 -238.297827) (xy 366.163828 -238.280375)
			(xy 366.121207 -238.255768) (xy 366.083086 -238.224643) (xy 366.050451 -238.187806) (xy 366.024148 -238.14621)
			(xy 366.004857 -238.100934) (xy 365.99308 -238.05315) (xy 365.98912 -238.004096) (xy 365.670592 -238.004096)
			(xy 365.67008 -238.029542) (xy 365.661916 -238.079776) (xy 365.6458 -238.12805) (xy 365.622149 -238.173113)
			(xy 365.591576 -238.213799) (xy 365.554872 -238.249054) (xy 365.512988 -238.277964) (xy 365.467009 -238.299781)
			(xy 365.418125 -238.313941) (xy 365.367604 -238.320075) (xy 365.316752 -238.318026) (xy 365.266888 -238.307846)
			(xy 365.219302 -238.289799) (xy 365.175228 -238.264353) (xy 365.135806 -238.232166) (xy 365.102058 -238.194072)
			(xy 365.074857 -238.151058) (xy 365.054909 -238.104238) (xy 365.04273 -238.054824) (xy 365.038635 -238.004096)
			(xy 364.730538 -238.004096) (xy 364.730026 -238.029542) (xy 364.721862 -238.079776) (xy 364.705746 -238.12805)
			(xy 364.682095 -238.173113) (xy 364.651522 -238.213799) (xy 364.614818 -238.249054) (xy 364.572934 -238.277964)
			(xy 364.526955 -238.299781) (xy 364.478071 -238.313941) (xy 364.42755 -238.320075) (xy 364.376698 -238.318026)
			(xy 364.326834 -238.307846) (xy 364.279248 -238.289799) (xy 364.235174 -238.264353) (xy 364.195752 -238.232166)
			(xy 364.162004 -238.194072) (xy 364.134803 -238.151058) (xy 364.114855 -238.104238) (xy 364.102676 -238.054824)
			(xy 364.098581 -238.004096) (xy 363.78007 -238.004096) (xy 363.779575 -238.028703) (xy 363.77168 -238.07728)
			(xy 363.756096 -238.123961) (xy 363.733225 -238.167538) (xy 363.70366 -238.206882) (xy 363.668167 -238.240974)
			(xy 363.627664 -238.26893) (xy 363.583202 -238.290028) (xy 363.535931 -238.30372) (xy 363.487076 -238.309652)
			(xy 363.437901 -238.307671) (xy 363.389682 -238.297827) (xy 363.343666 -238.280375) (xy 363.301045 -238.255768)
			(xy 363.262924 -238.224643) (xy 363.230289 -238.187806) (xy 363.203986 -238.14621) (xy 363.184695 -238.100934)
			(xy 363.172918 -238.05315) (xy 363.168958 -238.004096) (xy 362.840016 -238.004096) (xy 362.839521 -238.028703)
			(xy 362.831626 -238.07728) (xy 362.816042 -238.123961) (xy 362.793171 -238.167538) (xy 362.763606 -238.206882)
			(xy 362.728113 -238.240974) (xy 362.68761 -238.26893) (xy 362.643148 -238.290028) (xy 362.595877 -238.30372)
			(xy 362.547022 -238.309652) (xy 362.497847 -238.307671) (xy 362.449628 -238.297827) (xy 362.403612 -238.280375)
			(xy 362.360991 -238.255768) (xy 362.32287 -238.224643) (xy 362.290235 -238.187806) (xy 362.263932 -238.14621)
			(xy 362.244641 -238.100934) (xy 362.232864 -238.05315) (xy 362.228904 -238.004096) (xy 361.900216 -238.004096)
			(xy 361.899721 -238.028703) (xy 361.891826 -238.07728) (xy 361.876242 -238.123961) (xy 361.853371 -238.167538)
			(xy 361.823806 -238.206882) (xy 361.788313 -238.240974) (xy 361.74781 -238.26893) (xy 361.703348 -238.290028)
			(xy 361.656077 -238.30372) (xy 361.607222 -238.309652) (xy 361.558047 -238.307671) (xy 361.509828 -238.297827)
			(xy 361.463812 -238.280375) (xy 361.421191 -238.255768) (xy 361.38307 -238.224643) (xy 361.350435 -238.187806)
			(xy 361.324132 -238.14621) (xy 361.304841 -238.100934) (xy 361.293064 -238.05315) (xy 361.289104 -238.004096)
			(xy 360.83748 -238.004096) (xy 360.83748 -238.44631) (xy 360.83875 -238.457486) (xy 360.841036 -238.468408)
			(xy 360.844846 -238.479076) (xy 360.84891 -238.487458) (xy 360.93527 -238.540544) (xy 360.940933 -238.543765)
			(xy 360.953407 -238.547507) (xy 360.959908 -238.54791) (xy 360.97337 -238.548418) (xy 360.985308 -238.542322)
			(xy 361.006888 -238.531772) (xy 361.052544 -238.51685) (xy 361.099976 -238.509279) (xy 361.123992 -238.508794)
			(xy 361.124754 -238.508794) (xy 361.150014 -238.509283) (xy 361.199846 -238.517592) (xy 361.247631 -238.53399)
			(xy 361.292064 -238.55803) (xy 361.331934 -238.589057) (xy 361.366153 -238.626223) (xy 361.393787 -238.668515)
			(xy 361.414083 -238.714779) (xy 361.426486 -238.763753) (xy 361.430658 -238.8141) (xy 361.430658 -238.814102)
			(xy 361.748573 -238.814102) (xy 361.752668 -238.763374) (xy 361.764847 -238.71396) (xy 361.784795 -238.66714)
			(xy 361.811996 -238.624126) (xy 361.845744 -238.586032) (xy 361.885166 -238.553845) (xy 361.92924 -238.528399)
			(xy 361.976826 -238.510352) (xy 362.02669 -238.500172) (xy 362.077542 -238.498123) (xy 362.128063 -238.504257)
			(xy 362.176947 -238.518417) (xy 362.222926 -238.540234) (xy 362.26481 -238.569144) (xy 362.301514 -238.604399)
			(xy 362.332087 -238.645085) (xy 362.355738 -238.690148) (xy 362.371854 -238.738422) (xy 362.380018 -238.788656)
			(xy 362.38053 -238.814102) (xy 362.688627 -238.814102) (xy 362.692722 -238.763374) (xy 362.704901 -238.71396)
			(xy 362.724849 -238.66714) (xy 362.75205 -238.624126) (xy 362.785798 -238.586032) (xy 362.82522 -238.553845)
			(xy 362.869294 -238.528399) (xy 362.91688 -238.510352) (xy 362.966744 -238.500172) (xy 363.017596 -238.498123)
			(xy 363.068117 -238.504257) (xy 363.117001 -238.518417) (xy 363.16298 -238.540234) (xy 363.204864 -238.569144)
			(xy 363.241568 -238.604399) (xy 363.272141 -238.645085) (xy 363.295792 -238.690148) (xy 363.311908 -238.738422)
			(xy 363.320072 -238.788656) (xy 363.320584 -238.814102) (xy 363.639112 -238.814102) (xy 363.643072 -238.765048)
			(xy 363.654849 -238.717264) (xy 363.67414 -238.671988) (xy 363.700443 -238.630392) (xy 363.733078 -238.593555)
			(xy 363.771199 -238.56243) (xy 363.81382 -238.537823) (xy 363.859836 -238.520371) (xy 363.908055 -238.510527)
			(xy 363.95723 -238.508546) (xy 364.006085 -238.514478) (xy 364.053356 -238.52817) (xy 364.097818 -238.549268)
			(xy 364.138321 -238.577224) (xy 364.173814 -238.611316) (xy 364.203379 -238.65066) (xy 364.22625 -238.694237)
			(xy 364.241834 -238.740918) (xy 364.249729 -238.789495) (xy 364.250224 -238.814102) (xy 366.45902 -238.814102)
			(xy 366.46298 -238.765048) (xy 366.474757 -238.717264) (xy 366.494048 -238.671988) (xy 366.520351 -238.630392)
			(xy 366.552986 -238.593555) (xy 366.591107 -238.56243) (xy 366.633728 -238.537823) (xy 366.679744 -238.520371)
			(xy 366.727963 -238.510527) (xy 366.777138 -238.508546) (xy 366.825993 -238.514478) (xy 366.873264 -238.52817)
			(xy 366.917726 -238.549268) (xy 366.958229 -238.577224) (xy 366.993722 -238.611316) (xy 367.023287 -238.65066)
			(xy 367.046158 -238.694237) (xy 367.061742 -238.740918) (xy 367.069637 -238.789495) (xy 367.070132 -238.814102)
			(xy 369.278928 -238.814102) (xy 369.282888 -238.765048) (xy 369.294665 -238.717264) (xy 369.313956 -238.671988)
			(xy 369.340259 -238.630392) (xy 369.372894 -238.593555) (xy 369.411015 -238.56243) (xy 369.453636 -238.537823)
			(xy 369.499652 -238.520371) (xy 369.547871 -238.510527) (xy 369.597046 -238.508546) (xy 369.645901 -238.514478)
			(xy 369.693172 -238.52817) (xy 369.737634 -238.549268) (xy 369.778137 -238.577224) (xy 369.81363 -238.611316)
			(xy 369.843195 -238.65066) (xy 369.866066 -238.694237) (xy 369.88165 -238.740918) (xy 369.889545 -238.789495)
			(xy 369.89004 -238.814102) (xy 372.09909 -238.814102) (xy 372.10305 -238.765048) (xy 372.114827 -238.717264)
			(xy 372.134118 -238.671988) (xy 372.160421 -238.630392) (xy 372.193056 -238.593555) (xy 372.231177 -238.56243)
			(xy 372.273798 -238.537823) (xy 372.319814 -238.520371) (xy 372.368033 -238.510527) (xy 372.417208 -238.508546)
			(xy 372.466063 -238.514478) (xy 372.513334 -238.52817) (xy 372.557796 -238.549268) (xy 372.598299 -238.577224)
			(xy 372.633792 -238.611316) (xy 372.663357 -238.65066) (xy 372.686228 -238.694237) (xy 372.701812 -238.740918)
			(xy 372.709707 -238.789495) (xy 372.710202 -238.814102) (xy 372.709707 -238.838709) (xy 372.701812 -238.887286)
			(xy 372.686228 -238.933967) (xy 372.663357 -238.977544) (xy 372.633792 -239.016888) (xy 372.598299 -239.05098)
			(xy 372.557796 -239.078936) (xy 372.513334 -239.100034) (xy 372.466063 -239.113726) (xy 372.417208 -239.119658)
			(xy 372.368033 -239.117677) (xy 372.319814 -239.107833) (xy 372.273798 -239.090381) (xy 372.231177 -239.065774)
			(xy 372.193056 -239.034649) (xy 372.160421 -238.997812) (xy 372.134118 -238.956216) (xy 372.114827 -238.91094)
			(xy 372.10305 -238.863156) (xy 372.09909 -238.814102) (xy 369.89004 -238.814102) (xy 369.889545 -238.838709)
			(xy 369.88165 -238.887286) (xy 369.866066 -238.933967) (xy 369.843195 -238.977544) (xy 369.81363 -239.016888)
			(xy 369.778137 -239.05098) (xy 369.737634 -239.078936) (xy 369.693172 -239.100034) (xy 369.645901 -239.113726)
			(xy 369.597046 -239.119658) (xy 369.547871 -239.117677) (xy 369.499652 -239.107833) (xy 369.453636 -239.090381)
			(xy 369.411015 -239.065774) (xy 369.372894 -239.034649) (xy 369.340259 -238.997812) (xy 369.313956 -238.956216)
			(xy 369.294665 -238.91094) (xy 369.282888 -238.863156) (xy 369.278928 -238.814102) (xy 367.070132 -238.814102)
			(xy 367.069637 -238.838709) (xy 367.061742 -238.887286) (xy 367.046158 -238.933967) (xy 367.023287 -238.977544)
			(xy 366.993722 -239.016888) (xy 366.958229 -239.05098) (xy 366.917726 -239.078936) (xy 366.873264 -239.100034)
			(xy 366.825993 -239.113726) (xy 366.777138 -239.119658) (xy 366.727963 -239.117677) (xy 366.679744 -239.107833)
			(xy 366.633728 -239.090381) (xy 366.591107 -239.065774) (xy 366.552986 -239.034649) (xy 366.520351 -238.997812)
			(xy 366.494048 -238.956216) (xy 366.474757 -238.91094) (xy 366.46298 -238.863156) (xy 366.45902 -238.814102)
			(xy 364.250224 -238.814102) (xy 364.249729 -238.838709) (xy 364.241834 -238.887286) (xy 364.22625 -238.933967)
			(xy 364.203379 -238.977544) (xy 364.173814 -239.016888) (xy 364.138321 -239.05098) (xy 364.097818 -239.078936)
			(xy 364.053356 -239.100034) (xy 364.006085 -239.113726) (xy 363.95723 -239.119658) (xy 363.908055 -239.117677)
			(xy 363.859836 -239.107833) (xy 363.81382 -239.090381) (xy 363.771199 -239.065774) (xy 363.733078 -239.034649)
			(xy 363.700443 -238.997812) (xy 363.67414 -238.956216) (xy 363.654849 -238.91094) (xy 363.643072 -238.863156)
			(xy 363.639112 -238.814102) (xy 363.320584 -238.814102) (xy 363.320072 -238.839548) (xy 363.311908 -238.889782)
			(xy 363.295792 -238.938056) (xy 363.272141 -238.983119) (xy 363.241568 -239.023805) (xy 363.204864 -239.05906)
			(xy 363.16298 -239.08797) (xy 363.117001 -239.109787) (xy 363.068117 -239.123947) (xy 363.017596 -239.130081)
			(xy 362.966744 -239.128032) (xy 362.91688 -239.117852) (xy 362.869294 -239.099805) (xy 362.82522 -239.074359)
			(xy 362.785798 -239.042172) (xy 362.75205 -239.004078) (xy 362.724849 -238.961064) (xy 362.704901 -238.914244)
			(xy 362.692722 -238.86483) (xy 362.688627 -238.814102) (xy 362.38053 -238.814102) (xy 362.380018 -238.839548)
			(xy 362.371854 -238.889782) (xy 362.355738 -238.938056) (xy 362.332087 -238.983119) (xy 362.301514 -239.023805)
			(xy 362.26481 -239.05906) (xy 362.222926 -239.08797) (xy 362.176947 -239.109787) (xy 362.128063 -239.123947)
			(xy 362.077542 -239.130081) (xy 362.02669 -239.128032) (xy 361.976826 -239.117852) (xy 361.92924 -239.099805)
			(xy 361.885166 -239.074359) (xy 361.845744 -239.042172) (xy 361.811996 -239.004078) (xy 361.784795 -238.961064)
			(xy 361.764847 -238.914244) (xy 361.752668 -238.86483) (xy 361.748573 -238.814102) (xy 361.430658 -238.814102)
			(xy 361.426486 -238.864447) (xy 361.414083 -238.913421) (xy 361.393787 -238.959685) (xy 361.366153 -239.001977)
			(xy 361.331934 -239.039143) (xy 361.292064 -239.07017) (xy 361.247631 -239.09421) (xy 361.199846 -239.110608)
			(xy 361.150014 -239.118917) (xy 361.124754 -239.11941) (xy 361.123992 -239.11941) (xy 361.09998 -239.118893)
			(xy 361.052559 -239.111297) (xy 361.006907 -239.096385) (xy 360.985308 -239.085882) (xy 360.985054 -239.085882)
			(xy 360.979211 -239.083139) (xy 360.966618 -239.080324) (xy 360.960162 -239.080294) (xy 360.9467 -239.080802)
			(xy 360.861864 -239.132872) (xy 360.855677 -239.136857) (xy 360.845735 -239.147697) (xy 360.842306 -239.154208)
			(xy 360.83748 -239.164876) (xy 360.83748 -239.624108) (xy 363.168958 -239.624108) (xy 363.172918 -239.575054)
			(xy 363.184695 -239.52727) (xy 363.203986 -239.481994) (xy 363.230289 -239.440398) (xy 363.262924 -239.403561)
			(xy 363.301045 -239.372436) (xy 363.343666 -239.347829) (xy 363.389682 -239.330377) (xy 363.437901 -239.320533)
			(xy 363.487076 -239.318552) (xy 363.535931 -239.324484) (xy 363.583202 -239.338176) (xy 363.627664 -239.359274)
			(xy 363.668167 -239.38723) (xy 363.70366 -239.421322) (xy 363.733225 -239.460666) (xy 363.756096 -239.504243)
			(xy 363.77168 -239.550924) (xy 363.779575 -239.599501) (xy 363.78007 -239.624108) (xy 364.098581 -239.624108)
			(xy 364.102676 -239.57338) (xy 364.114855 -239.523966) (xy 364.134803 -239.477146) (xy 364.162004 -239.434132)
			(xy 364.195752 -239.396038) (xy 364.235174 -239.363851) (xy 364.279248 -239.338405) (xy 364.326834 -239.320358)
			(xy 364.376698 -239.310178) (xy 364.42755 -239.308129) (xy 364.478071 -239.314263) (xy 364.526955 -239.328423)
			(xy 364.572934 -239.35024) (xy 364.614818 -239.37915) (xy 364.651522 -239.414405) (xy 364.682095 -239.455091)
			(xy 364.705746 -239.500154) (xy 364.721862 -239.548428) (xy 364.730026 -239.598662) (xy 364.730538 -239.624108)
			(xy 365.038635 -239.624108) (xy 365.04273 -239.57338) (xy 365.054909 -239.523966) (xy 365.074857 -239.477146)
			(xy 365.102058 -239.434132) (xy 365.135806 -239.396038) (xy 365.175228 -239.363851) (xy 365.219302 -239.338405)
			(xy 365.266888 -239.320358) (xy 365.316752 -239.310178) (xy 365.367604 -239.308129) (xy 365.418125 -239.314263)
			(xy 365.467009 -239.328423) (xy 365.512988 -239.35024) (xy 365.554872 -239.37915) (xy 365.591576 -239.414405)
			(xy 365.622149 -239.455091) (xy 365.6458 -239.500154) (xy 365.661916 -239.548428) (xy 365.67008 -239.598662)
			(xy 365.670592 -239.624108) (xy 365.98912 -239.624108) (xy 365.99308 -239.575054) (xy 366.004857 -239.52727)
			(xy 366.024148 -239.481994) (xy 366.050451 -239.440398) (xy 366.083086 -239.403561) (xy 366.121207 -239.372436)
			(xy 366.163828 -239.347829) (xy 366.209844 -239.330377) (xy 366.258063 -239.320533) (xy 366.307238 -239.318552)
			(xy 366.356093 -239.324484) (xy 366.403364 -239.338176) (xy 366.447826 -239.359274) (xy 366.488329 -239.38723)
			(xy 366.523822 -239.421322) (xy 366.553387 -239.460666) (xy 366.576258 -239.504243) (xy 366.591842 -239.550924)
			(xy 366.599737 -239.599501) (xy 366.600232 -239.624108) (xy 366.918489 -239.624108) (xy 366.922584 -239.57338)
			(xy 366.934763 -239.523966) (xy 366.954711 -239.477146) (xy 366.981912 -239.434132) (xy 367.01566 -239.396038)
			(xy 367.055082 -239.363851) (xy 367.099156 -239.338405) (xy 367.146742 -239.320358) (xy 367.196606 -239.310178)
			(xy 367.247458 -239.308129) (xy 367.297979 -239.314263) (xy 367.346863 -239.328423) (xy 367.392842 -239.35024)
			(xy 367.434726 -239.37915) (xy 367.47143 -239.414405) (xy 367.502003 -239.455091) (xy 367.525654 -239.500154)
			(xy 367.54177 -239.548428) (xy 367.549934 -239.598662) (xy 367.550446 -239.624108) (xy 367.858543 -239.624108)
			(xy 367.862638 -239.57338) (xy 367.874817 -239.523966) (xy 367.894765 -239.477146) (xy 367.921966 -239.434132)
			(xy 367.955714 -239.396038) (xy 367.995136 -239.363851) (xy 368.03921 -239.338405) (xy 368.086796 -239.320358)
			(xy 368.13666 -239.310178) (xy 368.187512 -239.308129) (xy 368.238033 -239.314263) (xy 368.286917 -239.328423)
			(xy 368.332896 -239.35024) (xy 368.37478 -239.37915) (xy 368.411484 -239.414405) (xy 368.442057 -239.455091)
			(xy 368.465708 -239.500154) (xy 368.481824 -239.548428) (xy 368.489988 -239.598662) (xy 368.4905 -239.624108)
			(xy 368.809028 -239.624108) (xy 368.812988 -239.575054) (xy 368.824765 -239.52727) (xy 368.844056 -239.481994)
			(xy 368.870359 -239.440398) (xy 368.902994 -239.403561) (xy 368.941115 -239.372436) (xy 368.983736 -239.347829)
			(xy 369.029752 -239.330377) (xy 369.077971 -239.320533) (xy 369.127146 -239.318552) (xy 369.176001 -239.324484)
			(xy 369.223272 -239.338176) (xy 369.267734 -239.359274) (xy 369.308237 -239.38723) (xy 369.34373 -239.421322)
			(xy 369.373295 -239.460666) (xy 369.396166 -239.504243) (xy 369.41175 -239.550924) (xy 369.419645 -239.599501)
			(xy 369.42014 -239.624108) (xy 369.738651 -239.624108) (xy 369.742746 -239.57338) (xy 369.754925 -239.523966)
			(xy 369.774873 -239.477146) (xy 369.802074 -239.434132) (xy 369.835822 -239.396038) (xy 369.875244 -239.363851)
			(xy 369.919318 -239.338405) (xy 369.966904 -239.320358) (xy 370.016768 -239.310178) (xy 370.06762 -239.308129)
			(xy 370.118141 -239.314263) (xy 370.167025 -239.328423) (xy 370.213004 -239.35024) (xy 370.254888 -239.37915)
			(xy 370.291592 -239.414405) (xy 370.322165 -239.455091) (xy 370.345816 -239.500154) (xy 370.361932 -239.548428)
			(xy 370.370096 -239.598662) (xy 370.370608 -239.624108) (xy 370.678451 -239.624108) (xy 370.682546 -239.57338)
			(xy 370.694725 -239.523966) (xy 370.714673 -239.477146) (xy 370.741874 -239.434132) (xy 370.775622 -239.396038)
			(xy 370.815044 -239.363851) (xy 370.859118 -239.338405) (xy 370.906704 -239.320358) (xy 370.956568 -239.310178)
			(xy 371.00742 -239.308129) (xy 371.057941 -239.314263) (xy 371.106825 -239.328423) (xy 371.152804 -239.35024)
			(xy 371.194688 -239.37915) (xy 371.231392 -239.414405) (xy 371.261965 -239.455091) (xy 371.285616 -239.500154)
			(xy 371.301732 -239.548428) (xy 371.309896 -239.598662) (xy 371.310408 -239.624108) (xy 371.628936 -239.624108)
			(xy 371.632896 -239.575054) (xy 371.644673 -239.52727) (xy 371.663964 -239.481994) (xy 371.690267 -239.440398)
			(xy 371.722902 -239.403561) (xy 371.761023 -239.372436) (xy 371.803644 -239.347829) (xy 371.84966 -239.330377)
			(xy 371.897879 -239.320533) (xy 371.947054 -239.318552) (xy 371.995909 -239.324484) (xy 372.04318 -239.338176)
			(xy 372.087642 -239.359274) (xy 372.128145 -239.38723) (xy 372.163638 -239.421322) (xy 372.193203 -239.460666)
			(xy 372.216074 -239.504243) (xy 372.231658 -239.550924) (xy 372.239553 -239.599501) (xy 372.240048 -239.624108)
			(xy 372.558559 -239.624108) (xy 372.562654 -239.57338) (xy 372.574833 -239.523966) (xy 372.594781 -239.477146)
			(xy 372.621982 -239.434132) (xy 372.65573 -239.396038) (xy 372.695152 -239.363851) (xy 372.739226 -239.338405)
			(xy 372.786812 -239.320358) (xy 372.836676 -239.310178) (xy 372.887528 -239.308129) (xy 372.938049 -239.314263)
			(xy 372.986933 -239.328423) (xy 373.032912 -239.35024) (xy 373.074796 -239.37915) (xy 373.1115 -239.414405)
			(xy 373.142073 -239.455091) (xy 373.165724 -239.500154) (xy 373.18184 -239.548428) (xy 373.190004 -239.598662)
			(xy 373.190516 -239.624108) (xy 373.498613 -239.624108) (xy 373.502708 -239.57338) (xy 373.514887 -239.523966)
			(xy 373.534835 -239.477146) (xy 373.562036 -239.434132) (xy 373.595784 -239.396038) (xy 373.635206 -239.363851)
			(xy 373.67928 -239.338405) (xy 373.726866 -239.320358) (xy 373.77673 -239.310178) (xy 373.827582 -239.308129)
			(xy 373.878103 -239.314263) (xy 373.926987 -239.328423) (xy 373.972966 -239.35024) (xy 374.01485 -239.37915)
			(xy 374.051554 -239.414405) (xy 374.082127 -239.455091) (xy 374.105778 -239.500154) (xy 374.121894 -239.548428)
			(xy 374.130058 -239.598662) (xy 374.13057 -239.624108) (xy 374.130058 -239.649554) (xy 374.121894 -239.699788)
			(xy 374.105778 -239.748062) (xy 374.082127 -239.793125) (xy 374.051554 -239.833811) (xy 374.01485 -239.869066)
			(xy 373.972966 -239.897976) (xy 373.926987 -239.919793) (xy 373.878103 -239.933953) (xy 373.827582 -239.940087)
			(xy 373.77673 -239.938038) (xy 373.726866 -239.927858) (xy 373.67928 -239.909811) (xy 373.635206 -239.884365)
			(xy 373.595784 -239.852178) (xy 373.562036 -239.814084) (xy 373.534835 -239.77107) (xy 373.514887 -239.72425)
			(xy 373.502708 -239.674836) (xy 373.498613 -239.624108) (xy 373.190516 -239.624108) (xy 373.190004 -239.649554)
			(xy 373.18184 -239.699788) (xy 373.165724 -239.748062) (xy 373.142073 -239.793125) (xy 373.1115 -239.833811)
			(xy 373.074796 -239.869066) (xy 373.032912 -239.897976) (xy 372.986933 -239.919793) (xy 372.938049 -239.933953)
			(xy 372.887528 -239.940087) (xy 372.836676 -239.938038) (xy 372.786812 -239.927858) (xy 372.739226 -239.909811)
			(xy 372.695152 -239.884365) (xy 372.65573 -239.852178) (xy 372.621982 -239.814084) (xy 372.594781 -239.77107)
			(xy 372.574833 -239.72425) (xy 372.562654 -239.674836) (xy 372.558559 -239.624108) (xy 372.240048 -239.624108)
			(xy 372.239553 -239.648715) (xy 372.231658 -239.697292) (xy 372.216074 -239.743973) (xy 372.193203 -239.78755)
			(xy 372.163638 -239.826894) (xy 372.128145 -239.860986) (xy 372.087642 -239.888942) (xy 372.04318 -239.91004)
			(xy 371.995909 -239.923732) (xy 371.947054 -239.929664) (xy 371.897879 -239.927683) (xy 371.84966 -239.917839)
			(xy 371.803644 -239.900387) (xy 371.761023 -239.87578) (xy 371.722902 -239.844655) (xy 371.690267 -239.807818)
			(xy 371.663964 -239.766222) (xy 371.644673 -239.720946) (xy 371.632896 -239.673162) (xy 371.628936 -239.624108)
			(xy 371.310408 -239.624108) (xy 371.309896 -239.649554) (xy 371.301732 -239.699788) (xy 371.285616 -239.748062)
			(xy 371.261965 -239.793125) (xy 371.231392 -239.833811) (xy 371.194688 -239.869066) (xy 371.152804 -239.897976)
			(xy 371.106825 -239.919793) (xy 371.057941 -239.933953) (xy 371.00742 -239.940087) (xy 370.956568 -239.938038)
			(xy 370.906704 -239.927858) (xy 370.859118 -239.909811) (xy 370.815044 -239.884365) (xy 370.775622 -239.852178)
			(xy 370.741874 -239.814084) (xy 370.714673 -239.77107) (xy 370.694725 -239.72425) (xy 370.682546 -239.674836)
			(xy 370.678451 -239.624108) (xy 370.370608 -239.624108) (xy 370.370096 -239.649554) (xy 370.361932 -239.699788)
			(xy 370.345816 -239.748062) (xy 370.322165 -239.793125) (xy 370.291592 -239.833811) (xy 370.254888 -239.869066)
			(xy 370.213004 -239.897976) (xy 370.167025 -239.919793) (xy 370.118141 -239.933953) (xy 370.06762 -239.940087)
			(xy 370.016768 -239.938038) (xy 369.966904 -239.927858) (xy 369.919318 -239.909811) (xy 369.875244 -239.884365)
			(xy 369.835822 -239.852178) (xy 369.802074 -239.814084) (xy 369.774873 -239.77107) (xy 369.754925 -239.72425)
			(xy 369.742746 -239.674836) (xy 369.738651 -239.624108) (xy 369.42014 -239.624108) (xy 369.419645 -239.648715)
			(xy 369.41175 -239.697292) (xy 369.396166 -239.743973) (xy 369.373295 -239.78755) (xy 369.34373 -239.826894)
			(xy 369.308237 -239.860986) (xy 369.267734 -239.888942) (xy 369.223272 -239.91004) (xy 369.176001 -239.923732)
			(xy 369.127146 -239.929664) (xy 369.077971 -239.927683) (xy 369.029752 -239.917839) (xy 368.983736 -239.900387)
			(xy 368.941115 -239.87578) (xy 368.902994 -239.844655) (xy 368.870359 -239.807818) (xy 368.844056 -239.766222)
			(xy 368.824765 -239.720946) (xy 368.812988 -239.673162) (xy 368.809028 -239.624108) (xy 368.4905 -239.624108)
			(xy 368.489988 -239.649554) (xy 368.481824 -239.699788) (xy 368.465708 -239.748062) (xy 368.442057 -239.793125)
			(xy 368.411484 -239.833811) (xy 368.37478 -239.869066) (xy 368.332896 -239.897976) (xy 368.286917 -239.919793)
			(xy 368.238033 -239.933953) (xy 368.187512 -239.940087) (xy 368.13666 -239.938038) (xy 368.086796 -239.927858)
			(xy 368.03921 -239.909811) (xy 367.995136 -239.884365) (xy 367.955714 -239.852178) (xy 367.921966 -239.814084)
			(xy 367.894765 -239.77107) (xy 367.874817 -239.72425) (xy 367.862638 -239.674836) (xy 367.858543 -239.624108)
			(xy 367.550446 -239.624108) (xy 367.549934 -239.649554) (xy 367.54177 -239.699788) (xy 367.525654 -239.748062)
			(xy 367.502003 -239.793125) (xy 367.47143 -239.833811) (xy 367.434726 -239.869066) (xy 367.392842 -239.897976)
			(xy 367.346863 -239.919793) (xy 367.297979 -239.933953) (xy 367.247458 -239.940087) (xy 367.196606 -239.938038)
			(xy 367.146742 -239.927858) (xy 367.099156 -239.909811) (xy 367.055082 -239.884365) (xy 367.01566 -239.852178)
			(xy 366.981912 -239.814084) (xy 366.954711 -239.77107) (xy 366.934763 -239.72425) (xy 366.922584 -239.674836)
			(xy 366.918489 -239.624108) (xy 366.600232 -239.624108) (xy 366.599737 -239.648715) (xy 366.591842 -239.697292)
			(xy 366.576258 -239.743973) (xy 366.553387 -239.78755) (xy 366.523822 -239.826894) (xy 366.488329 -239.860986)
			(xy 366.447826 -239.888942) (xy 366.403364 -239.91004) (xy 366.356093 -239.923732) (xy 366.307238 -239.929664)
			(xy 366.258063 -239.927683) (xy 366.209844 -239.917839) (xy 366.163828 -239.900387) (xy 366.121207 -239.87578)
			(xy 366.083086 -239.844655) (xy 366.050451 -239.807818) (xy 366.024148 -239.766222) (xy 366.004857 -239.720946)
			(xy 365.99308 -239.673162) (xy 365.98912 -239.624108) (xy 365.670592 -239.624108) (xy 365.67008 -239.649554)
			(xy 365.661916 -239.699788) (xy 365.6458 -239.748062) (xy 365.622149 -239.793125) (xy 365.591576 -239.833811)
			(xy 365.554872 -239.869066) (xy 365.512988 -239.897976) (xy 365.467009 -239.919793) (xy 365.418125 -239.933953)
			(xy 365.367604 -239.940087) (xy 365.316752 -239.938038) (xy 365.266888 -239.927858) (xy 365.219302 -239.909811)
			(xy 365.175228 -239.884365) (xy 365.135806 -239.852178) (xy 365.102058 -239.814084) (xy 365.074857 -239.77107)
			(xy 365.054909 -239.72425) (xy 365.04273 -239.674836) (xy 365.038635 -239.624108) (xy 364.730538 -239.624108)
			(xy 364.730026 -239.649554) (xy 364.721862 -239.699788) (xy 364.705746 -239.748062) (xy 364.682095 -239.793125)
			(xy 364.651522 -239.833811) (xy 364.614818 -239.869066) (xy 364.572934 -239.897976) (xy 364.526955 -239.919793)
			(xy 364.478071 -239.933953) (xy 364.42755 -239.940087) (xy 364.376698 -239.938038) (xy 364.326834 -239.927858)
			(xy 364.279248 -239.909811) (xy 364.235174 -239.884365) (xy 364.195752 -239.852178) (xy 364.162004 -239.814084)
			(xy 364.134803 -239.77107) (xy 364.114855 -239.72425) (xy 364.102676 -239.674836) (xy 364.098581 -239.624108)
			(xy 363.78007 -239.624108) (xy 363.779575 -239.648715) (xy 363.77168 -239.697292) (xy 363.756096 -239.743973)
			(xy 363.733225 -239.78755) (xy 363.70366 -239.826894) (xy 363.668167 -239.860986) (xy 363.627664 -239.888942)
			(xy 363.583202 -239.91004) (xy 363.535931 -239.923732) (xy 363.487076 -239.929664) (xy 363.437901 -239.927683)
			(xy 363.389682 -239.917839) (xy 363.343666 -239.900387) (xy 363.301045 -239.87578) (xy 363.262924 -239.844655)
			(xy 363.230289 -239.807818) (xy 363.203986 -239.766222) (xy 363.184695 -239.720946) (xy 363.172918 -239.673162)
			(xy 363.168958 -239.624108) (xy 360.83748 -239.624108) (xy 360.83748 -240.066322) (xy 360.83875 -240.077498)
			(xy 360.841036 -240.08842) (xy 360.844846 -240.099088) (xy 360.84891 -240.10747) (xy 360.93527 -240.160556)
			(xy 360.940933 -240.163776) (xy 360.953407 -240.167517) (xy 360.959908 -240.167922) (xy 360.97337 -240.16843)
			(xy 360.985308 -240.162334) (xy 361.006888 -240.151784) (xy 361.052544 -240.136861) (xy 361.099976 -240.12929)
			(xy 361.123992 -240.128806) (xy 361.124754 -240.128806) (xy 361.150013 -240.129295) (xy 361.199843 -240.137603)
			(xy 361.247626 -240.154001) (xy 361.292058 -240.17804) (xy 361.331926 -240.209065) (xy 361.366144 -240.24623)
			(xy 361.393777 -240.288521) (xy 361.414071 -240.334783) (xy 361.426474 -240.383755) (xy 361.430646 -240.4341)
			(xy 361.430645 -240.434114) (xy 361.748573 -240.434114) (xy 361.752668 -240.383386) (xy 361.764847 -240.333972)
			(xy 361.784795 -240.287152) (xy 361.811996 -240.244138) (xy 361.845744 -240.206044) (xy 361.885166 -240.173857)
			(xy 361.92924 -240.148411) (xy 361.976826 -240.130364) (xy 362.02669 -240.120184) (xy 362.077542 -240.118135)
			(xy 362.128063 -240.124269) (xy 362.176947 -240.138429) (xy 362.222926 -240.160246) (xy 362.26481 -240.189156)
			(xy 362.301514 -240.224411) (xy 362.332087 -240.265097) (xy 362.355738 -240.31016) (xy 362.371854 -240.358434)
			(xy 362.380018 -240.408668) (xy 362.38053 -240.434114) (xy 362.688627 -240.434114) (xy 362.692722 -240.383386)
			(xy 362.704901 -240.333972) (xy 362.724849 -240.287152) (xy 362.75205 -240.244138) (xy 362.785798 -240.206044)
			(xy 362.82522 -240.173857) (xy 362.869294 -240.148411) (xy 362.91688 -240.130364) (xy 362.966744 -240.120184)
			(xy 363.017596 -240.118135) (xy 363.068117 -240.124269) (xy 363.117001 -240.138429) (xy 363.16298 -240.160246)
			(xy 363.204864 -240.189156) (xy 363.241568 -240.224411) (xy 363.272141 -240.265097) (xy 363.295792 -240.31016)
			(xy 363.311908 -240.358434) (xy 363.320072 -240.408668) (xy 363.320584 -240.434114) (xy 363.639112 -240.434114)
			(xy 363.643072 -240.38506) (xy 363.654849 -240.337276) (xy 363.67414 -240.292) (xy 363.700443 -240.250404)
			(xy 363.733078 -240.213567) (xy 363.771199 -240.182442) (xy 363.81382 -240.157835) (xy 363.859836 -240.140383)
			(xy 363.908055 -240.130539) (xy 363.95723 -240.128558) (xy 364.006085 -240.13449) (xy 364.053356 -240.148182)
			(xy 364.097818 -240.16928) (xy 364.138321 -240.197236) (xy 364.173814 -240.231328) (xy 364.203379 -240.270672)
			(xy 364.22625 -240.314249) (xy 364.241834 -240.36093) (xy 364.249729 -240.409507) (xy 364.250224 -240.434114)
			(xy 364.578912 -240.434114) (xy 364.582872 -240.38506) (xy 364.594649 -240.337276) (xy 364.61394 -240.292)
			(xy 364.640243 -240.250404) (xy 364.672878 -240.213567) (xy 364.710999 -240.182442) (xy 364.75362 -240.157835)
			(xy 364.799636 -240.140383) (xy 364.847855 -240.130539) (xy 364.89703 -240.128558) (xy 364.945885 -240.13449)
			(xy 364.993156 -240.148182) (xy 365.037618 -240.16928) (xy 365.078121 -240.197236) (xy 365.113614 -240.231328)
			(xy 365.143179 -240.270672) (xy 365.16605 -240.314249) (xy 365.181634 -240.36093) (xy 365.189529 -240.409507)
			(xy 365.190024 -240.434114) (xy 365.518966 -240.434114) (xy 365.522926 -240.38506) (xy 365.534703 -240.337276)
			(xy 365.553994 -240.292) (xy 365.580297 -240.250404) (xy 365.612932 -240.213567) (xy 365.651053 -240.182442)
			(xy 365.693674 -240.157835) (xy 365.73969 -240.140383) (xy 365.787909 -240.130539) (xy 365.837084 -240.128558)
			(xy 365.885939 -240.13449) (xy 365.93321 -240.148182) (xy 365.977672 -240.16928) (xy 366.018175 -240.197236)
			(xy 366.053668 -240.231328) (xy 366.083233 -240.270672) (xy 366.106104 -240.314249) (xy 366.121688 -240.36093)
			(xy 366.129583 -240.409507) (xy 366.130078 -240.434114) (xy 366.45902 -240.434114) (xy 366.46298 -240.38506)
			(xy 366.474757 -240.337276) (xy 366.494048 -240.292) (xy 366.520351 -240.250404) (xy 366.552986 -240.213567)
			(xy 366.591107 -240.182442) (xy 366.633728 -240.157835) (xy 366.679744 -240.140383) (xy 366.727963 -240.130539)
			(xy 366.777138 -240.128558) (xy 366.825993 -240.13449) (xy 366.873264 -240.148182) (xy 366.917726 -240.16928)
			(xy 366.958229 -240.197236) (xy 366.993722 -240.231328) (xy 367.023287 -240.270672) (xy 367.046158 -240.314249)
			(xy 367.061742 -240.36093) (xy 367.069637 -240.409507) (xy 367.070132 -240.434114) (xy 367.399074 -240.434114)
			(xy 367.403034 -240.38506) (xy 367.414811 -240.337276) (xy 367.434102 -240.292) (xy 367.460405 -240.250404)
			(xy 367.49304 -240.213567) (xy 367.531161 -240.182442) (xy 367.573782 -240.157835) (xy 367.619798 -240.140383)
			(xy 367.668017 -240.130539) (xy 367.717192 -240.128558) (xy 367.766047 -240.13449) (xy 367.813318 -240.148182)
			(xy 367.85778 -240.16928) (xy 367.898283 -240.197236) (xy 367.933776 -240.231328) (xy 367.963341 -240.270672)
			(xy 367.986212 -240.314249) (xy 368.001796 -240.36093) (xy 368.009691 -240.409507) (xy 368.010186 -240.434114)
			(xy 368.338874 -240.434114) (xy 368.342834 -240.38506) (xy 368.354611 -240.337276) (xy 368.373902 -240.292)
			(xy 368.400205 -240.250404) (xy 368.43284 -240.213567) (xy 368.470961 -240.182442) (xy 368.513582 -240.157835)
			(xy 368.559598 -240.140383) (xy 368.607817 -240.130539) (xy 368.656992 -240.128558) (xy 368.705847 -240.13449)
			(xy 368.753118 -240.148182) (xy 368.79758 -240.16928) (xy 368.838083 -240.197236) (xy 368.873576 -240.231328)
			(xy 368.903141 -240.270672) (xy 368.926012 -240.314249) (xy 368.941596 -240.36093) (xy 368.949491 -240.409507)
			(xy 368.949986 -240.434114) (xy 369.278928 -240.434114) (xy 369.282888 -240.38506) (xy 369.294665 -240.337276)
			(xy 369.313956 -240.292) (xy 369.340259 -240.250404) (xy 369.372894 -240.213567) (xy 369.411015 -240.182442)
			(xy 369.453636 -240.157835) (xy 369.499652 -240.140383) (xy 369.547871 -240.130539) (xy 369.597046 -240.128558)
			(xy 369.645901 -240.13449) (xy 369.693172 -240.148182) (xy 369.737634 -240.16928) (xy 369.778137 -240.197236)
			(xy 369.81363 -240.231328) (xy 369.843195 -240.270672) (xy 369.866066 -240.314249) (xy 369.88165 -240.36093)
			(xy 369.889545 -240.409507) (xy 369.89004 -240.434114) (xy 370.218982 -240.434114) (xy 370.222942 -240.38506)
			(xy 370.234719 -240.337276) (xy 370.25401 -240.292) (xy 370.280313 -240.250404) (xy 370.312948 -240.213567)
			(xy 370.351069 -240.182442) (xy 370.39369 -240.157835) (xy 370.439706 -240.140383) (xy 370.487925 -240.130539)
			(xy 370.5371 -240.128558) (xy 370.585955 -240.13449) (xy 370.633226 -240.148182) (xy 370.677688 -240.16928)
			(xy 370.718191 -240.197236) (xy 370.753684 -240.231328) (xy 370.783249 -240.270672) (xy 370.80612 -240.314249)
			(xy 370.821704 -240.36093) (xy 370.829599 -240.409507) (xy 370.830094 -240.434114) (xy 371.159036 -240.434114)
			(xy 371.162996 -240.38506) (xy 371.174773 -240.337276) (xy 371.194064 -240.292) (xy 371.220367 -240.250404)
			(xy 371.253002 -240.213567) (xy 371.291123 -240.182442) (xy 371.333744 -240.157835) (xy 371.37976 -240.140383)
			(xy 371.427979 -240.130539) (xy 371.477154 -240.128558) (xy 371.526009 -240.13449) (xy 371.57328 -240.148182)
			(xy 371.617742 -240.16928) (xy 371.658245 -240.197236) (xy 371.693738 -240.231328) (xy 371.723303 -240.270672)
			(xy 371.746174 -240.314249) (xy 371.761758 -240.36093) (xy 371.769653 -240.409507) (xy 371.770148 -240.434114)
			(xy 372.09909 -240.434114) (xy 372.10305 -240.38506) (xy 372.114827 -240.337276) (xy 372.134118 -240.292)
			(xy 372.160421 -240.250404) (xy 372.193056 -240.213567) (xy 372.231177 -240.182442) (xy 372.273798 -240.157835)
			(xy 372.319814 -240.140383) (xy 372.368033 -240.130539) (xy 372.417208 -240.128558) (xy 372.466063 -240.13449)
			(xy 372.513334 -240.148182) (xy 372.557796 -240.16928) (xy 372.598299 -240.197236) (xy 372.633792 -240.231328)
			(xy 372.663357 -240.270672) (xy 372.686228 -240.314249) (xy 372.701812 -240.36093) (xy 372.709707 -240.409507)
			(xy 372.710202 -240.434114) (xy 373.03889 -240.434114) (xy 373.04285 -240.38506) (xy 373.054627 -240.337276)
			(xy 373.073918 -240.292) (xy 373.100221 -240.250404) (xy 373.132856 -240.213567) (xy 373.170977 -240.182442)
			(xy 373.213598 -240.157835) (xy 373.259614 -240.140383) (xy 373.307833 -240.130539) (xy 373.357008 -240.128558)
			(xy 373.405863 -240.13449) (xy 373.453134 -240.148182) (xy 373.497596 -240.16928) (xy 373.538099 -240.197236)
			(xy 373.573592 -240.231328) (xy 373.603157 -240.270672) (xy 373.626028 -240.314249) (xy 373.641612 -240.36093)
			(xy 373.649507 -240.409507) (xy 373.650002 -240.434114) (xy 373.649507 -240.458721) (xy 373.641612 -240.507298)
			(xy 373.626028 -240.553979) (xy 373.603157 -240.597556) (xy 373.573592 -240.6369) (xy 373.538099 -240.670992)
			(xy 373.497596 -240.698948) (xy 373.453134 -240.720046) (xy 373.405863 -240.733738) (xy 373.357008 -240.73967)
			(xy 373.307833 -240.737689) (xy 373.259614 -240.727845) (xy 373.213598 -240.710393) (xy 373.170977 -240.685786)
			(xy 373.132856 -240.654661) (xy 373.100221 -240.617824) (xy 373.073918 -240.576228) (xy 373.054627 -240.530952)
			(xy 373.04285 -240.483168) (xy 373.03889 -240.434114) (xy 372.710202 -240.434114) (xy 372.709707 -240.458721)
			(xy 372.701812 -240.507298) (xy 372.686228 -240.553979) (xy 372.663357 -240.597556) (xy 372.633792 -240.6369)
			(xy 372.598299 -240.670992) (xy 372.557796 -240.698948) (xy 372.513334 -240.720046) (xy 372.466063 -240.733738)
			(xy 372.417208 -240.73967) (xy 372.368033 -240.737689) (xy 372.319814 -240.727845) (xy 372.273798 -240.710393)
			(xy 372.231177 -240.685786) (xy 372.193056 -240.654661) (xy 372.160421 -240.617824) (xy 372.134118 -240.576228)
			(xy 372.114827 -240.530952) (xy 372.10305 -240.483168) (xy 372.09909 -240.434114) (xy 371.770148 -240.434114)
			(xy 371.769653 -240.458721) (xy 371.761758 -240.507298) (xy 371.746174 -240.553979) (xy 371.723303 -240.597556)
			(xy 371.693738 -240.6369) (xy 371.658245 -240.670992) (xy 371.617742 -240.698948) (xy 371.57328 -240.720046)
			(xy 371.526009 -240.733738) (xy 371.477154 -240.73967) (xy 371.427979 -240.737689) (xy 371.37976 -240.727845)
			(xy 371.333744 -240.710393) (xy 371.291123 -240.685786) (xy 371.253002 -240.654661) (xy 371.220367 -240.617824)
			(xy 371.194064 -240.576228) (xy 371.174773 -240.530952) (xy 371.162996 -240.483168) (xy 371.159036 -240.434114)
			(xy 370.830094 -240.434114) (xy 370.829599 -240.458721) (xy 370.821704 -240.507298) (xy 370.80612 -240.553979)
			(xy 370.783249 -240.597556) (xy 370.753684 -240.6369) (xy 370.718191 -240.670992) (xy 370.677688 -240.698948)
			(xy 370.633226 -240.720046) (xy 370.585955 -240.733738) (xy 370.5371 -240.73967) (xy 370.487925 -240.737689)
			(xy 370.439706 -240.727845) (xy 370.39369 -240.710393) (xy 370.351069 -240.685786) (xy 370.312948 -240.654661)
			(xy 370.280313 -240.617824) (xy 370.25401 -240.576228) (xy 370.234719 -240.530952) (xy 370.222942 -240.483168)
			(xy 370.218982 -240.434114) (xy 369.89004 -240.434114) (xy 369.889545 -240.458721) (xy 369.88165 -240.507298)
			(xy 369.866066 -240.553979) (xy 369.843195 -240.597556) (xy 369.81363 -240.6369) (xy 369.778137 -240.670992)
			(xy 369.737634 -240.698948) (xy 369.693172 -240.720046) (xy 369.645901 -240.733738) (xy 369.597046 -240.73967)
			(xy 369.547871 -240.737689) (xy 369.499652 -240.727845) (xy 369.453636 -240.710393) (xy 369.411015 -240.685786)
			(xy 369.372894 -240.654661) (xy 369.340259 -240.617824) (xy 369.313956 -240.576228) (xy 369.294665 -240.530952)
			(xy 369.282888 -240.483168) (xy 369.278928 -240.434114) (xy 368.949986 -240.434114) (xy 368.949491 -240.458721)
			(xy 368.941596 -240.507298) (xy 368.926012 -240.553979) (xy 368.903141 -240.597556) (xy 368.873576 -240.6369)
			(xy 368.838083 -240.670992) (xy 368.79758 -240.698948) (xy 368.753118 -240.720046) (xy 368.705847 -240.733738)
			(xy 368.656992 -240.73967) (xy 368.607817 -240.737689) (xy 368.559598 -240.727845) (xy 368.513582 -240.710393)
			(xy 368.470961 -240.685786) (xy 368.43284 -240.654661) (xy 368.400205 -240.617824) (xy 368.373902 -240.576228)
			(xy 368.354611 -240.530952) (xy 368.342834 -240.483168) (xy 368.338874 -240.434114) (xy 368.010186 -240.434114)
			(xy 368.009691 -240.458721) (xy 368.001796 -240.507298) (xy 367.986212 -240.553979) (xy 367.963341 -240.597556)
			(xy 367.933776 -240.6369) (xy 367.898283 -240.670992) (xy 367.85778 -240.698948) (xy 367.813318 -240.720046)
			(xy 367.766047 -240.733738) (xy 367.717192 -240.73967) (xy 367.668017 -240.737689) (xy 367.619798 -240.727845)
			(xy 367.573782 -240.710393) (xy 367.531161 -240.685786) (xy 367.49304 -240.654661) (xy 367.460405 -240.617824)
			(xy 367.434102 -240.576228) (xy 367.414811 -240.530952) (xy 367.403034 -240.483168) (xy 367.399074 -240.434114)
			(xy 367.070132 -240.434114) (xy 367.069637 -240.458721) (xy 367.061742 -240.507298) (xy 367.046158 -240.553979)
			(xy 367.023287 -240.597556) (xy 366.993722 -240.6369) (xy 366.958229 -240.670992) (xy 366.917726 -240.698948)
			(xy 366.873264 -240.720046) (xy 366.825993 -240.733738) (xy 366.777138 -240.73967) (xy 366.727963 -240.737689)
			(xy 366.679744 -240.727845) (xy 366.633728 -240.710393) (xy 366.591107 -240.685786) (xy 366.552986 -240.654661)
			(xy 366.520351 -240.617824) (xy 366.494048 -240.576228) (xy 366.474757 -240.530952) (xy 366.46298 -240.483168)
			(xy 366.45902 -240.434114) (xy 366.130078 -240.434114) (xy 366.129583 -240.458721) (xy 366.121688 -240.507298)
			(xy 366.106104 -240.553979) (xy 366.083233 -240.597556) (xy 366.053668 -240.6369) (xy 366.018175 -240.670992)
			(xy 365.977672 -240.698948) (xy 365.93321 -240.720046) (xy 365.885939 -240.733738) (xy 365.837084 -240.73967)
			(xy 365.787909 -240.737689) (xy 365.73969 -240.727845) (xy 365.693674 -240.710393) (xy 365.651053 -240.685786)
			(xy 365.612932 -240.654661) (xy 365.580297 -240.617824) (xy 365.553994 -240.576228) (xy 365.534703 -240.530952)
			(xy 365.522926 -240.483168) (xy 365.518966 -240.434114) (xy 365.190024 -240.434114) (xy 365.189529 -240.458721)
			(xy 365.181634 -240.507298) (xy 365.16605 -240.553979) (xy 365.143179 -240.597556) (xy 365.113614 -240.6369)
			(xy 365.078121 -240.670992) (xy 365.037618 -240.698948) (xy 364.993156 -240.720046) (xy 364.945885 -240.733738)
			(xy 364.89703 -240.73967) (xy 364.847855 -240.737689) (xy 364.799636 -240.727845) (xy 364.75362 -240.710393)
			(xy 364.710999 -240.685786) (xy 364.672878 -240.654661) (xy 364.640243 -240.617824) (xy 364.61394 -240.576228)
			(xy 364.594649 -240.530952) (xy 364.582872 -240.483168) (xy 364.578912 -240.434114) (xy 364.250224 -240.434114)
			(xy 364.249729 -240.458721) (xy 364.241834 -240.507298) (xy 364.22625 -240.553979) (xy 364.203379 -240.597556)
			(xy 364.173814 -240.6369) (xy 364.138321 -240.670992) (xy 364.097818 -240.698948) (xy 364.053356 -240.720046)
			(xy 364.006085 -240.733738) (xy 363.95723 -240.73967) (xy 363.908055 -240.737689) (xy 363.859836 -240.727845)
			(xy 363.81382 -240.710393) (xy 363.771199 -240.685786) (xy 363.733078 -240.654661) (xy 363.700443 -240.617824)
			(xy 363.67414 -240.576228) (xy 363.654849 -240.530952) (xy 363.643072 -240.483168) (xy 363.639112 -240.434114)
			(xy 363.320584 -240.434114) (xy 363.320072 -240.45956) (xy 363.311908 -240.509794) (xy 363.295792 -240.558068)
			(xy 363.272141 -240.603131) (xy 363.241568 -240.643817) (xy 363.204864 -240.679072) (xy 363.16298 -240.707982)
			(xy 363.117001 -240.729799) (xy 363.068117 -240.743959) (xy 363.017596 -240.750093) (xy 362.966744 -240.748044)
			(xy 362.91688 -240.737864) (xy 362.869294 -240.719817) (xy 362.82522 -240.694371) (xy 362.785798 -240.662184)
			(xy 362.75205 -240.62409) (xy 362.724849 -240.581076) (xy 362.704901 -240.534256) (xy 362.692722 -240.484842)
			(xy 362.688627 -240.434114) (xy 362.38053 -240.434114) (xy 362.380018 -240.45956) (xy 362.371854 -240.509794)
			(xy 362.355738 -240.558068) (xy 362.332087 -240.603131) (xy 362.301514 -240.643817) (xy 362.26481 -240.679072)
			(xy 362.222926 -240.707982) (xy 362.176947 -240.729799) (xy 362.128063 -240.743959) (xy 362.077542 -240.750093)
			(xy 362.02669 -240.748044) (xy 361.976826 -240.737864) (xy 361.92924 -240.719817) (xy 361.885166 -240.694371)
			(xy 361.845744 -240.662184) (xy 361.811996 -240.62409) (xy 361.784795 -240.581076) (xy 361.764847 -240.534256)
			(xy 361.752668 -240.484842) (xy 361.748573 -240.434114) (xy 361.430645 -240.434114) (xy 361.426474 -240.484445)
			(xy 361.414071 -240.533417) (xy 361.393777 -240.579679) (xy 361.366144 -240.62197) (xy 361.331926 -240.659135)
			(xy 361.292058 -240.69016) (xy 361.247626 -240.714199) (xy 361.199843 -240.730597) (xy 361.150013 -240.738905)
			(xy 361.124754 -240.739422) (xy 361.123992 -240.739422) (xy 361.09998 -240.738905) (xy 361.052559 -240.731309)
			(xy 361.006907 -240.716398) (xy 360.985308 -240.705894) (xy 360.985054 -240.705894) (xy 360.979211 -240.70315)
			(xy 360.966618 -240.700335) (xy 360.960162 -240.700306) (xy 360.9467 -240.700814) (xy 360.861864 -240.752884)
			(xy 360.855678 -240.756869) (xy 360.845738 -240.767711) (xy 360.842306 -240.77422) (xy 360.83748 -240.784888)
			(xy 360.83748 -241.126518) (xy 360.837053 -241.136586) (xy 360.829332 -241.155184) (xy 360.822494 -241.162586)
			(xy 360.74096 -241.24412) (xy 361.289104 -241.24412) (xy 361.293064 -241.195066) (xy 361.304841 -241.147282)
			(xy 361.324132 -241.102006) (xy 361.350435 -241.06041) (xy 361.38307 -241.023573) (xy 361.421191 -240.992448)
			(xy 361.463812 -240.967841) (xy 361.509828 -240.950389) (xy 361.558047 -240.940545) (xy 361.607222 -240.938564)
			(xy 361.656077 -240.944496) (xy 361.703348 -240.958188) (xy 361.74781 -240.979286) (xy 361.788313 -241.007242)
			(xy 361.823806 -241.041334) (xy 361.853371 -241.080678) (xy 361.876242 -241.124255) (xy 361.891826 -241.170936)
			(xy 361.899721 -241.219513) (xy 361.900216 -241.24412) (xy 362.228904 -241.24412) (xy 362.232864 -241.195066)
			(xy 362.244641 -241.147282) (xy 362.263932 -241.102006) (xy 362.290235 -241.06041) (xy 362.32287 -241.023573)
			(xy 362.360991 -240.992448) (xy 362.403612 -240.967841) (xy 362.449628 -240.950389) (xy 362.497847 -240.940545)
			(xy 362.547022 -240.938564) (xy 362.595877 -240.944496) (xy 362.643148 -240.958188) (xy 362.68761 -240.979286)
			(xy 362.728113 -241.007242) (xy 362.763606 -241.041334) (xy 362.793171 -241.080678) (xy 362.816042 -241.124255)
			(xy 362.831626 -241.170936) (xy 362.839521 -241.219513) (xy 362.840016 -241.24412) (xy 363.168958 -241.24412)
			(xy 363.172918 -241.195066) (xy 363.184695 -241.147282) (xy 363.203986 -241.102006) (xy 363.230289 -241.06041)
			(xy 363.262924 -241.023573) (xy 363.301045 -240.992448) (xy 363.343666 -240.967841) (xy 363.389682 -240.950389)
			(xy 363.437901 -240.940545) (xy 363.487076 -240.938564) (xy 363.535931 -240.944496) (xy 363.583202 -240.958188)
			(xy 363.627664 -240.979286) (xy 363.668167 -241.007242) (xy 363.70366 -241.041334) (xy 363.733225 -241.080678)
			(xy 363.756096 -241.124255) (xy 363.77168 -241.170936) (xy 363.779575 -241.219513) (xy 363.78007 -241.24412)
			(xy 364.098581 -241.24412) (xy 364.102676 -241.193392) (xy 364.114855 -241.143978) (xy 364.134803 -241.097158)
			(xy 364.162004 -241.054144) (xy 364.195752 -241.01605) (xy 364.235174 -240.983863) (xy 364.279248 -240.958417)
			(xy 364.326834 -240.94037) (xy 364.376698 -240.93019) (xy 364.42755 -240.928141) (xy 364.478071 -240.934275)
			(xy 364.526955 -240.948435) (xy 364.572934 -240.970252) (xy 364.614818 -240.999162) (xy 364.651522 -241.034417)
			(xy 364.682095 -241.075103) (xy 364.705746 -241.120166) (xy 364.721862 -241.16844) (xy 364.730026 -241.218674)
			(xy 364.730538 -241.24412) (xy 365.038635 -241.24412) (xy 365.04273 -241.193392) (xy 365.054909 -241.143978)
			(xy 365.074857 -241.097158) (xy 365.102058 -241.054144) (xy 365.135806 -241.01605) (xy 365.175228 -240.983863)
			(xy 365.219302 -240.958417) (xy 365.266888 -240.94037) (xy 365.316752 -240.93019) (xy 365.367604 -240.928141)
			(xy 365.418125 -240.934275) (xy 365.467009 -240.948435) (xy 365.512988 -240.970252) (xy 365.554872 -240.999162)
			(xy 365.591576 -241.034417) (xy 365.622149 -241.075103) (xy 365.6458 -241.120166) (xy 365.661916 -241.16844)
			(xy 365.67008 -241.218674) (xy 365.670592 -241.24412) (xy 365.98912 -241.24412) (xy 365.99308 -241.195066)
			(xy 366.004857 -241.147282) (xy 366.024148 -241.102006) (xy 366.050451 -241.06041) (xy 366.083086 -241.023573)
			(xy 366.121207 -240.992448) (xy 366.163828 -240.967841) (xy 366.209844 -240.950389) (xy 366.258063 -240.940545)
			(xy 366.307238 -240.938564) (xy 366.356093 -240.944496) (xy 366.403364 -240.958188) (xy 366.447826 -240.979286)
			(xy 366.488329 -241.007242) (xy 366.523822 -241.041334) (xy 366.553387 -241.080678) (xy 366.576258 -241.124255)
			(xy 366.591842 -241.170936) (xy 366.599737 -241.219513) (xy 366.600232 -241.24412) (xy 366.918489 -241.24412)
			(xy 366.922584 -241.193392) (xy 366.934763 -241.143978) (xy 366.954711 -241.097158) (xy 366.981912 -241.054144)
			(xy 367.01566 -241.01605) (xy 367.055082 -240.983863) (xy 367.099156 -240.958417) (xy 367.146742 -240.94037)
			(xy 367.196606 -240.93019) (xy 367.247458 -240.928141) (xy 367.297979 -240.934275) (xy 367.346863 -240.948435)
			(xy 367.392842 -240.970252) (xy 367.434726 -240.999162) (xy 367.47143 -241.034417) (xy 367.502003 -241.075103)
			(xy 367.525654 -241.120166) (xy 367.54177 -241.16844) (xy 367.549934 -241.218674) (xy 367.550446 -241.24412)
			(xy 367.858543 -241.24412) (xy 367.862638 -241.193392) (xy 367.874817 -241.143978) (xy 367.894765 -241.097158)
			(xy 367.921966 -241.054144) (xy 367.955714 -241.01605) (xy 367.995136 -240.983863) (xy 368.03921 -240.958417)
			(xy 368.086796 -240.94037) (xy 368.13666 -240.93019) (xy 368.187512 -240.928141) (xy 368.238033 -240.934275)
			(xy 368.286917 -240.948435) (xy 368.332896 -240.970252) (xy 368.37478 -240.999162) (xy 368.411484 -241.034417)
			(xy 368.442057 -241.075103) (xy 368.465708 -241.120166) (xy 368.481824 -241.16844) (xy 368.489988 -241.218674)
			(xy 368.4905 -241.24412) (xy 368.809028 -241.24412) (xy 368.812988 -241.195066) (xy 368.824765 -241.147282)
			(xy 368.844056 -241.102006) (xy 368.870359 -241.06041) (xy 368.902994 -241.023573) (xy 368.941115 -240.992448)
			(xy 368.983736 -240.967841) (xy 369.029752 -240.950389) (xy 369.077971 -240.940545) (xy 369.127146 -240.938564)
			(xy 369.176001 -240.944496) (xy 369.223272 -240.958188) (xy 369.267734 -240.979286) (xy 369.308237 -241.007242)
			(xy 369.34373 -241.041334) (xy 369.373295 -241.080678) (xy 369.396166 -241.124255) (xy 369.41175 -241.170936)
			(xy 369.419645 -241.219513) (xy 369.42014 -241.24412) (xy 369.738651 -241.24412) (xy 369.742746 -241.193392)
			(xy 369.754925 -241.143978) (xy 369.774873 -241.097158) (xy 369.802074 -241.054144) (xy 369.835822 -241.01605)
			(xy 369.875244 -240.983863) (xy 369.919318 -240.958417) (xy 369.966904 -240.94037) (xy 370.016768 -240.93019)
			(xy 370.06762 -240.928141) (xy 370.118141 -240.934275) (xy 370.167025 -240.948435) (xy 370.213004 -240.970252)
			(xy 370.254888 -240.999162) (xy 370.291592 -241.034417) (xy 370.322165 -241.075103) (xy 370.345816 -241.120166)
			(xy 370.361932 -241.16844) (xy 370.370096 -241.218674) (xy 370.370608 -241.24412) (xy 370.678451 -241.24412)
			(xy 370.682546 -241.193392) (xy 370.694725 -241.143978) (xy 370.714673 -241.097158) (xy 370.741874 -241.054144)
			(xy 370.775622 -241.01605) (xy 370.815044 -240.983863) (xy 370.859118 -240.958417) (xy 370.906704 -240.94037)
			(xy 370.956568 -240.93019) (xy 371.00742 -240.928141) (xy 371.057941 -240.934275) (xy 371.106825 -240.948435)
			(xy 371.152804 -240.970252) (xy 371.194688 -240.999162) (xy 371.231392 -241.034417) (xy 371.261965 -241.075103)
			(xy 371.285616 -241.120166) (xy 371.301732 -241.16844) (xy 371.309896 -241.218674) (xy 371.310408 -241.24412)
			(xy 371.628936 -241.24412) (xy 371.632896 -241.195066) (xy 371.644673 -241.147282) (xy 371.663964 -241.102006)
			(xy 371.690267 -241.06041) (xy 371.722902 -241.023573) (xy 371.761023 -240.992448) (xy 371.803644 -240.967841)
			(xy 371.84966 -240.950389) (xy 371.897879 -240.940545) (xy 371.947054 -240.938564) (xy 371.995909 -240.944496)
			(xy 372.04318 -240.958188) (xy 372.087642 -240.979286) (xy 372.128145 -241.007242) (xy 372.163638 -241.041334)
			(xy 372.193203 -241.080678) (xy 372.216074 -241.124255) (xy 372.231658 -241.170936) (xy 372.239553 -241.219513)
			(xy 372.240048 -241.24412) (xy 372.558559 -241.24412) (xy 372.562654 -241.193392) (xy 372.574833 -241.143978)
			(xy 372.594781 -241.097158) (xy 372.621982 -241.054144) (xy 372.65573 -241.01605) (xy 372.695152 -240.983863)
			(xy 372.739226 -240.958417) (xy 372.786812 -240.94037) (xy 372.836676 -240.93019) (xy 372.887528 -240.928141)
			(xy 372.938049 -240.934275) (xy 372.986933 -240.948435) (xy 373.032912 -240.970252) (xy 373.074796 -240.999162)
			(xy 373.1115 -241.034417) (xy 373.142073 -241.075103) (xy 373.165724 -241.120166) (xy 373.18184 -241.16844)
			(xy 373.190004 -241.218674) (xy 373.190516 -241.24412) (xy 373.498613 -241.24412) (xy 373.502708 -241.193392)
			(xy 373.514887 -241.143978) (xy 373.534835 -241.097158) (xy 373.562036 -241.054144) (xy 373.595784 -241.01605)
			(xy 373.635206 -240.983863) (xy 373.67928 -240.958417) (xy 373.726866 -240.94037) (xy 373.77673 -240.93019)
			(xy 373.827582 -240.928141) (xy 373.878103 -240.934275) (xy 373.926987 -240.948435) (xy 373.972966 -240.970252)
			(xy 374.01485 -240.999162) (xy 374.051554 -241.034417) (xy 374.082127 -241.075103) (xy 374.105778 -241.120166)
			(xy 374.121894 -241.16844) (xy 374.130058 -241.218674) (xy 374.13057 -241.24412) (xy 374.130058 -241.269566)
			(xy 374.121894 -241.3198) (xy 374.105778 -241.368074) (xy 374.082127 -241.413137) (xy 374.051554 -241.453823)
			(xy 374.01485 -241.489078) (xy 373.972966 -241.517988) (xy 373.926987 -241.539805) (xy 373.878103 -241.553965)
			(xy 373.827582 -241.560099) (xy 373.77673 -241.55805) (xy 373.726866 -241.54787) (xy 373.67928 -241.529823)
			(xy 373.635206 -241.504377) (xy 373.595784 -241.47219) (xy 373.562036 -241.434096) (xy 373.534835 -241.391082)
			(xy 373.514887 -241.344262) (xy 373.502708 -241.294848) (xy 373.498613 -241.24412) (xy 373.190516 -241.24412)
			(xy 373.190004 -241.269566) (xy 373.18184 -241.3198) (xy 373.165724 -241.368074) (xy 373.142073 -241.413137)
			(xy 373.1115 -241.453823) (xy 373.074796 -241.489078) (xy 373.032912 -241.517988) (xy 372.986933 -241.539805)
			(xy 372.938049 -241.553965) (xy 372.887528 -241.560099) (xy 372.836676 -241.55805) (xy 372.786812 -241.54787)
			(xy 372.739226 -241.529823) (xy 372.695152 -241.504377) (xy 372.65573 -241.47219) (xy 372.621982 -241.434096)
			(xy 372.594781 -241.391082) (xy 372.574833 -241.344262) (xy 372.562654 -241.294848) (xy 372.558559 -241.24412)
			(xy 372.240048 -241.24412) (xy 372.239553 -241.268727) (xy 372.231658 -241.317304) (xy 372.216074 -241.363985)
			(xy 372.193203 -241.407562) (xy 372.163638 -241.446906) (xy 372.128145 -241.480998) (xy 372.087642 -241.508954)
			(xy 372.04318 -241.530052) (xy 371.995909 -241.543744) (xy 371.947054 -241.549676) (xy 371.897879 -241.547695)
			(xy 371.84966 -241.537851) (xy 371.803644 -241.520399) (xy 371.761023 -241.495792) (xy 371.722902 -241.464667)
			(xy 371.690267 -241.42783) (xy 371.663964 -241.386234) (xy 371.644673 -241.340958) (xy 371.632896 -241.293174)
			(xy 371.628936 -241.24412) (xy 371.310408 -241.24412) (xy 371.309896 -241.269566) (xy 371.301732 -241.3198)
			(xy 371.285616 -241.368074) (xy 371.261965 -241.413137) (xy 371.231392 -241.453823) (xy 371.194688 -241.489078)
			(xy 371.152804 -241.517988) (xy 371.106825 -241.539805) (xy 371.057941 -241.553965) (xy 371.00742 -241.560099)
			(xy 370.956568 -241.55805) (xy 370.906704 -241.54787) (xy 370.859118 -241.529823) (xy 370.815044 -241.504377)
			(xy 370.775622 -241.47219) (xy 370.741874 -241.434096) (xy 370.714673 -241.391082) (xy 370.694725 -241.344262)
			(xy 370.682546 -241.294848) (xy 370.678451 -241.24412) (xy 370.370608 -241.24412) (xy 370.370096 -241.269566)
			(xy 370.361932 -241.3198) (xy 370.345816 -241.368074) (xy 370.322165 -241.413137) (xy 370.291592 -241.453823)
			(xy 370.254888 -241.489078) (xy 370.213004 -241.517988) (xy 370.167025 -241.539805) (xy 370.118141 -241.553965)
			(xy 370.06762 -241.560099) (xy 370.016768 -241.55805) (xy 369.966904 -241.54787) (xy 369.919318 -241.529823)
			(xy 369.875244 -241.504377) (xy 369.835822 -241.47219) (xy 369.802074 -241.434096) (xy 369.774873 -241.391082)
			(xy 369.754925 -241.344262) (xy 369.742746 -241.294848) (xy 369.738651 -241.24412) (xy 369.42014 -241.24412)
			(xy 369.419645 -241.268727) (xy 369.41175 -241.317304) (xy 369.396166 -241.363985) (xy 369.373295 -241.407562)
			(xy 369.34373 -241.446906) (xy 369.308237 -241.480998) (xy 369.267734 -241.508954) (xy 369.223272 -241.530052)
			(xy 369.176001 -241.543744) (xy 369.127146 -241.549676) (xy 369.077971 -241.547695) (xy 369.029752 -241.537851)
			(xy 368.983736 -241.520399) (xy 368.941115 -241.495792) (xy 368.902994 -241.464667) (xy 368.870359 -241.42783)
			(xy 368.844056 -241.386234) (xy 368.824765 -241.340958) (xy 368.812988 -241.293174) (xy 368.809028 -241.24412)
			(xy 368.4905 -241.24412) (xy 368.489988 -241.269566) (xy 368.481824 -241.3198) (xy 368.465708 -241.368074)
			(xy 368.442057 -241.413137) (xy 368.411484 -241.453823) (xy 368.37478 -241.489078) (xy 368.332896 -241.517988)
			(xy 368.286917 -241.539805) (xy 368.238033 -241.553965) (xy 368.187512 -241.560099) (xy 368.13666 -241.55805)
			(xy 368.086796 -241.54787) (xy 368.03921 -241.529823) (xy 367.995136 -241.504377) (xy 367.955714 -241.47219)
			(xy 367.921966 -241.434096) (xy 367.894765 -241.391082) (xy 367.874817 -241.344262) (xy 367.862638 -241.294848)
			(xy 367.858543 -241.24412) (xy 367.550446 -241.24412) (xy 367.549934 -241.269566) (xy 367.54177 -241.3198)
			(xy 367.525654 -241.368074) (xy 367.502003 -241.413137) (xy 367.47143 -241.453823) (xy 367.434726 -241.489078)
			(xy 367.392842 -241.517988) (xy 367.346863 -241.539805) (xy 367.297979 -241.553965) (xy 367.247458 -241.560099)
			(xy 367.196606 -241.55805) (xy 367.146742 -241.54787) (xy 367.099156 -241.529823) (xy 367.055082 -241.504377)
			(xy 367.01566 -241.47219) (xy 366.981912 -241.434096) (xy 366.954711 -241.391082) (xy 366.934763 -241.344262)
			(xy 366.922584 -241.294848) (xy 366.918489 -241.24412) (xy 366.600232 -241.24412) (xy 366.599737 -241.268727)
			(xy 366.591842 -241.317304) (xy 366.576258 -241.363985) (xy 366.553387 -241.407562) (xy 366.523822 -241.446906)
			(xy 366.488329 -241.480998) (xy 366.447826 -241.508954) (xy 366.403364 -241.530052) (xy 366.356093 -241.543744)
			(xy 366.307238 -241.549676) (xy 366.258063 -241.547695) (xy 366.209844 -241.537851) (xy 366.163828 -241.520399)
			(xy 366.121207 -241.495792) (xy 366.083086 -241.464667) (xy 366.050451 -241.42783) (xy 366.024148 -241.386234)
			(xy 366.004857 -241.340958) (xy 365.99308 -241.293174) (xy 365.98912 -241.24412) (xy 365.670592 -241.24412)
			(xy 365.67008 -241.269566) (xy 365.661916 -241.3198) (xy 365.6458 -241.368074) (xy 365.622149 -241.413137)
			(xy 365.591576 -241.453823) (xy 365.554872 -241.489078) (xy 365.512988 -241.517988) (xy 365.467009 -241.539805)
			(xy 365.418125 -241.553965) (xy 365.367604 -241.560099) (xy 365.316752 -241.55805) (xy 365.266888 -241.54787)
			(xy 365.219302 -241.529823) (xy 365.175228 -241.504377) (xy 365.135806 -241.47219) (xy 365.102058 -241.434096)
			(xy 365.074857 -241.391082) (xy 365.054909 -241.344262) (xy 365.04273 -241.294848) (xy 365.038635 -241.24412)
			(xy 364.730538 -241.24412) (xy 364.730026 -241.269566) (xy 364.721862 -241.3198) (xy 364.705746 -241.368074)
			(xy 364.682095 -241.413137) (xy 364.651522 -241.453823) (xy 364.614818 -241.489078) (xy 364.572934 -241.517988)
			(xy 364.526955 -241.539805) (xy 364.478071 -241.553965) (xy 364.42755 -241.560099) (xy 364.376698 -241.55805)
			(xy 364.326834 -241.54787) (xy 364.279248 -241.529823) (xy 364.235174 -241.504377) (xy 364.195752 -241.47219)
			(xy 364.162004 -241.434096) (xy 364.134803 -241.391082) (xy 364.114855 -241.344262) (xy 364.102676 -241.294848)
			(xy 364.098581 -241.24412) (xy 363.78007 -241.24412) (xy 363.779575 -241.268727) (xy 363.77168 -241.317304)
			(xy 363.756096 -241.363985) (xy 363.733225 -241.407562) (xy 363.70366 -241.446906) (xy 363.668167 -241.480998)
			(xy 363.627664 -241.508954) (xy 363.583202 -241.530052) (xy 363.535931 -241.543744) (xy 363.487076 -241.549676)
			(xy 363.437901 -241.547695) (xy 363.389682 -241.537851) (xy 363.343666 -241.520399) (xy 363.301045 -241.495792)
			(xy 363.262924 -241.464667) (xy 363.230289 -241.42783) (xy 363.203986 -241.386234) (xy 363.184695 -241.340958)
			(xy 363.172918 -241.293174) (xy 363.168958 -241.24412) (xy 362.840016 -241.24412) (xy 362.839521 -241.268727)
			(xy 362.831626 -241.317304) (xy 362.816042 -241.363985) (xy 362.793171 -241.407562) (xy 362.763606 -241.446906)
			(xy 362.728113 -241.480998) (xy 362.68761 -241.508954) (xy 362.643148 -241.530052) (xy 362.595877 -241.543744)
			(xy 362.547022 -241.549676) (xy 362.497847 -241.547695) (xy 362.449628 -241.537851) (xy 362.403612 -241.520399)
			(xy 362.360991 -241.495792) (xy 362.32287 -241.464667) (xy 362.290235 -241.42783) (xy 362.263932 -241.386234)
			(xy 362.244641 -241.340958) (xy 362.232864 -241.293174) (xy 362.228904 -241.24412) (xy 361.900216 -241.24412)
			(xy 361.899721 -241.268727) (xy 361.891826 -241.317304) (xy 361.876242 -241.363985) (xy 361.853371 -241.407562)
			(xy 361.823806 -241.446906) (xy 361.788313 -241.480998) (xy 361.74781 -241.508954) (xy 361.703348 -241.530052)
			(xy 361.656077 -241.543744) (xy 361.607222 -241.549676) (xy 361.558047 -241.547695) (xy 361.509828 -241.537851)
			(xy 361.463812 -241.520399) (xy 361.421191 -241.495792) (xy 361.38307 -241.464667) (xy 361.350435 -241.42783)
			(xy 361.324132 -241.386234) (xy 361.304841 -241.340958) (xy 361.293064 -241.293174) (xy 361.289104 -241.24412)
			(xy 360.74096 -241.24412) (xy 359.930954 -242.054126) (xy 360.81895 -242.054126) (xy 360.82291 -242.005072)
			(xy 360.834687 -241.957288) (xy 360.853978 -241.912012) (xy 360.880281 -241.870416) (xy 360.912916 -241.833579)
			(xy 360.951037 -241.802454) (xy 360.993658 -241.777847) (xy 361.039674 -241.760395) (xy 361.087893 -241.750551)
			(xy 361.137068 -241.74857) (xy 361.185923 -241.754502) (xy 361.233194 -241.768194) (xy 361.277656 -241.789292)
			(xy 361.318159 -241.817248) (xy 361.353652 -241.85134) (xy 361.383217 -241.890684) (xy 361.406088 -241.934261)
			(xy 361.421672 -241.980942) (xy 361.429567 -242.029519) (xy 361.430062 -242.054126) (xy 361.748573 -242.054126)
			(xy 361.752668 -242.003398) (xy 361.764847 -241.953984) (xy 361.784795 -241.907164) (xy 361.811996 -241.86415)
			(xy 361.845744 -241.826056) (xy 361.885166 -241.793869) (xy 361.92924 -241.768423) (xy 361.976826 -241.750376)
			(xy 362.02669 -241.740196) (xy 362.077542 -241.738147) (xy 362.128063 -241.744281) (xy 362.176947 -241.758441)
			(xy 362.222926 -241.780258) (xy 362.26481 -241.809168) (xy 362.301514 -241.844423) (xy 362.332087 -241.885109)
			(xy 362.355738 -241.930172) (xy 362.371854 -241.978446) (xy 362.380018 -242.02868) (xy 362.38053 -242.054126)
			(xy 362.688627 -242.054126) (xy 362.692722 -242.003398) (xy 362.704901 -241.953984) (xy 362.724849 -241.907164)
			(xy 362.75205 -241.86415) (xy 362.785798 -241.826056) (xy 362.82522 -241.793869) (xy 362.869294 -241.768423)
			(xy 362.91688 -241.750376) (xy 362.966744 -241.740196) (xy 363.017596 -241.738147) (xy 363.068117 -241.744281)
			(xy 363.117001 -241.758441) (xy 363.16298 -241.780258) (xy 363.204864 -241.809168) (xy 363.241568 -241.844423)
			(xy 363.272141 -241.885109) (xy 363.295792 -241.930172) (xy 363.311908 -241.978446) (xy 363.320072 -242.02868)
			(xy 363.320584 -242.054126) (xy 363.639112 -242.054126) (xy 363.643072 -242.005072) (xy 363.654849 -241.957288)
			(xy 363.67414 -241.912012) (xy 363.700443 -241.870416) (xy 363.733078 -241.833579) (xy 363.771199 -241.802454)
			(xy 363.81382 -241.777847) (xy 363.859836 -241.760395) (xy 363.908055 -241.750551) (xy 363.95723 -241.74857)
			(xy 364.006085 -241.754502) (xy 364.053356 -241.768194) (xy 364.097818 -241.789292) (xy 364.138321 -241.817248)
			(xy 364.173814 -241.85134) (xy 364.203379 -241.890684) (xy 364.22625 -241.934261) (xy 364.241834 -241.980942)
			(xy 364.249729 -242.029519) (xy 364.250224 -242.054126) (xy 366.45902 -242.054126) (xy 366.46298 -242.005072)
			(xy 366.474757 -241.957288) (xy 366.494048 -241.912012) (xy 366.520351 -241.870416) (xy 366.552986 -241.833579)
			(xy 366.591107 -241.802454) (xy 366.633728 -241.777847) (xy 366.679744 -241.760395) (xy 366.727963 -241.750551)
			(xy 366.777138 -241.74857) (xy 366.825993 -241.754502) (xy 366.873264 -241.768194) (xy 366.917726 -241.789292)
			(xy 366.958229 -241.817248) (xy 366.993722 -241.85134) (xy 367.023287 -241.890684) (xy 367.046158 -241.934261)
			(xy 367.061742 -241.980942) (xy 367.069637 -242.029519) (xy 367.070132 -242.054126) (xy 369.278928 -242.054126)
			(xy 369.282888 -242.005072) (xy 369.294665 -241.957288) (xy 369.313956 -241.912012) (xy 369.340259 -241.870416)
			(xy 369.372894 -241.833579) (xy 369.411015 -241.802454) (xy 369.453636 -241.777847) (xy 369.499652 -241.760395)
			(xy 369.547871 -241.750551) (xy 369.597046 -241.74857) (xy 369.645901 -241.754502) (xy 369.693172 -241.768194)
			(xy 369.737634 -241.789292) (xy 369.778137 -241.817248) (xy 369.81363 -241.85134) (xy 369.843195 -241.890684)
			(xy 369.866066 -241.934261) (xy 369.88165 -241.980942) (xy 369.889545 -242.029519) (xy 369.89004 -242.054126)
			(xy 372.09909 -242.054126) (xy 372.10305 -242.005072) (xy 372.114827 -241.957288) (xy 372.134118 -241.912012)
			(xy 372.160421 -241.870416) (xy 372.193056 -241.833579) (xy 372.231177 -241.802454) (xy 372.273798 -241.777847)
			(xy 372.319814 -241.760395) (xy 372.368033 -241.750551) (xy 372.417208 -241.74857) (xy 372.466063 -241.754502)
			(xy 372.513334 -241.768194) (xy 372.557796 -241.789292) (xy 372.598299 -241.817248) (xy 372.633792 -241.85134)
			(xy 372.663357 -241.890684) (xy 372.686228 -241.934261) (xy 372.701812 -241.980942) (xy 372.709707 -242.029519)
			(xy 372.710202 -242.054126) (xy 372.709707 -242.078733) (xy 372.701812 -242.12731) (xy 372.686228 -242.173991)
			(xy 372.663357 -242.217568) (xy 372.633792 -242.256912) (xy 372.598299 -242.291004) (xy 372.557796 -242.31896)
			(xy 372.513334 -242.340058) (xy 372.466063 -242.35375) (xy 372.417208 -242.359682) (xy 372.368033 -242.357701)
			(xy 372.319814 -242.347857) (xy 372.273798 -242.330405) (xy 372.231177 -242.305798) (xy 372.193056 -242.274673)
			(xy 372.160421 -242.237836) (xy 372.134118 -242.19624) (xy 372.114827 -242.150964) (xy 372.10305 -242.10318)
			(xy 372.09909 -242.054126) (xy 369.89004 -242.054126) (xy 369.889545 -242.078733) (xy 369.88165 -242.12731)
			(xy 369.866066 -242.173991) (xy 369.843195 -242.217568) (xy 369.81363 -242.256912) (xy 369.778137 -242.291004)
			(xy 369.737634 -242.31896) (xy 369.693172 -242.340058) (xy 369.645901 -242.35375) (xy 369.597046 -242.359682)
			(xy 369.547871 -242.357701) (xy 369.499652 -242.347857) (xy 369.453636 -242.330405) (xy 369.411015 -242.305798)
			(xy 369.372894 -242.274673) (xy 369.340259 -242.237836) (xy 369.313956 -242.19624) (xy 369.294665 -242.150964)
			(xy 369.282888 -242.10318) (xy 369.278928 -242.054126) (xy 367.070132 -242.054126) (xy 367.069637 -242.078733)
			(xy 367.061742 -242.12731) (xy 367.046158 -242.173991) (xy 367.023287 -242.217568) (xy 366.993722 -242.256912)
			(xy 366.958229 -242.291004) (xy 366.917726 -242.31896) (xy 366.873264 -242.340058) (xy 366.825993 -242.35375)
			(xy 366.777138 -242.359682) (xy 366.727963 -242.357701) (xy 366.679744 -242.347857) (xy 366.633728 -242.330405)
			(xy 366.591107 -242.305798) (xy 366.552986 -242.274673) (xy 366.520351 -242.237836) (xy 366.494048 -242.19624)
			(xy 366.474757 -242.150964) (xy 366.46298 -242.10318) (xy 366.45902 -242.054126) (xy 364.250224 -242.054126)
			(xy 364.249729 -242.078733) (xy 364.241834 -242.12731) (xy 364.22625 -242.173991) (xy 364.203379 -242.217568)
			(xy 364.173814 -242.256912) (xy 364.138321 -242.291004) (xy 364.097818 -242.31896) (xy 364.053356 -242.340058)
			(xy 364.006085 -242.35375) (xy 363.95723 -242.359682) (xy 363.908055 -242.357701) (xy 363.859836 -242.347857)
			(xy 363.81382 -242.330405) (xy 363.771199 -242.305798) (xy 363.733078 -242.274673) (xy 363.700443 -242.237836)
			(xy 363.67414 -242.19624) (xy 363.654849 -242.150964) (xy 363.643072 -242.10318) (xy 363.639112 -242.054126)
			(xy 363.320584 -242.054126) (xy 363.320072 -242.079572) (xy 363.311908 -242.129806) (xy 363.295792 -242.17808)
			(xy 363.272141 -242.223143) (xy 363.241568 -242.263829) (xy 363.204864 -242.299084) (xy 363.16298 -242.327994)
			(xy 363.117001 -242.349811) (xy 363.068117 -242.363971) (xy 363.017596 -242.370105) (xy 362.966744 -242.368056)
			(xy 362.91688 -242.357876) (xy 362.869294 -242.339829) (xy 362.82522 -242.314383) (xy 362.785798 -242.282196)
			(xy 362.75205 -242.244102) (xy 362.724849 -242.201088) (xy 362.704901 -242.154268) (xy 362.692722 -242.104854)
			(xy 362.688627 -242.054126) (xy 362.38053 -242.054126) (xy 362.380018 -242.079572) (xy 362.371854 -242.129806)
			(xy 362.355738 -242.17808) (xy 362.332087 -242.223143) (xy 362.301514 -242.263829) (xy 362.26481 -242.299084)
			(xy 362.222926 -242.327994) (xy 362.176947 -242.349811) (xy 362.128063 -242.363971) (xy 362.077542 -242.370105)
			(xy 362.02669 -242.368056) (xy 361.976826 -242.357876) (xy 361.92924 -242.339829) (xy 361.885166 -242.314383)
			(xy 361.845744 -242.282196) (xy 361.811996 -242.244102) (xy 361.784795 -242.201088) (xy 361.764847 -242.154268)
			(xy 361.752668 -242.104854) (xy 361.748573 -242.054126) (xy 361.430062 -242.054126) (xy 361.429567 -242.078733)
			(xy 361.421672 -242.12731) (xy 361.406088 -242.173991) (xy 361.383217 -242.217568) (xy 361.353652 -242.256912)
			(xy 361.318159 -242.291004) (xy 361.277656 -242.31896) (xy 361.233194 -242.340058) (xy 361.185923 -242.35375)
			(xy 361.137068 -242.359682) (xy 361.087893 -242.357701) (xy 361.039674 -242.347857) (xy 360.993658 -242.330405)
			(xy 360.951037 -242.305798) (xy 360.912916 -242.274673) (xy 360.880281 -242.237836) (xy 360.853978 -242.19624)
			(xy 360.834687 -242.150964) (xy 360.82291 -242.10318) (xy 360.81895 -242.054126) (xy 359.930954 -242.054126)
			(xy 359.120948 -242.864132) (xy 363.168958 -242.864132) (xy 363.172918 -242.815078) (xy 363.184695 -242.767294)
			(xy 363.203986 -242.722018) (xy 363.230289 -242.680422) (xy 363.262924 -242.643585) (xy 363.301045 -242.61246)
			(xy 363.343666 -242.587853) (xy 363.389682 -242.570401) (xy 363.437901 -242.560557) (xy 363.487076 -242.558576)
			(xy 363.535931 -242.564508) (xy 363.583202 -242.5782) (xy 363.627664 -242.599298) (xy 363.668167 -242.627254)
			(xy 363.70366 -242.661346) (xy 363.733225 -242.70069) (xy 363.756096 -242.744267) (xy 363.77168 -242.790948)
			(xy 363.779575 -242.839525) (xy 363.78007 -242.864132) (xy 364.098581 -242.864132) (xy 364.102676 -242.813404)
			(xy 364.114855 -242.76399) (xy 364.134803 -242.71717) (xy 364.162004 -242.674156) (xy 364.195752 -242.636062)
			(xy 364.235174 -242.603875) (xy 364.279248 -242.578429) (xy 364.326834 -242.560382) (xy 364.376698 -242.550202)
			(xy 364.42755 -242.548153) (xy 364.478071 -242.554287) (xy 364.526955 -242.568447) (xy 364.572934 -242.590264)
			(xy 364.614818 -242.619174) (xy 364.651522 -242.654429) (xy 364.682095 -242.695115) (xy 364.705746 -242.740178)
			(xy 364.721862 -242.788452) (xy 364.730026 -242.838686) (xy 364.730538 -242.864132) (xy 365.038635 -242.864132)
			(xy 365.04273 -242.813404) (xy 365.054909 -242.76399) (xy 365.074857 -242.71717) (xy 365.102058 -242.674156)
			(xy 365.135806 -242.636062) (xy 365.175228 -242.603875) (xy 365.219302 -242.578429) (xy 365.266888 -242.560382)
			(xy 365.316752 -242.550202) (xy 365.367604 -242.548153) (xy 365.418125 -242.554287) (xy 365.467009 -242.568447)
			(xy 365.512988 -242.590264) (xy 365.554872 -242.619174) (xy 365.591576 -242.654429) (xy 365.622149 -242.695115)
			(xy 365.6458 -242.740178) (xy 365.661916 -242.788452) (xy 365.67008 -242.838686) (xy 365.670592 -242.864132)
			(xy 365.98912 -242.864132) (xy 365.99308 -242.815078) (xy 366.004857 -242.767294) (xy 366.024148 -242.722018)
			(xy 366.050451 -242.680422) (xy 366.083086 -242.643585) (xy 366.121207 -242.61246) (xy 366.163828 -242.587853)
			(xy 366.209844 -242.570401) (xy 366.258063 -242.560557) (xy 366.307238 -242.558576) (xy 366.356093 -242.564508)
			(xy 366.403364 -242.5782) (xy 366.447826 -242.599298) (xy 366.488329 -242.627254) (xy 366.523822 -242.661346)
			(xy 366.553387 -242.70069) (xy 366.576258 -242.744267) (xy 366.591842 -242.790948) (xy 366.599737 -242.839525)
			(xy 366.600232 -242.864132) (xy 366.918489 -242.864132) (xy 366.922584 -242.813404) (xy 366.934763 -242.76399)
			(xy 366.954711 -242.71717) (xy 366.981912 -242.674156) (xy 367.01566 -242.636062) (xy 367.055082 -242.603875)
			(xy 367.099156 -242.578429) (xy 367.146742 -242.560382) (xy 367.196606 -242.550202) (xy 367.247458 -242.548153)
			(xy 367.297979 -242.554287) (xy 367.346863 -242.568447) (xy 367.392842 -242.590264) (xy 367.434726 -242.619174)
			(xy 367.47143 -242.654429) (xy 367.502003 -242.695115) (xy 367.525654 -242.740178) (xy 367.54177 -242.788452)
			(xy 367.549934 -242.838686) (xy 367.550446 -242.864132) (xy 367.858543 -242.864132) (xy 367.862638 -242.813404)
			(xy 367.874817 -242.76399) (xy 367.894765 -242.71717) (xy 367.921966 -242.674156) (xy 367.955714 -242.636062)
			(xy 367.995136 -242.603875) (xy 368.03921 -242.578429) (xy 368.086796 -242.560382) (xy 368.13666 -242.550202)
			(xy 368.187512 -242.548153) (xy 368.238033 -242.554287) (xy 368.286917 -242.568447) (xy 368.332896 -242.590264)
			(xy 368.37478 -242.619174) (xy 368.411484 -242.654429) (xy 368.442057 -242.695115) (xy 368.465708 -242.740178)
			(xy 368.481824 -242.788452) (xy 368.489988 -242.838686) (xy 368.4905 -242.864132) (xy 368.809028 -242.864132)
			(xy 368.812988 -242.815078) (xy 368.824765 -242.767294) (xy 368.844056 -242.722018) (xy 368.870359 -242.680422)
			(xy 368.902994 -242.643585) (xy 368.941115 -242.61246) (xy 368.983736 -242.587853) (xy 369.029752 -242.570401)
			(xy 369.077971 -242.560557) (xy 369.127146 -242.558576) (xy 369.176001 -242.564508) (xy 369.223272 -242.5782)
			(xy 369.267734 -242.599298) (xy 369.308237 -242.627254) (xy 369.34373 -242.661346) (xy 369.373295 -242.70069)
			(xy 369.396166 -242.744267) (xy 369.41175 -242.790948) (xy 369.419645 -242.839525) (xy 369.42014 -242.864132)
			(xy 369.738651 -242.864132) (xy 369.742746 -242.813404) (xy 369.754925 -242.76399) (xy 369.774873 -242.71717)
			(xy 369.802074 -242.674156) (xy 369.835822 -242.636062) (xy 369.875244 -242.603875) (xy 369.919318 -242.578429)
			(xy 369.966904 -242.560382) (xy 370.016768 -242.550202) (xy 370.06762 -242.548153) (xy 370.118141 -242.554287)
			(xy 370.167025 -242.568447) (xy 370.213004 -242.590264) (xy 370.254888 -242.619174) (xy 370.291592 -242.654429)
			(xy 370.322165 -242.695115) (xy 370.345816 -242.740178) (xy 370.361932 -242.788452) (xy 370.370096 -242.838686)
			(xy 370.370608 -242.864132) (xy 370.678451 -242.864132) (xy 370.682546 -242.813404) (xy 370.694725 -242.76399)
			(xy 370.714673 -242.71717) (xy 370.741874 -242.674156) (xy 370.775622 -242.636062) (xy 370.815044 -242.603875)
			(xy 370.859118 -242.578429) (xy 370.906704 -242.560382) (xy 370.956568 -242.550202) (xy 371.00742 -242.548153)
			(xy 371.057941 -242.554287) (xy 371.106825 -242.568447) (xy 371.152804 -242.590264) (xy 371.194688 -242.619174)
			(xy 371.231392 -242.654429) (xy 371.261965 -242.695115) (xy 371.285616 -242.740178) (xy 371.301732 -242.788452)
			(xy 371.309896 -242.838686) (xy 371.310408 -242.864132) (xy 371.628936 -242.864132) (xy 371.632896 -242.815078)
			(xy 371.644673 -242.767294) (xy 371.663964 -242.722018) (xy 371.690267 -242.680422) (xy 371.722902 -242.643585)
			(xy 371.761023 -242.61246) (xy 371.803644 -242.587853) (xy 371.84966 -242.570401) (xy 371.897879 -242.560557)
			(xy 371.947054 -242.558576) (xy 371.995909 -242.564508) (xy 372.04318 -242.5782) (xy 372.087642 -242.599298)
			(xy 372.128145 -242.627254) (xy 372.163638 -242.661346) (xy 372.193203 -242.70069) (xy 372.216074 -242.744267)
			(xy 372.231658 -242.790948) (xy 372.239553 -242.839525) (xy 372.240048 -242.864132) (xy 372.558559 -242.864132)
			(xy 372.562654 -242.813404) (xy 372.574833 -242.76399) (xy 372.594781 -242.71717) (xy 372.621982 -242.674156)
			(xy 372.65573 -242.636062) (xy 372.695152 -242.603875) (xy 372.739226 -242.578429) (xy 372.786812 -242.560382)
			(xy 372.836676 -242.550202) (xy 372.887528 -242.548153) (xy 372.938049 -242.554287) (xy 372.986933 -242.568447)
			(xy 373.032912 -242.590264) (xy 373.074796 -242.619174) (xy 373.1115 -242.654429) (xy 373.142073 -242.695115)
			(xy 373.165724 -242.740178) (xy 373.18184 -242.788452) (xy 373.190004 -242.838686) (xy 373.190516 -242.864132)
			(xy 373.498613 -242.864132) (xy 373.502708 -242.813404) (xy 373.514887 -242.76399) (xy 373.534835 -242.71717)
			(xy 373.562036 -242.674156) (xy 373.595784 -242.636062) (xy 373.635206 -242.603875) (xy 373.67928 -242.578429)
			(xy 373.726866 -242.560382) (xy 373.77673 -242.550202) (xy 373.827582 -242.548153) (xy 373.878103 -242.554287)
			(xy 373.926987 -242.568447) (xy 373.972966 -242.590264) (xy 374.01485 -242.619174) (xy 374.051554 -242.654429)
			(xy 374.082127 -242.695115) (xy 374.105778 -242.740178) (xy 374.121894 -242.788452) (xy 374.130058 -242.838686)
			(xy 374.13057 -242.864132) (xy 374.130058 -242.889578) (xy 374.121894 -242.939812) (xy 374.105778 -242.988086)
			(xy 374.082127 -243.033149) (xy 374.051554 -243.073835) (xy 374.01485 -243.10909) (xy 373.972966 -243.138)
			(xy 373.926987 -243.159817) (xy 373.878103 -243.173977) (xy 373.827582 -243.180111) (xy 373.77673 -243.178062)
			(xy 373.726866 -243.167882) (xy 373.67928 -243.149835) (xy 373.635206 -243.124389) (xy 373.595784 -243.092202)
			(xy 373.562036 -243.054108) (xy 373.534835 -243.011094) (xy 373.514887 -242.964274) (xy 373.502708 -242.91486)
			(xy 373.498613 -242.864132) (xy 373.190516 -242.864132) (xy 373.190004 -242.889578) (xy 373.18184 -242.939812)
			(xy 373.165724 -242.988086) (xy 373.142073 -243.033149) (xy 373.1115 -243.073835) (xy 373.074796 -243.10909)
			(xy 373.032912 -243.138) (xy 372.986933 -243.159817) (xy 372.938049 -243.173977) (xy 372.887528 -243.180111)
			(xy 372.836676 -243.178062) (xy 372.786812 -243.167882) (xy 372.739226 -243.149835) (xy 372.695152 -243.124389)
			(xy 372.65573 -243.092202) (xy 372.621982 -243.054108) (xy 372.594781 -243.011094) (xy 372.574833 -242.964274)
			(xy 372.562654 -242.91486) (xy 372.558559 -242.864132) (xy 372.240048 -242.864132) (xy 372.239553 -242.888739)
			(xy 372.231658 -242.937316) (xy 372.216074 -242.983997) (xy 372.193203 -243.027574) (xy 372.163638 -243.066918)
			(xy 372.128145 -243.10101) (xy 372.087642 -243.128966) (xy 372.04318 -243.150064) (xy 371.995909 -243.163756)
			(xy 371.947054 -243.169688) (xy 371.897879 -243.167707) (xy 371.84966 -243.157863) (xy 371.803644 -243.140411)
			(xy 371.761023 -243.115804) (xy 371.722902 -243.084679) (xy 371.690267 -243.047842) (xy 371.663964 -243.006246)
			(xy 371.644673 -242.96097) (xy 371.632896 -242.913186) (xy 371.628936 -242.864132) (xy 371.310408 -242.864132)
			(xy 371.309896 -242.889578) (xy 371.301732 -242.939812) (xy 371.285616 -242.988086) (xy 371.261965 -243.033149)
			(xy 371.231392 -243.073835) (xy 371.194688 -243.10909) (xy 371.152804 -243.138) (xy 371.106825 -243.159817)
			(xy 371.057941 -243.173977) (xy 371.00742 -243.180111) (xy 370.956568 -243.178062) (xy 370.906704 -243.167882)
			(xy 370.859118 -243.149835) (xy 370.815044 -243.124389) (xy 370.775622 -243.092202) (xy 370.741874 -243.054108)
			(xy 370.714673 -243.011094) (xy 370.694725 -242.964274) (xy 370.682546 -242.91486) (xy 370.678451 -242.864132)
			(xy 370.370608 -242.864132) (xy 370.370096 -242.889578) (xy 370.361932 -242.939812) (xy 370.345816 -242.988086)
			(xy 370.322165 -243.033149) (xy 370.291592 -243.073835) (xy 370.254888 -243.10909) (xy 370.213004 -243.138)
			(xy 370.167025 -243.159817) (xy 370.118141 -243.173977) (xy 370.06762 -243.180111) (xy 370.016768 -243.178062)
			(xy 369.966904 -243.167882) (xy 369.919318 -243.149835) (xy 369.875244 -243.124389) (xy 369.835822 -243.092202)
			(xy 369.802074 -243.054108) (xy 369.774873 -243.011094) (xy 369.754925 -242.964274) (xy 369.742746 -242.91486)
			(xy 369.738651 -242.864132) (xy 369.42014 -242.864132) (xy 369.419645 -242.888739) (xy 369.41175 -242.937316)
			(xy 369.396166 -242.983997) (xy 369.373295 -243.027574) (xy 369.34373 -243.066918) (xy 369.308237 -243.10101)
			(xy 369.267734 -243.128966) (xy 369.223272 -243.150064) (xy 369.176001 -243.163756) (xy 369.127146 -243.169688)
			(xy 369.077971 -243.167707) (xy 369.029752 -243.157863) (xy 368.983736 -243.140411) (xy 368.941115 -243.115804)
			(xy 368.902994 -243.084679) (xy 368.870359 -243.047842) (xy 368.844056 -243.006246) (xy 368.824765 -242.96097)
			(xy 368.812988 -242.913186) (xy 368.809028 -242.864132) (xy 368.4905 -242.864132) (xy 368.489988 -242.889578)
			(xy 368.481824 -242.939812) (xy 368.465708 -242.988086) (xy 368.442057 -243.033149) (xy 368.411484 -243.073835)
			(xy 368.37478 -243.10909) (xy 368.332896 -243.138) (xy 368.286917 -243.159817) (xy 368.238033 -243.173977)
			(xy 368.187512 -243.180111) (xy 368.13666 -243.178062) (xy 368.086796 -243.167882) (xy 368.03921 -243.149835)
			(xy 367.995136 -243.124389) (xy 367.955714 -243.092202) (xy 367.921966 -243.054108) (xy 367.894765 -243.011094)
			(xy 367.874817 -242.964274) (xy 367.862638 -242.91486) (xy 367.858543 -242.864132) (xy 367.550446 -242.864132)
			(xy 367.549934 -242.889578) (xy 367.54177 -242.939812) (xy 367.525654 -242.988086) (xy 367.502003 -243.033149)
			(xy 367.47143 -243.073835) (xy 367.434726 -243.10909) (xy 367.392842 -243.138) (xy 367.346863 -243.159817)
			(xy 367.297979 -243.173977) (xy 367.247458 -243.180111) (xy 367.196606 -243.178062) (xy 367.146742 -243.167882)
			(xy 367.099156 -243.149835) (xy 367.055082 -243.124389) (xy 367.01566 -243.092202) (xy 366.981912 -243.054108)
			(xy 366.954711 -243.011094) (xy 366.934763 -242.964274) (xy 366.922584 -242.91486) (xy 366.918489 -242.864132)
			(xy 366.600232 -242.864132) (xy 366.599737 -242.888739) (xy 366.591842 -242.937316) (xy 366.576258 -242.983997)
			(xy 366.553387 -243.027574) (xy 366.523822 -243.066918) (xy 366.488329 -243.10101) (xy 366.447826 -243.128966)
			(xy 366.403364 -243.150064) (xy 366.356093 -243.163756) (xy 366.307238 -243.169688) (xy 366.258063 -243.167707)
			(xy 366.209844 -243.157863) (xy 366.163828 -243.140411) (xy 366.121207 -243.115804) (xy 366.083086 -243.084679)
			(xy 366.050451 -243.047842) (xy 366.024148 -243.006246) (xy 366.004857 -242.96097) (xy 365.99308 -242.913186)
			(xy 365.98912 -242.864132) (xy 365.670592 -242.864132) (xy 365.67008 -242.889578) (xy 365.661916 -242.939812)
			(xy 365.6458 -242.988086) (xy 365.622149 -243.033149) (xy 365.591576 -243.073835) (xy 365.554872 -243.10909)
			(xy 365.512988 -243.138) (xy 365.467009 -243.159817) (xy 365.418125 -243.173977) (xy 365.367604 -243.180111)
			(xy 365.316752 -243.178062) (xy 365.266888 -243.167882) (xy 365.219302 -243.149835) (xy 365.175228 -243.124389)
			(xy 365.135806 -243.092202) (xy 365.102058 -243.054108) (xy 365.074857 -243.011094) (xy 365.054909 -242.964274)
			(xy 365.04273 -242.91486) (xy 365.038635 -242.864132) (xy 364.730538 -242.864132) (xy 364.730026 -242.889578)
			(xy 364.721862 -242.939812) (xy 364.705746 -242.988086) (xy 364.682095 -243.033149) (xy 364.651522 -243.073835)
			(xy 364.614818 -243.10909) (xy 364.572934 -243.138) (xy 364.526955 -243.159817) (xy 364.478071 -243.173977)
			(xy 364.42755 -243.180111) (xy 364.376698 -243.178062) (xy 364.326834 -243.167882) (xy 364.279248 -243.149835)
			(xy 364.235174 -243.124389) (xy 364.195752 -243.092202) (xy 364.162004 -243.054108) (xy 364.134803 -243.011094)
			(xy 364.114855 -242.964274) (xy 364.102676 -242.91486) (xy 364.098581 -242.864132) (xy 363.78007 -242.864132)
			(xy 363.779575 -242.888739) (xy 363.77168 -242.937316) (xy 363.756096 -242.983997) (xy 363.733225 -243.027574)
			(xy 363.70366 -243.066918) (xy 363.668167 -243.10101) (xy 363.627664 -243.128966) (xy 363.583202 -243.150064)
			(xy 363.535931 -243.163756) (xy 363.487076 -243.169688) (xy 363.437901 -243.167707) (xy 363.389682 -243.157863)
			(xy 363.343666 -243.140411) (xy 363.301045 -243.115804) (xy 363.262924 -243.084679) (xy 363.230289 -243.047842)
			(xy 363.203986 -243.006246) (xy 363.184695 -242.96097) (xy 363.172918 -242.913186) (xy 363.168958 -242.864132)
			(xy 359.120948 -242.864132) (xy 358.546908 -243.438172) (xy 358.544114 -243.475764) (xy 358.555544 -243.491004)
			(xy 358.569867 -243.51096) (xy 358.592629 -243.554486) (xy 358.608135 -243.601092) (xy 358.615986 -243.649579)
			(xy 358.616504 -243.674138) (xy 360.81895 -243.674138) (xy 360.82291 -243.625084) (xy 360.834687 -243.5773)
			(xy 360.853978 -243.532024) (xy 360.880281 -243.490428) (xy 360.912916 -243.453591) (xy 360.951037 -243.422466)
			(xy 360.993658 -243.397859) (xy 361.039674 -243.380407) (xy 361.087893 -243.370563) (xy 361.137068 -243.368582)
			(xy 361.185923 -243.374514) (xy 361.233194 -243.388206) (xy 361.277656 -243.409304) (xy 361.318159 -243.43726)
			(xy 361.353652 -243.471352) (xy 361.383217 -243.510696) (xy 361.406088 -243.554273) (xy 361.421672 -243.600954)
			(xy 361.429567 -243.649531) (xy 361.430062 -243.674138) (xy 361.748573 -243.674138) (xy 361.752668 -243.62341)
			(xy 361.764847 -243.573996) (xy 361.784795 -243.527176) (xy 361.811996 -243.484162) (xy 361.845744 -243.446068)
			(xy 361.885166 -243.413881) (xy 361.92924 -243.388435) (xy 361.976826 -243.370388) (xy 362.02669 -243.360208)
			(xy 362.077542 -243.358159) (xy 362.128063 -243.364293) (xy 362.176947 -243.378453) (xy 362.222926 -243.40027)
			(xy 362.26481 -243.42918) (xy 362.301514 -243.464435) (xy 362.332087 -243.505121) (xy 362.355738 -243.550184)
			(xy 362.371854 -243.598458) (xy 362.380018 -243.648692) (xy 362.38053 -243.674138) (xy 362.688627 -243.674138)
			(xy 362.692722 -243.62341) (xy 362.704901 -243.573996) (xy 362.724849 -243.527176) (xy 362.75205 -243.484162)
			(xy 362.785798 -243.446068) (xy 362.82522 -243.413881) (xy 362.869294 -243.388435) (xy 362.91688 -243.370388)
			(xy 362.966744 -243.360208) (xy 363.017596 -243.358159) (xy 363.068117 -243.364293) (xy 363.117001 -243.378453)
			(xy 363.16298 -243.40027) (xy 363.204864 -243.42918) (xy 363.241568 -243.464435) (xy 363.272141 -243.505121)
			(xy 363.295792 -243.550184) (xy 363.311908 -243.598458) (xy 363.320072 -243.648692) (xy 363.320584 -243.674138)
			(xy 363.639112 -243.674138) (xy 363.643072 -243.625084) (xy 363.654849 -243.5773) (xy 363.67414 -243.532024)
			(xy 363.700443 -243.490428) (xy 363.733078 -243.453591) (xy 363.771199 -243.422466) (xy 363.81382 -243.397859)
			(xy 363.859836 -243.380407) (xy 363.908055 -243.370563) (xy 363.95723 -243.368582) (xy 364.006085 -243.374514)
			(xy 364.053356 -243.388206) (xy 364.097818 -243.409304) (xy 364.138321 -243.43726) (xy 364.173814 -243.471352)
			(xy 364.203379 -243.510696) (xy 364.22625 -243.554273) (xy 364.241834 -243.600954) (xy 364.249729 -243.649531)
			(xy 364.250224 -243.674138) (xy 364.578912 -243.674138) (xy 364.582872 -243.625084) (xy 364.594649 -243.5773)
			(xy 364.61394 -243.532024) (xy 364.640243 -243.490428) (xy 364.672878 -243.453591) (xy 364.710999 -243.422466)
			(xy 364.75362 -243.397859) (xy 364.799636 -243.380407) (xy 364.847855 -243.370563) (xy 364.89703 -243.368582)
			(xy 364.945885 -243.374514) (xy 364.993156 -243.388206) (xy 365.037618 -243.409304) (xy 365.078121 -243.43726)
			(xy 365.113614 -243.471352) (xy 365.143179 -243.510696) (xy 365.16605 -243.554273) (xy 365.181634 -243.600954)
			(xy 365.189529 -243.649531) (xy 365.190024 -243.674138) (xy 365.518966 -243.674138) (xy 365.522926 -243.625084)
			(xy 365.534703 -243.5773) (xy 365.553994 -243.532024) (xy 365.580297 -243.490428) (xy 365.612932 -243.453591)
			(xy 365.651053 -243.422466) (xy 365.693674 -243.397859) (xy 365.73969 -243.380407) (xy 365.787909 -243.370563)
			(xy 365.837084 -243.368582) (xy 365.885939 -243.374514) (xy 365.93321 -243.388206) (xy 365.977672 -243.409304)
			(xy 366.018175 -243.43726) (xy 366.053668 -243.471352) (xy 366.083233 -243.510696) (xy 366.106104 -243.554273)
			(xy 366.121688 -243.600954) (xy 366.129583 -243.649531) (xy 366.130078 -243.674138) (xy 366.45902 -243.674138)
			(xy 366.46298 -243.625084) (xy 366.474757 -243.5773) (xy 366.494048 -243.532024) (xy 366.520351 -243.490428)
			(xy 366.552986 -243.453591) (xy 366.591107 -243.422466) (xy 366.633728 -243.397859) (xy 366.679744 -243.380407)
			(xy 366.727963 -243.370563) (xy 366.777138 -243.368582) (xy 366.825993 -243.374514) (xy 366.873264 -243.388206)
			(xy 366.917726 -243.409304) (xy 366.958229 -243.43726) (xy 366.993722 -243.471352) (xy 367.023287 -243.510696)
			(xy 367.046158 -243.554273) (xy 367.061742 -243.600954) (xy 367.069637 -243.649531) (xy 367.070132 -243.674138)
			(xy 367.399074 -243.674138) (xy 367.403034 -243.625084) (xy 367.414811 -243.5773) (xy 367.434102 -243.532024)
			(xy 367.460405 -243.490428) (xy 367.49304 -243.453591) (xy 367.531161 -243.422466) (xy 367.573782 -243.397859)
			(xy 367.619798 -243.380407) (xy 367.668017 -243.370563) (xy 367.717192 -243.368582) (xy 367.766047 -243.374514)
			(xy 367.813318 -243.388206) (xy 367.85778 -243.409304) (xy 367.898283 -243.43726) (xy 367.933776 -243.471352)
			(xy 367.963341 -243.510696) (xy 367.986212 -243.554273) (xy 368.001796 -243.600954) (xy 368.009691 -243.649531)
			(xy 368.010186 -243.674138) (xy 368.338874 -243.674138) (xy 368.342834 -243.625084) (xy 368.354611 -243.5773)
			(xy 368.373902 -243.532024) (xy 368.400205 -243.490428) (xy 368.43284 -243.453591) (xy 368.470961 -243.422466)
			(xy 368.513582 -243.397859) (xy 368.559598 -243.380407) (xy 368.607817 -243.370563) (xy 368.656992 -243.368582)
			(xy 368.705847 -243.374514) (xy 368.753118 -243.388206) (xy 368.79758 -243.409304) (xy 368.838083 -243.43726)
			(xy 368.873576 -243.471352) (xy 368.903141 -243.510696) (xy 368.926012 -243.554273) (xy 368.941596 -243.600954)
			(xy 368.949491 -243.649531) (xy 368.949986 -243.674138) (xy 369.278928 -243.674138) (xy 369.282888 -243.625084)
			(xy 369.294665 -243.5773) (xy 369.313956 -243.532024) (xy 369.340259 -243.490428) (xy 369.372894 -243.453591)
			(xy 369.411015 -243.422466) (xy 369.453636 -243.397859) (xy 369.499652 -243.380407) (xy 369.547871 -243.370563)
			(xy 369.597046 -243.368582) (xy 369.645901 -243.374514) (xy 369.693172 -243.388206) (xy 369.737634 -243.409304)
			(xy 369.778137 -243.43726) (xy 369.81363 -243.471352) (xy 369.843195 -243.510696) (xy 369.866066 -243.554273)
			(xy 369.88165 -243.600954) (xy 369.889545 -243.649531) (xy 369.89004 -243.674138) (xy 370.218982 -243.674138)
			(xy 370.222942 -243.625084) (xy 370.234719 -243.5773) (xy 370.25401 -243.532024) (xy 370.280313 -243.490428)
			(xy 370.312948 -243.453591) (xy 370.351069 -243.422466) (xy 370.39369 -243.397859) (xy 370.439706 -243.380407)
			(xy 370.487925 -243.370563) (xy 370.5371 -243.368582) (xy 370.585955 -243.374514) (xy 370.633226 -243.388206)
			(xy 370.677688 -243.409304) (xy 370.718191 -243.43726) (xy 370.753684 -243.471352) (xy 370.783249 -243.510696)
			(xy 370.80612 -243.554273) (xy 370.821704 -243.600954) (xy 370.829599 -243.649531) (xy 370.830094 -243.674138)
			(xy 371.159036 -243.674138) (xy 371.162996 -243.625084) (xy 371.174773 -243.5773) (xy 371.194064 -243.532024)
			(xy 371.220367 -243.490428) (xy 371.253002 -243.453591) (xy 371.291123 -243.422466) (xy 371.333744 -243.397859)
			(xy 371.37976 -243.380407) (xy 371.427979 -243.370563) (xy 371.477154 -243.368582) (xy 371.526009 -243.374514)
			(xy 371.57328 -243.388206) (xy 371.617742 -243.409304) (xy 371.658245 -243.43726) (xy 371.693738 -243.471352)
			(xy 371.723303 -243.510696) (xy 371.746174 -243.554273) (xy 371.761758 -243.600954) (xy 371.769653 -243.649531)
			(xy 371.770148 -243.674138) (xy 372.09909 -243.674138) (xy 372.10305 -243.625084) (xy 372.114827 -243.5773)
			(xy 372.134118 -243.532024) (xy 372.160421 -243.490428) (xy 372.193056 -243.453591) (xy 372.231177 -243.422466)
			(xy 372.273798 -243.397859) (xy 372.319814 -243.380407) (xy 372.368033 -243.370563) (xy 372.417208 -243.368582)
			(xy 372.466063 -243.374514) (xy 372.513334 -243.388206) (xy 372.557796 -243.409304) (xy 372.598299 -243.43726)
			(xy 372.633792 -243.471352) (xy 372.663357 -243.510696) (xy 372.686228 -243.554273) (xy 372.701812 -243.600954)
			(xy 372.709707 -243.649531) (xy 372.710202 -243.674138) (xy 373.03889 -243.674138) (xy 373.04285 -243.625084)
			(xy 373.054627 -243.5773) (xy 373.073918 -243.532024) (xy 373.100221 -243.490428) (xy 373.132856 -243.453591)
			(xy 373.170977 -243.422466) (xy 373.213598 -243.397859) (xy 373.259614 -243.380407) (xy 373.307833 -243.370563)
			(xy 373.357008 -243.368582) (xy 373.405863 -243.374514) (xy 373.453134 -243.388206) (xy 373.497596 -243.409304)
			(xy 373.538099 -243.43726) (xy 373.573592 -243.471352) (xy 373.603157 -243.510696) (xy 373.626028 -243.554273)
			(xy 373.641612 -243.600954) (xy 373.649507 -243.649531) (xy 373.650002 -243.674138) (xy 373.649507 -243.698745)
			(xy 373.641612 -243.747322) (xy 373.626028 -243.794003) (xy 373.603157 -243.83758) (xy 373.573592 -243.876924)
			(xy 373.538099 -243.911016) (xy 373.497596 -243.938972) (xy 373.453134 -243.96007) (xy 373.405863 -243.973762)
			(xy 373.357008 -243.979694) (xy 373.307833 -243.977713) (xy 373.259614 -243.967869) (xy 373.213598 -243.950417)
			(xy 373.170977 -243.92581) (xy 373.132856 -243.894685) (xy 373.100221 -243.857848) (xy 373.073918 -243.816252)
			(xy 373.054627 -243.770976) (xy 373.04285 -243.723192) (xy 373.03889 -243.674138) (xy 372.710202 -243.674138)
			(xy 372.709707 -243.698745) (xy 372.701812 -243.747322) (xy 372.686228 -243.794003) (xy 372.663357 -243.83758)
			(xy 372.633792 -243.876924) (xy 372.598299 -243.911016) (xy 372.557796 -243.938972) (xy 372.513334 -243.96007)
			(xy 372.466063 -243.973762) (xy 372.417208 -243.979694) (xy 372.368033 -243.977713) (xy 372.319814 -243.967869)
			(xy 372.273798 -243.950417) (xy 372.231177 -243.92581) (xy 372.193056 -243.894685) (xy 372.160421 -243.857848)
			(xy 372.134118 -243.816252) (xy 372.114827 -243.770976) (xy 372.10305 -243.723192) (xy 372.09909 -243.674138)
			(xy 371.770148 -243.674138) (xy 371.769653 -243.698745) (xy 371.761758 -243.747322) (xy 371.746174 -243.794003)
			(xy 371.723303 -243.83758) (xy 371.693738 -243.876924) (xy 371.658245 -243.911016) (xy 371.617742 -243.938972)
			(xy 371.57328 -243.96007) (xy 371.526009 -243.973762) (xy 371.477154 -243.979694) (xy 371.427979 -243.977713)
			(xy 371.37976 -243.967869) (xy 371.333744 -243.950417) (xy 371.291123 -243.92581) (xy 371.253002 -243.894685)
			(xy 371.220367 -243.857848) (xy 371.194064 -243.816252) (xy 371.174773 -243.770976) (xy 371.162996 -243.723192)
			(xy 371.159036 -243.674138) (xy 370.830094 -243.674138) (xy 370.829599 -243.698745) (xy 370.821704 -243.747322)
			(xy 370.80612 -243.794003) (xy 370.783249 -243.83758) (xy 370.753684 -243.876924) (xy 370.718191 -243.911016)
			(xy 370.677688 -243.938972) (xy 370.633226 -243.96007) (xy 370.585955 -243.973762) (xy 370.5371 -243.979694)
			(xy 370.487925 -243.977713) (xy 370.439706 -243.967869) (xy 370.39369 -243.950417) (xy 370.351069 -243.92581)
			(xy 370.312948 -243.894685) (xy 370.280313 -243.857848) (xy 370.25401 -243.816252) (xy 370.234719 -243.770976)
			(xy 370.222942 -243.723192) (xy 370.218982 -243.674138) (xy 369.89004 -243.674138) (xy 369.889545 -243.698745)
			(xy 369.88165 -243.747322) (xy 369.866066 -243.794003) (xy 369.843195 -243.83758) (xy 369.81363 -243.876924)
			(xy 369.778137 -243.911016) (xy 369.737634 -243.938972) (xy 369.693172 -243.96007) (xy 369.645901 -243.973762)
			(xy 369.597046 -243.979694) (xy 369.547871 -243.977713) (xy 369.499652 -243.967869) (xy 369.453636 -243.950417)
			(xy 369.411015 -243.92581) (xy 369.372894 -243.894685) (xy 369.340259 -243.857848) (xy 369.313956 -243.816252)
			(xy 369.294665 -243.770976) (xy 369.282888 -243.723192) (xy 369.278928 -243.674138) (xy 368.949986 -243.674138)
			(xy 368.949491 -243.698745) (xy 368.941596 -243.747322) (xy 368.926012 -243.794003) (xy 368.903141 -243.83758)
			(xy 368.873576 -243.876924) (xy 368.838083 -243.911016) (xy 368.79758 -243.938972) (xy 368.753118 -243.96007)
			(xy 368.705847 -243.973762) (xy 368.656992 -243.979694) (xy 368.607817 -243.977713) (xy 368.559598 -243.967869)
			(xy 368.513582 -243.950417) (xy 368.470961 -243.92581) (xy 368.43284 -243.894685) (xy 368.400205 -243.857848)
			(xy 368.373902 -243.816252) (xy 368.354611 -243.770976) (xy 368.342834 -243.723192) (xy 368.338874 -243.674138)
			(xy 368.010186 -243.674138) (xy 368.009691 -243.698745) (xy 368.001796 -243.747322) (xy 367.986212 -243.794003)
			(xy 367.963341 -243.83758) (xy 367.933776 -243.876924) (xy 367.898283 -243.911016) (xy 367.85778 -243.938972)
			(xy 367.813318 -243.96007) (xy 367.766047 -243.973762) (xy 367.717192 -243.979694) (xy 367.668017 -243.977713)
			(xy 367.619798 -243.967869) (xy 367.573782 -243.950417) (xy 367.531161 -243.92581) (xy 367.49304 -243.894685)
			(xy 367.460405 -243.857848) (xy 367.434102 -243.816252) (xy 367.414811 -243.770976) (xy 367.403034 -243.723192)
			(xy 367.399074 -243.674138) (xy 367.070132 -243.674138) (xy 367.069637 -243.698745) (xy 367.061742 -243.747322)
			(xy 367.046158 -243.794003) (xy 367.023287 -243.83758) (xy 366.993722 -243.876924) (xy 366.958229 -243.911016)
			(xy 366.917726 -243.938972) (xy 366.873264 -243.96007) (xy 366.825993 -243.973762) (xy 366.777138 -243.979694)
			(xy 366.727963 -243.977713) (xy 366.679744 -243.967869) (xy 366.633728 -243.950417) (xy 366.591107 -243.92581)
			(xy 366.552986 -243.894685) (xy 366.520351 -243.857848) (xy 366.494048 -243.816252) (xy 366.474757 -243.770976)
			(xy 366.46298 -243.723192) (xy 366.45902 -243.674138) (xy 366.130078 -243.674138) (xy 366.129583 -243.698745)
			(xy 366.121688 -243.747322) (xy 366.106104 -243.794003) (xy 366.083233 -243.83758) (xy 366.053668 -243.876924)
			(xy 366.018175 -243.911016) (xy 365.977672 -243.938972) (xy 365.93321 -243.96007) (xy 365.885939 -243.973762)
			(xy 365.837084 -243.979694) (xy 365.787909 -243.977713) (xy 365.73969 -243.967869) (xy 365.693674 -243.950417)
			(xy 365.651053 -243.92581) (xy 365.612932 -243.894685) (xy 365.580297 -243.857848) (xy 365.553994 -243.816252)
			(xy 365.534703 -243.770976) (xy 365.522926 -243.723192) (xy 365.518966 -243.674138) (xy 365.190024 -243.674138)
			(xy 365.189529 -243.698745) (xy 365.181634 -243.747322) (xy 365.16605 -243.794003) (xy 365.143179 -243.83758)
			(xy 365.113614 -243.876924) (xy 365.078121 -243.911016) (xy 365.037618 -243.938972) (xy 364.993156 -243.96007)
			(xy 364.945885 -243.973762) (xy 364.89703 -243.979694) (xy 364.847855 -243.977713) (xy 364.799636 -243.967869)
			(xy 364.75362 -243.950417) (xy 364.710999 -243.92581) (xy 364.672878 -243.894685) (xy 364.640243 -243.857848)
			(xy 364.61394 -243.816252) (xy 364.594649 -243.770976) (xy 364.582872 -243.723192) (xy 364.578912 -243.674138)
			(xy 364.250224 -243.674138) (xy 364.249729 -243.698745) (xy 364.241834 -243.747322) (xy 364.22625 -243.794003)
			(xy 364.203379 -243.83758) (xy 364.173814 -243.876924) (xy 364.138321 -243.911016) (xy 364.097818 -243.938972)
			(xy 364.053356 -243.96007) (xy 364.006085 -243.973762) (xy 363.95723 -243.979694) (xy 363.908055 -243.977713)
			(xy 363.859836 -243.967869) (xy 363.81382 -243.950417) (xy 363.771199 -243.92581) (xy 363.733078 -243.894685)
			(xy 363.700443 -243.857848) (xy 363.67414 -243.816252) (xy 363.654849 -243.770976) (xy 363.643072 -243.723192)
			(xy 363.639112 -243.674138) (xy 363.320584 -243.674138) (xy 363.320072 -243.699584) (xy 363.311908 -243.749818)
			(xy 363.295792 -243.798092) (xy 363.272141 -243.843155) (xy 363.241568 -243.883841) (xy 363.204864 -243.919096)
			(xy 363.16298 -243.948006) (xy 363.117001 -243.969823) (xy 363.068117 -243.983983) (xy 363.017596 -243.990117)
			(xy 362.966744 -243.988068) (xy 362.91688 -243.977888) (xy 362.869294 -243.959841) (xy 362.82522 -243.934395)
			(xy 362.785798 -243.902208) (xy 362.75205 -243.864114) (xy 362.724849 -243.8211) (xy 362.704901 -243.77428)
			(xy 362.692722 -243.724866) (xy 362.688627 -243.674138) (xy 362.38053 -243.674138) (xy 362.380018 -243.699584)
			(xy 362.371854 -243.749818) (xy 362.355738 -243.798092) (xy 362.332087 -243.843155) (xy 362.301514 -243.883841)
			(xy 362.26481 -243.919096) (xy 362.222926 -243.948006) (xy 362.176947 -243.969823) (xy 362.128063 -243.983983)
			(xy 362.077542 -243.990117) (xy 362.02669 -243.988068) (xy 361.976826 -243.977888) (xy 361.92924 -243.959841)
			(xy 361.885166 -243.934395) (xy 361.845744 -243.902208) (xy 361.811996 -243.864114) (xy 361.784795 -243.8211)
			(xy 361.764847 -243.77428) (xy 361.752668 -243.724866) (xy 361.748573 -243.674138) (xy 361.430062 -243.674138)
			(xy 361.429567 -243.698745) (xy 361.421672 -243.747322) (xy 361.406088 -243.794003) (xy 361.383217 -243.83758)
			(xy 361.353652 -243.876924) (xy 361.318159 -243.911016) (xy 361.277656 -243.938972) (xy 361.233194 -243.96007)
			(xy 361.185923 -243.973762) (xy 361.137068 -243.979694) (xy 361.087893 -243.977713) (xy 361.039674 -243.967869)
			(xy 360.993658 -243.950417) (xy 360.951037 -243.92581) (xy 360.912916 -243.894685) (xy 360.880281 -243.857848)
			(xy 360.853978 -243.816252) (xy 360.834687 -243.770976) (xy 360.82291 -243.723192) (xy 360.81895 -243.674138)
			(xy 358.616504 -243.674138) (xy 358.616031 -243.698127) (xy 358.60852 -243.745514) (xy 358.593689 -243.791143)
			(xy 358.571903 -243.83389) (xy 358.543699 -243.872703) (xy 358.509771 -243.906626) (xy 358.470954 -243.934825)
			(xy 358.428204 -243.956605) (xy 358.382573 -243.97143) (xy 358.335185 -243.978934) (xy 358.311196 -243.979446)
			(xy 358.286636 -243.978956) (xy 358.238148 -243.971096) (xy 358.191542 -243.955581) (xy 358.148019 -243.93281)
			(xy 358.128062 -243.918486) (xy 358.112822 -243.907056) (xy 358.07523 -243.90985) (xy 357.941626 -244.043454)
			(xy 357.933425 -244.052596) (xy 357.925985 -244.075959) (xy 357.927402 -244.088158) (xy 357.941626 -244.1702)
			(xy 357.942388 -244.17401) (xy 357.945809 -244.184821) (xy 357.960317 -244.202211) (xy 357.970328 -244.207538)
			(xy 357.992537 -244.218445) (xy 358.033396 -244.246344) (xy 358.069222 -244.280467) (xy 358.099075 -244.319921)
			(xy 358.122175 -244.363672) (xy 358.137917 -244.410577) (xy 358.145889 -244.459406) (xy 358.14635 -244.484144)
			(xy 361.289104 -244.484144) (xy 361.293064 -244.43509) (xy 361.304841 -244.387306) (xy 361.324132 -244.34203)
			(xy 361.350435 -244.300434) (xy 361.38307 -244.263597) (xy 361.421191 -244.232472) (xy 361.463812 -244.207865)
			(xy 361.509828 -244.190413) (xy 361.558047 -244.180569) (xy 361.607222 -244.178588) (xy 361.656077 -244.18452)
			(xy 361.703348 -244.198212) (xy 361.74781 -244.21931) (xy 361.788313 -244.247266) (xy 361.823806 -244.281358)
			(xy 361.853371 -244.320702) (xy 361.876242 -244.364279) (xy 361.891826 -244.41096) (xy 361.899721 -244.459537)
			(xy 361.900216 -244.484144) (xy 362.228904 -244.484144) (xy 362.232864 -244.43509) (xy 362.244641 -244.387306)
			(xy 362.263932 -244.34203) (xy 362.290235 -244.300434) (xy 362.32287 -244.263597) (xy 362.360991 -244.232472)
			(xy 362.403612 -244.207865) (xy 362.449628 -244.190413) (xy 362.497847 -244.180569) (xy 362.547022 -244.178588)
			(xy 362.595877 -244.18452) (xy 362.643148 -244.198212) (xy 362.68761 -244.21931) (xy 362.728113 -244.247266)
			(xy 362.763606 -244.281358) (xy 362.793171 -244.320702) (xy 362.816042 -244.364279) (xy 362.831626 -244.41096)
			(xy 362.839521 -244.459537) (xy 362.840016 -244.484144) (xy 363.168958 -244.484144) (xy 363.172918 -244.43509)
			(xy 363.184695 -244.387306) (xy 363.203986 -244.34203) (xy 363.230289 -244.300434) (xy 363.262924 -244.263597)
			(xy 363.301045 -244.232472) (xy 363.343666 -244.207865) (xy 363.389682 -244.190413) (xy 363.437901 -244.180569)
			(xy 363.487076 -244.178588) (xy 363.535931 -244.18452) (xy 363.583202 -244.198212) (xy 363.627664 -244.21931)
			(xy 363.668167 -244.247266) (xy 363.70366 -244.281358) (xy 363.733225 -244.320702) (xy 363.756096 -244.364279)
			(xy 363.77168 -244.41096) (xy 363.779575 -244.459537) (xy 363.78007 -244.484144) (xy 364.098581 -244.484144)
			(xy 364.102676 -244.433416) (xy 364.114855 -244.384002) (xy 364.134803 -244.337182) (xy 364.162004 -244.294168)
			(xy 364.195752 -244.256074) (xy 364.235174 -244.223887) (xy 364.279248 -244.198441) (xy 364.326834 -244.180394)
			(xy 364.376698 -244.170214) (xy 364.42755 -244.168165) (xy 364.478071 -244.174299) (xy 364.526955 -244.188459)
			(xy 364.572934 -244.210276) (xy 364.614818 -244.239186) (xy 364.651522 -244.274441) (xy 364.682095 -244.315127)
			(xy 364.705746 -244.36019) (xy 364.721862 -244.408464) (xy 364.730026 -244.458698) (xy 364.730538 -244.484144)
			(xy 365.038635 -244.484144) (xy 365.04273 -244.433416) (xy 365.054909 -244.384002) (xy 365.074857 -244.337182)
			(xy 365.102058 -244.294168) (xy 365.135806 -244.256074) (xy 365.175228 -244.223887) (xy 365.219302 -244.198441)
			(xy 365.266888 -244.180394) (xy 365.316752 -244.170214) (xy 365.367604 -244.168165) (xy 365.418125 -244.174299)
			(xy 365.467009 -244.188459) (xy 365.512988 -244.210276) (xy 365.554872 -244.239186) (xy 365.591576 -244.274441)
			(xy 365.622149 -244.315127) (xy 365.6458 -244.36019) (xy 365.661916 -244.408464) (xy 365.67008 -244.458698)
			(xy 365.670592 -244.484144) (xy 365.98912 -244.484144) (xy 365.99308 -244.43509) (xy 366.004857 -244.387306)
			(xy 366.024148 -244.34203) (xy 366.050451 -244.300434) (xy 366.083086 -244.263597) (xy 366.121207 -244.232472)
			(xy 366.163828 -244.207865) (xy 366.209844 -244.190413) (xy 366.258063 -244.180569) (xy 366.307238 -244.178588)
			(xy 366.356093 -244.18452) (xy 366.403364 -244.198212) (xy 366.447826 -244.21931) (xy 366.488329 -244.247266)
			(xy 366.523822 -244.281358) (xy 366.553387 -244.320702) (xy 366.576258 -244.364279) (xy 366.591842 -244.41096)
			(xy 366.599737 -244.459537) (xy 366.600232 -244.484144) (xy 366.918489 -244.484144) (xy 366.922584 -244.433416)
			(xy 366.934763 -244.384002) (xy 366.954711 -244.337182) (xy 366.981912 -244.294168) (xy 367.01566 -244.256074)
			(xy 367.055082 -244.223887) (xy 367.099156 -244.198441) (xy 367.146742 -244.180394) (xy 367.196606 -244.170214)
			(xy 367.247458 -244.168165) (xy 367.297979 -244.174299) (xy 367.346863 -244.188459) (xy 367.392842 -244.210276)
			(xy 367.434726 -244.239186) (xy 367.47143 -244.274441) (xy 367.502003 -244.315127) (xy 367.525654 -244.36019)
			(xy 367.54177 -244.408464) (xy 367.549934 -244.458698) (xy 367.550446 -244.484144) (xy 367.858543 -244.484144)
			(xy 367.862638 -244.433416) (xy 367.874817 -244.384002) (xy 367.894765 -244.337182) (xy 367.921966 -244.294168)
			(xy 367.955714 -244.256074) (xy 367.995136 -244.223887) (xy 368.03921 -244.198441) (xy 368.086796 -244.180394)
			(xy 368.13666 -244.170214) (xy 368.187512 -244.168165) (xy 368.238033 -244.174299) (xy 368.286917 -244.188459)
			(xy 368.332896 -244.210276) (xy 368.37478 -244.239186) (xy 368.411484 -244.274441) (xy 368.442057 -244.315127)
			(xy 368.465708 -244.36019) (xy 368.481824 -244.408464) (xy 368.489988 -244.458698) (xy 368.4905 -244.484144)
			(xy 368.809028 -244.484144) (xy 368.812988 -244.43509) (xy 368.824765 -244.387306) (xy 368.844056 -244.34203)
			(xy 368.870359 -244.300434) (xy 368.902994 -244.263597) (xy 368.941115 -244.232472) (xy 368.983736 -244.207865)
			(xy 369.029752 -244.190413) (xy 369.077971 -244.180569) (xy 369.127146 -244.178588) (xy 369.176001 -244.18452)
			(xy 369.223272 -244.198212) (xy 369.267734 -244.21931) (xy 369.308237 -244.247266) (xy 369.34373 -244.281358)
			(xy 369.373295 -244.320702) (xy 369.396166 -244.364279) (xy 369.41175 -244.41096) (xy 369.419645 -244.459537)
			(xy 369.42014 -244.484144) (xy 369.738651 -244.484144) (xy 369.742746 -244.433416) (xy 369.754925 -244.384002)
			(xy 369.774873 -244.337182) (xy 369.802074 -244.294168) (xy 369.835822 -244.256074) (xy 369.875244 -244.223887)
			(xy 369.919318 -244.198441) (xy 369.966904 -244.180394) (xy 370.016768 -244.170214) (xy 370.06762 -244.168165)
			(xy 370.118141 -244.174299) (xy 370.167025 -244.188459) (xy 370.213004 -244.210276) (xy 370.254888 -244.239186)
			(xy 370.291592 -244.274441) (xy 370.322165 -244.315127) (xy 370.345816 -244.36019) (xy 370.361932 -244.408464)
			(xy 370.370096 -244.458698) (xy 370.370608 -244.484144) (xy 370.678451 -244.484144) (xy 370.682546 -244.433416)
			(xy 370.694725 -244.384002) (xy 370.714673 -244.337182) (xy 370.741874 -244.294168) (xy 370.775622 -244.256074)
			(xy 370.815044 -244.223887) (xy 370.859118 -244.198441) (xy 370.906704 -244.180394) (xy 370.956568 -244.170214)
			(xy 371.00742 -244.168165) (xy 371.057941 -244.174299) (xy 371.106825 -244.188459) (xy 371.152804 -244.210276)
			(xy 371.194688 -244.239186) (xy 371.231392 -244.274441) (xy 371.261965 -244.315127) (xy 371.285616 -244.36019)
			(xy 371.301732 -244.408464) (xy 371.309896 -244.458698) (xy 371.310408 -244.484144) (xy 371.628936 -244.484144)
			(xy 371.632896 -244.43509) (xy 371.644673 -244.387306) (xy 371.663964 -244.34203) (xy 371.690267 -244.300434)
			(xy 371.722902 -244.263597) (xy 371.761023 -244.232472) (xy 371.803644 -244.207865) (xy 371.84966 -244.190413)
			(xy 371.897879 -244.180569) (xy 371.947054 -244.178588) (xy 371.995909 -244.18452) (xy 372.04318 -244.198212)
			(xy 372.087642 -244.21931) (xy 372.128145 -244.247266) (xy 372.163638 -244.281358) (xy 372.193203 -244.320702)
			(xy 372.216074 -244.364279) (xy 372.231658 -244.41096) (xy 372.239553 -244.459537) (xy 372.240048 -244.484144)
			(xy 372.558559 -244.484144) (xy 372.562654 -244.433416) (xy 372.574833 -244.384002) (xy 372.594781 -244.337182)
			(xy 372.621982 -244.294168) (xy 372.65573 -244.256074) (xy 372.695152 -244.223887) (xy 372.739226 -244.198441)
			(xy 372.786812 -244.180394) (xy 372.836676 -244.170214) (xy 372.887528 -244.168165) (xy 372.938049 -244.174299)
			(xy 372.986933 -244.188459) (xy 373.032912 -244.210276) (xy 373.074796 -244.239186) (xy 373.1115 -244.274441)
			(xy 373.142073 -244.315127) (xy 373.165724 -244.36019) (xy 373.18184 -244.408464) (xy 373.190004 -244.458698)
			(xy 373.190516 -244.484144) (xy 373.498613 -244.484144) (xy 373.502708 -244.433416) (xy 373.514887 -244.384002)
			(xy 373.534835 -244.337182) (xy 373.562036 -244.294168) (xy 373.595784 -244.256074) (xy 373.635206 -244.223887)
			(xy 373.67928 -244.198441) (xy 373.726866 -244.180394) (xy 373.77673 -244.170214) (xy 373.827582 -244.168165)
			(xy 373.878103 -244.174299) (xy 373.926987 -244.188459) (xy 373.972966 -244.210276) (xy 374.01485 -244.239186)
			(xy 374.051554 -244.274441) (xy 374.082127 -244.315127) (xy 374.105778 -244.36019) (xy 374.121894 -244.408464)
			(xy 374.130058 -244.458698) (xy 374.13057 -244.484144) (xy 374.130058 -244.50959) (xy 374.121894 -244.559824)
			(xy 374.105778 -244.608098) (xy 374.082127 -244.653161) (xy 374.051554 -244.693847) (xy 374.01485 -244.729102)
			(xy 373.972966 -244.758012) (xy 373.926987 -244.779829) (xy 373.878103 -244.793989) (xy 373.827582 -244.800123)
			(xy 373.77673 -244.798074) (xy 373.726866 -244.787894) (xy 373.67928 -244.769847) (xy 373.635206 -244.744401)
			(xy 373.595784 -244.712214) (xy 373.562036 -244.67412) (xy 373.534835 -244.631106) (xy 373.514887 -244.584286)
			(xy 373.502708 -244.534872) (xy 373.498613 -244.484144) (xy 373.190516 -244.484144) (xy 373.190004 -244.50959)
			(xy 373.18184 -244.559824) (xy 373.165724 -244.608098) (xy 373.142073 -244.653161) (xy 373.1115 -244.693847)
			(xy 373.074796 -244.729102) (xy 373.032912 -244.758012) (xy 372.986933 -244.779829) (xy 372.938049 -244.793989)
			(xy 372.887528 -244.800123) (xy 372.836676 -244.798074) (xy 372.786812 -244.787894) (xy 372.739226 -244.769847)
			(xy 372.695152 -244.744401) (xy 372.65573 -244.712214) (xy 372.621982 -244.67412) (xy 372.594781 -244.631106)
			(xy 372.574833 -244.584286) (xy 372.562654 -244.534872) (xy 372.558559 -244.484144) (xy 372.240048 -244.484144)
			(xy 372.239553 -244.508751) (xy 372.231658 -244.557328) (xy 372.216074 -244.604009) (xy 372.193203 -244.647586)
			(xy 372.163638 -244.68693) (xy 372.128145 -244.721022) (xy 372.087642 -244.748978) (xy 372.04318 -244.770076)
			(xy 371.995909 -244.783768) (xy 371.947054 -244.7897) (xy 371.897879 -244.787719) (xy 371.84966 -244.777875)
			(xy 371.803644 -244.760423) (xy 371.761023 -244.735816) (xy 371.722902 -244.704691) (xy 371.690267 -244.667854)
			(xy 371.663964 -244.626258) (xy 371.644673 -244.580982) (xy 371.632896 -244.533198) (xy 371.628936 -244.484144)
			(xy 371.310408 -244.484144) (xy 371.309896 -244.50959) (xy 371.301732 -244.559824) (xy 371.285616 -244.608098)
			(xy 371.261965 -244.653161) (xy 371.231392 -244.693847) (xy 371.194688 -244.729102) (xy 371.152804 -244.758012)
			(xy 371.106825 -244.779829) (xy 371.057941 -244.793989) (xy 371.00742 -244.800123) (xy 370.956568 -244.798074)
			(xy 370.906704 -244.787894) (xy 370.859118 -244.769847) (xy 370.815044 -244.744401) (xy 370.775622 -244.712214)
			(xy 370.741874 -244.67412) (xy 370.714673 -244.631106) (xy 370.694725 -244.584286) (xy 370.682546 -244.534872)
			(xy 370.678451 -244.484144) (xy 370.370608 -244.484144) (xy 370.370096 -244.50959) (xy 370.361932 -244.559824)
			(xy 370.345816 -244.608098) (xy 370.322165 -244.653161) (xy 370.291592 -244.693847) (xy 370.254888 -244.729102)
			(xy 370.213004 -244.758012) (xy 370.167025 -244.779829) (xy 370.118141 -244.793989) (xy 370.06762 -244.800123)
			(xy 370.016768 -244.798074) (xy 369.966904 -244.787894) (xy 369.919318 -244.769847) (xy 369.875244 -244.744401)
			(xy 369.835822 -244.712214) (xy 369.802074 -244.67412) (xy 369.774873 -244.631106) (xy 369.754925 -244.584286)
			(xy 369.742746 -244.534872) (xy 369.738651 -244.484144) (xy 369.42014 -244.484144) (xy 369.419645 -244.508751)
			(xy 369.41175 -244.557328) (xy 369.396166 -244.604009) (xy 369.373295 -244.647586) (xy 369.34373 -244.68693)
			(xy 369.308237 -244.721022) (xy 369.267734 -244.748978) (xy 369.223272 -244.770076) (xy 369.176001 -244.783768)
			(xy 369.127146 -244.7897) (xy 369.077971 -244.787719) (xy 369.029752 -244.777875) (xy 368.983736 -244.760423)
			(xy 368.941115 -244.735816) (xy 368.902994 -244.704691) (xy 368.870359 -244.667854) (xy 368.844056 -244.626258)
			(xy 368.824765 -244.580982) (xy 368.812988 -244.533198) (xy 368.809028 -244.484144) (xy 368.4905 -244.484144)
			(xy 368.489988 -244.50959) (xy 368.481824 -244.559824) (xy 368.465708 -244.608098) (xy 368.442057 -244.653161)
			(xy 368.411484 -244.693847) (xy 368.37478 -244.729102) (xy 368.332896 -244.758012) (xy 368.286917 -244.779829)
			(xy 368.238033 -244.793989) (xy 368.187512 -244.800123) (xy 368.13666 -244.798074) (xy 368.086796 -244.787894)
			(xy 368.03921 -244.769847) (xy 367.995136 -244.744401) (xy 367.955714 -244.712214) (xy 367.921966 -244.67412)
			(xy 367.894765 -244.631106) (xy 367.874817 -244.584286) (xy 367.862638 -244.534872) (xy 367.858543 -244.484144)
			(xy 367.550446 -244.484144) (xy 367.549934 -244.50959) (xy 367.54177 -244.559824) (xy 367.525654 -244.608098)
			(xy 367.502003 -244.653161) (xy 367.47143 -244.693847) (xy 367.434726 -244.729102) (xy 367.392842 -244.758012)
			(xy 367.346863 -244.779829) (xy 367.297979 -244.793989) (xy 367.247458 -244.800123) (xy 367.196606 -244.798074)
			(xy 367.146742 -244.787894) (xy 367.099156 -244.769847) (xy 367.055082 -244.744401) (xy 367.01566 -244.712214)
			(xy 366.981912 -244.67412) (xy 366.954711 -244.631106) (xy 366.934763 -244.584286) (xy 366.922584 -244.534872)
			(xy 366.918489 -244.484144) (xy 366.600232 -244.484144) (xy 366.599737 -244.508751) (xy 366.591842 -244.557328)
			(xy 366.576258 -244.604009) (xy 366.553387 -244.647586) (xy 366.523822 -244.68693) (xy 366.488329 -244.721022)
			(xy 366.447826 -244.748978) (xy 366.403364 -244.770076) (xy 366.356093 -244.783768) (xy 366.307238 -244.7897)
			(xy 366.258063 -244.787719) (xy 366.209844 -244.777875) (xy 366.163828 -244.760423) (xy 366.121207 -244.735816)
			(xy 366.083086 -244.704691) (xy 366.050451 -244.667854) (xy 366.024148 -244.626258) (xy 366.004857 -244.580982)
			(xy 365.99308 -244.533198) (xy 365.98912 -244.484144) (xy 365.670592 -244.484144) (xy 365.67008 -244.50959)
			(xy 365.661916 -244.559824) (xy 365.6458 -244.608098) (xy 365.622149 -244.653161) (xy 365.591576 -244.693847)
			(xy 365.554872 -244.729102) (xy 365.512988 -244.758012) (xy 365.467009 -244.779829) (xy 365.418125 -244.793989)
			(xy 365.367604 -244.800123) (xy 365.316752 -244.798074) (xy 365.266888 -244.787894) (xy 365.219302 -244.769847)
			(xy 365.175228 -244.744401) (xy 365.135806 -244.712214) (xy 365.102058 -244.67412) (xy 365.074857 -244.631106)
			(xy 365.054909 -244.584286) (xy 365.04273 -244.534872) (xy 365.038635 -244.484144) (xy 364.730538 -244.484144)
			(xy 364.730026 -244.50959) (xy 364.721862 -244.559824) (xy 364.705746 -244.608098) (xy 364.682095 -244.653161)
			(xy 364.651522 -244.693847) (xy 364.614818 -244.729102) (xy 364.572934 -244.758012) (xy 364.526955 -244.779829)
			(xy 364.478071 -244.793989) (xy 364.42755 -244.800123) (xy 364.376698 -244.798074) (xy 364.326834 -244.787894)
			(xy 364.279248 -244.769847) (xy 364.235174 -244.744401) (xy 364.195752 -244.712214) (xy 364.162004 -244.67412)
			(xy 364.134803 -244.631106) (xy 364.114855 -244.584286) (xy 364.102676 -244.534872) (xy 364.098581 -244.484144)
			(xy 363.78007 -244.484144) (xy 363.779575 -244.508751) (xy 363.77168 -244.557328) (xy 363.756096 -244.604009)
			(xy 363.733225 -244.647586) (xy 363.70366 -244.68693) (xy 363.668167 -244.721022) (xy 363.627664 -244.748978)
			(xy 363.583202 -244.770076) (xy 363.535931 -244.783768) (xy 363.487076 -244.7897) (xy 363.437901 -244.787719)
			(xy 363.389682 -244.777875) (xy 363.343666 -244.760423) (xy 363.301045 -244.735816) (xy 363.262924 -244.704691)
			(xy 363.230289 -244.667854) (xy 363.203986 -244.626258) (xy 363.184695 -244.580982) (xy 363.172918 -244.533198)
			(xy 363.168958 -244.484144) (xy 362.840016 -244.484144) (xy 362.839521 -244.508751) (xy 362.831626 -244.557328)
			(xy 362.816042 -244.604009) (xy 362.793171 -244.647586) (xy 362.763606 -244.68693) (xy 362.728113 -244.721022)
			(xy 362.68761 -244.748978) (xy 362.643148 -244.770076) (xy 362.595877 -244.783768) (xy 362.547022 -244.7897)
			(xy 362.497847 -244.787719) (xy 362.449628 -244.777875) (xy 362.403612 -244.760423) (xy 362.360991 -244.735816)
			(xy 362.32287 -244.704691) (xy 362.290235 -244.667854) (xy 362.263932 -244.626258) (xy 362.244641 -244.580982)
			(xy 362.232864 -244.533198) (xy 362.228904 -244.484144) (xy 361.900216 -244.484144) (xy 361.899721 -244.508751)
			(xy 361.891826 -244.557328) (xy 361.876242 -244.604009) (xy 361.853371 -244.647586) (xy 361.823806 -244.68693)
			(xy 361.788313 -244.721022) (xy 361.74781 -244.748978) (xy 361.703348 -244.770076) (xy 361.656077 -244.783768)
			(xy 361.607222 -244.7897) (xy 361.558047 -244.787719) (xy 361.509828 -244.777875) (xy 361.463812 -244.760423)
			(xy 361.421191 -244.735816) (xy 361.38307 -244.704691) (xy 361.350435 -244.667854) (xy 361.324132 -244.626258)
			(xy 361.304841 -244.580982) (xy 361.293064 -244.533198) (xy 361.289104 -244.484144) (xy 358.14635 -244.484144)
			(xy 358.145876 -244.508134) (xy 358.138365 -244.555523) (xy 358.123534 -244.601154) (xy 358.101749 -244.643903)
			(xy 358.073545 -244.68272) (xy 358.039618 -244.716647) (xy 358.000802 -244.74485) (xy 357.958052 -244.766635)
			(xy 357.912421 -244.781465) (xy 357.865032 -244.788976) (xy 357.841042 -244.789452) (xy 357.815342 -244.788918)
			(xy 357.764667 -244.780305) (xy 357.71615 -244.763331) (xy 357.671158 -244.738476) (xy 357.63096 -244.706441)
			(xy 357.596693 -244.668129) (xy 357.569321 -244.624622) (xy 357.549618 -244.577147) (xy 357.543354 -244.552216)
			(xy 357.541576 -244.544596) (xy 357.534464 -244.531896) (xy 357.528622 -244.526562) (xy 357.521183 -244.520114)
			(xy 357.502878 -244.512919) (xy 357.483211 -244.513135) (xy 357.46507 -244.520733) (xy 357.457756 -244.527324)
			(xy 357.450644 -244.534436) (xy 357.443246 -244.541281) (xy 357.424647 -244.549005) (xy 357.414576 -244.549422)
			(xy 357.221536 -244.549422) (xy 357.19512 -244.568218) (xy 357.189786 -244.583712) (xy 357.18107 -244.607381)
			(xy 357.157005 -244.651704) (xy 357.125981 -244.691469) (xy 357.088842 -244.725592) (xy 357.046599 -244.753147)
			(xy 357.000401 -244.773382) (xy 356.951505 -244.785747) (xy 356.901242 -244.789907) (xy 356.850979 -244.785747)
			(xy 356.802083 -244.773382) (xy 356.755885 -244.753147) (xy 356.713642 -244.725592) (xy 356.676503 -244.691469)
			(xy 356.645479 -244.651704) (xy 356.621414 -244.607381) (xy 356.612698 -244.583712) (xy 356.607364 -244.568218)
			(xy 356.580948 -244.549422) (xy 356.281482 -244.549422) (xy 356.255066 -244.568218) (xy 356.249732 -244.583712)
			(xy 356.241016 -244.607381) (xy 356.216951 -244.651704) (xy 356.185927 -244.691469) (xy 356.148788 -244.725592)
			(xy 356.106545 -244.753147) (xy 356.060347 -244.773382) (xy 356.011451 -244.785747) (xy 355.961188 -244.789907)
			(xy 355.910925 -244.785747) (xy 355.862029 -244.773382) (xy 355.815831 -244.753147) (xy 355.773588 -244.725592)
			(xy 355.736449 -244.691469) (xy 355.705425 -244.651704) (xy 355.68136 -244.607381) (xy 355.672644 -244.583712)
			(xy 355.66731 -244.568218) (xy 355.640894 -244.549422) (xy 355.341428 -244.549422) (xy 355.315012 -244.568218)
			(xy 355.309678 -244.583712) (xy 355.300962 -244.607381) (xy 355.276897 -244.651704) (xy 355.245873 -244.691469)
			(xy 355.208734 -244.725592) (xy 355.166491 -244.753147) (xy 355.120293 -244.773382) (xy 355.071397 -244.785747)
			(xy 355.021134 -244.789907) (xy 354.970871 -244.785747) (xy 354.921975 -244.773382) (xy 354.875777 -244.753147)
			(xy 354.833534 -244.725592) (xy 354.796395 -244.691469) (xy 354.765371 -244.651704) (xy 354.741306 -244.607381)
			(xy 354.73259 -244.583712) (xy 354.727256 -244.568218) (xy 354.70084 -244.549422) (xy 354.401374 -244.549422)
			(xy 354.374958 -244.568218) (xy 354.369624 -244.583712) (xy 354.360908 -244.607381) (xy 354.336843 -244.651704)
			(xy 354.305819 -244.691469) (xy 354.26868 -244.725592) (xy 354.226437 -244.753147) (xy 354.180239 -244.773382)
			(xy 354.131343 -244.785747) (xy 354.08108 -244.789907) (xy 354.030817 -244.785747) (xy 353.981921 -244.773382)
			(xy 353.935723 -244.753147) (xy 353.89348 -244.725592) (xy 353.856341 -244.691469) (xy 353.825317 -244.651704)
			(xy 353.801252 -244.607381) (xy 353.792536 -244.583712) (xy 353.787202 -244.568218) (xy 353.760786 -244.549422)
			(xy 353.46132 -244.549422) (xy 353.434904 -244.568218) (xy 353.42957 -244.583712) (xy 353.420854 -244.607381)
			(xy 353.396789 -244.651704) (xy 353.365765 -244.691469) (xy 353.328626 -244.725592) (xy 353.286383 -244.753147)
			(xy 353.240185 -244.773382) (xy 353.191289 -244.785747) (xy 353.141026 -244.789907) (xy 353.090763 -244.785747)
			(xy 353.041867 -244.773382) (xy 352.995669 -244.753147) (xy 352.953426 -244.725592) (xy 352.916287 -244.691469)
			(xy 352.885263 -244.651704) (xy 352.861198 -244.607381) (xy 352.852482 -244.583712) (xy 352.847148 -244.568218)
			(xy 352.820732 -244.549422) (xy 352.52152 -244.549422) (xy 352.495104 -244.568218) (xy 352.48977 -244.583712)
			(xy 352.481054 -244.607381) (xy 352.456989 -244.651704) (xy 352.425965 -244.691469) (xy 352.388826 -244.725592)
			(xy 352.346583 -244.753147) (xy 352.300385 -244.773382) (xy 352.251489 -244.785747) (xy 352.201226 -244.789907)
			(xy 352.150963 -244.785747) (xy 352.102067 -244.773382) (xy 352.055869 -244.753147) (xy 352.013626 -244.725592)
			(xy 351.976487 -244.691469) (xy 351.945463 -244.651704) (xy 351.921398 -244.607381) (xy 351.912682 -244.583712)
			(xy 351.907348 -244.568218) (xy 351.880932 -244.549422) (xy 351.581466 -244.549422) (xy 351.55505 -244.568218)
			(xy 351.549716 -244.583712) (xy 351.541 -244.607381) (xy 351.516935 -244.651704) (xy 351.485911 -244.691469)
			(xy 351.448772 -244.725592) (xy 351.406529 -244.753147) (xy 351.360331 -244.773382) (xy 351.311435 -244.785747)
			(xy 351.261172 -244.789907) (xy 351.210909 -244.785747) (xy 351.162013 -244.773382) (xy 351.115815 -244.753147)
			(xy 351.073572 -244.725592) (xy 351.036433 -244.691469) (xy 351.005409 -244.651704) (xy 350.981344 -244.607381)
			(xy 350.972628 -244.583712) (xy 350.967294 -244.568218) (xy 350.940878 -244.549422) (xy 350.641412 -244.549422)
			(xy 350.614996 -244.568218) (xy 350.609662 -244.583712) (xy 350.600946 -244.607381) (xy 350.576881 -244.651704)
			(xy 350.545857 -244.691469) (xy 350.508718 -244.725592) (xy 350.466475 -244.753147) (xy 350.420277 -244.773382)
			(xy 350.371381 -244.785747) (xy 350.321118 -244.789907) (xy 350.270855 -244.785747) (xy 350.221959 -244.773382)
			(xy 350.175761 -244.753147) (xy 350.133518 -244.725592) (xy 350.096379 -244.691469) (xy 350.065355 -244.651704)
			(xy 350.04129 -244.607381) (xy 350.032574 -244.583712) (xy 350.02724 -244.568218) (xy 350.000824 -244.549422)
			(xy 349.701358 -244.549422) (xy 349.674942 -244.568218) (xy 349.669608 -244.583712) (xy 349.660892 -244.607381)
			(xy 349.636827 -244.651704) (xy 349.605803 -244.691469) (xy 349.568664 -244.725592) (xy 349.526421 -244.753147)
			(xy 349.480223 -244.773382) (xy 349.431327 -244.785747) (xy 349.381064 -244.789907) (xy 349.330801 -244.785747)
			(xy 349.281905 -244.773382) (xy 349.235707 -244.753147) (xy 349.193464 -244.725592) (xy 349.156325 -244.691469)
			(xy 349.125301 -244.651704) (xy 349.101236 -244.607381) (xy 349.09252 -244.583712) (xy 349.087186 -244.568218)
			(xy 349.06077 -244.549422) (xy 348.761304 -244.549422) (xy 348.734888 -244.568218) (xy 348.729554 -244.583712)
			(xy 348.720838 -244.607381) (xy 348.696773 -244.651704) (xy 348.665749 -244.691469) (xy 348.62861 -244.725592)
			(xy 348.586367 -244.753147) (xy 348.540169 -244.773382) (xy 348.491273 -244.785747) (xy 348.44101 -244.789907)
			(xy 348.390747 -244.785747) (xy 348.341851 -244.773382) (xy 348.295653 -244.753147) (xy 348.25341 -244.725592)
			(xy 348.216271 -244.691469) (xy 348.185247 -244.651704) (xy 348.161182 -244.607381) (xy 348.152466 -244.583712)
			(xy 348.147132 -244.568218) (xy 348.120716 -244.549422) (xy 347.821504 -244.549422) (xy 347.795088 -244.568218)
			(xy 347.789754 -244.583712) (xy 347.781038 -244.607381) (xy 347.756973 -244.651704) (xy 347.725949 -244.691469)
			(xy 347.68881 -244.725592) (xy 347.646567 -244.753147) (xy 347.600369 -244.773382) (xy 347.551473 -244.785747)
			(xy 347.50121 -244.789907) (xy 347.450947 -244.785747) (xy 347.402051 -244.773382) (xy 347.355853 -244.753147)
			(xy 347.31361 -244.725592) (xy 347.276471 -244.691469) (xy 347.245447 -244.651704) (xy 347.221382 -244.607381)
			(xy 347.212666 -244.583712) (xy 347.207332 -244.568218) (xy 347.180916 -244.549422) (xy 346.88145 -244.549422)
			(xy 346.855034 -244.568218) (xy 346.8497 -244.583712) (xy 346.840984 -244.607381) (xy 346.816919 -244.651704)
			(xy 346.785895 -244.691469) (xy 346.748756 -244.725592) (xy 346.706513 -244.753147) (xy 346.660315 -244.773382)
			(xy 346.611419 -244.785747) (xy 346.561156 -244.789907) (xy 346.510893 -244.785747) (xy 346.461997 -244.773382)
			(xy 346.415799 -244.753147) (xy 346.373556 -244.725592) (xy 346.336417 -244.691469) (xy 346.305393 -244.651704)
			(xy 346.281328 -244.607381) (xy 346.272612 -244.583712) (xy 346.267278 -244.568218) (xy 346.240862 -244.549422)
			(xy 345.941396 -244.549422) (xy 345.91498 -244.568218) (xy 345.909646 -244.583712) (xy 345.901511 -244.605915)
			(xy 345.879374 -244.647697) (xy 345.851063 -244.68557) (xy 345.817255 -244.718628) (xy 345.778757 -244.746082)
			(xy 345.736488 -244.767275) (xy 345.691459 -244.781703) (xy 345.644744 -244.78902) (xy 345.621102 -244.789452)
			(xy 345.595184 -244.788904) (xy 345.544093 -244.780149) (xy 345.495214 -244.762891) (xy 345.449952 -244.737626)
			(xy 345.409608 -244.705078) (xy 345.375341 -244.666185) (xy 345.36126 -244.644418) (xy 345.35491 -244.634258)
			(xy 345.335606 -244.622066) (xy 345.244928 -244.611144) (xy 345.234366 -244.610316) (xy 345.214122 -244.616508)
			(xy 345.205812 -244.623082) (xy 345.204288 -244.624352) (xy 344.858086 -244.970554) (xy 344.851239 -244.977951)
			(xy 344.843511 -244.996551) (xy 344.8431 -245.006622) (xy 344.8431 -245.29415) (xy 346.725252 -245.29415)
			(xy 346.729212 -245.245096) (xy 346.740989 -245.197312) (xy 346.76028 -245.152036) (xy 346.786583 -245.11044)
			(xy 346.819218 -245.073603) (xy 346.857339 -245.042478) (xy 346.89996 -245.017871) (xy 346.945976 -245.000419)
			(xy 346.994195 -244.990575) (xy 347.04337 -244.988594) (xy 347.092225 -244.994526) (xy 347.139496 -245.008218)
			(xy 347.183958 -245.029316) (xy 347.224461 -245.057272) (xy 347.259954 -245.091364) (xy 347.289519 -245.130708)
			(xy 347.31239 -245.174285) (xy 347.327974 -245.220966) (xy 347.335869 -245.269543) (xy 347.336364 -245.29415)
			(xy 349.545414 -245.29415) (xy 349.549374 -245.245096) (xy 349.561151 -245.197312) (xy 349.580442 -245.152036)
			(xy 349.606745 -245.11044) (xy 349.63938 -245.073603) (xy 349.677501 -245.042478) (xy 349.720122 -245.017871)
			(xy 349.766138 -245.000419) (xy 349.814357 -244.990575) (xy 349.863532 -244.988594) (xy 349.912387 -244.994526)
			(xy 349.959658 -245.008218) (xy 350.00412 -245.029316) (xy 350.044623 -245.057272) (xy 350.080116 -245.091364)
			(xy 350.109681 -245.130708) (xy 350.132552 -245.174285) (xy 350.148136 -245.220966) (xy 350.156031 -245.269543)
			(xy 350.156526 -245.29415) (xy 352.365322 -245.29415) (xy 352.369282 -245.245096) (xy 352.381059 -245.197312)
			(xy 352.40035 -245.152036) (xy 352.426653 -245.11044) (xy 352.459288 -245.073603) (xy 352.497409 -245.042478)
			(xy 352.54003 -245.017871) (xy 352.586046 -245.000419) (xy 352.634265 -244.990575) (xy 352.68344 -244.988594)
			(xy 352.732295 -244.994526) (xy 352.779566 -245.008218) (xy 352.824028 -245.029316) (xy 352.864531 -245.057272)
			(xy 352.900024 -245.091364) (xy 352.929589 -245.130708) (xy 352.95246 -245.174285) (xy 352.968044 -245.220966)
			(xy 352.975939 -245.269543) (xy 352.976434 -245.29415) (xy 355.18523 -245.29415) (xy 355.18919 -245.245096)
			(xy 355.200967 -245.197312) (xy 355.220258 -245.152036) (xy 355.246561 -245.11044) (xy 355.279196 -245.073603)
			(xy 355.317317 -245.042478) (xy 355.359938 -245.017871) (xy 355.405954 -245.000419) (xy 355.454173 -244.990575)
			(xy 355.503348 -244.988594) (xy 355.552203 -244.994526) (xy 355.599474 -245.008218) (xy 355.643936 -245.029316)
			(xy 355.684439 -245.057272) (xy 355.719932 -245.091364) (xy 355.749497 -245.130708) (xy 355.772368 -245.174285)
			(xy 355.787952 -245.220966) (xy 355.795847 -245.269543) (xy 355.796342 -245.29415) (xy 356.125284 -245.29415)
			(xy 356.129244 -245.245096) (xy 356.141021 -245.197312) (xy 356.160312 -245.152036) (xy 356.186615 -245.11044)
			(xy 356.21925 -245.073603) (xy 356.257371 -245.042478) (xy 356.299992 -245.017871) (xy 356.346008 -245.000419)
			(xy 356.394227 -244.990575) (xy 356.443402 -244.988594) (xy 356.492257 -244.994526) (xy 356.539528 -245.008218)
			(xy 356.58399 -245.029316) (xy 356.624493 -245.057272) (xy 356.659986 -245.091364) (xy 356.689551 -245.130708)
			(xy 356.712422 -245.174285) (xy 356.728006 -245.220966) (xy 356.735901 -245.269543) (xy 356.736396 -245.29415)
			(xy 357.065338 -245.29415) (xy 357.069298 -245.245096) (xy 357.081075 -245.197312) (xy 357.100366 -245.152036)
			(xy 357.126669 -245.11044) (xy 357.159304 -245.073603) (xy 357.197425 -245.042478) (xy 357.240046 -245.017871)
			(xy 357.286062 -245.000419) (xy 357.334281 -244.990575) (xy 357.383456 -244.988594) (xy 357.432311 -244.994526)
			(xy 357.479582 -245.008218) (xy 357.524044 -245.029316) (xy 357.564547 -245.057272) (xy 357.60004 -245.091364)
			(xy 357.629605 -245.130708) (xy 357.652476 -245.174285) (xy 357.66806 -245.220966) (xy 357.675955 -245.269543)
			(xy 357.67645 -245.29415) (xy 358.005392 -245.29415) (xy 358.009352 -245.245096) (xy 358.021129 -245.197312)
			(xy 358.04042 -245.152036) (xy 358.066723 -245.11044) (xy 358.099358 -245.073603) (xy 358.137479 -245.042478)
			(xy 358.1801 -245.017871) (xy 358.226116 -245.000419) (xy 358.274335 -244.990575) (xy 358.32351 -244.988594)
			(xy 358.372365 -244.994526) (xy 358.419636 -245.008218) (xy 358.464098 -245.029316) (xy 358.504601 -245.057272)
			(xy 358.540094 -245.091364) (xy 358.569659 -245.130708) (xy 358.59253 -245.174285) (xy 358.608114 -245.220966)
			(xy 358.616009 -245.269543) (xy 358.616504 -245.29415) (xy 358.616009 -245.318757) (xy 358.608114 -245.367334)
			(xy 358.59253 -245.414015) (xy 358.569659 -245.457592) (xy 358.540094 -245.496936) (xy 358.504601 -245.531028)
			(xy 358.474274 -245.55196) (xy 359.396541 -245.55196) (xy 359.400571 -245.499462) (xy 359.412568 -245.448194)
			(xy 359.432251 -245.399359) (xy 359.459157 -245.3541) (xy 359.492657 -245.313479) (xy 359.531965 -245.278448)
			(xy 359.57616 -245.249828) (xy 359.624205 -245.228289) (xy 359.674976 -245.214337) (xy 359.727281 -245.208299)
			(xy 359.779895 -245.210316) (xy 359.831585 -245.22034) (xy 359.881138 -245.238138) (xy 359.927394 -245.263291)
			(xy 359.967877 -245.29415) (xy 360.81895 -245.29415) (xy 360.82291 -245.245096) (xy 360.834687 -245.197312)
			(xy 360.853978 -245.152036) (xy 360.880281 -245.11044) (xy 360.912916 -245.073603) (xy 360.951037 -245.042478)
			(xy 360.993658 -245.017871) (xy 361.039674 -245.000419) (xy 361.087893 -244.990575) (xy 361.137068 -244.988594)
			(xy 361.185923 -244.994526) (xy 361.233194 -245.008218) (xy 361.277656 -245.029316) (xy 361.318159 -245.057272)
			(xy 361.353652 -245.091364) (xy 361.383217 -245.130708) (xy 361.406088 -245.174285) (xy 361.421672 -245.220966)
			(xy 361.429567 -245.269543) (xy 361.430062 -245.29415) (xy 361.748573 -245.29415) (xy 361.752668 -245.243422)
			(xy 361.764847 -245.194008) (xy 361.784795 -245.147188) (xy 361.811996 -245.104174) (xy 361.845744 -245.06608)
			(xy 361.885166 -245.033893) (xy 361.92924 -245.008447) (xy 361.976826 -244.9904) (xy 362.02669 -244.98022)
			(xy 362.077542 -244.978171) (xy 362.128063 -244.984305) (xy 362.176947 -244.998465) (xy 362.222926 -245.020282)
			(xy 362.26481 -245.049192) (xy 362.301514 -245.084447) (xy 362.332087 -245.125133) (xy 362.355738 -245.170196)
			(xy 362.371854 -245.21847) (xy 362.380018 -245.268704) (xy 362.38053 -245.29415) (xy 362.688627 -245.29415)
			(xy 362.692722 -245.243422) (xy 362.704901 -245.194008) (xy 362.724849 -245.147188) (xy 362.75205 -245.104174)
			(xy 362.785798 -245.06608) (xy 362.82522 -245.033893) (xy 362.869294 -245.008447) (xy 362.91688 -244.9904)
			(xy 362.966744 -244.98022) (xy 363.017596 -244.978171) (xy 363.068117 -244.984305) (xy 363.117001 -244.998465)
			(xy 363.16298 -245.020282) (xy 363.204864 -245.049192) (xy 363.241568 -245.084447) (xy 363.272141 -245.125133)
			(xy 363.295792 -245.170196) (xy 363.311908 -245.21847) (xy 363.320072 -245.268704) (xy 363.320584 -245.29415)
			(xy 363.639112 -245.29415) (xy 363.643072 -245.245096) (xy 363.654849 -245.197312) (xy 363.67414 -245.152036)
			(xy 363.700443 -245.11044) (xy 363.733078 -245.073603) (xy 363.771199 -245.042478) (xy 363.81382 -245.017871)
			(xy 363.859836 -245.000419) (xy 363.908055 -244.990575) (xy 363.95723 -244.988594) (xy 364.006085 -244.994526)
			(xy 364.053356 -245.008218) (xy 364.097818 -245.029316) (xy 364.138321 -245.057272) (xy 364.173814 -245.091364)
			(xy 364.203379 -245.130708) (xy 364.22625 -245.174285) (xy 364.241834 -245.220966) (xy 364.249729 -245.269543)
			(xy 364.250224 -245.29415) (xy 366.45902 -245.29415) (xy 366.46298 -245.245096) (xy 366.474757 -245.197312)
			(xy 366.494048 -245.152036) (xy 366.520351 -245.11044) (xy 366.552986 -245.073603) (xy 366.591107 -245.042478)
			(xy 366.633728 -245.017871) (xy 366.679744 -245.000419) (xy 366.727963 -244.990575) (xy 366.777138 -244.988594)
			(xy 366.825993 -244.994526) (xy 366.873264 -245.008218) (xy 366.917726 -245.029316) (xy 366.958229 -245.057272)
			(xy 366.993722 -245.091364) (xy 367.023287 -245.130708) (xy 367.046158 -245.174285) (xy 367.061742 -245.220966)
			(xy 367.069637 -245.269543) (xy 367.070132 -245.29415) (xy 369.278928 -245.29415) (xy 369.282888 -245.245096)
			(xy 369.294665 -245.197312) (xy 369.313956 -245.152036) (xy 369.340259 -245.11044) (xy 369.372894 -245.073603)
			(xy 369.411015 -245.042478) (xy 369.453636 -245.017871) (xy 369.499652 -245.000419) (xy 369.547871 -244.990575)
			(xy 369.597046 -244.988594) (xy 369.645901 -244.994526) (xy 369.693172 -245.008218) (xy 369.737634 -245.029316)
			(xy 369.778137 -245.057272) (xy 369.81363 -245.091364) (xy 369.843195 -245.130708) (xy 369.866066 -245.174285)
			(xy 369.88165 -245.220966) (xy 369.889545 -245.269543) (xy 369.89004 -245.29415) (xy 372.09909 -245.29415)
			(xy 372.10305 -245.245096) (xy 372.114827 -245.197312) (xy 372.134118 -245.152036) (xy 372.160421 -245.11044)
			(xy 372.193056 -245.073603) (xy 372.231177 -245.042478) (xy 372.273798 -245.017871) (xy 372.319814 -245.000419)
			(xy 372.368033 -244.990575) (xy 372.417208 -244.988594) (xy 372.466063 -244.994526) (xy 372.513334 -245.008218)
			(xy 372.557796 -245.029316) (xy 372.598299 -245.057272) (xy 372.633792 -245.091364) (xy 372.663357 -245.130708)
			(xy 372.686228 -245.174285) (xy 372.701812 -245.220966) (xy 372.709707 -245.269543) (xy 372.710202 -245.29415)
			(xy 372.709707 -245.318757) (xy 372.701812 -245.367334) (xy 372.686228 -245.414015) (xy 372.663357 -245.457592)
			(xy 372.633792 -245.496936) (xy 372.598299 -245.531028) (xy 372.557796 -245.558984) (xy 372.513334 -245.580082)
			(xy 372.466063 -245.593774) (xy 372.417208 -245.599706) (xy 372.368033 -245.597725) (xy 372.319814 -245.587881)
			(xy 372.273798 -245.570429) (xy 372.231177 -245.545822) (xy 372.193056 -245.514697) (xy 372.160421 -245.47786)
			(xy 372.134118 -245.436264) (xy 372.114827 -245.390988) (xy 372.10305 -245.343204) (xy 372.09909 -245.29415)
			(xy 369.89004 -245.29415) (xy 369.889545 -245.318757) (xy 369.88165 -245.367334) (xy 369.866066 -245.414015)
			(xy 369.843195 -245.457592) (xy 369.81363 -245.496936) (xy 369.778137 -245.531028) (xy 369.737634 -245.558984)
			(xy 369.693172 -245.580082) (xy 369.645901 -245.593774) (xy 369.597046 -245.599706) (xy 369.547871 -245.597725)
			(xy 369.499652 -245.587881) (xy 369.453636 -245.570429) (xy 369.411015 -245.545822) (xy 369.372894 -245.514697)
			(xy 369.340259 -245.47786) (xy 369.313956 -245.436264) (xy 369.294665 -245.390988) (xy 369.282888 -245.343204)
			(xy 369.278928 -245.29415) (xy 367.070132 -245.29415) (xy 367.069637 -245.318757) (xy 367.061742 -245.367334)
			(xy 367.046158 -245.414015) (xy 367.023287 -245.457592) (xy 366.993722 -245.496936) (xy 366.958229 -245.531028)
			(xy 366.917726 -245.558984) (xy 366.873264 -245.580082) (xy 366.825993 -245.593774) (xy 366.777138 -245.599706)
			(xy 366.727963 -245.597725) (xy 366.679744 -245.587881) (xy 366.633728 -245.570429) (xy 366.591107 -245.545822)
			(xy 366.552986 -245.514697) (xy 366.520351 -245.47786) (xy 366.494048 -245.436264) (xy 366.474757 -245.390988)
			(xy 366.46298 -245.343204) (xy 366.45902 -245.29415) (xy 364.250224 -245.29415) (xy 364.249729 -245.318757)
			(xy 364.241834 -245.367334) (xy 364.22625 -245.414015) (xy 364.203379 -245.457592) (xy 364.173814 -245.496936)
			(xy 364.138321 -245.531028) (xy 364.097818 -245.558984) (xy 364.053356 -245.580082) (xy 364.006085 -245.593774)
			(xy 363.95723 -245.599706) (xy 363.908055 -245.597725) (xy 363.859836 -245.587881) (xy 363.81382 -245.570429)
			(xy 363.771199 -245.545822) (xy 363.733078 -245.514697) (xy 363.700443 -245.47786) (xy 363.67414 -245.436264)
			(xy 363.654849 -245.390988) (xy 363.643072 -245.343204) (xy 363.639112 -245.29415) (xy 363.320584 -245.29415)
			(xy 363.320072 -245.319596) (xy 363.311908 -245.36983) (xy 363.295792 -245.418104) (xy 363.272141 -245.463167)
			(xy 363.241568 -245.503853) (xy 363.204864 -245.539108) (xy 363.16298 -245.568018) (xy 363.117001 -245.589835)
			(xy 363.068117 -245.603995) (xy 363.017596 -245.610129) (xy 362.966744 -245.60808) (xy 362.91688 -245.5979)
			(xy 362.869294 -245.579853) (xy 362.82522 -245.554407) (xy 362.785798 -245.52222) (xy 362.75205 -245.484126)
			(xy 362.724849 -245.441112) (xy 362.704901 -245.394292) (xy 362.692722 -245.344878) (xy 362.688627 -245.29415)
			(xy 362.38053 -245.29415) (xy 362.380018 -245.319596) (xy 362.371854 -245.36983) (xy 362.355738 -245.418104)
			(xy 362.332087 -245.463167) (xy 362.301514 -245.503853) (xy 362.26481 -245.539108) (xy 362.222926 -245.568018)
			(xy 362.176947 -245.589835) (xy 362.128063 -245.603995) (xy 362.077542 -245.610129) (xy 362.02669 -245.60808)
			(xy 361.976826 -245.5979) (xy 361.92924 -245.579853) (xy 361.885166 -245.554407) (xy 361.845744 -245.52222)
			(xy 361.811996 -245.484126) (xy 361.784795 -245.441112) (xy 361.764847 -245.394292) (xy 361.752668 -245.344878)
			(xy 361.748573 -245.29415) (xy 361.430062 -245.29415) (xy 361.429567 -245.318757) (xy 361.421672 -245.367334)
			(xy 361.406088 -245.414015) (xy 361.383217 -245.457592) (xy 361.353652 -245.496936) (xy 361.318159 -245.531028)
			(xy 361.277656 -245.558984) (xy 361.233194 -245.580082) (xy 361.185923 -245.593774) (xy 361.137068 -245.599706)
			(xy 361.087893 -245.597725) (xy 361.039674 -245.587881) (xy 360.993658 -245.570429) (xy 360.951037 -245.545822)
			(xy 360.912916 -245.514697) (xy 360.880281 -245.47786) (xy 360.853978 -245.436264) (xy 360.834687 -245.390988)
			(xy 360.82291 -245.343204) (xy 360.81895 -245.29415) (xy 359.967877 -245.29415) (xy 359.969268 -245.29521)
			(xy 360.00578 -245.333148) (xy 360.036072 -245.376214) (xy 360.059435 -245.423399) (xy 360.075321 -245.473598)
			(xy 360.083358 -245.525634) (xy 360.083862 -245.55196) (xy 360.083358 -245.578286) (xy 360.075321 -245.630322)
			(xy 360.059435 -245.680521) (xy 360.036072 -245.727706) (xy 360.00578 -245.770772) (xy 359.969268 -245.80871)
			(xy 359.927394 -245.840629) (xy 359.881138 -245.865782) (xy 359.831585 -245.88358) (xy 359.779895 -245.893604)
			(xy 359.727281 -245.895621) (xy 359.674976 -245.889583) (xy 359.624205 -245.875631) (xy 359.57616 -245.854092)
			(xy 359.531965 -245.825472) (xy 359.492657 -245.790441) (xy 359.459157 -245.74982) (xy 359.432251 -245.704561)
			(xy 359.412568 -245.655726) (xy 359.400571 -245.604458) (xy 359.396541 -245.55196) (xy 358.474274 -245.55196)
			(xy 358.464098 -245.558984) (xy 358.419636 -245.580082) (xy 358.372365 -245.593774) (xy 358.32351 -245.599706)
			(xy 358.274335 -245.597725) (xy 358.226116 -245.587881) (xy 358.1801 -245.570429) (xy 358.137479 -245.545822)
			(xy 358.099358 -245.514697) (xy 358.066723 -245.47786) (xy 358.04042 -245.436264) (xy 358.021129 -245.390988)
			(xy 358.009352 -245.343204) (xy 358.005392 -245.29415) (xy 357.67645 -245.29415) (xy 357.675955 -245.318757)
			(xy 357.66806 -245.367334) (xy 357.652476 -245.414015) (xy 357.629605 -245.457592) (xy 357.60004 -245.496936)
			(xy 357.564547 -245.531028) (xy 357.524044 -245.558984) (xy 357.479582 -245.580082) (xy 357.432311 -245.593774)
			(xy 357.383456 -245.599706) (xy 357.334281 -245.597725) (xy 357.286062 -245.587881) (xy 357.240046 -245.570429)
			(xy 357.197425 -245.545822) (xy 357.159304 -245.514697) (xy 357.126669 -245.47786) (xy 357.100366 -245.436264)
			(xy 357.081075 -245.390988) (xy 357.069298 -245.343204) (xy 357.065338 -245.29415) (xy 356.736396 -245.29415)
			(xy 356.735901 -245.318757) (xy 356.728006 -245.367334) (xy 356.712422 -245.414015) (xy 356.689551 -245.457592)
			(xy 356.659986 -245.496936) (xy 356.624493 -245.531028) (xy 356.58399 -245.558984) (xy 356.539528 -245.580082)
			(xy 356.492257 -245.593774) (xy 356.443402 -245.599706) (xy 356.394227 -245.597725) (xy 356.346008 -245.587881)
			(xy 356.299992 -245.570429) (xy 356.257371 -245.545822) (xy 356.21925 -245.514697) (xy 356.186615 -245.47786)
			(xy 356.160312 -245.436264) (xy 356.141021 -245.390988) (xy 356.129244 -245.343204) (xy 356.125284 -245.29415)
			(xy 355.796342 -245.29415) (xy 355.795847 -245.318757) (xy 355.787952 -245.367334) (xy 355.772368 -245.414015)
			(xy 355.749497 -245.457592) (xy 355.719932 -245.496936) (xy 355.684439 -245.531028) (xy 355.643936 -245.558984)
			(xy 355.599474 -245.580082) (xy 355.552203 -245.593774) (xy 355.503348 -245.599706) (xy 355.454173 -245.597725)
			(xy 355.405954 -245.587881) (xy 355.359938 -245.570429) (xy 355.317317 -245.545822) (xy 355.279196 -245.514697)
			(xy 355.246561 -245.47786) (xy 355.220258 -245.436264) (xy 355.200967 -245.390988) (xy 355.18919 -245.343204)
			(xy 355.18523 -245.29415) (xy 352.976434 -245.29415) (xy 352.975939 -245.318757) (xy 352.968044 -245.367334)
			(xy 352.95246 -245.414015) (xy 352.929589 -245.457592) (xy 352.900024 -245.496936) (xy 352.864531 -245.531028)
			(xy 352.824028 -245.558984) (xy 352.779566 -245.580082) (xy 352.732295 -245.593774) (xy 352.68344 -245.599706)
			(xy 352.634265 -245.597725) (xy 352.586046 -245.587881) (xy 352.54003 -245.570429) (xy 352.497409 -245.545822)
			(xy 352.459288 -245.514697) (xy 352.426653 -245.47786) (xy 352.40035 -245.436264) (xy 352.381059 -245.390988)
			(xy 352.369282 -245.343204) (xy 352.365322 -245.29415) (xy 350.156526 -245.29415) (xy 350.156031 -245.318757)
			(xy 350.148136 -245.367334) (xy 350.132552 -245.414015) (xy 350.109681 -245.457592) (xy 350.080116 -245.496936)
			(xy 350.044623 -245.531028) (xy 350.00412 -245.558984) (xy 349.959658 -245.580082) (xy 349.912387 -245.593774)
			(xy 349.863532 -245.599706) (xy 349.814357 -245.597725) (xy 349.766138 -245.587881) (xy 349.720122 -245.570429)
			(xy 349.677501 -245.545822) (xy 349.63938 -245.514697) (xy 349.606745 -245.47786) (xy 349.580442 -245.436264)
			(xy 349.561151 -245.390988) (xy 349.549374 -245.343204) (xy 349.545414 -245.29415) (xy 347.336364 -245.29415)
			(xy 347.335869 -245.318757) (xy 347.327974 -245.367334) (xy 347.31239 -245.414015) (xy 347.289519 -245.457592)
			(xy 347.259954 -245.496936) (xy 347.224461 -245.531028) (xy 347.183958 -245.558984) (xy 347.139496 -245.580082)
			(xy 347.092225 -245.593774) (xy 347.04337 -245.599706) (xy 346.994195 -245.597725) (xy 346.945976 -245.587881)
			(xy 346.89996 -245.570429) (xy 346.857339 -245.545822) (xy 346.819218 -245.514697) (xy 346.786583 -245.47786)
			(xy 346.76028 -245.436264) (xy 346.740989 -245.390988) (xy 346.729212 -245.343204) (xy 346.725252 -245.29415)
			(xy 344.8431 -245.29415) (xy 344.8431 -245.80088) (xy 344.84437 -245.81231) (xy 344.848434 -245.829074)
			(xy 344.848434 -245.829328) (xy 344.860372 -245.853712) (xy 344.86723 -245.862094) (xy 344.871802 -245.86565)
			(xy 344.890929 -245.881592) (xy 344.924236 -245.918601) (xy 344.951103 -245.960519) (xy 344.97082 -246.006238)
			(xy 344.982864 -246.054548) (xy 344.986917 -246.104156) (xy 345.315298 -246.104156) (xy 345.319258 -246.055102)
			(xy 345.331035 -246.007318) (xy 345.350326 -245.962042) (xy 345.376629 -245.920446) (xy 345.409264 -245.883609)
			(xy 345.447385 -245.852484) (xy 345.490006 -245.827877) (xy 345.536022 -245.810425) (xy 345.584241 -245.800581)
			(xy 345.633416 -245.7986) (xy 345.682271 -245.804532) (xy 345.729542 -245.818224) (xy 345.774004 -245.839322)
			(xy 345.814507 -245.867278) (xy 345.85 -245.90137) (xy 345.879565 -245.940714) (xy 345.902436 -245.984291)
			(xy 345.91802 -246.030972) (xy 345.925915 -246.079549) (xy 345.92641 -246.104156) (xy 346.255352 -246.104156)
			(xy 346.259312 -246.055102) (xy 346.271089 -246.007318) (xy 346.29038 -245.962042) (xy 346.316683 -245.920446)
			(xy 346.349318 -245.883609) (xy 346.387439 -245.852484) (xy 346.43006 -245.827877) (xy 346.476076 -245.810425)
			(xy 346.524295 -245.800581) (xy 346.57347 -245.7986) (xy 346.622325 -245.804532) (xy 346.669596 -245.818224)
			(xy 346.714058 -245.839322) (xy 346.754561 -245.867278) (xy 346.790054 -245.90137) (xy 346.819619 -245.940714)
			(xy 346.84249 -245.984291) (xy 346.858074 -246.030972) (xy 346.865969 -246.079549) (xy 346.866464 -246.104156)
			(xy 347.195406 -246.104156) (xy 347.199366 -246.055102) (xy 347.211143 -246.007318) (xy 347.230434 -245.962042)
			(xy 347.256737 -245.920446) (xy 347.289372 -245.883609) (xy 347.327493 -245.852484) (xy 347.370114 -245.827877)
			(xy 347.41613 -245.810425) (xy 347.464349 -245.800581) (xy 347.513524 -245.7986) (xy 347.562379 -245.804532)
			(xy 347.60965 -245.818224) (xy 347.654112 -245.839322) (xy 347.694615 -245.867278) (xy 347.730108 -245.90137)
			(xy 347.759673 -245.940714) (xy 347.782544 -245.984291) (xy 347.798128 -246.030972) (xy 347.806023 -246.079549)
			(xy 347.806518 -246.104156) (xy 348.135206 -246.104156) (xy 348.139166 -246.055102) (xy 348.150943 -246.007318)
			(xy 348.170234 -245.962042) (xy 348.196537 -245.920446) (xy 348.229172 -245.883609) (xy 348.267293 -245.852484)
			(xy 348.309914 -245.827877) (xy 348.35593 -245.810425) (xy 348.404149 -245.800581) (xy 348.453324 -245.7986)
			(xy 348.502179 -245.804532) (xy 348.54945 -245.818224) (xy 348.593912 -245.839322) (xy 348.634415 -245.867278)
			(xy 348.669908 -245.90137) (xy 348.699473 -245.940714) (xy 348.722344 -245.984291) (xy 348.737928 -246.030972)
			(xy 348.745823 -246.079549) (xy 348.746318 -246.104156) (xy 349.07526 -246.104156) (xy 349.07922 -246.055102)
			(xy 349.090997 -246.007318) (xy 349.110288 -245.962042) (xy 349.136591 -245.920446) (xy 349.169226 -245.883609)
			(xy 349.207347 -245.852484) (xy 349.249968 -245.827877) (xy 349.295984 -245.810425) (xy 349.344203 -245.800581)
			(xy 349.393378 -245.7986) (xy 349.442233 -245.804532) (xy 349.489504 -245.818224) (xy 349.533966 -245.839322)
			(xy 349.574469 -245.867278) (xy 349.609962 -245.90137) (xy 349.639527 -245.940714) (xy 349.662398 -245.984291)
			(xy 349.677982 -246.030972) (xy 349.685877 -246.079549) (xy 349.686372 -246.104156) (xy 350.015314 -246.104156)
			(xy 350.019274 -246.055102) (xy 350.031051 -246.007318) (xy 350.050342 -245.962042) (xy 350.076645 -245.920446)
			(xy 350.10928 -245.883609) (xy 350.147401 -245.852484) (xy 350.190022 -245.827877) (xy 350.236038 -245.810425)
			(xy 350.284257 -245.800581) (xy 350.333432 -245.7986) (xy 350.382287 -245.804532) (xy 350.429558 -245.818224)
			(xy 350.47402 -245.839322) (xy 350.514523 -245.867278) (xy 350.550016 -245.90137) (xy 350.579581 -245.940714)
			(xy 350.602452 -245.984291) (xy 350.618036 -246.030972) (xy 350.625931 -246.079549) (xy 350.626426 -246.104156)
			(xy 350.955368 -246.104156) (xy 350.959328 -246.055102) (xy 350.971105 -246.007318) (xy 350.990396 -245.962042)
			(xy 351.016699 -245.920446) (xy 351.049334 -245.883609) (xy 351.087455 -245.852484) (xy 351.130076 -245.827877)
			(xy 351.176092 -245.810425) (xy 351.224311 -245.800581) (xy 351.273486 -245.7986) (xy 351.322341 -245.804532)
			(xy 351.369612 -245.818224) (xy 351.414074 -245.839322) (xy 351.454577 -245.867278) (xy 351.49007 -245.90137)
			(xy 351.519635 -245.940714) (xy 351.542506 -245.984291) (xy 351.55809 -246.030972) (xy 351.565985 -246.079549)
			(xy 351.56648 -246.104156) (xy 351.895422 -246.104156) (xy 351.899382 -246.055102) (xy 351.911159 -246.007318)
			(xy 351.93045 -245.962042) (xy 351.956753 -245.920446) (xy 351.989388 -245.883609) (xy 352.027509 -245.852484)
			(xy 352.07013 -245.827877) (xy 352.116146 -245.810425) (xy 352.164365 -245.800581) (xy 352.21354 -245.7986)
			(xy 352.262395 -245.804532) (xy 352.309666 -245.818224) (xy 352.354128 -245.839322) (xy 352.394631 -245.867278)
			(xy 352.430124 -245.90137) (xy 352.459689 -245.940714) (xy 352.48256 -245.984291) (xy 352.498144 -246.030972)
			(xy 352.506039 -246.079549) (xy 352.506534 -246.104156) (xy 352.835222 -246.104156) (xy 352.839182 -246.055102)
			(xy 352.850959 -246.007318) (xy 352.87025 -245.962042) (xy 352.896553 -245.920446) (xy 352.929188 -245.883609)
			(xy 352.967309 -245.852484) (xy 353.00993 -245.827877) (xy 353.055946 -245.810425) (xy 353.104165 -245.800581)
			(xy 353.15334 -245.7986) (xy 353.202195 -245.804532) (xy 353.249466 -245.818224) (xy 353.293928 -245.839322)
			(xy 353.334431 -245.867278) (xy 353.369924 -245.90137) (xy 353.399489 -245.940714) (xy 353.42236 -245.984291)
			(xy 353.437944 -246.030972) (xy 353.445839 -246.079549) (xy 353.446334 -246.104156) (xy 353.775276 -246.104156)
			(xy 353.779236 -246.055102) (xy 353.791013 -246.007318) (xy 353.810304 -245.962042) (xy 353.836607 -245.920446)
			(xy 353.869242 -245.883609) (xy 353.907363 -245.852484) (xy 353.949984 -245.827877) (xy 353.996 -245.810425)
			(xy 354.044219 -245.800581) (xy 354.093394 -245.7986) (xy 354.142249 -245.804532) (xy 354.18952 -245.818224)
			(xy 354.233982 -245.839322) (xy 354.274485 -245.867278) (xy 354.309978 -245.90137) (xy 354.339543 -245.940714)
			(xy 354.362414 -245.984291) (xy 354.377998 -246.030972) (xy 354.385893 -246.079549) (xy 354.386388 -246.104156)
			(xy 354.71533 -246.104156) (xy 354.71929 -246.055102) (xy 354.731067 -246.007318) (xy 354.750358 -245.962042)
			(xy 354.776661 -245.920446) (xy 354.809296 -245.883609) (xy 354.847417 -245.852484) (xy 354.890038 -245.827877)
			(xy 354.936054 -245.810425) (xy 354.984273 -245.800581) (xy 355.033448 -245.7986) (xy 355.082303 -245.804532)
			(xy 355.129574 -245.818224) (xy 355.174036 -245.839322) (xy 355.214539 -245.867278) (xy 355.250032 -245.90137)
			(xy 355.279597 -245.940714) (xy 355.302468 -245.984291) (xy 355.318052 -246.030972) (xy 355.325947 -246.079549)
			(xy 355.326442 -246.104156) (xy 355.655384 -246.104156) (xy 355.659344 -246.055102) (xy 355.671121 -246.007318)
			(xy 355.690412 -245.962042) (xy 355.716715 -245.920446) (xy 355.74935 -245.883609) (xy 355.787471 -245.852484)
			(xy 355.830092 -245.827877) (xy 355.876108 -245.810425) (xy 355.924327 -245.800581) (xy 355.973502 -245.7986)
			(xy 356.022357 -245.804532) (xy 356.069628 -245.818224) (xy 356.11409 -245.839322) (xy 356.154593 -245.867278)
			(xy 356.190086 -245.90137) (xy 356.219651 -245.940714) (xy 356.242522 -245.984291) (xy 356.258106 -246.030972)
			(xy 356.266001 -246.079549) (xy 356.266496 -246.104156) (xy 363.168958 -246.104156) (xy 363.172918 -246.055102)
			(xy 363.184695 -246.007318) (xy 363.203986 -245.962042) (xy 363.230289 -245.920446) (xy 363.262924 -245.883609)
			(xy 363.301045 -245.852484) (xy 363.343666 -245.827877) (xy 363.389682 -245.810425) (xy 363.437901 -245.800581)
			(xy 363.487076 -245.7986) (xy 363.535931 -245.804532) (xy 363.583202 -245.818224) (xy 363.627664 -245.839322)
			(xy 363.668167 -245.867278) (xy 363.70366 -245.90137) (xy 363.733225 -245.940714) (xy 363.756096 -245.984291)
			(xy 363.77168 -246.030972) (xy 363.779575 -246.079549) (xy 363.78007 -246.104156) (xy 364.098581 -246.104156)
			(xy 364.102676 -246.053428) (xy 364.114855 -246.004014) (xy 364.134803 -245.957194) (xy 364.162004 -245.91418)
			(xy 364.195752 -245.876086) (xy 364.235174 -245.843899) (xy 364.279248 -245.818453) (xy 364.326834 -245.800406)
			(xy 364.376698 -245.790226) (xy 364.42755 -245.788177) (xy 364.478071 -245.794311) (xy 364.526955 -245.808471)
			(xy 364.572934 -245.830288) (xy 364.614818 -245.859198) (xy 364.651522 -245.894453) (xy 364.682095 -245.935139)
			(xy 364.705746 -245.980202) (xy 364.721862 -246.028476) (xy 364.730026 -246.07871) (xy 364.730538 -246.104156)
			(xy 365.038635 -246.104156) (xy 365.04273 -246.053428) (xy 365.054909 -246.004014) (xy 365.074857 -245.957194)
			(xy 365.102058 -245.91418) (xy 365.135806 -245.876086) (xy 365.175228 -245.843899) (xy 365.219302 -245.818453)
			(xy 365.266888 -245.800406) (xy 365.316752 -245.790226) (xy 365.367604 -245.788177) (xy 365.418125 -245.794311)
			(xy 365.467009 -245.808471) (xy 365.512988 -245.830288) (xy 365.554872 -245.859198) (xy 365.591576 -245.894453)
			(xy 365.622149 -245.935139) (xy 365.6458 -245.980202) (xy 365.661916 -246.028476) (xy 365.67008 -246.07871)
			(xy 365.670592 -246.104156) (xy 365.98912 -246.104156) (xy 365.99308 -246.055102) (xy 366.004857 -246.007318)
			(xy 366.024148 -245.962042) (xy 366.050451 -245.920446) (xy 366.083086 -245.883609) (xy 366.121207 -245.852484)
			(xy 366.163828 -245.827877) (xy 366.209844 -245.810425) (xy 366.258063 -245.800581) (xy 366.307238 -245.7986)
			(xy 366.356093 -245.804532) (xy 366.403364 -245.818224) (xy 366.447826 -245.839322) (xy 366.488329 -245.867278)
			(xy 366.523822 -245.90137) (xy 366.553387 -245.940714) (xy 366.576258 -245.984291) (xy 366.591842 -246.030972)
			(xy 366.599737 -246.079549) (xy 366.600232 -246.104156) (xy 366.918489 -246.104156) (xy 366.922584 -246.053428)
			(xy 366.934763 -246.004014) (xy 366.954711 -245.957194) (xy 366.981912 -245.91418) (xy 367.01566 -245.876086)
			(xy 367.055082 -245.843899) (xy 367.099156 -245.818453) (xy 367.146742 -245.800406) (xy 367.196606 -245.790226)
			(xy 367.247458 -245.788177) (xy 367.297979 -245.794311) (xy 367.346863 -245.808471) (xy 367.392842 -245.830288)
			(xy 367.434726 -245.859198) (xy 367.47143 -245.894453) (xy 367.502003 -245.935139) (xy 367.525654 -245.980202)
			(xy 367.54177 -246.028476) (xy 367.549934 -246.07871) (xy 367.550446 -246.104156) (xy 367.858543 -246.104156)
			(xy 367.862638 -246.053428) (xy 367.874817 -246.004014) (xy 367.894765 -245.957194) (xy 367.921966 -245.91418)
			(xy 367.955714 -245.876086) (xy 367.995136 -245.843899) (xy 368.03921 -245.818453) (xy 368.086796 -245.800406)
			(xy 368.13666 -245.790226) (xy 368.187512 -245.788177) (xy 368.238033 -245.794311) (xy 368.286917 -245.808471)
			(xy 368.332896 -245.830288) (xy 368.37478 -245.859198) (xy 368.411484 -245.894453) (xy 368.442057 -245.935139)
			(xy 368.465708 -245.980202) (xy 368.481824 -246.028476) (xy 368.489988 -246.07871) (xy 368.4905 -246.104156)
			(xy 368.809028 -246.104156) (xy 368.812988 -246.055102) (xy 368.824765 -246.007318) (xy 368.844056 -245.962042)
			(xy 368.870359 -245.920446) (xy 368.902994 -245.883609) (xy 368.941115 -245.852484) (xy 368.983736 -245.827877)
			(xy 369.029752 -245.810425) (xy 369.077971 -245.800581) (xy 369.127146 -245.7986) (xy 369.176001 -245.804532)
			(xy 369.223272 -245.818224) (xy 369.267734 -245.839322) (xy 369.308237 -245.867278) (xy 369.34373 -245.90137)
			(xy 369.373295 -245.940714) (xy 369.396166 -245.984291) (xy 369.41175 -246.030972) (xy 369.419645 -246.079549)
			(xy 369.42014 -246.104156) (xy 369.738651 -246.104156) (xy 369.742746 -246.053428) (xy 369.754925 -246.004014)
			(xy 369.774873 -245.957194) (xy 369.802074 -245.91418) (xy 369.835822 -245.876086) (xy 369.875244 -245.843899)
			(xy 369.919318 -245.818453) (xy 369.966904 -245.800406) (xy 370.016768 -245.790226) (xy 370.06762 -245.788177)
			(xy 370.118141 -245.794311) (xy 370.167025 -245.808471) (xy 370.213004 -245.830288) (xy 370.254888 -245.859198)
			(xy 370.291592 -245.894453) (xy 370.322165 -245.935139) (xy 370.345816 -245.980202) (xy 370.361932 -246.028476)
			(xy 370.370096 -246.07871) (xy 370.370608 -246.104156) (xy 370.678451 -246.104156) (xy 370.682546 -246.053428)
			(xy 370.694725 -246.004014) (xy 370.714673 -245.957194) (xy 370.741874 -245.91418) (xy 370.775622 -245.876086)
			(xy 370.815044 -245.843899) (xy 370.859118 -245.818453) (xy 370.906704 -245.800406) (xy 370.956568 -245.790226)
			(xy 371.00742 -245.788177) (xy 371.057941 -245.794311) (xy 371.106825 -245.808471) (xy 371.152804 -245.830288)
			(xy 371.194688 -245.859198) (xy 371.231392 -245.894453) (xy 371.261965 -245.935139) (xy 371.285616 -245.980202)
			(xy 371.301732 -246.028476) (xy 371.309896 -246.07871) (xy 371.310408 -246.104156) (xy 371.628936 -246.104156)
			(xy 371.632896 -246.055102) (xy 371.644673 -246.007318) (xy 371.663964 -245.962042) (xy 371.690267 -245.920446)
			(xy 371.722902 -245.883609) (xy 371.761023 -245.852484) (xy 371.803644 -245.827877) (xy 371.84966 -245.810425)
			(xy 371.897879 -245.800581) (xy 371.947054 -245.7986) (xy 371.995909 -245.804532) (xy 372.04318 -245.818224)
			(xy 372.087642 -245.839322) (xy 372.128145 -245.867278) (xy 372.163638 -245.90137) (xy 372.193203 -245.940714)
			(xy 372.216074 -245.984291) (xy 372.231658 -246.030972) (xy 372.239553 -246.079549) (xy 372.240048 -246.104156)
			(xy 372.558559 -246.104156) (xy 372.562654 -246.053428) (xy 372.574833 -246.004014) (xy 372.594781 -245.957194)
			(xy 372.621982 -245.91418) (xy 372.65573 -245.876086) (xy 372.695152 -245.843899) (xy 372.739226 -245.818453)
			(xy 372.786812 -245.800406) (xy 372.836676 -245.790226) (xy 372.887528 -245.788177) (xy 372.938049 -245.794311)
			(xy 372.986933 -245.808471) (xy 373.032912 -245.830288) (xy 373.074796 -245.859198) (xy 373.1115 -245.894453)
			(xy 373.142073 -245.935139) (xy 373.165724 -245.980202) (xy 373.18184 -246.028476) (xy 373.190004 -246.07871)
			(xy 373.190516 -246.104156) (xy 373.498613 -246.104156) (xy 373.502708 -246.053428) (xy 373.514887 -246.004014)
			(xy 373.534835 -245.957194) (xy 373.562036 -245.91418) (xy 373.595784 -245.876086) (xy 373.635206 -245.843899)
			(xy 373.67928 -245.818453) (xy 373.726866 -245.800406) (xy 373.77673 -245.790226) (xy 373.827582 -245.788177)
			(xy 373.878103 -245.794311) (xy 373.926987 -245.808471) (xy 373.972966 -245.830288) (xy 374.01485 -245.859198)
			(xy 374.051554 -245.894453) (xy 374.082127 -245.935139) (xy 374.105778 -245.980202) (xy 374.121894 -246.028476)
			(xy 374.130058 -246.07871) (xy 374.13057 -246.104156) (xy 374.130058 -246.129602) (xy 374.121894 -246.179836)
			(xy 374.105778 -246.22811) (xy 374.082127 -246.273173) (xy 374.051554 -246.313859) (xy 374.01485 -246.349114)
			(xy 373.972966 -246.378024) (xy 373.926987 -246.399841) (xy 373.878103 -246.414001) (xy 373.827582 -246.420135)
			(xy 373.77673 -246.418086) (xy 373.726866 -246.407906) (xy 373.67928 -246.389859) (xy 373.635206 -246.364413)
			(xy 373.595784 -246.332226) (xy 373.562036 -246.294132) (xy 373.534835 -246.251118) (xy 373.514887 -246.204298)
			(xy 373.502708 -246.154884) (xy 373.498613 -246.104156) (xy 373.190516 -246.104156) (xy 373.190004 -246.129602)
			(xy 373.18184 -246.179836) (xy 373.165724 -246.22811) (xy 373.142073 -246.273173) (xy 373.1115 -246.313859)
			(xy 373.074796 -246.349114) (xy 373.032912 -246.378024) (xy 372.986933 -246.399841) (xy 372.938049 -246.414001)
			(xy 372.887528 -246.420135) (xy 372.836676 -246.418086) (xy 372.786812 -246.407906) (xy 372.739226 -246.389859)
			(xy 372.695152 -246.364413) (xy 372.65573 -246.332226) (xy 372.621982 -246.294132) (xy 372.594781 -246.251118)
			(xy 372.574833 -246.204298) (xy 372.562654 -246.154884) (xy 372.558559 -246.104156) (xy 372.240048 -246.104156)
			(xy 372.239553 -246.128763) (xy 372.231658 -246.17734) (xy 372.216074 -246.224021) (xy 372.193203 -246.267598)
			(xy 372.163638 -246.306942) (xy 372.128145 -246.341034) (xy 372.087642 -246.36899) (xy 372.04318 -246.390088)
			(xy 371.995909 -246.40378) (xy 371.947054 -246.409712) (xy 371.897879 -246.407731) (xy 371.84966 -246.397887)
			(xy 371.803644 -246.380435) (xy 371.761023 -246.355828) (xy 371.722902 -246.324703) (xy 371.690267 -246.287866)
			(xy 371.663964 -246.24627) (xy 371.644673 -246.200994) (xy 371.632896 -246.15321) (xy 371.628936 -246.104156)
			(xy 371.310408 -246.104156) (xy 371.309896 -246.129602) (xy 371.301732 -246.179836) (xy 371.285616 -246.22811)
			(xy 371.261965 -246.273173) (xy 371.231392 -246.313859) (xy 371.194688 -246.349114) (xy 371.152804 -246.378024)
			(xy 371.106825 -246.399841) (xy 371.057941 -246.414001) (xy 371.00742 -246.420135) (xy 370.956568 -246.418086)
			(xy 370.906704 -246.407906) (xy 370.859118 -246.389859) (xy 370.815044 -246.364413) (xy 370.775622 -246.332226)
			(xy 370.741874 -246.294132) (xy 370.714673 -246.251118) (xy 370.694725 -246.204298) (xy 370.682546 -246.154884)
			(xy 370.678451 -246.104156) (xy 370.370608 -246.104156) (xy 370.370096 -246.129602) (xy 370.361932 -246.179836)
			(xy 370.345816 -246.22811) (xy 370.322165 -246.273173) (xy 370.291592 -246.313859) (xy 370.254888 -246.349114)
			(xy 370.213004 -246.378024) (xy 370.167025 -246.399841) (xy 370.118141 -246.414001) (xy 370.06762 -246.420135)
			(xy 370.016768 -246.418086) (xy 369.966904 -246.407906) (xy 369.919318 -246.389859) (xy 369.875244 -246.364413)
			(xy 369.835822 -246.332226) (xy 369.802074 -246.294132) (xy 369.774873 -246.251118) (xy 369.754925 -246.204298)
			(xy 369.742746 -246.154884) (xy 369.738651 -246.104156) (xy 369.42014 -246.104156) (xy 369.419645 -246.128763)
			(xy 369.41175 -246.17734) (xy 369.396166 -246.224021) (xy 369.373295 -246.267598) (xy 369.34373 -246.306942)
			(xy 369.308237 -246.341034) (xy 369.267734 -246.36899) (xy 369.223272 -246.390088) (xy 369.176001 -246.40378)
			(xy 369.127146 -246.409712) (xy 369.077971 -246.407731) (xy 369.029752 -246.397887) (xy 368.983736 -246.380435)
			(xy 368.941115 -246.355828) (xy 368.902994 -246.324703) (xy 368.870359 -246.287866) (xy 368.844056 -246.24627)
			(xy 368.824765 -246.200994) (xy 368.812988 -246.15321) (xy 368.809028 -246.104156) (xy 368.4905 -246.104156)
			(xy 368.489988 -246.129602) (xy 368.481824 -246.179836) (xy 368.465708 -246.22811) (xy 368.442057 -246.273173)
			(xy 368.411484 -246.313859) (xy 368.37478 -246.349114) (xy 368.332896 -246.378024) (xy 368.286917 -246.399841)
			(xy 368.238033 -246.414001) (xy 368.187512 -246.420135) (xy 368.13666 -246.418086) (xy 368.086796 -246.407906)
			(xy 368.03921 -246.389859) (xy 367.995136 -246.364413) (xy 367.955714 -246.332226) (xy 367.921966 -246.294132)
			(xy 367.894765 -246.251118) (xy 367.874817 -246.204298) (xy 367.862638 -246.154884) (xy 367.858543 -246.104156)
			(xy 367.550446 -246.104156) (xy 367.549934 -246.129602) (xy 367.54177 -246.179836) (xy 367.525654 -246.22811)
			(xy 367.502003 -246.273173) (xy 367.47143 -246.313859) (xy 367.434726 -246.349114) (xy 367.392842 -246.378024)
			(xy 367.346863 -246.399841) (xy 367.297979 -246.414001) (xy 367.247458 -246.420135) (xy 367.196606 -246.418086)
			(xy 367.146742 -246.407906) (xy 367.099156 -246.389859) (xy 367.055082 -246.364413) (xy 367.01566 -246.332226)
			(xy 366.981912 -246.294132) (xy 366.954711 -246.251118) (xy 366.934763 -246.204298) (xy 366.922584 -246.154884)
			(xy 366.918489 -246.104156) (xy 366.600232 -246.104156) (xy 366.599737 -246.128763) (xy 366.591842 -246.17734)
			(xy 366.576258 -246.224021) (xy 366.553387 -246.267598) (xy 366.523822 -246.306942) (xy 366.488329 -246.341034)
			(xy 366.447826 -246.36899) (xy 366.403364 -246.390088) (xy 366.356093 -246.40378) (xy 366.307238 -246.409712)
			(xy 366.258063 -246.407731) (xy 366.209844 -246.397887) (xy 366.163828 -246.380435) (xy 366.121207 -246.355828)
			(xy 366.083086 -246.324703) (xy 366.050451 -246.287866) (xy 366.024148 -246.24627) (xy 366.004857 -246.200994)
			(xy 365.99308 -246.15321) (xy 365.98912 -246.104156) (xy 365.670592 -246.104156) (xy 365.67008 -246.129602)
			(xy 365.661916 -246.179836) (xy 365.6458 -246.22811) (xy 365.622149 -246.273173) (xy 365.591576 -246.313859)
			(xy 365.554872 -246.349114) (xy 365.512988 -246.378024) (xy 365.467009 -246.399841) (xy 365.418125 -246.414001)
			(xy 365.367604 -246.420135) (xy 365.316752 -246.418086) (xy 365.266888 -246.407906) (xy 365.219302 -246.389859)
			(xy 365.175228 -246.364413) (xy 365.135806 -246.332226) (xy 365.102058 -246.294132) (xy 365.074857 -246.251118)
			(xy 365.054909 -246.204298) (xy 365.04273 -246.154884) (xy 365.038635 -246.104156) (xy 364.730538 -246.104156)
			(xy 364.730026 -246.129602) (xy 364.721862 -246.179836) (xy 364.705746 -246.22811) (xy 364.682095 -246.273173)
			(xy 364.651522 -246.313859) (xy 364.614818 -246.349114) (xy 364.572934 -246.378024) (xy 364.526955 -246.399841)
			(xy 364.478071 -246.414001) (xy 364.42755 -246.420135) (xy 364.376698 -246.418086) (xy 364.326834 -246.407906)
			(xy 364.279248 -246.389859) (xy 364.235174 -246.364413) (xy 364.195752 -246.332226) (xy 364.162004 -246.294132)
			(xy 364.134803 -246.251118) (xy 364.114855 -246.204298) (xy 364.102676 -246.154884) (xy 364.098581 -246.104156)
			(xy 363.78007 -246.104156) (xy 363.779575 -246.128763) (xy 363.77168 -246.17734) (xy 363.756096 -246.224021)
			(xy 363.733225 -246.267598) (xy 363.70366 -246.306942) (xy 363.668167 -246.341034) (xy 363.627664 -246.36899)
			(xy 363.583202 -246.390088) (xy 363.535931 -246.40378) (xy 363.487076 -246.409712) (xy 363.437901 -246.407731)
			(xy 363.389682 -246.397887) (xy 363.343666 -246.380435) (xy 363.301045 -246.355828) (xy 363.262924 -246.324703)
			(xy 363.230289 -246.287866) (xy 363.203986 -246.24627) (xy 363.184695 -246.200994) (xy 363.172918 -246.15321)
			(xy 363.168958 -246.104156) (xy 356.266496 -246.104156) (xy 356.266001 -246.128763) (xy 356.258106 -246.17734)
			(xy 356.242522 -246.224021) (xy 356.219651 -246.267598) (xy 356.190086 -246.306942) (xy 356.154593 -246.341034)
			(xy 356.11409 -246.36899) (xy 356.069628 -246.390088) (xy 356.022357 -246.40378) (xy 355.973502 -246.409712)
			(xy 355.924327 -246.407731) (xy 355.876108 -246.397887) (xy 355.830092 -246.380435) (xy 355.787471 -246.355828)
			(xy 355.74935 -246.324703) (xy 355.716715 -246.287866) (xy 355.690412 -246.24627) (xy 355.671121 -246.200994)
			(xy 355.659344 -246.15321) (xy 355.655384 -246.104156) (xy 355.326442 -246.104156) (xy 355.325947 -246.128763)
			(xy 355.318052 -246.17734) (xy 355.302468 -246.224021) (xy 355.279597 -246.267598) (xy 355.250032 -246.306942)
			(xy 355.214539 -246.341034) (xy 355.174036 -246.36899) (xy 355.129574 -246.390088) (xy 355.082303 -246.40378)
			(xy 355.033448 -246.409712) (xy 354.984273 -246.407731) (xy 354.936054 -246.397887) (xy 354.890038 -246.380435)
			(xy 354.847417 -246.355828) (xy 354.809296 -246.324703) (xy 354.776661 -246.287866) (xy 354.750358 -246.24627)
			(xy 354.731067 -246.200994) (xy 354.71929 -246.15321) (xy 354.71533 -246.104156) (xy 354.386388 -246.104156)
			(xy 354.385893 -246.128763) (xy 354.377998 -246.17734) (xy 354.362414 -246.224021) (xy 354.339543 -246.267598)
			(xy 354.309978 -246.306942) (xy 354.274485 -246.341034) (xy 354.233982 -246.36899) (xy 354.18952 -246.390088)
			(xy 354.142249 -246.40378) (xy 354.093394 -246.409712) (xy 354.044219 -246.407731) (xy 353.996 -246.397887)
			(xy 353.949984 -246.380435) (xy 353.907363 -246.355828) (xy 353.869242 -246.324703) (xy 353.836607 -246.287866)
			(xy 353.810304 -246.24627) (xy 353.791013 -246.200994) (xy 353.779236 -246.15321) (xy 353.775276 -246.104156)
			(xy 353.446334 -246.104156) (xy 353.445839 -246.128763) (xy 353.437944 -246.17734) (xy 353.42236 -246.224021)
			(xy 353.399489 -246.267598) (xy 353.369924 -246.306942) (xy 353.334431 -246.341034) (xy 353.293928 -246.36899)
			(xy 353.249466 -246.390088) (xy 353.202195 -246.40378) (xy 353.15334 -246.409712) (xy 353.104165 -246.407731)
			(xy 353.055946 -246.397887) (xy 353.00993 -246.380435) (xy 352.967309 -246.355828) (xy 352.929188 -246.324703)
			(xy 352.896553 -246.287866) (xy 352.87025 -246.24627) (xy 352.850959 -246.200994) (xy 352.839182 -246.15321)
			(xy 352.835222 -246.104156) (xy 352.506534 -246.104156) (xy 352.506039 -246.128763) (xy 352.498144 -246.17734)
			(xy 352.48256 -246.224021) (xy 352.459689 -246.267598) (xy 352.430124 -246.306942) (xy 352.394631 -246.341034)
			(xy 352.354128 -246.36899) (xy 352.309666 -246.390088) (xy 352.262395 -246.40378) (xy 352.21354 -246.409712)
			(xy 352.164365 -246.407731) (xy 352.116146 -246.397887) (xy 352.07013 -246.380435) (xy 352.027509 -246.355828)
			(xy 351.989388 -246.324703) (xy 351.956753 -246.287866) (xy 351.93045 -246.24627) (xy 351.911159 -246.200994)
			(xy 351.899382 -246.15321) (xy 351.895422 -246.104156) (xy 351.56648 -246.104156) (xy 351.565985 -246.128763)
			(xy 351.55809 -246.17734) (xy 351.542506 -246.224021) (xy 351.519635 -246.267598) (xy 351.49007 -246.306942)
			(xy 351.454577 -246.341034) (xy 351.414074 -246.36899) (xy 351.369612 -246.390088) (xy 351.322341 -246.40378)
			(xy 351.273486 -246.409712) (xy 351.224311 -246.407731) (xy 351.176092 -246.397887) (xy 351.130076 -246.380435)
			(xy 351.087455 -246.355828) (xy 351.049334 -246.324703) (xy 351.016699 -246.287866) (xy 350.990396 -246.24627)
			(xy 350.971105 -246.200994) (xy 350.959328 -246.15321) (xy 350.955368 -246.104156) (xy 350.626426 -246.104156)
			(xy 350.625931 -246.128763) (xy 350.618036 -246.17734) (xy 350.602452 -246.224021) (xy 350.579581 -246.267598)
			(xy 350.550016 -246.306942) (xy 350.514523 -246.341034) (xy 350.47402 -246.36899) (xy 350.429558 -246.390088)
			(xy 350.382287 -246.40378) (xy 350.333432 -246.409712) (xy 350.284257 -246.407731) (xy 350.236038 -246.397887)
			(xy 350.190022 -246.380435) (xy 350.147401 -246.355828) (xy 350.10928 -246.324703) (xy 350.076645 -246.287866)
			(xy 350.050342 -246.24627) (xy 350.031051 -246.200994) (xy 350.019274 -246.15321) (xy 350.015314 -246.104156)
			(xy 349.686372 -246.104156) (xy 349.685877 -246.128763) (xy 349.677982 -246.17734) (xy 349.662398 -246.224021)
			(xy 349.639527 -246.267598) (xy 349.609962 -246.306942) (xy 349.574469 -246.341034) (xy 349.533966 -246.36899)
			(xy 349.489504 -246.390088) (xy 349.442233 -246.40378) (xy 349.393378 -246.409712) (xy 349.344203 -246.407731)
			(xy 349.295984 -246.397887) (xy 349.249968 -246.380435) (xy 349.207347 -246.355828) (xy 349.169226 -246.324703)
			(xy 349.136591 -246.287866) (xy 349.110288 -246.24627) (xy 349.090997 -246.200994) (xy 349.07922 -246.15321)
			(xy 349.07526 -246.104156) (xy 348.746318 -246.104156) (xy 348.745823 -246.128763) (xy 348.737928 -246.17734)
			(xy 348.722344 -246.224021) (xy 348.699473 -246.267598) (xy 348.669908 -246.306942) (xy 348.634415 -246.341034)
			(xy 348.593912 -246.36899) (xy 348.54945 -246.390088) (xy 348.502179 -246.40378) (xy 348.453324 -246.409712)
			(xy 348.404149 -246.407731) (xy 348.35593 -246.397887) (xy 348.309914 -246.380435) (xy 348.267293 -246.355828)
			(xy 348.229172 -246.324703) (xy 348.196537 -246.287866) (xy 348.170234 -246.24627) (xy 348.150943 -246.200994)
			(xy 348.139166 -246.15321) (xy 348.135206 -246.104156) (xy 347.806518 -246.104156) (xy 347.806023 -246.128763)
			(xy 347.798128 -246.17734) (xy 347.782544 -246.224021) (xy 347.759673 -246.267598) (xy 347.730108 -246.306942)
			(xy 347.694615 -246.341034) (xy 347.654112 -246.36899) (xy 347.60965 -246.390088) (xy 347.562379 -246.40378)
			(xy 347.513524 -246.409712) (xy 347.464349 -246.407731) (xy 347.41613 -246.397887) (xy 347.370114 -246.380435)
			(xy 347.327493 -246.355828) (xy 347.289372 -246.324703) (xy 347.256737 -246.287866) (xy 347.230434 -246.24627)
			(xy 347.211143 -246.200994) (xy 347.199366 -246.15321) (xy 347.195406 -246.104156) (xy 346.866464 -246.104156)
			(xy 346.865969 -246.128763) (xy 346.858074 -246.17734) (xy 346.84249 -246.224021) (xy 346.819619 -246.267598)
			(xy 346.790054 -246.306942) (xy 346.754561 -246.341034) (xy 346.714058 -246.36899) (xy 346.669596 -246.390088)
			(xy 346.622325 -246.40378) (xy 346.57347 -246.409712) (xy 346.524295 -246.407731) (xy 346.476076 -246.397887)
			(xy 346.43006 -246.380435) (xy 346.387439 -246.355828) (xy 346.349318 -246.324703) (xy 346.316683 -246.287866)
			(xy 346.29038 -246.24627) (xy 346.271089 -246.200994) (xy 346.259312 -246.15321) (xy 346.255352 -246.104156)
			(xy 345.92641 -246.104156) (xy 345.925915 -246.128763) (xy 345.91802 -246.17734) (xy 345.902436 -246.224021)
			(xy 345.879565 -246.267598) (xy 345.85 -246.306942) (xy 345.814507 -246.341034) (xy 345.774004 -246.36899)
			(xy 345.729542 -246.390088) (xy 345.682271 -246.40378) (xy 345.633416 -246.409712) (xy 345.584241 -246.407731)
			(xy 345.536022 -246.397887) (xy 345.490006 -246.380435) (xy 345.447385 -246.355828) (xy 345.409264 -246.324703)
			(xy 345.376629 -246.287866) (xy 345.350326 -246.24627) (xy 345.331035 -246.200994) (xy 345.319258 -246.15321)
			(xy 345.315298 -246.104156) (xy 344.986917 -246.104156) (xy 344.986918 -246.104172) (xy 344.982873 -246.153797)
			(xy 344.970837 -246.20211) (xy 344.951129 -246.247833) (xy 344.924269 -246.289756) (xy 344.890969 -246.32677)
			(xy 344.871802 -246.342662) (xy 344.86723 -246.346218) (xy 344.860372 -246.3546) (xy 344.848434 -246.378984)
			(xy 344.84564 -246.384572) (xy 344.8431 -246.395494) (xy 344.8431 -246.563388) (xy 344.843425 -246.571935)
			(xy 344.849049 -246.588078) (xy 344.859674 -246.601468) (xy 344.866722 -246.606314) (xy 344.867738 -246.607076)
			(xy 344.945208 -246.651272) (xy 344.951143 -246.654417) (xy 344.964146 -246.657764) (xy 344.970862 -246.657876)
			(xy 344.984324 -246.657876) (xy 344.996262 -246.651018) (xy 344.996516 -246.650764) (xy 345.020142 -246.637587)
			(xy 345.070897 -246.618881) (xy 345.124155 -246.609416) (xy 345.151202 -246.608854) (xy 345.156282 -246.608854)
			(xy 345.18001 -246.6097) (xy 345.226787 -246.61783) (xy 345.271741 -246.633103) (xy 345.313789 -246.655152)
			(xy 345.351917 -246.683444) (xy 345.385205 -246.717298) (xy 345.412851 -246.755897) (xy 345.434188 -246.79831)
			(xy 345.448702 -246.843516) (xy 345.456042 -246.890423) (xy 345.45651 -246.914162) (xy 345.785198 -246.914162)
			(xy 345.789158 -246.865108) (xy 345.800935 -246.817324) (xy 345.820226 -246.772048) (xy 345.846529 -246.730452)
			(xy 345.879164 -246.693615) (xy 345.917285 -246.66249) (xy 345.959906 -246.637883) (xy 346.005922 -246.620431)
			(xy 346.054141 -246.610587) (xy 346.103316 -246.608606) (xy 346.152171 -246.614538) (xy 346.199442 -246.62823)
			(xy 346.243904 -246.649328) (xy 346.284407 -246.677284) (xy 346.3199 -246.711376) (xy 346.349465 -246.75072)
			(xy 346.372336 -246.794297) (xy 346.38792 -246.840978) (xy 346.395815 -246.889555) (xy 346.39631 -246.914162)
			(xy 346.725252 -246.914162) (xy 346.729212 -246.865108) (xy 346.740989 -246.817324) (xy 346.76028 -246.772048)
			(xy 346.786583 -246.730452) (xy 346.819218 -246.693615) (xy 346.857339 -246.66249) (xy 346.89996 -246.637883)
			(xy 346.945976 -246.620431) (xy 346.994195 -246.610587) (xy 347.04337 -246.608606) (xy 347.092225 -246.614538)
			(xy 347.139496 -246.62823) (xy 347.183958 -246.649328) (xy 347.224461 -246.677284) (xy 347.259954 -246.711376)
			(xy 347.289519 -246.75072) (xy 347.31239 -246.794297) (xy 347.327974 -246.840978) (xy 347.335869 -246.889555)
			(xy 347.336364 -246.914162) (xy 347.665306 -246.914162) (xy 347.669266 -246.865108) (xy 347.681043 -246.817324)
			(xy 347.700334 -246.772048) (xy 347.726637 -246.730452) (xy 347.759272 -246.693615) (xy 347.797393 -246.66249)
			(xy 347.840014 -246.637883) (xy 347.88603 -246.620431) (xy 347.934249 -246.610587) (xy 347.983424 -246.608606)
			(xy 348.032279 -246.614538) (xy 348.07955 -246.62823) (xy 348.124012 -246.649328) (xy 348.164515 -246.677284)
			(xy 348.200008 -246.711376) (xy 348.229573 -246.75072) (xy 348.252444 -246.794297) (xy 348.268028 -246.840978)
			(xy 348.275923 -246.889555) (xy 348.276418 -246.914162) (xy 348.60536 -246.914162) (xy 348.60932 -246.865108)
			(xy 348.621097 -246.817324) (xy 348.640388 -246.772048) (xy 348.666691 -246.730452) (xy 348.699326 -246.693615)
			(xy 348.737447 -246.66249) (xy 348.780068 -246.637883) (xy 348.826084 -246.620431) (xy 348.874303 -246.610587)
			(xy 348.923478 -246.608606) (xy 348.972333 -246.614538) (xy 349.019604 -246.62823) (xy 349.064066 -246.649328)
			(xy 349.104569 -246.677284) (xy 349.140062 -246.711376) (xy 349.169627 -246.75072) (xy 349.192498 -246.794297)
			(xy 349.208082 -246.840978) (xy 349.215977 -246.889555) (xy 349.216472 -246.914162) (xy 349.545414 -246.914162)
			(xy 349.549374 -246.865108) (xy 349.561151 -246.817324) (xy 349.580442 -246.772048) (xy 349.606745 -246.730452)
			(xy 349.63938 -246.693615) (xy 349.677501 -246.66249) (xy 349.720122 -246.637883) (xy 349.766138 -246.620431)
			(xy 349.814357 -246.610587) (xy 349.863532 -246.608606) (xy 349.912387 -246.614538) (xy 349.959658 -246.62823)
			(xy 350.00412 -246.649328) (xy 350.044623 -246.677284) (xy 350.080116 -246.711376) (xy 350.109681 -246.75072)
			(xy 350.132552 -246.794297) (xy 350.148136 -246.840978) (xy 350.156031 -246.889555) (xy 350.156526 -246.914162)
			(xy 350.485214 -246.914162) (xy 350.489174 -246.865108) (xy 350.500951 -246.817324) (xy 350.520242 -246.772048)
			(xy 350.546545 -246.730452) (xy 350.57918 -246.693615) (xy 350.617301 -246.66249) (xy 350.659922 -246.637883)
			(xy 350.705938 -246.620431) (xy 350.754157 -246.610587) (xy 350.803332 -246.608606) (xy 350.852187 -246.614538)
			(xy 350.899458 -246.62823) (xy 350.94392 -246.649328) (xy 350.984423 -246.677284) (xy 351.019916 -246.711376)
			(xy 351.049481 -246.75072) (xy 351.072352 -246.794297) (xy 351.087936 -246.840978) (xy 351.095831 -246.889555)
			(xy 351.096326 -246.914162) (xy 351.425268 -246.914162) (xy 351.429228 -246.865108) (xy 351.441005 -246.817324)
			(xy 351.460296 -246.772048) (xy 351.486599 -246.730452) (xy 351.519234 -246.693615) (xy 351.557355 -246.66249)
			(xy 351.599976 -246.637883) (xy 351.645992 -246.620431) (xy 351.694211 -246.610587) (xy 351.743386 -246.608606)
			(xy 351.792241 -246.614538) (xy 351.839512 -246.62823) (xy 351.883974 -246.649328) (xy 351.924477 -246.677284)
			(xy 351.95997 -246.711376) (xy 351.989535 -246.75072) (xy 352.012406 -246.794297) (xy 352.02799 -246.840978)
			(xy 352.035885 -246.889555) (xy 352.03638 -246.914162) (xy 352.365322 -246.914162) (xy 352.369282 -246.865108)
			(xy 352.381059 -246.817324) (xy 352.40035 -246.772048) (xy 352.426653 -246.730452) (xy 352.459288 -246.693615)
			(xy 352.497409 -246.66249) (xy 352.54003 -246.637883) (xy 352.586046 -246.620431) (xy 352.634265 -246.610587)
			(xy 352.68344 -246.608606) (xy 352.732295 -246.614538) (xy 352.779566 -246.62823) (xy 352.824028 -246.649328)
			(xy 352.864531 -246.677284) (xy 352.900024 -246.711376) (xy 352.929589 -246.75072) (xy 352.95246 -246.794297)
			(xy 352.968044 -246.840978) (xy 352.975939 -246.889555) (xy 352.976434 -246.914162) (xy 353.305376 -246.914162)
			(xy 353.309336 -246.865108) (xy 353.321113 -246.817324) (xy 353.340404 -246.772048) (xy 353.366707 -246.730452)
			(xy 353.399342 -246.693615) (xy 353.437463 -246.66249) (xy 353.480084 -246.637883) (xy 353.5261 -246.620431)
			(xy 353.574319 -246.610587) (xy 353.623494 -246.608606) (xy 353.672349 -246.614538) (xy 353.71962 -246.62823)
			(xy 353.764082 -246.649328) (xy 353.804585 -246.677284) (xy 353.840078 -246.711376) (xy 353.869643 -246.75072)
			(xy 353.892514 -246.794297) (xy 353.908098 -246.840978) (xy 353.915993 -246.889555) (xy 353.916488 -246.914162)
			(xy 354.24543 -246.914162) (xy 354.24939 -246.865108) (xy 354.261167 -246.817324) (xy 354.280458 -246.772048)
			(xy 354.306761 -246.730452) (xy 354.339396 -246.693615) (xy 354.377517 -246.66249) (xy 354.420138 -246.637883)
			(xy 354.466154 -246.620431) (xy 354.514373 -246.610587) (xy 354.563548 -246.608606) (xy 354.612403 -246.614538)
			(xy 354.659674 -246.62823) (xy 354.704136 -246.649328) (xy 354.744639 -246.677284) (xy 354.780132 -246.711376)
			(xy 354.809697 -246.75072) (xy 354.832568 -246.794297) (xy 354.848152 -246.840978) (xy 354.856047 -246.889555)
			(xy 354.856542 -246.914162) (xy 355.18523 -246.914162) (xy 355.18919 -246.865108) (xy 355.200967 -246.817324)
			(xy 355.220258 -246.772048) (xy 355.246561 -246.730452) (xy 355.279196 -246.693615) (xy 355.317317 -246.66249)
			(xy 355.359938 -246.637883) (xy 355.405954 -246.620431) (xy 355.454173 -246.610587) (xy 355.503348 -246.608606)
			(xy 355.552203 -246.614538) (xy 355.599474 -246.62823) (xy 355.643936 -246.649328) (xy 355.684439 -246.677284)
			(xy 355.719932 -246.711376) (xy 355.749497 -246.75072) (xy 355.772368 -246.794297) (xy 355.787952 -246.840978)
			(xy 355.795847 -246.889555) (xy 355.796342 -246.914162) (xy 356.125284 -246.914162) (xy 356.129244 -246.865108)
			(xy 356.141021 -246.817324) (xy 356.160312 -246.772048) (xy 356.186615 -246.730452) (xy 356.21925 -246.693615)
			(xy 356.257371 -246.66249) (xy 356.299992 -246.637883) (xy 356.346008 -246.620431) (xy 356.394227 -246.610587)
			(xy 356.443402 -246.608606) (xy 356.492257 -246.614538) (xy 356.539528 -246.62823) (xy 356.58399 -246.649328)
			(xy 356.624493 -246.677284) (xy 356.659986 -246.711376) (xy 356.689551 -246.75072) (xy 356.712422 -246.794297)
			(xy 356.728006 -246.840978) (xy 356.735901 -246.889555) (xy 356.736396 -246.914162) (xy 357.065338 -246.914162)
			(xy 357.069298 -246.865108) (xy 357.081075 -246.817324) (xy 357.100366 -246.772048) (xy 357.126669 -246.730452)
			(xy 357.159304 -246.693615) (xy 357.197425 -246.66249) (xy 357.240046 -246.637883) (xy 357.286062 -246.620431)
			(xy 357.334281 -246.610587) (xy 357.383456 -246.608606) (xy 357.432311 -246.614538) (xy 357.479582 -246.62823)
			(xy 357.524044 -246.649328) (xy 357.564547 -246.677284) (xy 357.60004 -246.711376) (xy 357.629605 -246.75072)
			(xy 357.652476 -246.794297) (xy 357.66806 -246.840978) (xy 357.675955 -246.889555) (xy 357.67645 -246.914162)
			(xy 358.005392 -246.914162) (xy 358.009352 -246.865108) (xy 358.021129 -246.817324) (xy 358.04042 -246.772048)
			(xy 358.066723 -246.730452) (xy 358.099358 -246.693615) (xy 358.137479 -246.66249) (xy 358.1801 -246.637883)
			(xy 358.226116 -246.620431) (xy 358.274335 -246.610587) (xy 358.32351 -246.608606) (xy 358.372365 -246.614538)
			(xy 358.419636 -246.62823) (xy 358.464098 -246.649328) (xy 358.504601 -246.677284) (xy 358.540094 -246.711376)
			(xy 358.569659 -246.75072) (xy 358.59253 -246.794297) (xy 358.608114 -246.840978) (xy 358.616009 -246.889555)
			(xy 358.616504 -246.914162) (xy 360.81895 -246.914162) (xy 360.82291 -246.865108) (xy 360.834687 -246.817324)
			(xy 360.853978 -246.772048) (xy 360.880281 -246.730452) (xy 360.912916 -246.693615) (xy 360.951037 -246.66249)
			(xy 360.993658 -246.637883) (xy 361.039674 -246.620431) (xy 361.087893 -246.610587) (xy 361.137068 -246.608606)
			(xy 361.185923 -246.614538) (xy 361.233194 -246.62823) (xy 361.277656 -246.649328) (xy 361.318159 -246.677284)
			(xy 361.353652 -246.711376) (xy 361.383217 -246.75072) (xy 361.406088 -246.794297) (xy 361.421672 -246.840978)
			(xy 361.429567 -246.889555) (xy 361.430062 -246.914162) (xy 361.748573 -246.914162) (xy 361.752668 -246.863434)
			(xy 361.764847 -246.81402) (xy 361.784795 -246.7672) (xy 361.811996 -246.724186) (xy 361.845744 -246.686092)
			(xy 361.885166 -246.653905) (xy 361.92924 -246.628459) (xy 361.976826 -246.610412) (xy 362.02669 -246.600232)
			(xy 362.077542 -246.598183) (xy 362.128063 -246.604317) (xy 362.176947 -246.618477) (xy 362.222926 -246.640294)
			(xy 362.26481 -246.669204) (xy 362.301514 -246.704459) (xy 362.332087 -246.745145) (xy 362.355738 -246.790208)
			(xy 362.371854 -246.838482) (xy 362.380018 -246.888716) (xy 362.38053 -246.914162) (xy 362.688627 -246.914162)
			(xy 362.692722 -246.863434) (xy 362.704901 -246.81402) (xy 362.724849 -246.7672) (xy 362.75205 -246.724186)
			(xy 362.785798 -246.686092) (xy 362.82522 -246.653905) (xy 362.869294 -246.628459) (xy 362.91688 -246.610412)
			(xy 362.966744 -246.600232) (xy 363.017596 -246.598183) (xy 363.068117 -246.604317) (xy 363.117001 -246.618477)
			(xy 363.16298 -246.640294) (xy 363.204864 -246.669204) (xy 363.241568 -246.704459) (xy 363.272141 -246.745145)
			(xy 363.295792 -246.790208) (xy 363.311908 -246.838482) (xy 363.320072 -246.888716) (xy 363.320584 -246.914162)
			(xy 363.639112 -246.914162) (xy 363.643072 -246.865108) (xy 363.654849 -246.817324) (xy 363.67414 -246.772048)
			(xy 363.700443 -246.730452) (xy 363.733078 -246.693615) (xy 363.771199 -246.66249) (xy 363.81382 -246.637883)
			(xy 363.859836 -246.620431) (xy 363.908055 -246.610587) (xy 363.95723 -246.608606) (xy 364.006085 -246.614538)
			(xy 364.053356 -246.62823) (xy 364.097818 -246.649328) (xy 364.138321 -246.677284) (xy 364.173814 -246.711376)
			(xy 364.203379 -246.75072) (xy 364.22625 -246.794297) (xy 364.241834 -246.840978) (xy 364.249729 -246.889555)
			(xy 364.250224 -246.914162) (xy 364.578912 -246.914162) (xy 364.582872 -246.865108) (xy 364.594649 -246.817324)
			(xy 364.61394 -246.772048) (xy 364.640243 -246.730452) (xy 364.672878 -246.693615) (xy 364.710999 -246.66249)
			(xy 364.75362 -246.637883) (xy 364.799636 -246.620431) (xy 364.847855 -246.610587) (xy 364.89703 -246.608606)
			(xy 364.945885 -246.614538) (xy 364.993156 -246.62823) (xy 365.037618 -246.649328) (xy 365.078121 -246.677284)
			(xy 365.113614 -246.711376) (xy 365.143179 -246.75072) (xy 365.16605 -246.794297) (xy 365.181634 -246.840978)
			(xy 365.189529 -246.889555) (xy 365.190024 -246.914162) (xy 365.518966 -246.914162) (xy 365.522926 -246.865108)
			(xy 365.534703 -246.817324) (xy 365.553994 -246.772048) (xy 365.580297 -246.730452) (xy 365.612932 -246.693615)
			(xy 365.651053 -246.66249) (xy 365.693674 -246.637883) (xy 365.73969 -246.620431) (xy 365.787909 -246.610587)
			(xy 365.837084 -246.608606) (xy 365.885939 -246.614538) (xy 365.93321 -246.62823) (xy 365.977672 -246.649328)
			(xy 366.018175 -246.677284) (xy 366.053668 -246.711376) (xy 366.083233 -246.75072) (xy 366.106104 -246.794297)
			(xy 366.121688 -246.840978) (xy 366.129583 -246.889555) (xy 366.130078 -246.914162) (xy 366.45902 -246.914162)
			(xy 366.46298 -246.865108) (xy 366.474757 -246.817324) (xy 366.494048 -246.772048) (xy 366.520351 -246.730452)
			(xy 366.552986 -246.693615) (xy 366.591107 -246.66249) (xy 366.633728 -246.637883) (xy 366.679744 -246.620431)
			(xy 366.727963 -246.610587) (xy 366.777138 -246.608606) (xy 366.825993 -246.614538) (xy 366.873264 -246.62823)
			(xy 366.917726 -246.649328) (xy 366.958229 -246.677284) (xy 366.993722 -246.711376) (xy 367.023287 -246.75072)
			(xy 367.046158 -246.794297) (xy 367.061742 -246.840978) (xy 367.069637 -246.889555) (xy 367.070132 -246.914162)
			(xy 367.399074 -246.914162) (xy 367.403034 -246.865108) (xy 367.414811 -246.817324) (xy 367.434102 -246.772048)
			(xy 367.460405 -246.730452) (xy 367.49304 -246.693615) (xy 367.531161 -246.66249) (xy 367.573782 -246.637883)
			(xy 367.619798 -246.620431) (xy 367.668017 -246.610587) (xy 367.717192 -246.608606) (xy 367.766047 -246.614538)
			(xy 367.813318 -246.62823) (xy 367.85778 -246.649328) (xy 367.898283 -246.677284) (xy 367.933776 -246.711376)
			(xy 367.963341 -246.75072) (xy 367.986212 -246.794297) (xy 368.001796 -246.840978) (xy 368.009691 -246.889555)
			(xy 368.010186 -246.914162) (xy 368.338874 -246.914162) (xy 368.342834 -246.865108) (xy 368.354611 -246.817324)
			(xy 368.373902 -246.772048) (xy 368.400205 -246.730452) (xy 368.43284 -246.693615) (xy 368.470961 -246.66249)
			(xy 368.513582 -246.637883) (xy 368.559598 -246.620431) (xy 368.607817 -246.610587) (xy 368.656992 -246.608606)
			(xy 368.705847 -246.614538) (xy 368.753118 -246.62823) (xy 368.79758 -246.649328) (xy 368.838083 -246.677284)
			(xy 368.873576 -246.711376) (xy 368.903141 -246.75072) (xy 368.926012 -246.794297) (xy 368.941596 -246.840978)
			(xy 368.949491 -246.889555) (xy 368.949986 -246.914162) (xy 369.278928 -246.914162) (xy 369.282888 -246.865108)
			(xy 369.294665 -246.817324) (xy 369.313956 -246.772048) (xy 369.340259 -246.730452) (xy 369.372894 -246.693615)
			(xy 369.411015 -246.66249) (xy 369.453636 -246.637883) (xy 369.499652 -246.620431) (xy 369.547871 -246.610587)
			(xy 369.597046 -246.608606) (xy 369.645901 -246.614538) (xy 369.693172 -246.62823) (xy 369.737634 -246.649328)
			(xy 369.778137 -246.677284) (xy 369.81363 -246.711376) (xy 369.843195 -246.75072) (xy 369.866066 -246.794297)
			(xy 369.88165 -246.840978) (xy 369.889545 -246.889555) (xy 369.89004 -246.914162) (xy 370.218982 -246.914162)
			(xy 370.222942 -246.865108) (xy 370.234719 -246.817324) (xy 370.25401 -246.772048) (xy 370.280313 -246.730452)
			(xy 370.312948 -246.693615) (xy 370.351069 -246.66249) (xy 370.39369 -246.637883) (xy 370.439706 -246.620431)
			(xy 370.487925 -246.610587) (xy 370.5371 -246.608606) (xy 370.585955 -246.614538) (xy 370.633226 -246.62823)
			(xy 370.677688 -246.649328) (xy 370.718191 -246.677284) (xy 370.753684 -246.711376) (xy 370.783249 -246.75072)
			(xy 370.80612 -246.794297) (xy 370.821704 -246.840978) (xy 370.829599 -246.889555) (xy 370.830094 -246.914162)
			(xy 371.159036 -246.914162) (xy 371.162996 -246.865108) (xy 371.174773 -246.817324) (xy 371.194064 -246.772048)
			(xy 371.220367 -246.730452) (xy 371.253002 -246.693615) (xy 371.291123 -246.66249) (xy 371.333744 -246.637883)
			(xy 371.37976 -246.620431) (xy 371.427979 -246.610587) (xy 371.477154 -246.608606) (xy 371.526009 -246.614538)
			(xy 371.57328 -246.62823) (xy 371.617742 -246.649328) (xy 371.658245 -246.677284) (xy 371.693738 -246.711376)
			(xy 371.723303 -246.75072) (xy 371.746174 -246.794297) (xy 371.761758 -246.840978) (xy 371.769653 -246.889555)
			(xy 371.770148 -246.914162) (xy 372.09909 -246.914162) (xy 372.10305 -246.865108) (xy 372.114827 -246.817324)
			(xy 372.134118 -246.772048) (xy 372.160421 -246.730452) (xy 372.193056 -246.693615) (xy 372.231177 -246.66249)
			(xy 372.273798 -246.637883) (xy 372.319814 -246.620431) (xy 372.368033 -246.610587) (xy 372.417208 -246.608606)
			(xy 372.466063 -246.614538) (xy 372.513334 -246.62823) (xy 372.557796 -246.649328) (xy 372.598299 -246.677284)
			(xy 372.633792 -246.711376) (xy 372.663357 -246.75072) (xy 372.686228 -246.794297) (xy 372.701812 -246.840978)
			(xy 372.709707 -246.889555) (xy 372.710202 -246.914162) (xy 373.03889 -246.914162) (xy 373.04285 -246.865108)
			(xy 373.054627 -246.817324) (xy 373.073918 -246.772048) (xy 373.100221 -246.730452) (xy 373.132856 -246.693615)
			(xy 373.170977 -246.66249) (xy 373.213598 -246.637883) (xy 373.259614 -246.620431) (xy 373.307833 -246.610587)
			(xy 373.357008 -246.608606) (xy 373.405863 -246.614538) (xy 373.453134 -246.62823) (xy 373.497596 -246.649328)
			(xy 373.538099 -246.677284) (xy 373.573592 -246.711376) (xy 373.603157 -246.75072) (xy 373.626028 -246.794297)
			(xy 373.641612 -246.840978) (xy 373.649507 -246.889555) (xy 373.650002 -246.914162) (xy 373.649507 -246.938769)
			(xy 373.641612 -246.987346) (xy 373.626028 -247.034027) (xy 373.603157 -247.077604) (xy 373.573592 -247.116948)
			(xy 373.538099 -247.15104) (xy 373.497596 -247.178996) (xy 373.453134 -247.200094) (xy 373.405863 -247.213786)
			(xy 373.357008 -247.219718) (xy 373.307833 -247.217737) (xy 373.259614 -247.207893) (xy 373.213598 -247.190441)
			(xy 373.170977 -247.165834) (xy 373.132856 -247.134709) (xy 373.100221 -247.097872) (xy 373.073918 -247.056276)
			(xy 373.054627 -247.011) (xy 373.04285 -246.963216) (xy 373.03889 -246.914162) (xy 372.710202 -246.914162)
			(xy 372.709707 -246.938769) (xy 372.701812 -246.987346) (xy 372.686228 -247.034027) (xy 372.663357 -247.077604)
			(xy 372.633792 -247.116948) (xy 372.598299 -247.15104) (xy 372.557796 -247.178996) (xy 372.513334 -247.200094)
			(xy 372.466063 -247.213786) (xy 372.417208 -247.219718) (xy 372.368033 -247.217737) (xy 372.319814 -247.207893)
			(xy 372.273798 -247.190441) (xy 372.231177 -247.165834) (xy 372.193056 -247.134709) (xy 372.160421 -247.097872)
			(xy 372.134118 -247.056276) (xy 372.114827 -247.011) (xy 372.10305 -246.963216) (xy 372.09909 -246.914162)
			(xy 371.770148 -246.914162) (xy 371.769653 -246.938769) (xy 371.761758 -246.987346) (xy 371.746174 -247.034027)
			(xy 371.723303 -247.077604) (xy 371.693738 -247.116948) (xy 371.658245 -247.15104) (xy 371.617742 -247.178996)
			(xy 371.57328 -247.200094) (xy 371.526009 -247.213786) (xy 371.477154 -247.219718) (xy 371.427979 -247.217737)
			(xy 371.37976 -247.207893) (xy 371.333744 -247.190441) (xy 371.291123 -247.165834) (xy 371.253002 -247.134709)
			(xy 371.220367 -247.097872) (xy 371.194064 -247.056276) (xy 371.174773 -247.011) (xy 371.162996 -246.963216)
			(xy 371.159036 -246.914162) (xy 370.830094 -246.914162) (xy 370.829599 -246.938769) (xy 370.821704 -246.987346)
			(xy 370.80612 -247.034027) (xy 370.783249 -247.077604) (xy 370.753684 -247.116948) (xy 370.718191 -247.15104)
			(xy 370.677688 -247.178996) (xy 370.633226 -247.200094) (xy 370.585955 -247.213786) (xy 370.5371 -247.219718)
			(xy 370.487925 -247.217737) (xy 370.439706 -247.207893) (xy 370.39369 -247.190441) (xy 370.351069 -247.165834)
			(xy 370.312948 -247.134709) (xy 370.280313 -247.097872) (xy 370.25401 -247.056276) (xy 370.234719 -247.011)
			(xy 370.222942 -246.963216) (xy 370.218982 -246.914162) (xy 369.89004 -246.914162) (xy 369.889545 -246.938769)
			(xy 369.88165 -246.987346) (xy 369.866066 -247.034027) (xy 369.843195 -247.077604) (xy 369.81363 -247.116948)
			(xy 369.778137 -247.15104) (xy 369.737634 -247.178996) (xy 369.693172 -247.200094) (xy 369.645901 -247.213786)
			(xy 369.597046 -247.219718) (xy 369.547871 -247.217737) (xy 369.499652 -247.207893) (xy 369.453636 -247.190441)
			(xy 369.411015 -247.165834) (xy 369.372894 -247.134709) (xy 369.340259 -247.097872) (xy 369.313956 -247.056276)
			(xy 369.294665 -247.011) (xy 369.282888 -246.963216) (xy 369.278928 -246.914162) (xy 368.949986 -246.914162)
			(xy 368.949491 -246.938769) (xy 368.941596 -246.987346) (xy 368.926012 -247.034027) (xy 368.903141 -247.077604)
			(xy 368.873576 -247.116948) (xy 368.838083 -247.15104) (xy 368.79758 -247.178996) (xy 368.753118 -247.200094)
			(xy 368.705847 -247.213786) (xy 368.656992 -247.219718) (xy 368.607817 -247.217737) (xy 368.559598 -247.207893)
			(xy 368.513582 -247.190441) (xy 368.470961 -247.165834) (xy 368.43284 -247.134709) (xy 368.400205 -247.097872)
			(xy 368.373902 -247.056276) (xy 368.354611 -247.011) (xy 368.342834 -246.963216) (xy 368.338874 -246.914162)
			(xy 368.010186 -246.914162) (xy 368.009691 -246.938769) (xy 368.001796 -246.987346) (xy 367.986212 -247.034027)
			(xy 367.963341 -247.077604) (xy 367.933776 -247.116948) (xy 367.898283 -247.15104) (xy 367.85778 -247.178996)
			(xy 367.813318 -247.200094) (xy 367.766047 -247.213786) (xy 367.717192 -247.219718) (xy 367.668017 -247.217737)
			(xy 367.619798 -247.207893) (xy 367.573782 -247.190441) (xy 367.531161 -247.165834) (xy 367.49304 -247.134709)
			(xy 367.460405 -247.097872) (xy 367.434102 -247.056276) (xy 367.414811 -247.011) (xy 367.403034 -246.963216)
			(xy 367.399074 -246.914162) (xy 367.070132 -246.914162) (xy 367.069637 -246.938769) (xy 367.061742 -246.987346)
			(xy 367.046158 -247.034027) (xy 367.023287 -247.077604) (xy 366.993722 -247.116948) (xy 366.958229 -247.15104)
			(xy 366.917726 -247.178996) (xy 366.873264 -247.200094) (xy 366.825993 -247.213786) (xy 366.777138 -247.219718)
			(xy 366.727963 -247.217737) (xy 366.679744 -247.207893) (xy 366.633728 -247.190441) (xy 366.591107 -247.165834)
			(xy 366.552986 -247.134709) (xy 366.520351 -247.097872) (xy 366.494048 -247.056276) (xy 366.474757 -247.011)
			(xy 366.46298 -246.963216) (xy 366.45902 -246.914162) (xy 366.130078 -246.914162) (xy 366.129583 -246.938769)
			(xy 366.121688 -246.987346) (xy 366.106104 -247.034027) (xy 366.083233 -247.077604) (xy 366.053668 -247.116948)
			(xy 366.018175 -247.15104) (xy 365.977672 -247.178996) (xy 365.93321 -247.200094) (xy 365.885939 -247.213786)
			(xy 365.837084 -247.219718) (xy 365.787909 -247.217737) (xy 365.73969 -247.207893) (xy 365.693674 -247.190441)
			(xy 365.651053 -247.165834) (xy 365.612932 -247.134709) (xy 365.580297 -247.097872) (xy 365.553994 -247.056276)
			(xy 365.534703 -247.011) (xy 365.522926 -246.963216) (xy 365.518966 -246.914162) (xy 365.190024 -246.914162)
			(xy 365.189529 -246.938769) (xy 365.181634 -246.987346) (xy 365.16605 -247.034027) (xy 365.143179 -247.077604)
			(xy 365.113614 -247.116948) (xy 365.078121 -247.15104) (xy 365.037618 -247.178996) (xy 364.993156 -247.200094)
			(xy 364.945885 -247.213786) (xy 364.89703 -247.219718) (xy 364.847855 -247.217737) (xy 364.799636 -247.207893)
			(xy 364.75362 -247.190441) (xy 364.710999 -247.165834) (xy 364.672878 -247.134709) (xy 364.640243 -247.097872)
			(xy 364.61394 -247.056276) (xy 364.594649 -247.011) (xy 364.582872 -246.963216) (xy 364.578912 -246.914162)
			(xy 364.250224 -246.914162) (xy 364.249729 -246.938769) (xy 364.241834 -246.987346) (xy 364.22625 -247.034027)
			(xy 364.203379 -247.077604) (xy 364.173814 -247.116948) (xy 364.138321 -247.15104) (xy 364.097818 -247.178996)
			(xy 364.053356 -247.200094) (xy 364.006085 -247.213786) (xy 363.95723 -247.219718) (xy 363.908055 -247.217737)
			(xy 363.859836 -247.207893) (xy 363.81382 -247.190441) (xy 363.771199 -247.165834) (xy 363.733078 -247.134709)
			(xy 363.700443 -247.097872) (xy 363.67414 -247.056276) (xy 363.654849 -247.011) (xy 363.643072 -246.963216)
			(xy 363.639112 -246.914162) (xy 363.320584 -246.914162) (xy 363.320072 -246.939608) (xy 363.311908 -246.989842)
			(xy 363.295792 -247.038116) (xy 363.272141 -247.083179) (xy 363.241568 -247.123865) (xy 363.204864 -247.15912)
			(xy 363.16298 -247.18803) (xy 363.117001 -247.209847) (xy 363.068117 -247.224007) (xy 363.017596 -247.230141)
			(xy 362.966744 -247.228092) (xy 362.91688 -247.217912) (xy 362.869294 -247.199865) (xy 362.82522 -247.174419)
			(xy 362.785798 -247.142232) (xy 362.75205 -247.104138) (xy 362.724849 -247.061124) (xy 362.704901 -247.014304)
			(xy 362.692722 -246.96489) (xy 362.688627 -246.914162) (xy 362.38053 -246.914162) (xy 362.380018 -246.939608)
			(xy 362.371854 -246.989842) (xy 362.355738 -247.038116) (xy 362.332087 -247.083179) (xy 362.301514 -247.123865)
			(xy 362.26481 -247.15912) (xy 362.222926 -247.18803) (xy 362.176947 -247.209847) (xy 362.128063 -247.224007)
			(xy 362.077542 -247.230141) (xy 362.02669 -247.228092) (xy 361.976826 -247.217912) (xy 361.92924 -247.199865)
			(xy 361.885166 -247.174419) (xy 361.845744 -247.142232) (xy 361.811996 -247.104138) (xy 361.784795 -247.061124)
			(xy 361.764847 -247.014304) (xy 361.752668 -246.96489) (xy 361.748573 -246.914162) (xy 361.430062 -246.914162)
			(xy 361.429567 -246.938769) (xy 361.421672 -246.987346) (xy 361.406088 -247.034027) (xy 361.383217 -247.077604)
			(xy 361.353652 -247.116948) (xy 361.318159 -247.15104) (xy 361.277656 -247.178996) (xy 361.233194 -247.200094)
			(xy 361.185923 -247.213786) (xy 361.137068 -247.219718) (xy 361.087893 -247.217737) (xy 361.039674 -247.207893)
			(xy 360.993658 -247.190441) (xy 360.951037 -247.165834) (xy 360.912916 -247.134709) (xy 360.880281 -247.097872)
			(xy 360.853978 -247.056276) (xy 360.834687 -247.011) (xy 360.82291 -246.963216) (xy 360.81895 -246.914162)
			(xy 358.616504 -246.914162) (xy 358.616009 -246.938769) (xy 358.608114 -246.987346) (xy 358.59253 -247.034027)
			(xy 358.569659 -247.077604) (xy 358.540094 -247.116948) (xy 358.504601 -247.15104) (xy 358.464098 -247.178996)
			(xy 358.419636 -247.200094) (xy 358.372365 -247.213786) (xy 358.32351 -247.219718) (xy 358.274335 -247.217737)
			(xy 358.226116 -247.207893) (xy 358.1801 -247.190441) (xy 358.137479 -247.165834) (xy 358.099358 -247.134709)
			(xy 358.066723 -247.097872) (xy 358.04042 -247.056276) (xy 358.021129 -247.011) (xy 358.009352 -246.963216)
			(xy 358.005392 -246.914162) (xy 357.67645 -246.914162) (xy 357.675955 -246.938769) (xy 357.66806 -246.987346)
			(xy 357.652476 -247.034027) (xy 357.629605 -247.077604) (xy 357.60004 -247.116948) (xy 357.564547 -247.15104)
			(xy 357.524044 -247.178996) (xy 357.479582 -247.200094) (xy 357.432311 -247.213786) (xy 357.383456 -247.219718)
			(xy 357.334281 -247.217737) (xy 357.286062 -247.207893) (xy 357.240046 -247.190441) (xy 357.197425 -247.165834)
			(xy 357.159304 -247.134709) (xy 357.126669 -247.097872) (xy 357.100366 -247.056276) (xy 357.081075 -247.011)
			(xy 357.069298 -246.963216) (xy 357.065338 -246.914162) (xy 356.736396 -246.914162) (xy 356.735901 -246.938769)
			(xy 356.728006 -246.987346) (xy 356.712422 -247.034027) (xy 356.689551 -247.077604) (xy 356.659986 -247.116948)
			(xy 356.624493 -247.15104) (xy 356.58399 -247.178996) (xy 356.539528 -247.200094) (xy 356.492257 -247.213786)
			(xy 356.443402 -247.219718) (xy 356.394227 -247.217737) (xy 356.346008 -247.207893) (xy 356.299992 -247.190441)
			(xy 356.257371 -247.165834) (xy 356.21925 -247.134709) (xy 356.186615 -247.097872) (xy 356.160312 -247.056276)
			(xy 356.141021 -247.011) (xy 356.129244 -246.963216) (xy 356.125284 -246.914162) (xy 355.796342 -246.914162)
			(xy 355.795847 -246.938769) (xy 355.787952 -246.987346) (xy 355.772368 -247.034027) (xy 355.749497 -247.077604)
			(xy 355.719932 -247.116948) (xy 355.684439 -247.15104) (xy 355.643936 -247.178996) (xy 355.599474 -247.200094)
			(xy 355.552203 -247.213786) (xy 355.503348 -247.219718) (xy 355.454173 -247.217737) (xy 355.405954 -247.207893)
			(xy 355.359938 -247.190441) (xy 355.317317 -247.165834) (xy 355.279196 -247.134709) (xy 355.246561 -247.097872)
			(xy 355.220258 -247.056276) (xy 355.200967 -247.011) (xy 355.18919 -246.963216) (xy 355.18523 -246.914162)
			(xy 354.856542 -246.914162) (xy 354.856047 -246.938769) (xy 354.848152 -246.987346) (xy 354.832568 -247.034027)
			(xy 354.809697 -247.077604) (xy 354.780132 -247.116948) (xy 354.744639 -247.15104) (xy 354.704136 -247.178996)
			(xy 354.659674 -247.200094) (xy 354.612403 -247.213786) (xy 354.563548 -247.219718) (xy 354.514373 -247.217737)
			(xy 354.466154 -247.207893) (xy 354.420138 -247.190441) (xy 354.377517 -247.165834) (xy 354.339396 -247.134709)
			(xy 354.306761 -247.097872) (xy 354.280458 -247.056276) (xy 354.261167 -247.011) (xy 354.24939 -246.963216)
			(xy 354.24543 -246.914162) (xy 353.916488 -246.914162) (xy 353.915993 -246.938769) (xy 353.908098 -246.987346)
			(xy 353.892514 -247.034027) (xy 353.869643 -247.077604) (xy 353.840078 -247.116948) (xy 353.804585 -247.15104)
			(xy 353.764082 -247.178996) (xy 353.71962 -247.200094) (xy 353.672349 -247.213786) (xy 353.623494 -247.219718)
			(xy 353.574319 -247.217737) (xy 353.5261 -247.207893) (xy 353.480084 -247.190441) (xy 353.437463 -247.165834)
			(xy 353.399342 -247.134709) (xy 353.366707 -247.097872) (xy 353.340404 -247.056276) (xy 353.321113 -247.011)
			(xy 353.309336 -246.963216) (xy 353.305376 -246.914162) (xy 352.976434 -246.914162) (xy 352.975939 -246.938769)
			(xy 352.968044 -246.987346) (xy 352.95246 -247.034027) (xy 352.929589 -247.077604) (xy 352.900024 -247.116948)
			(xy 352.864531 -247.15104) (xy 352.824028 -247.178996) (xy 352.779566 -247.200094) (xy 352.732295 -247.213786)
			(xy 352.68344 -247.219718) (xy 352.634265 -247.217737) (xy 352.586046 -247.207893) (xy 352.54003 -247.190441)
			(xy 352.497409 -247.165834) (xy 352.459288 -247.134709) (xy 352.426653 -247.097872) (xy 352.40035 -247.056276)
			(xy 352.381059 -247.011) (xy 352.369282 -246.963216) (xy 352.365322 -246.914162) (xy 352.03638 -246.914162)
			(xy 352.035885 -246.938769) (xy 352.02799 -246.987346) (xy 352.012406 -247.034027) (xy 351.989535 -247.077604)
			(xy 351.95997 -247.116948) (xy 351.924477 -247.15104) (xy 351.883974 -247.178996) (xy 351.839512 -247.200094)
			(xy 351.792241 -247.213786) (xy 351.743386 -247.219718) (xy 351.694211 -247.217737) (xy 351.645992 -247.207893)
			(xy 351.599976 -247.190441) (xy 351.557355 -247.165834) (xy 351.519234 -247.134709) (xy 351.486599 -247.097872)
			(xy 351.460296 -247.056276) (xy 351.441005 -247.011) (xy 351.429228 -246.963216) (xy 351.425268 -246.914162)
			(xy 351.096326 -246.914162) (xy 351.095831 -246.938769) (xy 351.087936 -246.987346) (xy 351.072352 -247.034027)
			(xy 351.049481 -247.077604) (xy 351.019916 -247.116948) (xy 350.984423 -247.15104) (xy 350.94392 -247.178996)
			(xy 350.899458 -247.200094) (xy 350.852187 -247.213786) (xy 350.803332 -247.219718) (xy 350.754157 -247.217737)
			(xy 350.705938 -247.207893) (xy 350.659922 -247.190441) (xy 350.617301 -247.165834) (xy 350.57918 -247.134709)
			(xy 350.546545 -247.097872) (xy 350.520242 -247.056276) (xy 350.500951 -247.011) (xy 350.489174 -246.963216)
			(xy 350.485214 -246.914162) (xy 350.156526 -246.914162) (xy 350.156031 -246.938769) (xy 350.148136 -246.987346)
			(xy 350.132552 -247.034027) (xy 350.109681 -247.077604) (xy 350.080116 -247.116948) (xy 350.044623 -247.15104)
			(xy 350.00412 -247.178996) (xy 349.959658 -247.200094) (xy 349.912387 -247.213786) (xy 349.863532 -247.219718)
			(xy 349.814357 -247.217737) (xy 349.766138 -247.207893) (xy 349.720122 -247.190441) (xy 349.677501 -247.165834)
			(xy 349.63938 -247.134709) (xy 349.606745 -247.097872) (xy 349.580442 -247.056276) (xy 349.561151 -247.011)
			(xy 349.549374 -246.963216) (xy 349.545414 -246.914162) (xy 349.216472 -246.914162) (xy 349.215977 -246.938769)
			(xy 349.208082 -246.987346) (xy 349.192498 -247.034027) (xy 349.169627 -247.077604) (xy 349.140062 -247.116948)
			(xy 349.104569 -247.15104) (xy 349.064066 -247.178996) (xy 349.019604 -247.200094) (xy 348.972333 -247.213786)
			(xy 348.923478 -247.219718) (xy 348.874303 -247.217737) (xy 348.826084 -247.207893) (xy 348.780068 -247.190441)
			(xy 348.737447 -247.165834) (xy 348.699326 -247.134709) (xy 348.666691 -247.097872) (xy 348.640388 -247.056276)
			(xy 348.621097 -247.011) (xy 348.60932 -246.963216) (xy 348.60536 -246.914162) (xy 348.276418 -246.914162)
			(xy 348.275923 -246.938769) (xy 348.268028 -246.987346) (xy 348.252444 -247.034027) (xy 348.229573 -247.077604)
			(xy 348.200008 -247.116948) (xy 348.164515 -247.15104) (xy 348.124012 -247.178996) (xy 348.07955 -247.200094)
			(xy 348.032279 -247.213786) (xy 347.983424 -247.219718) (xy 347.934249 -247.217737) (xy 347.88603 -247.207893)
			(xy 347.840014 -247.190441) (xy 347.797393 -247.165834) (xy 347.759272 -247.134709) (xy 347.726637 -247.097872)
			(xy 347.700334 -247.056276) (xy 347.681043 -247.011) (xy 347.669266 -246.963216) (xy 347.665306 -246.914162)
			(xy 347.336364 -246.914162) (xy 347.335869 -246.938769) (xy 347.327974 -246.987346) (xy 347.31239 -247.034027)
			(xy 347.289519 -247.077604) (xy 347.259954 -247.116948) (xy 347.224461 -247.15104) (xy 347.183958 -247.178996)
			(xy 347.139496 -247.200094) (xy 347.092225 -247.213786) (xy 347.04337 -247.219718) (xy 346.994195 -247.217737)
			(xy 346.945976 -247.207893) (xy 346.89996 -247.190441) (xy 346.857339 -247.165834) (xy 346.819218 -247.134709)
			(xy 346.786583 -247.097872) (xy 346.76028 -247.056276) (xy 346.740989 -247.011) (xy 346.729212 -246.963216)
			(xy 346.725252 -246.914162) (xy 346.39631 -246.914162) (xy 346.395815 -246.938769) (xy 346.38792 -246.987346)
			(xy 346.372336 -247.034027) (xy 346.349465 -247.077604) (xy 346.3199 -247.116948) (xy 346.284407 -247.15104)
			(xy 346.243904 -247.178996) (xy 346.199442 -247.200094) (xy 346.152171 -247.213786) (xy 346.103316 -247.219718)
			(xy 346.054141 -247.217737) (xy 346.005922 -247.207893) (xy 345.959906 -247.190441) (xy 345.917285 -247.165834)
			(xy 345.879164 -247.134709) (xy 345.846529 -247.097872) (xy 345.820226 -247.056276) (xy 345.800935 -247.011)
			(xy 345.789158 -246.963216) (xy 345.785198 -246.914162) (xy 345.45651 -246.914162) (xy 345.456067 -246.938157)
			(xy 345.448565 -246.985557) (xy 345.433739 -247.0312) (xy 345.411956 -247.073962) (xy 345.383751 -247.112789)
			(xy 345.349819 -247.146725) (xy 345.310996 -247.174935) (xy 345.268237 -247.196724) (xy 345.222596 -247.211555)
			(xy 345.175197 -247.219064) (xy 345.151202 -247.21947) (xy 345.150948 -247.21947) (xy 345.123945 -247.218891)
			(xy 345.070779 -247.209396) (xy 345.020108 -247.190711) (xy 344.996516 -247.17756) (xy 344.996262 -247.177306)
			(xy 344.995754 -247.177052) (xy 344.990047 -247.174024) (xy 344.977572 -247.170686) (xy 344.971116 -247.170448)
			(xy 344.957146 -247.170194) (xy 344.868754 -247.22074) (xy 344.856816 -247.227598) (xy 344.8431 -247.25122)
			(xy 344.8431 -247.420892) (xy 344.84437 -247.432322) (xy 344.848434 -247.449086) (xy 344.848434 -247.44934)
			(xy 344.860372 -247.473724) (xy 344.86723 -247.482106) (xy 344.871802 -247.485662) (xy 344.890928 -247.501604)
			(xy 344.924233 -247.538612) (xy 344.951098 -247.58053) (xy 344.970813 -247.626248) (xy 344.982856 -247.674557)
			(xy 344.986907 -247.724168) (xy 345.315298 -247.724168) (xy 345.319258 -247.675114) (xy 345.331035 -247.62733)
			(xy 345.350326 -247.582054) (xy 345.376629 -247.540458) (xy 345.409264 -247.503621) (xy 345.447385 -247.472496)
			(xy 345.490006 -247.447889) (xy 345.536022 -247.430437) (xy 345.584241 -247.420593) (xy 345.633416 -247.418612)
			(xy 345.682271 -247.424544) (xy 345.729542 -247.438236) (xy 345.774004 -247.459334) (xy 345.814507 -247.48729)
			(xy 345.85 -247.521382) (xy 345.879565 -247.560726) (xy 345.902436 -247.604303) (xy 345.91802 -247.650984)
			(xy 345.925915 -247.699561) (xy 345.92641 -247.724168) (xy 346.255352 -247.724168) (xy 346.259312 -247.675114)
			(xy 346.271089 -247.62733) (xy 346.29038 -247.582054) (xy 346.316683 -247.540458) (xy 346.349318 -247.503621)
			(xy 346.387439 -247.472496) (xy 346.43006 -247.447889) (xy 346.476076 -247.430437) (xy 346.524295 -247.420593)
			(xy 346.57347 -247.418612) (xy 346.622325 -247.424544) (xy 346.669596 -247.438236) (xy 346.714058 -247.459334)
			(xy 346.754561 -247.48729) (xy 346.790054 -247.521382) (xy 346.819619 -247.560726) (xy 346.84249 -247.604303)
			(xy 346.858074 -247.650984) (xy 346.865969 -247.699561) (xy 346.866464 -247.724168) (xy 347.195406 -247.724168)
			(xy 347.199366 -247.675114) (xy 347.211143 -247.62733) (xy 347.230434 -247.582054) (xy 347.256737 -247.540458)
			(xy 347.289372 -247.503621) (xy 347.327493 -247.472496) (xy 347.370114 -247.447889) (xy 347.41613 -247.430437)
			(xy 347.464349 -247.420593) (xy 347.513524 -247.418612) (xy 347.562379 -247.424544) (xy 347.60965 -247.438236)
			(xy 347.654112 -247.459334) (xy 347.694615 -247.48729) (xy 347.730108 -247.521382) (xy 347.759673 -247.560726)
			(xy 347.782544 -247.604303) (xy 347.798128 -247.650984) (xy 347.806023 -247.699561) (xy 347.806518 -247.724168)
			(xy 348.135206 -247.724168) (xy 348.139166 -247.675114) (xy 348.150943 -247.62733) (xy 348.170234 -247.582054)
			(xy 348.196537 -247.540458) (xy 348.229172 -247.503621) (xy 348.267293 -247.472496) (xy 348.309914 -247.447889)
			(xy 348.35593 -247.430437) (xy 348.404149 -247.420593) (xy 348.453324 -247.418612) (xy 348.502179 -247.424544)
			(xy 348.54945 -247.438236) (xy 348.593912 -247.459334) (xy 348.634415 -247.48729) (xy 348.669908 -247.521382)
			(xy 348.699473 -247.560726) (xy 348.722344 -247.604303) (xy 348.737928 -247.650984) (xy 348.745823 -247.699561)
			(xy 348.746318 -247.724168) (xy 349.07526 -247.724168) (xy 349.07922 -247.675114) (xy 349.090997 -247.62733)
			(xy 349.110288 -247.582054) (xy 349.136591 -247.540458) (xy 349.169226 -247.503621) (xy 349.207347 -247.472496)
			(xy 349.249968 -247.447889) (xy 349.295984 -247.430437) (xy 349.344203 -247.420593) (xy 349.393378 -247.418612)
			(xy 349.442233 -247.424544) (xy 349.489504 -247.438236) (xy 349.533966 -247.459334) (xy 349.574469 -247.48729)
			(xy 349.609962 -247.521382) (xy 349.639527 -247.560726) (xy 349.662398 -247.604303) (xy 349.677982 -247.650984)
			(xy 349.685877 -247.699561) (xy 349.686372 -247.724168) (xy 350.015314 -247.724168) (xy 350.019274 -247.675114)
			(xy 350.031051 -247.62733) (xy 350.050342 -247.582054) (xy 350.076645 -247.540458) (xy 350.10928 -247.503621)
			(xy 350.147401 -247.472496) (xy 350.190022 -247.447889) (xy 350.236038 -247.430437) (xy 350.284257 -247.420593)
			(xy 350.333432 -247.418612) (xy 350.382287 -247.424544) (xy 350.429558 -247.438236) (xy 350.47402 -247.459334)
			(xy 350.514523 -247.48729) (xy 350.550016 -247.521382) (xy 350.579581 -247.560726) (xy 350.602452 -247.604303)
			(xy 350.618036 -247.650984) (xy 350.625931 -247.699561) (xy 350.626426 -247.724168) (xy 350.955368 -247.724168)
			(xy 350.959328 -247.675114) (xy 350.971105 -247.62733) (xy 350.990396 -247.582054) (xy 351.016699 -247.540458)
			(xy 351.049334 -247.503621) (xy 351.087455 -247.472496) (xy 351.130076 -247.447889) (xy 351.176092 -247.430437)
			(xy 351.224311 -247.420593) (xy 351.273486 -247.418612) (xy 351.322341 -247.424544) (xy 351.369612 -247.438236)
			(xy 351.414074 -247.459334) (xy 351.454577 -247.48729) (xy 351.49007 -247.521382) (xy 351.519635 -247.560726)
			(xy 351.542506 -247.604303) (xy 351.55809 -247.650984) (xy 351.565985 -247.699561) (xy 351.56648 -247.724168)
			(xy 351.895422 -247.724168) (xy 351.899382 -247.675114) (xy 351.911159 -247.62733) (xy 351.93045 -247.582054)
			(xy 351.956753 -247.540458) (xy 351.989388 -247.503621) (xy 352.027509 -247.472496) (xy 352.07013 -247.447889)
			(xy 352.116146 -247.430437) (xy 352.164365 -247.420593) (xy 352.21354 -247.418612) (xy 352.262395 -247.424544)
			(xy 352.309666 -247.438236) (xy 352.354128 -247.459334) (xy 352.394631 -247.48729) (xy 352.430124 -247.521382)
			(xy 352.459689 -247.560726) (xy 352.48256 -247.604303) (xy 352.498144 -247.650984) (xy 352.506039 -247.699561)
			(xy 352.506534 -247.724168) (xy 352.835222 -247.724168) (xy 352.839182 -247.675114) (xy 352.850959 -247.62733)
			(xy 352.87025 -247.582054) (xy 352.896553 -247.540458) (xy 352.929188 -247.503621) (xy 352.967309 -247.472496)
			(xy 353.00993 -247.447889) (xy 353.055946 -247.430437) (xy 353.104165 -247.420593) (xy 353.15334 -247.418612)
			(xy 353.202195 -247.424544) (xy 353.249466 -247.438236) (xy 353.293928 -247.459334) (xy 353.334431 -247.48729)
			(xy 353.369924 -247.521382) (xy 353.399489 -247.560726) (xy 353.42236 -247.604303) (xy 353.437944 -247.650984)
			(xy 353.445839 -247.699561) (xy 353.446334 -247.724168) (xy 353.775276 -247.724168) (xy 353.779236 -247.675114)
			(xy 353.791013 -247.62733) (xy 353.810304 -247.582054) (xy 353.836607 -247.540458) (xy 353.869242 -247.503621)
			(xy 353.907363 -247.472496) (xy 353.949984 -247.447889) (xy 353.996 -247.430437) (xy 354.044219 -247.420593)
			(xy 354.093394 -247.418612) (xy 354.142249 -247.424544) (xy 354.18952 -247.438236) (xy 354.233982 -247.459334)
			(xy 354.274485 -247.48729) (xy 354.309978 -247.521382) (xy 354.339543 -247.560726) (xy 354.362414 -247.604303)
			(xy 354.377998 -247.650984) (xy 354.385893 -247.699561) (xy 354.386388 -247.724168) (xy 354.71533 -247.724168)
			(xy 354.71929 -247.675114) (xy 354.731067 -247.62733) (xy 354.750358 -247.582054) (xy 354.776661 -247.540458)
			(xy 354.809296 -247.503621) (xy 354.847417 -247.472496) (xy 354.890038 -247.447889) (xy 354.936054 -247.430437)
			(xy 354.984273 -247.420593) (xy 355.033448 -247.418612) (xy 355.082303 -247.424544) (xy 355.129574 -247.438236)
			(xy 355.174036 -247.459334) (xy 355.214539 -247.48729) (xy 355.250032 -247.521382) (xy 355.279597 -247.560726)
			(xy 355.302468 -247.604303) (xy 355.318052 -247.650984) (xy 355.325947 -247.699561) (xy 355.326442 -247.724168)
			(xy 355.655384 -247.724168) (xy 355.659344 -247.675114) (xy 355.671121 -247.62733) (xy 355.690412 -247.582054)
			(xy 355.716715 -247.540458) (xy 355.74935 -247.503621) (xy 355.787471 -247.472496) (xy 355.830092 -247.447889)
			(xy 355.876108 -247.430437) (xy 355.924327 -247.420593) (xy 355.973502 -247.418612) (xy 356.022357 -247.424544)
			(xy 356.069628 -247.438236) (xy 356.11409 -247.459334) (xy 356.154593 -247.48729) (xy 356.190086 -247.521382)
			(xy 356.219651 -247.560726) (xy 356.242522 -247.604303) (xy 356.258106 -247.650984) (xy 356.266001 -247.699561)
			(xy 356.266496 -247.724168) (xy 356.595438 -247.724168) (xy 356.599398 -247.675114) (xy 356.611175 -247.62733)
			(xy 356.630466 -247.582054) (xy 356.656769 -247.540458) (xy 356.689404 -247.503621) (xy 356.727525 -247.472496)
			(xy 356.770146 -247.447889) (xy 356.816162 -247.430437) (xy 356.864381 -247.420593) (xy 356.913556 -247.418612)
			(xy 356.962411 -247.424544) (xy 357.009682 -247.438236) (xy 357.054144 -247.459334) (xy 357.094647 -247.48729)
			(xy 357.13014 -247.521382) (xy 357.159705 -247.560726) (xy 357.182576 -247.604303) (xy 357.19816 -247.650984)
			(xy 357.206055 -247.699561) (xy 357.20655 -247.724168) (xy 357.535238 -247.724168) (xy 357.539198 -247.675114)
			(xy 357.550975 -247.62733) (xy 357.570266 -247.582054) (xy 357.596569 -247.540458) (xy 357.629204 -247.503621)
			(xy 357.667325 -247.472496) (xy 357.709946 -247.447889) (xy 357.755962 -247.430437) (xy 357.804181 -247.420593)
			(xy 357.853356 -247.418612) (xy 357.902211 -247.424544) (xy 357.949482 -247.438236) (xy 357.988941 -247.45696)
			(xy 359.396541 -247.45696) (xy 359.400571 -247.404462) (xy 359.412568 -247.353194) (xy 359.432251 -247.304359)
			(xy 359.459157 -247.2591) (xy 359.492657 -247.218479) (xy 359.531965 -247.183448) (xy 359.57616 -247.154828)
			(xy 359.624205 -247.133289) (xy 359.674976 -247.119337) (xy 359.727281 -247.113299) (xy 359.779895 -247.115316)
			(xy 359.831585 -247.12534) (xy 359.881138 -247.143138) (xy 359.927394 -247.168291) (xy 359.969268 -247.20021)
			(xy 360.00578 -247.238148) (xy 360.036072 -247.281214) (xy 360.059435 -247.328399) (xy 360.075321 -247.378598)
			(xy 360.083358 -247.430634) (xy 360.083862 -247.45696) (xy 360.083358 -247.483286) (xy 360.075321 -247.535322)
			(xy 360.059435 -247.585521) (xy 360.036072 -247.632706) (xy 360.00578 -247.675772) (xy 359.969268 -247.71371)
			(xy 359.955548 -247.724168) (xy 361.289104 -247.724168) (xy 361.293064 -247.675114) (xy 361.304841 -247.62733)
			(xy 361.324132 -247.582054) (xy 361.350435 -247.540458) (xy 361.38307 -247.503621) (xy 361.421191 -247.472496)
			(xy 361.463812 -247.447889) (xy 361.509828 -247.430437) (xy 361.558047 -247.420593) (xy 361.607222 -247.418612)
			(xy 361.656077 -247.424544) (xy 361.703348 -247.438236) (xy 361.74781 -247.459334) (xy 361.788313 -247.48729)
			(xy 361.823806 -247.521382) (xy 361.853371 -247.560726) (xy 361.876242 -247.604303) (xy 361.891826 -247.650984)
			(xy 361.899721 -247.699561) (xy 361.900216 -247.724168) (xy 362.228904 -247.724168) (xy 362.232864 -247.675114)
			(xy 362.244641 -247.62733) (xy 362.263932 -247.582054) (xy 362.290235 -247.540458) (xy 362.32287 -247.503621)
			(xy 362.360991 -247.472496) (xy 362.403612 -247.447889) (xy 362.449628 -247.430437) (xy 362.497847 -247.420593)
			(xy 362.547022 -247.418612) (xy 362.595877 -247.424544) (xy 362.643148 -247.438236) (xy 362.68761 -247.459334)
			(xy 362.728113 -247.48729) (xy 362.763606 -247.521382) (xy 362.793171 -247.560726) (xy 362.816042 -247.604303)
			(xy 362.831626 -247.650984) (xy 362.839521 -247.699561) (xy 362.840016 -247.724168) (xy 363.168958 -247.724168)
			(xy 363.172918 -247.675114) (xy 363.184695 -247.62733) (xy 363.203986 -247.582054) (xy 363.230289 -247.540458)
			(xy 363.262924 -247.503621) (xy 363.301045 -247.472496) (xy 363.343666 -247.447889) (xy 363.389682 -247.430437)
			(xy 363.437901 -247.420593) (xy 363.487076 -247.418612) (xy 363.535931 -247.424544) (xy 363.583202 -247.438236)
			(xy 363.627664 -247.459334) (xy 363.668167 -247.48729) (xy 363.70366 -247.521382) (xy 363.733225 -247.560726)
			(xy 363.756096 -247.604303) (xy 363.77168 -247.650984) (xy 363.779575 -247.699561) (xy 363.78007 -247.724168)
			(xy 364.098581 -247.724168) (xy 364.102676 -247.67344) (xy 364.114855 -247.624026) (xy 364.134803 -247.577206)
			(xy 364.162004 -247.534192) (xy 364.195752 -247.496098) (xy 364.235174 -247.463911) (xy 364.279248 -247.438465)
			(xy 364.326834 -247.420418) (xy 364.376698 -247.410238) (xy 364.42755 -247.408189) (xy 364.478071 -247.414323)
			(xy 364.526955 -247.428483) (xy 364.572934 -247.4503) (xy 364.614818 -247.47921) (xy 364.651522 -247.514465)
			(xy 364.682095 -247.555151) (xy 364.705746 -247.600214) (xy 364.721862 -247.648488) (xy 364.730026 -247.698722)
			(xy 364.730538 -247.724168) (xy 365.038635 -247.724168) (xy 365.04273 -247.67344) (xy 365.054909 -247.624026)
			(xy 365.074857 -247.577206) (xy 365.102058 -247.534192) (xy 365.135806 -247.496098) (xy 365.175228 -247.463911)
			(xy 365.219302 -247.438465) (xy 365.266888 -247.420418) (xy 365.316752 -247.410238) (xy 365.367604 -247.408189)
			(xy 365.418125 -247.414323) (xy 365.467009 -247.428483) (xy 365.512988 -247.4503) (xy 365.554872 -247.47921)
			(xy 365.591576 -247.514465) (xy 365.622149 -247.555151) (xy 365.6458 -247.600214) (xy 365.661916 -247.648488)
			(xy 365.67008 -247.698722) (xy 365.670592 -247.724168) (xy 365.98912 -247.724168) (xy 365.99308 -247.675114)
			(xy 366.004857 -247.62733) (xy 366.024148 -247.582054) (xy 366.050451 -247.540458) (xy 366.083086 -247.503621)
			(xy 366.121207 -247.472496) (xy 366.163828 -247.447889) (xy 366.209844 -247.430437) (xy 366.258063 -247.420593)
			(xy 366.307238 -247.418612) (xy 366.356093 -247.424544) (xy 366.403364 -247.438236) (xy 366.447826 -247.459334)
			(xy 366.488329 -247.48729) (xy 366.523822 -247.521382) (xy 366.553387 -247.560726) (xy 366.576258 -247.604303)
			(xy 366.591842 -247.650984) (xy 366.599737 -247.699561) (xy 366.600232 -247.724168) (xy 366.918489 -247.724168)
			(xy 366.922584 -247.67344) (xy 366.934763 -247.624026) (xy 366.954711 -247.577206) (xy 366.981912 -247.534192)
			(xy 367.01566 -247.496098) (xy 367.055082 -247.463911) (xy 367.099156 -247.438465) (xy 367.146742 -247.420418)
			(xy 367.196606 -247.410238) (xy 367.247458 -247.408189) (xy 367.297979 -247.414323) (xy 367.346863 -247.428483)
			(xy 367.392842 -247.4503) (xy 367.434726 -247.47921) (xy 367.47143 -247.514465) (xy 367.502003 -247.555151)
			(xy 367.525654 -247.600214) (xy 367.54177 -247.648488) (xy 367.549934 -247.698722) (xy 367.550446 -247.724168)
			(xy 367.858543 -247.724168) (xy 367.862638 -247.67344) (xy 367.874817 -247.624026) (xy 367.894765 -247.577206)
			(xy 367.921966 -247.534192) (xy 367.955714 -247.496098) (xy 367.995136 -247.463911) (xy 368.03921 -247.438465)
			(xy 368.086796 -247.420418) (xy 368.13666 -247.410238) (xy 368.187512 -247.408189) (xy 368.238033 -247.414323)
			(xy 368.286917 -247.428483) (xy 368.332896 -247.4503) (xy 368.37478 -247.47921) (xy 368.411484 -247.514465)
			(xy 368.442057 -247.555151) (xy 368.465708 -247.600214) (xy 368.481824 -247.648488) (xy 368.489988 -247.698722)
			(xy 368.4905 -247.724168) (xy 368.809028 -247.724168) (xy 368.812988 -247.675114) (xy 368.824765 -247.62733)
			(xy 368.844056 -247.582054) (xy 368.870359 -247.540458) (xy 368.902994 -247.503621) (xy 368.941115 -247.472496)
			(xy 368.983736 -247.447889) (xy 369.029752 -247.430437) (xy 369.077971 -247.420593) (xy 369.127146 -247.418612)
			(xy 369.176001 -247.424544) (xy 369.223272 -247.438236) (xy 369.267734 -247.459334) (xy 369.308237 -247.48729)
			(xy 369.34373 -247.521382) (xy 369.373295 -247.560726) (xy 369.396166 -247.604303) (xy 369.41175 -247.650984)
			(xy 369.419645 -247.699561) (xy 369.42014 -247.724168) (xy 369.738651 -247.724168) (xy 369.742746 -247.67344)
			(xy 369.754925 -247.624026) (xy 369.774873 -247.577206) (xy 369.802074 -247.534192) (xy 369.835822 -247.496098)
			(xy 369.875244 -247.463911) (xy 369.919318 -247.438465) (xy 369.966904 -247.420418) (xy 370.016768 -247.410238)
			(xy 370.06762 -247.408189) (xy 370.118141 -247.414323) (xy 370.167025 -247.428483) (xy 370.213004 -247.4503)
			(xy 370.254888 -247.47921) (xy 370.291592 -247.514465) (xy 370.322165 -247.555151) (xy 370.345816 -247.600214)
			(xy 370.361932 -247.648488) (xy 370.370096 -247.698722) (xy 370.370608 -247.724168) (xy 370.678451 -247.724168)
			(xy 370.682546 -247.67344) (xy 370.694725 -247.624026) (xy 370.714673 -247.577206) (xy 370.741874 -247.534192)
			(xy 370.775622 -247.496098) (xy 370.815044 -247.463911) (xy 370.859118 -247.438465) (xy 370.906704 -247.420418)
			(xy 370.956568 -247.410238) (xy 371.00742 -247.408189) (xy 371.057941 -247.414323) (xy 371.106825 -247.428483)
			(xy 371.152804 -247.4503) (xy 371.194688 -247.47921) (xy 371.231392 -247.514465) (xy 371.261965 -247.555151)
			(xy 371.285616 -247.600214) (xy 371.301732 -247.648488) (xy 371.309896 -247.698722) (xy 371.310408 -247.724168)
			(xy 371.628936 -247.724168) (xy 371.632896 -247.675114) (xy 371.644673 -247.62733) (xy 371.663964 -247.582054)
			(xy 371.690267 -247.540458) (xy 371.722902 -247.503621) (xy 371.761023 -247.472496) (xy 371.803644 -247.447889)
			(xy 371.84966 -247.430437) (xy 371.897879 -247.420593) (xy 371.947054 -247.418612) (xy 371.995909 -247.424544)
			(xy 372.04318 -247.438236) (xy 372.087642 -247.459334) (xy 372.128145 -247.48729) (xy 372.163638 -247.521382)
			(xy 372.193203 -247.560726) (xy 372.216074 -247.604303) (xy 372.231658 -247.650984) (xy 372.239553 -247.699561)
			(xy 372.240048 -247.724168) (xy 372.558559 -247.724168) (xy 372.562654 -247.67344) (xy 372.574833 -247.624026)
			(xy 372.594781 -247.577206) (xy 372.621982 -247.534192) (xy 372.65573 -247.496098) (xy 372.695152 -247.463911)
			(xy 372.739226 -247.438465) (xy 372.786812 -247.420418) (xy 372.836676 -247.410238) (xy 372.887528 -247.408189)
			(xy 372.938049 -247.414323) (xy 372.986933 -247.428483) (xy 373.032912 -247.4503) (xy 373.074796 -247.47921)
			(xy 373.1115 -247.514465) (xy 373.142073 -247.555151) (xy 373.165724 -247.600214) (xy 373.18184 -247.648488)
			(xy 373.190004 -247.698722) (xy 373.190516 -247.724168) (xy 373.498613 -247.724168) (xy 373.502708 -247.67344)
			(xy 373.514887 -247.624026) (xy 373.534835 -247.577206) (xy 373.562036 -247.534192) (xy 373.595784 -247.496098)
			(xy 373.635206 -247.463911) (xy 373.67928 -247.438465) (xy 373.726866 -247.420418) (xy 373.77673 -247.410238)
			(xy 373.827582 -247.408189) (xy 373.878103 -247.414323) (xy 373.926987 -247.428483) (xy 373.972966 -247.4503)
			(xy 374.01485 -247.47921) (xy 374.051554 -247.514465) (xy 374.082127 -247.555151) (xy 374.105778 -247.600214)
			(xy 374.121894 -247.648488) (xy 374.130058 -247.698722) (xy 374.13057 -247.724168) (xy 374.130058 -247.749614)
			(xy 374.121894 -247.799848) (xy 374.105778 -247.848122) (xy 374.082127 -247.893185) (xy 374.051554 -247.933871)
			(xy 374.01485 -247.969126) (xy 373.972966 -247.998036) (xy 373.926987 -248.019853) (xy 373.878103 -248.034013)
			(xy 373.827582 -248.040147) (xy 373.77673 -248.038098) (xy 373.726866 -248.027918) (xy 373.67928 -248.009871)
			(xy 373.635206 -247.984425) (xy 373.595784 -247.952238) (xy 373.562036 -247.914144) (xy 373.534835 -247.87113)
			(xy 373.514887 -247.82431) (xy 373.502708 -247.774896) (xy 373.498613 -247.724168) (xy 373.190516 -247.724168)
			(xy 373.190004 -247.749614) (xy 373.18184 -247.799848) (xy 373.165724 -247.848122) (xy 373.142073 -247.893185)
			(xy 373.1115 -247.933871) (xy 373.074796 -247.969126) (xy 373.032912 -247.998036) (xy 372.986933 -248.019853)
			(xy 372.938049 -248.034013) (xy 372.887528 -248.040147) (xy 372.836676 -248.038098) (xy 372.786812 -248.027918)
			(xy 372.739226 -248.009871) (xy 372.695152 -247.984425) (xy 372.65573 -247.952238) (xy 372.621982 -247.914144)
			(xy 372.594781 -247.87113) (xy 372.574833 -247.82431) (xy 372.562654 -247.774896) (xy 372.558559 -247.724168)
			(xy 372.240048 -247.724168) (xy 372.239553 -247.748775) (xy 372.231658 -247.797352) (xy 372.216074 -247.844033)
			(xy 372.193203 -247.88761) (xy 372.163638 -247.926954) (xy 372.128145 -247.961046) (xy 372.087642 -247.989002)
			(xy 372.04318 -248.0101) (xy 371.995909 -248.023792) (xy 371.947054 -248.029724) (xy 371.897879 -248.027743)
			(xy 371.84966 -248.017899) (xy 371.803644 -248.000447) (xy 371.761023 -247.97584) (xy 371.722902 -247.944715)
			(xy 371.690267 -247.907878) (xy 371.663964 -247.866282) (xy 371.644673 -247.821006) (xy 371.632896 -247.773222)
			(xy 371.628936 -247.724168) (xy 371.310408 -247.724168) (xy 371.309896 -247.749614) (xy 371.301732 -247.799848)
			(xy 371.285616 -247.848122) (xy 371.261965 -247.893185) (xy 371.231392 -247.933871) (xy 371.194688 -247.969126)
			(xy 371.152804 -247.998036) (xy 371.106825 -248.019853) (xy 371.057941 -248.034013) (xy 371.00742 -248.040147)
			(xy 370.956568 -248.038098) (xy 370.906704 -248.027918) (xy 370.859118 -248.009871) (xy 370.815044 -247.984425)
			(xy 370.775622 -247.952238) (xy 370.741874 -247.914144) (xy 370.714673 -247.87113) (xy 370.694725 -247.82431)
			(xy 370.682546 -247.774896) (xy 370.678451 -247.724168) (xy 370.370608 -247.724168) (xy 370.370096 -247.749614)
			(xy 370.361932 -247.799848) (xy 370.345816 -247.848122) (xy 370.322165 -247.893185) (xy 370.291592 -247.933871)
			(xy 370.254888 -247.969126) (xy 370.213004 -247.998036) (xy 370.167025 -248.019853) (xy 370.118141 -248.034013)
			(xy 370.06762 -248.040147) (xy 370.016768 -248.038098) (xy 369.966904 -248.027918) (xy 369.919318 -248.009871)
			(xy 369.875244 -247.984425) (xy 369.835822 -247.952238) (xy 369.802074 -247.914144) (xy 369.774873 -247.87113)
			(xy 369.754925 -247.82431) (xy 369.742746 -247.774896) (xy 369.738651 -247.724168) (xy 369.42014 -247.724168)
			(xy 369.419645 -247.748775) (xy 369.41175 -247.797352) (xy 369.396166 -247.844033) (xy 369.373295 -247.88761)
			(xy 369.34373 -247.926954) (xy 369.308237 -247.961046) (xy 369.267734 -247.989002) (xy 369.223272 -248.0101)
			(xy 369.176001 -248.023792) (xy 369.127146 -248.029724) (xy 369.077971 -248.027743) (xy 369.029752 -248.017899)
			(xy 368.983736 -248.000447) (xy 368.941115 -247.97584) (xy 368.902994 -247.944715) (xy 368.870359 -247.907878)
			(xy 368.844056 -247.866282) (xy 368.824765 -247.821006) (xy 368.812988 -247.773222) (xy 368.809028 -247.724168)
			(xy 368.4905 -247.724168) (xy 368.489988 -247.749614) (xy 368.481824 -247.799848) (xy 368.465708 -247.848122)
			(xy 368.442057 -247.893185) (xy 368.411484 -247.933871) (xy 368.37478 -247.969126) (xy 368.332896 -247.998036)
			(xy 368.286917 -248.019853) (xy 368.238033 -248.034013) (xy 368.187512 -248.040147) (xy 368.13666 -248.038098)
			(xy 368.086796 -248.027918) (xy 368.03921 -248.009871) (xy 367.995136 -247.984425) (xy 367.955714 -247.952238)
			(xy 367.921966 -247.914144) (xy 367.894765 -247.87113) (xy 367.874817 -247.82431) (xy 367.862638 -247.774896)
			(xy 367.858543 -247.724168) (xy 367.550446 -247.724168) (xy 367.549934 -247.749614) (xy 367.54177 -247.799848)
			(xy 367.525654 -247.848122) (xy 367.502003 -247.893185) (xy 367.47143 -247.933871) (xy 367.434726 -247.969126)
			(xy 367.392842 -247.998036) (xy 367.346863 -248.019853) (xy 367.297979 -248.034013) (xy 367.247458 -248.040147)
			(xy 367.196606 -248.038098) (xy 367.146742 -248.027918) (xy 367.099156 -248.009871) (xy 367.055082 -247.984425)
			(xy 367.01566 -247.952238) (xy 366.981912 -247.914144) (xy 366.954711 -247.87113) (xy 366.934763 -247.82431)
			(xy 366.922584 -247.774896) (xy 366.918489 -247.724168) (xy 366.600232 -247.724168) (xy 366.599737 -247.748775)
			(xy 366.591842 -247.797352) (xy 366.576258 -247.844033) (xy 366.553387 -247.88761) (xy 366.523822 -247.926954)
			(xy 366.488329 -247.961046) (xy 366.447826 -247.989002) (xy 366.403364 -248.0101) (xy 366.356093 -248.023792)
			(xy 366.307238 -248.029724) (xy 366.258063 -248.027743) (xy 366.209844 -248.017899) (xy 366.163828 -248.000447)
			(xy 366.121207 -247.97584) (xy 366.083086 -247.944715) (xy 366.050451 -247.907878) (xy 366.024148 -247.866282)
			(xy 366.004857 -247.821006) (xy 365.99308 -247.773222) (xy 365.98912 -247.724168) (xy 365.670592 -247.724168)
			(xy 365.67008 -247.749614) (xy 365.661916 -247.799848) (xy 365.6458 -247.848122) (xy 365.622149 -247.893185)
			(xy 365.591576 -247.933871) (xy 365.554872 -247.969126) (xy 365.512988 -247.998036) (xy 365.467009 -248.019853)
			(xy 365.418125 -248.034013) (xy 365.367604 -248.040147) (xy 365.316752 -248.038098) (xy 365.266888 -248.027918)
			(xy 365.219302 -248.009871) (xy 365.175228 -247.984425) (xy 365.135806 -247.952238) (xy 365.102058 -247.914144)
			(xy 365.074857 -247.87113) (xy 365.054909 -247.82431) (xy 365.04273 -247.774896) (xy 365.038635 -247.724168)
			(xy 364.730538 -247.724168) (xy 364.730026 -247.749614) (xy 364.721862 -247.799848) (xy 364.705746 -247.848122)
			(xy 364.682095 -247.893185) (xy 364.651522 -247.933871) (xy 364.614818 -247.969126) (xy 364.572934 -247.998036)
			(xy 364.526955 -248.019853) (xy 364.478071 -248.034013) (xy 364.42755 -248.040147) (xy 364.376698 -248.038098)
			(xy 364.326834 -248.027918) (xy 364.279248 -248.009871) (xy 364.235174 -247.984425) (xy 364.195752 -247.952238)
			(xy 364.162004 -247.914144) (xy 364.134803 -247.87113) (xy 364.114855 -247.82431) (xy 364.102676 -247.774896)
			(xy 364.098581 -247.724168) (xy 363.78007 -247.724168) (xy 363.779575 -247.748775) (xy 363.77168 -247.797352)
			(xy 363.756096 -247.844033) (xy 363.733225 -247.88761) (xy 363.70366 -247.926954) (xy 363.668167 -247.961046)
			(xy 363.627664 -247.989002) (xy 363.583202 -248.0101) (xy 363.535931 -248.023792) (xy 363.487076 -248.029724)
			(xy 363.437901 -248.027743) (xy 363.389682 -248.017899) (xy 363.343666 -248.000447) (xy 363.301045 -247.97584)
			(xy 363.262924 -247.944715) (xy 363.230289 -247.907878) (xy 363.203986 -247.866282) (xy 363.184695 -247.821006)
			(xy 363.172918 -247.773222) (xy 363.168958 -247.724168) (xy 362.840016 -247.724168) (xy 362.839521 -247.748775)
			(xy 362.831626 -247.797352) (xy 362.816042 -247.844033) (xy 362.793171 -247.88761) (xy 362.763606 -247.926954)
			(xy 362.728113 -247.961046) (xy 362.68761 -247.989002) (xy 362.643148 -248.0101) (xy 362.595877 -248.023792)
			(xy 362.547022 -248.029724) (xy 362.497847 -248.027743) (xy 362.449628 -248.017899) (xy 362.403612 -248.000447)
			(xy 362.360991 -247.97584) (xy 362.32287 -247.944715) (xy 362.290235 -247.907878) (xy 362.263932 -247.866282)
			(xy 362.244641 -247.821006) (xy 362.232864 -247.773222) (xy 362.228904 -247.724168) (xy 361.900216 -247.724168)
			(xy 361.899721 -247.748775) (xy 361.891826 -247.797352) (xy 361.876242 -247.844033) (xy 361.853371 -247.88761)
			(xy 361.823806 -247.926954) (xy 361.788313 -247.961046) (xy 361.74781 -247.989002) (xy 361.703348 -248.0101)
			(xy 361.656077 -248.023792) (xy 361.607222 -248.029724) (xy 361.558047 -248.027743) (xy 361.509828 -248.017899)
			(xy 361.463812 -248.000447) (xy 361.421191 -247.97584) (xy 361.38307 -247.944715) (xy 361.350435 -247.907878)
			(xy 361.324132 -247.866282) (xy 361.304841 -247.821006) (xy 361.293064 -247.773222) (xy 361.289104 -247.724168)
			(xy 359.955548 -247.724168) (xy 359.927394 -247.745629) (xy 359.881138 -247.770782) (xy 359.831585 -247.78858)
			(xy 359.779895 -247.798604) (xy 359.727281 -247.800621) (xy 359.674976 -247.794583) (xy 359.624205 -247.780631)
			(xy 359.57616 -247.759092) (xy 359.531965 -247.730472) (xy 359.492657 -247.695441) (xy 359.459157 -247.65482)
			(xy 359.432251 -247.609561) (xy 359.412568 -247.560726) (xy 359.400571 -247.509458) (xy 359.396541 -247.45696)
			(xy 357.988941 -247.45696) (xy 357.993944 -247.459334) (xy 358.034447 -247.48729) (xy 358.06994 -247.521382)
			(xy 358.099505 -247.560726) (xy 358.122376 -247.604303) (xy 358.13796 -247.650984) (xy 358.145855 -247.699561)
			(xy 358.14635 -247.724168) (xy 358.145855 -247.748775) (xy 358.13796 -247.797352) (xy 358.122376 -247.844033)
			(xy 358.099505 -247.88761) (xy 358.06994 -247.926954) (xy 358.034447 -247.961046) (xy 357.993944 -247.989002)
			(xy 357.949482 -248.0101) (xy 357.902211 -248.023792) (xy 357.853356 -248.029724) (xy 357.804181 -248.027743)
			(xy 357.755962 -248.017899) (xy 357.709946 -248.000447) (xy 357.667325 -247.97584) (xy 357.629204 -247.944715)
			(xy 357.596569 -247.907878) (xy 357.570266 -247.866282) (xy 357.550975 -247.821006) (xy 357.539198 -247.773222)
			(xy 357.535238 -247.724168) (xy 357.20655 -247.724168) (xy 357.206055 -247.748775) (xy 357.19816 -247.797352)
			(xy 357.182576 -247.844033) (xy 357.159705 -247.88761) (xy 357.13014 -247.926954) (xy 357.094647 -247.961046)
			(xy 357.054144 -247.989002) (xy 357.009682 -248.0101) (xy 356.962411 -248.023792) (xy 356.913556 -248.029724)
			(xy 356.864381 -248.027743) (xy 356.816162 -248.017899) (xy 356.770146 -248.000447) (xy 356.727525 -247.97584)
			(xy 356.689404 -247.944715) (xy 356.656769 -247.907878) (xy 356.630466 -247.866282) (xy 356.611175 -247.821006)
			(xy 356.599398 -247.773222) (xy 356.595438 -247.724168) (xy 356.266496 -247.724168) (xy 356.266001 -247.748775)
			(xy 356.258106 -247.797352) (xy 356.242522 -247.844033) (xy 356.219651 -247.88761) (xy 356.190086 -247.926954)
			(xy 356.154593 -247.961046) (xy 356.11409 -247.989002) (xy 356.069628 -248.0101) (xy 356.022357 -248.023792)
			(xy 355.973502 -248.029724) (xy 355.924327 -248.027743) (xy 355.876108 -248.017899) (xy 355.830092 -248.000447)
			(xy 355.787471 -247.97584) (xy 355.74935 -247.944715) (xy 355.716715 -247.907878) (xy 355.690412 -247.866282)
			(xy 355.671121 -247.821006) (xy 355.659344 -247.773222) (xy 355.655384 -247.724168) (xy 355.326442 -247.724168)
			(xy 355.325947 -247.748775) (xy 355.318052 -247.797352) (xy 355.302468 -247.844033) (xy 355.279597 -247.88761)
			(xy 355.250032 -247.926954) (xy 355.214539 -247.961046) (xy 355.174036 -247.989002) (xy 355.129574 -248.0101)
			(xy 355.082303 -248.023792) (xy 355.033448 -248.029724) (xy 354.984273 -248.027743) (xy 354.936054 -248.017899)
			(xy 354.890038 -248.000447) (xy 354.847417 -247.97584) (xy 354.809296 -247.944715) (xy 354.776661 -247.907878)
			(xy 354.750358 -247.866282) (xy 354.731067 -247.821006) (xy 354.71929 -247.773222) (xy 354.71533 -247.724168)
			(xy 354.386388 -247.724168) (xy 354.385893 -247.748775) (xy 354.377998 -247.797352) (xy 354.362414 -247.844033)
			(xy 354.339543 -247.88761) (xy 354.309978 -247.926954) (xy 354.274485 -247.961046) (xy 354.233982 -247.989002)
			(xy 354.18952 -248.0101) (xy 354.142249 -248.023792) (xy 354.093394 -248.029724) (xy 354.044219 -248.027743)
			(xy 353.996 -248.017899) (xy 353.949984 -248.000447) (xy 353.907363 -247.97584) (xy 353.869242 -247.944715)
			(xy 353.836607 -247.907878) (xy 353.810304 -247.866282) (xy 353.791013 -247.821006) (xy 353.779236 -247.773222)
			(xy 353.775276 -247.724168) (xy 353.446334 -247.724168) (xy 353.445839 -247.748775) (xy 353.437944 -247.797352)
			(xy 353.42236 -247.844033) (xy 353.399489 -247.88761) (xy 353.369924 -247.926954) (xy 353.334431 -247.961046)
			(xy 353.293928 -247.989002) (xy 353.249466 -248.0101) (xy 353.202195 -248.023792) (xy 353.15334 -248.029724)
			(xy 353.104165 -248.027743) (xy 353.055946 -248.017899) (xy 353.00993 -248.000447) (xy 352.967309 -247.97584)
			(xy 352.929188 -247.944715) (xy 352.896553 -247.907878) (xy 352.87025 -247.866282) (xy 352.850959 -247.821006)
			(xy 352.839182 -247.773222) (xy 352.835222 -247.724168) (xy 352.506534 -247.724168) (xy 352.506039 -247.748775)
			(xy 352.498144 -247.797352) (xy 352.48256 -247.844033) (xy 352.459689 -247.88761) (xy 352.430124 -247.926954)
			(xy 352.394631 -247.961046) (xy 352.354128 -247.989002) (xy 352.309666 -248.0101) (xy 352.262395 -248.023792)
			(xy 352.21354 -248.029724) (xy 352.164365 -248.027743) (xy 352.116146 -248.017899) (xy 352.07013 -248.000447)
			(xy 352.027509 -247.97584) (xy 351.989388 -247.944715) (xy 351.956753 -247.907878) (xy 351.93045 -247.866282)
			(xy 351.911159 -247.821006) (xy 351.899382 -247.773222) (xy 351.895422 -247.724168) (xy 351.56648 -247.724168)
			(xy 351.565985 -247.748775) (xy 351.55809 -247.797352) (xy 351.542506 -247.844033) (xy 351.519635 -247.88761)
			(xy 351.49007 -247.926954) (xy 351.454577 -247.961046) (xy 351.414074 -247.989002) (xy 351.369612 -248.0101)
			(xy 351.322341 -248.023792) (xy 351.273486 -248.029724) (xy 351.224311 -248.027743) (xy 351.176092 -248.017899)
			(xy 351.130076 -248.000447) (xy 351.087455 -247.97584) (xy 351.049334 -247.944715) (xy 351.016699 -247.907878)
			(xy 350.990396 -247.866282) (xy 350.971105 -247.821006) (xy 350.959328 -247.773222) (xy 350.955368 -247.724168)
			(xy 350.626426 -247.724168) (xy 350.625931 -247.748775) (xy 350.618036 -247.797352) (xy 350.602452 -247.844033)
			(xy 350.579581 -247.88761) (xy 350.550016 -247.926954) (xy 350.514523 -247.961046) (xy 350.47402 -247.989002)
			(xy 350.429558 -248.0101) (xy 350.382287 -248.023792) (xy 350.333432 -248.029724) (xy 350.284257 -248.027743)
			(xy 350.236038 -248.017899) (xy 350.190022 -248.000447) (xy 350.147401 -247.97584) (xy 350.10928 -247.944715)
			(xy 350.076645 -247.907878) (xy 350.050342 -247.866282) (xy 350.031051 -247.821006) (xy 350.019274 -247.773222)
			(xy 350.015314 -247.724168) (xy 349.686372 -247.724168) (xy 349.685877 -247.748775) (xy 349.677982 -247.797352)
			(xy 349.662398 -247.844033) (xy 349.639527 -247.88761) (xy 349.609962 -247.926954) (xy 349.574469 -247.961046)
			(xy 349.533966 -247.989002) (xy 349.489504 -248.0101) (xy 349.442233 -248.023792) (xy 349.393378 -248.029724)
			(xy 349.344203 -248.027743) (xy 349.295984 -248.017899) (xy 349.249968 -248.000447) (xy 349.207347 -247.97584)
			(xy 349.169226 -247.944715) (xy 349.136591 -247.907878) (xy 349.110288 -247.866282) (xy 349.090997 -247.821006)
			(xy 349.07922 -247.773222) (xy 349.07526 -247.724168) (xy 348.746318 -247.724168) (xy 348.745823 -247.748775)
			(xy 348.737928 -247.797352) (xy 348.722344 -247.844033) (xy 348.699473 -247.88761) (xy 348.669908 -247.926954)
			(xy 348.634415 -247.961046) (xy 348.593912 -247.989002) (xy 348.54945 -248.0101) (xy 348.502179 -248.023792)
			(xy 348.453324 -248.029724) (xy 348.404149 -248.027743) (xy 348.35593 -248.017899) (xy 348.309914 -248.000447)
			(xy 348.267293 -247.97584) (xy 348.229172 -247.944715) (xy 348.196537 -247.907878) (xy 348.170234 -247.866282)
			(xy 348.150943 -247.821006) (xy 348.139166 -247.773222) (xy 348.135206 -247.724168) (xy 347.806518 -247.724168)
			(xy 347.806023 -247.748775) (xy 347.798128 -247.797352) (xy 347.782544 -247.844033) (xy 347.759673 -247.88761)
			(xy 347.730108 -247.926954) (xy 347.694615 -247.961046) (xy 347.654112 -247.989002) (xy 347.60965 -248.0101)
			(xy 347.562379 -248.023792) (xy 347.513524 -248.029724) (xy 347.464349 -248.027743) (xy 347.41613 -248.017899)
			(xy 347.370114 -248.000447) (xy 347.327493 -247.97584) (xy 347.289372 -247.944715) (xy 347.256737 -247.907878)
			(xy 347.230434 -247.866282) (xy 347.211143 -247.821006) (xy 347.199366 -247.773222) (xy 347.195406 -247.724168)
			(xy 346.866464 -247.724168) (xy 346.865969 -247.748775) (xy 346.858074 -247.797352) (xy 346.84249 -247.844033)
			(xy 346.819619 -247.88761) (xy 346.790054 -247.926954) (xy 346.754561 -247.961046) (xy 346.714058 -247.989002)
			(xy 346.669596 -248.0101) (xy 346.622325 -248.023792) (xy 346.57347 -248.029724) (xy 346.524295 -248.027743)
			(xy 346.476076 -248.017899) (xy 346.43006 -248.000447) (xy 346.387439 -247.97584) (xy 346.349318 -247.944715)
			(xy 346.316683 -247.907878) (xy 346.29038 -247.866282) (xy 346.271089 -247.821006) (xy 346.259312 -247.773222)
			(xy 346.255352 -247.724168) (xy 345.92641 -247.724168) (xy 345.925915 -247.748775) (xy 345.91802 -247.797352)
			(xy 345.902436 -247.844033) (xy 345.879565 -247.88761) (xy 345.85 -247.926954) (xy 345.814507 -247.961046)
			(xy 345.774004 -247.989002) (xy 345.729542 -248.0101) (xy 345.682271 -248.023792) (xy 345.633416 -248.029724)
			(xy 345.584241 -248.027743) (xy 345.536022 -248.017899) (xy 345.490006 -248.000447) (xy 345.447385 -247.97584)
			(xy 345.409264 -247.944715) (xy 345.376629 -247.907878) (xy 345.350326 -247.866282) (xy 345.331035 -247.821006)
			(xy 345.319258 -247.773222) (xy 345.315298 -247.724168) (xy 344.986907 -247.724168) (xy 344.986908 -247.72418)
			(xy 344.982863 -247.773803) (xy 344.970826 -247.822114) (xy 344.951117 -247.867835) (xy 344.924257 -247.909756)
			(xy 344.890957 -247.946768) (xy 344.871802 -247.962674) (xy 344.86723 -247.96623) (xy 344.860372 -247.974612)
			(xy 344.848434 -247.998996) (xy 344.84564 -248.004584) (xy 344.8431 -248.015506) (xy 344.8431 -248.586498)
			(xy 344.843523 -248.596568) (xy 344.851237 -248.615173) (xy 344.858086 -248.622566) (xy 344.980768 -248.745248)
			(xy 344.988168 -248.752089) (xy 345.006766 -248.759807) (xy 345.016836 -248.760234) (xy 346.643706 -248.760234)
			(xy 346.655684 -248.759586) (xy 346.677024 -248.748708) (xy 346.6846 -248.739406) (xy 346.74048 -248.663206)
			(xy 346.74429 -248.63933) (xy 346.74048 -248.627646) (xy 346.733615 -248.60489) (xy 346.726214 -248.557939)
			(xy 346.725748 -248.534174) (xy 346.72627 -248.508919) (xy 346.734583 -248.459097) (xy 346.750984 -248.411323)
			(xy 346.775025 -248.3669) (xy 346.806049 -248.32704) (xy 346.843211 -248.29283) (xy 346.885497 -248.265204)
			(xy 346.931753 -248.244914) (xy 346.980718 -248.232514) (xy 347.031056 -248.228343) (xy 347.081394 -248.232514)
			(xy 347.130359 -248.244914) (xy 347.176615 -248.265204) (xy 347.218901 -248.29283) (xy 347.256063 -248.32704)
			(xy 347.287087 -248.3669) (xy 347.311128 -248.411323) (xy 347.327529 -248.459097) (xy 347.335842 -248.508919)
			(xy 347.336364 -248.534174) (xy 349.545414 -248.534174) (xy 349.549374 -248.48512) (xy 349.561151 -248.437336)
			(xy 349.580442 -248.39206) (xy 349.606745 -248.350464) (xy 349.63938 -248.313627) (xy 349.677501 -248.282502)
			(xy 349.720122 -248.257895) (xy 349.766138 -248.240443) (xy 349.814357 -248.230599) (xy 349.863532 -248.228618)
			(xy 349.912387 -248.23455) (xy 349.959658 -248.248242) (xy 350.00412 -248.26934) (xy 350.044623 -248.297296)
			(xy 350.080116 -248.331388) (xy 350.109681 -248.370732) (xy 350.132552 -248.414309) (xy 350.148136 -248.46099)
			(xy 350.156031 -248.509567) (xy 350.156526 -248.534174) (xy 352.365322 -248.534174) (xy 352.369282 -248.48512)
			(xy 352.381059 -248.437336) (xy 352.40035 -248.39206) (xy 352.426653 -248.350464) (xy 352.459288 -248.313627)
			(xy 352.497409 -248.282502) (xy 352.54003 -248.257895) (xy 352.586046 -248.240443) (xy 352.634265 -248.230599)
			(xy 352.68344 -248.228618) (xy 352.732295 -248.23455) (xy 352.779566 -248.248242) (xy 352.824028 -248.26934)
			(xy 352.864531 -248.297296) (xy 352.900024 -248.331388) (xy 352.929589 -248.370732) (xy 352.95246 -248.414309)
			(xy 352.968044 -248.46099) (xy 352.975939 -248.509567) (xy 352.976434 -248.534174) (xy 355.18523 -248.534174)
			(xy 355.18919 -248.48512) (xy 355.200967 -248.437336) (xy 355.220258 -248.39206) (xy 355.246561 -248.350464)
			(xy 355.279196 -248.313627) (xy 355.317317 -248.282502) (xy 355.359938 -248.257895) (xy 355.405954 -248.240443)
			(xy 355.454173 -248.230599) (xy 355.503348 -248.228618) (xy 355.552203 -248.23455) (xy 355.599474 -248.248242)
			(xy 355.643936 -248.26934) (xy 355.684439 -248.297296) (xy 355.719932 -248.331388) (xy 355.749497 -248.370732)
			(xy 355.772368 -248.414309) (xy 355.787952 -248.46099) (xy 355.795847 -248.509567) (xy 355.796342 -248.534174)
			(xy 356.125284 -248.534174) (xy 356.129244 -248.48512) (xy 356.141021 -248.437336) (xy 356.160312 -248.39206)
			(xy 356.186615 -248.350464) (xy 356.21925 -248.313627) (xy 356.257371 -248.282502) (xy 356.299992 -248.257895)
			(xy 356.346008 -248.240443) (xy 356.394227 -248.230599) (xy 356.443402 -248.228618) (xy 356.492257 -248.23455)
			(xy 356.539528 -248.248242) (xy 356.58399 -248.26934) (xy 356.624493 -248.297296) (xy 356.659986 -248.331388)
			(xy 356.689551 -248.370732) (xy 356.712422 -248.414309) (xy 356.728006 -248.46099) (xy 356.735901 -248.509567)
			(xy 356.736396 -248.534174) (xy 357.065338 -248.534174) (xy 357.069298 -248.48512) (xy 357.081075 -248.437336)
			(xy 357.100366 -248.39206) (xy 357.126669 -248.350464) (xy 357.159304 -248.313627) (xy 357.197425 -248.282502)
			(xy 357.240046 -248.257895) (xy 357.286062 -248.240443) (xy 357.334281 -248.230599) (xy 357.383456 -248.228618)
			(xy 357.432311 -248.23455) (xy 357.479582 -248.248242) (xy 357.524044 -248.26934) (xy 357.564547 -248.297296)
			(xy 357.60004 -248.331388) (xy 357.629605 -248.370732) (xy 357.652476 -248.414309) (xy 357.66806 -248.46099)
			(xy 357.675955 -248.509567) (xy 357.67645 -248.534174) (xy 358.005392 -248.534174) (xy 358.009352 -248.48512)
			(xy 358.021129 -248.437336) (xy 358.04042 -248.39206) (xy 358.066723 -248.350464) (xy 358.099358 -248.313627)
			(xy 358.137479 -248.282502) (xy 358.1801 -248.257895) (xy 358.226116 -248.240443) (xy 358.274335 -248.230599)
			(xy 358.32351 -248.228618) (xy 358.372365 -248.23455) (xy 358.419636 -248.248242) (xy 358.464098 -248.26934)
			(xy 358.504601 -248.297296) (xy 358.540094 -248.331388) (xy 358.569659 -248.370732) (xy 358.59253 -248.414309)
			(xy 358.608114 -248.46099) (xy 358.616009 -248.509567) (xy 358.616504 -248.534174) (xy 360.81895 -248.534174)
			(xy 360.82291 -248.48512) (xy 360.834687 -248.437336) (xy 360.853978 -248.39206) (xy 360.880281 -248.350464)
			(xy 360.912916 -248.313627) (xy 360.951037 -248.282502) (xy 360.993658 -248.257895) (xy 361.039674 -248.240443)
			(xy 361.087893 -248.230599) (xy 361.137068 -248.228618) (xy 361.185923 -248.23455) (xy 361.233194 -248.248242)
			(xy 361.277656 -248.26934) (xy 361.318159 -248.297296) (xy 361.353652 -248.331388) (xy 361.383217 -248.370732)
			(xy 361.406088 -248.414309) (xy 361.421672 -248.46099) (xy 361.429567 -248.509567) (xy 361.430062 -248.534174)
			(xy 361.748573 -248.534174) (xy 361.752668 -248.483446) (xy 361.764847 -248.434032) (xy 361.784795 -248.387212)
			(xy 361.811996 -248.344198) (xy 361.845744 -248.306104) (xy 361.885166 -248.273917) (xy 361.92924 -248.248471)
			(xy 361.976826 -248.230424) (xy 362.02669 -248.220244) (xy 362.077542 -248.218195) (xy 362.128063 -248.224329)
			(xy 362.176947 -248.238489) (xy 362.222926 -248.260306) (xy 362.26481 -248.289216) (xy 362.301514 -248.324471)
			(xy 362.332087 -248.365157) (xy 362.355738 -248.41022) (xy 362.371854 -248.458494) (xy 362.380018 -248.508728)
			(xy 362.38053 -248.534174) (xy 362.688627 -248.534174) (xy 362.692722 -248.483446) (xy 362.704901 -248.434032)
			(xy 362.724849 -248.387212) (xy 362.75205 -248.344198) (xy 362.785798 -248.306104) (xy 362.82522 -248.273917)
			(xy 362.869294 -248.248471) (xy 362.91688 -248.230424) (xy 362.966744 -248.220244) (xy 363.017596 -248.218195)
			(xy 363.068117 -248.224329) (xy 363.117001 -248.238489) (xy 363.16298 -248.260306) (xy 363.204864 -248.289216)
			(xy 363.241568 -248.324471) (xy 363.272141 -248.365157) (xy 363.295792 -248.41022) (xy 363.311908 -248.458494)
			(xy 363.320072 -248.508728) (xy 363.320584 -248.534174) (xy 363.639112 -248.534174) (xy 363.643072 -248.48512)
			(xy 363.654849 -248.437336) (xy 363.67414 -248.39206) (xy 363.700443 -248.350464) (xy 363.733078 -248.313627)
			(xy 363.771199 -248.282502) (xy 363.81382 -248.257895) (xy 363.859836 -248.240443) (xy 363.908055 -248.230599)
			(xy 363.95723 -248.228618) (xy 364.006085 -248.23455) (xy 364.053356 -248.248242) (xy 364.097818 -248.26934)
			(xy 364.138321 -248.297296) (xy 364.173814 -248.331388) (xy 364.203379 -248.370732) (xy 364.22625 -248.414309)
			(xy 364.241834 -248.46099) (xy 364.249729 -248.509567) (xy 364.250224 -248.534174) (xy 366.45902 -248.534174)
			(xy 366.46298 -248.48512) (xy 366.474757 -248.437336) (xy 366.494048 -248.39206) (xy 366.520351 -248.350464)
			(xy 366.552986 -248.313627) (xy 366.591107 -248.282502) (xy 366.633728 -248.257895) (xy 366.679744 -248.240443)
			(xy 366.727963 -248.230599) (xy 366.777138 -248.228618) (xy 366.825993 -248.23455) (xy 366.873264 -248.248242)
			(xy 366.917726 -248.26934) (xy 366.958229 -248.297296) (xy 366.993722 -248.331388) (xy 367.023287 -248.370732)
			(xy 367.046158 -248.414309) (xy 367.061742 -248.46099) (xy 367.069637 -248.509567) (xy 367.070132 -248.534174)
			(xy 369.278928 -248.534174) (xy 369.282888 -248.48512) (xy 369.294665 -248.437336) (xy 369.313956 -248.39206)
			(xy 369.340259 -248.350464) (xy 369.372894 -248.313627) (xy 369.411015 -248.282502) (xy 369.453636 -248.257895)
			(xy 369.499652 -248.240443) (xy 369.547871 -248.230599) (xy 369.597046 -248.228618) (xy 369.645901 -248.23455)
			(xy 369.693172 -248.248242) (xy 369.737634 -248.26934) (xy 369.778137 -248.297296) (xy 369.81363 -248.331388)
			(xy 369.843195 -248.370732) (xy 369.866066 -248.414309) (xy 369.88165 -248.46099) (xy 369.889545 -248.509567)
			(xy 369.89004 -248.534174) (xy 372.09909 -248.534174) (xy 372.10305 -248.48512) (xy 372.114827 -248.437336)
			(xy 372.134118 -248.39206) (xy 372.160421 -248.350464) (xy 372.193056 -248.313627) (xy 372.231177 -248.282502)
			(xy 372.273798 -248.257895) (xy 372.319814 -248.240443) (xy 372.368033 -248.230599) (xy 372.417208 -248.228618)
			(xy 372.466063 -248.23455) (xy 372.513334 -248.248242) (xy 372.557796 -248.26934) (xy 372.598299 -248.297296)
			(xy 372.633792 -248.331388) (xy 372.663357 -248.370732) (xy 372.686228 -248.414309) (xy 372.701812 -248.46099)
			(xy 372.709707 -248.509567) (xy 372.710202 -248.534174) (xy 372.709707 -248.558781) (xy 372.701812 -248.607358)
			(xy 372.686228 -248.654039) (xy 372.663357 -248.697616) (xy 372.633792 -248.73696) (xy 372.598299 -248.771052)
			(xy 372.557796 -248.799008) (xy 372.513334 -248.820106) (xy 372.466063 -248.833798) (xy 372.417208 -248.83973)
			(xy 372.368033 -248.837749) (xy 372.319814 -248.827905) (xy 372.273798 -248.810453) (xy 372.231177 -248.785846)
			(xy 372.193056 -248.754721) (xy 372.160421 -248.717884) (xy 372.134118 -248.676288) (xy 372.114827 -248.631012)
			(xy 372.10305 -248.583228) (xy 372.09909 -248.534174) (xy 369.89004 -248.534174) (xy 369.889545 -248.558781)
			(xy 369.88165 -248.607358) (xy 369.866066 -248.654039) (xy 369.843195 -248.697616) (xy 369.81363 -248.73696)
			(xy 369.778137 -248.771052) (xy 369.737634 -248.799008) (xy 369.693172 -248.820106) (xy 369.645901 -248.833798)
			(xy 369.597046 -248.83973) (xy 369.547871 -248.837749) (xy 369.499652 -248.827905) (xy 369.453636 -248.810453)
			(xy 369.411015 -248.785846) (xy 369.372894 -248.754721) (xy 369.340259 -248.717884) (xy 369.313956 -248.676288)
			(xy 369.294665 -248.631012) (xy 369.282888 -248.583228) (xy 369.278928 -248.534174) (xy 367.070132 -248.534174)
			(xy 367.069637 -248.558781) (xy 367.061742 -248.607358) (xy 367.046158 -248.654039) (xy 367.023287 -248.697616)
			(xy 366.993722 -248.73696) (xy 366.958229 -248.771052) (xy 366.917726 -248.799008) (xy 366.873264 -248.820106)
			(xy 366.825993 -248.833798) (xy 366.777138 -248.83973) (xy 366.727963 -248.837749) (xy 366.679744 -248.827905)
			(xy 366.633728 -248.810453) (xy 366.591107 -248.785846) (xy 366.552986 -248.754721) (xy 366.520351 -248.717884)
			(xy 366.494048 -248.676288) (xy 366.474757 -248.631012) (xy 366.46298 -248.583228) (xy 366.45902 -248.534174)
			(xy 364.250224 -248.534174) (xy 364.249729 -248.558781) (xy 364.241834 -248.607358) (xy 364.22625 -248.654039)
			(xy 364.203379 -248.697616) (xy 364.173814 -248.73696) (xy 364.138321 -248.771052) (xy 364.097818 -248.799008)
			(xy 364.053356 -248.820106) (xy 364.006085 -248.833798) (xy 363.95723 -248.83973) (xy 363.908055 -248.837749)
			(xy 363.859836 -248.827905) (xy 363.81382 -248.810453) (xy 363.771199 -248.785846) (xy 363.733078 -248.754721)
			(xy 363.700443 -248.717884) (xy 363.67414 -248.676288) (xy 363.654849 -248.631012) (xy 363.643072 -248.583228)
			(xy 363.639112 -248.534174) (xy 363.320584 -248.534174) (xy 363.320072 -248.55962) (xy 363.311908 -248.609854)
			(xy 363.295792 -248.658128) (xy 363.272141 -248.703191) (xy 363.241568 -248.743877) (xy 363.204864 -248.779132)
			(xy 363.16298 -248.808042) (xy 363.117001 -248.829859) (xy 363.068117 -248.844019) (xy 363.017596 -248.850153)
			(xy 362.966744 -248.848104) (xy 362.91688 -248.837924) (xy 362.869294 -248.819877) (xy 362.82522 -248.794431)
			(xy 362.785798 -248.762244) (xy 362.75205 -248.72415) (xy 362.724849 -248.681136) (xy 362.704901 -248.634316)
			(xy 362.692722 -248.584902) (xy 362.688627 -248.534174) (xy 362.38053 -248.534174) (xy 362.380018 -248.55962)
			(xy 362.371854 -248.609854) (xy 362.355738 -248.658128) (xy 362.332087 -248.703191) (xy 362.301514 -248.743877)
			(xy 362.26481 -248.779132) (xy 362.222926 -248.808042) (xy 362.176947 -248.829859) (xy 362.128063 -248.844019)
			(xy 362.077542 -248.850153) (xy 362.02669 -248.848104) (xy 361.976826 -248.837924) (xy 361.92924 -248.819877)
			(xy 361.885166 -248.794431) (xy 361.845744 -248.762244) (xy 361.811996 -248.72415) (xy 361.784795 -248.681136)
			(xy 361.764847 -248.634316) (xy 361.752668 -248.584902) (xy 361.748573 -248.534174) (xy 361.430062 -248.534174)
			(xy 361.429567 -248.558781) (xy 361.421672 -248.607358) (xy 361.406088 -248.654039) (xy 361.383217 -248.697616)
			(xy 361.353652 -248.73696) (xy 361.318159 -248.771052) (xy 361.277656 -248.799008) (xy 361.233194 -248.820106)
			(xy 361.185923 -248.833798) (xy 361.137068 -248.83973) (xy 361.087893 -248.837749) (xy 361.039674 -248.827905)
			(xy 360.993658 -248.810453) (xy 360.951037 -248.785846) (xy 360.912916 -248.754721) (xy 360.880281 -248.717884)
			(xy 360.853978 -248.676288) (xy 360.834687 -248.631012) (xy 360.82291 -248.583228) (xy 360.81895 -248.534174)
			(xy 358.616504 -248.534174) (xy 358.616009 -248.558781) (xy 358.608114 -248.607358) (xy 358.59253 -248.654039)
			(xy 358.569659 -248.697616) (xy 358.540094 -248.73696) (xy 358.504601 -248.771052) (xy 358.464098 -248.799008)
			(xy 358.419636 -248.820106) (xy 358.372365 -248.833798) (xy 358.32351 -248.83973) (xy 358.274335 -248.837749)
			(xy 358.226116 -248.827905) (xy 358.1801 -248.810453) (xy 358.137479 -248.785846) (xy 358.099358 -248.754721)
			(xy 358.066723 -248.717884) (xy 358.04042 -248.676288) (xy 358.021129 -248.631012) (xy 358.009352 -248.583228)
			(xy 358.005392 -248.534174) (xy 357.67645 -248.534174) (xy 357.675955 -248.558781) (xy 357.66806 -248.607358)
			(xy 357.652476 -248.654039) (xy 357.629605 -248.697616) (xy 357.60004 -248.73696) (xy 357.564547 -248.771052)
			(xy 357.524044 -248.799008) (xy 357.479582 -248.820106) (xy 357.432311 -248.833798) (xy 357.383456 -248.83973)
			(xy 357.334281 -248.837749) (xy 357.286062 -248.827905) (xy 357.240046 -248.810453) (xy 357.197425 -248.785846)
			(xy 357.159304 -248.754721) (xy 357.126669 -248.717884) (xy 357.100366 -248.676288) (xy 357.081075 -248.631012)
			(xy 357.069298 -248.583228) (xy 357.065338 -248.534174) (xy 356.736396 -248.534174) (xy 356.735901 -248.558781)
			(xy 356.728006 -248.607358) (xy 356.712422 -248.654039) (xy 356.689551 -248.697616) (xy 356.659986 -248.73696)
			(xy 356.624493 -248.771052) (xy 356.58399 -248.799008) (xy 356.539528 -248.820106) (xy 356.492257 -248.833798)
			(xy 356.443402 -248.83973) (xy 356.394227 -248.837749) (xy 356.346008 -248.827905) (xy 356.299992 -248.810453)
			(xy 356.257371 -248.785846) (xy 356.21925 -248.754721) (xy 356.186615 -248.717884) (xy 356.160312 -248.676288)
			(xy 356.141021 -248.631012) (xy 356.129244 -248.583228) (xy 356.125284 -248.534174) (xy 355.796342 -248.534174)
			(xy 355.795847 -248.558781) (xy 355.787952 -248.607358) (xy 355.772368 -248.654039) (xy 355.749497 -248.697616)
			(xy 355.719932 -248.73696) (xy 355.684439 -248.771052) (xy 355.643936 -248.799008) (xy 355.599474 -248.820106)
			(xy 355.552203 -248.833798) (xy 355.503348 -248.83973) (xy 355.454173 -248.837749) (xy 355.405954 -248.827905)
			(xy 355.359938 -248.810453) (xy 355.317317 -248.785846) (xy 355.279196 -248.754721) (xy 355.246561 -248.717884)
			(xy 355.220258 -248.676288) (xy 355.200967 -248.631012) (xy 355.18919 -248.583228) (xy 355.18523 -248.534174)
			(xy 352.976434 -248.534174) (xy 352.975939 -248.558781) (xy 352.968044 -248.607358) (xy 352.95246 -248.654039)
			(xy 352.929589 -248.697616) (xy 352.900024 -248.73696) (xy 352.864531 -248.771052) (xy 352.824028 -248.799008)
			(xy 352.779566 -248.820106) (xy 352.732295 -248.833798) (xy 352.68344 -248.83973) (xy 352.634265 -248.837749)
			(xy 352.586046 -248.827905) (xy 352.54003 -248.810453) (xy 352.497409 -248.785846) (xy 352.459288 -248.754721)
			(xy 352.426653 -248.717884) (xy 352.40035 -248.676288) (xy 352.381059 -248.631012) (xy 352.369282 -248.583228)
			(xy 352.365322 -248.534174) (xy 350.156526 -248.534174) (xy 350.156031 -248.558781) (xy 350.148136 -248.607358)
			(xy 350.132552 -248.654039) (xy 350.109681 -248.697616) (xy 350.080116 -248.73696) (xy 350.044623 -248.771052)
			(xy 350.00412 -248.799008) (xy 349.959658 -248.820106) (xy 349.912387 -248.833798) (xy 349.863532 -248.83973)
			(xy 349.814357 -248.837749) (xy 349.766138 -248.827905) (xy 349.720122 -248.810453) (xy 349.677501 -248.785846)
			(xy 349.63938 -248.754721) (xy 349.606745 -248.717884) (xy 349.580442 -248.676288) (xy 349.561151 -248.631012)
			(xy 349.549374 -248.583228) (xy 349.545414 -248.534174) (xy 347.336364 -248.534174) (xy 347.335892 -248.557939)
			(xy 347.328495 -248.604889) (xy 347.321632 -248.627646) (xy 347.317822 -248.63933) (xy 347.321632 -248.663206)
			(xy 347.377512 -248.739406) (xy 347.385115 -248.74867) (xy 347.406442 -248.759533) (xy 347.418406 -248.760234)
			(xy 347.542612 -248.760234) (xy 347.552681 -248.76066) (xy 347.571279 -248.768381) (xy 347.57868 -248.77522)
			(xy 348.14764 -249.34418) (xy 349.07526 -249.34418) (xy 349.07922 -249.295126) (xy 349.090997 -249.247342)
			(xy 349.110288 -249.202066) (xy 349.136591 -249.16047) (xy 349.169226 -249.123633) (xy 349.207347 -249.092508)
			(xy 349.249968 -249.067901) (xy 349.295984 -249.050449) (xy 349.344203 -249.040605) (xy 349.393378 -249.038624)
			(xy 349.442233 -249.044556) (xy 349.489504 -249.058248) (xy 349.533966 -249.079346) (xy 349.574469 -249.107302)
			(xy 349.609962 -249.141394) (xy 349.639527 -249.180738) (xy 349.662398 -249.224315) (xy 349.677982 -249.270996)
			(xy 349.685877 -249.319573) (xy 349.686372 -249.34418) (xy 350.955368 -249.34418) (xy 350.959328 -249.295126)
			(xy 350.971105 -249.247342) (xy 350.990396 -249.202066) (xy 351.016699 -249.16047) (xy 351.049334 -249.123633)
			(xy 351.087455 -249.092508) (xy 351.130076 -249.067901) (xy 351.176092 -249.050449) (xy 351.224311 -249.040605)
			(xy 351.273486 -249.038624) (xy 351.322341 -249.044556) (xy 351.369612 -249.058248) (xy 351.414074 -249.079346)
			(xy 351.454577 -249.107302) (xy 351.49007 -249.141394) (xy 351.519635 -249.180738) (xy 351.542506 -249.224315)
			(xy 351.55809 -249.270996) (xy 351.565985 -249.319573) (xy 351.56648 -249.34418) (xy 352.835222 -249.34418)
			(xy 352.839182 -249.295126) (xy 352.850959 -249.247342) (xy 352.87025 -249.202066) (xy 352.896553 -249.16047)
			(xy 352.929188 -249.123633) (xy 352.967309 -249.092508) (xy 353.00993 -249.067901) (xy 353.055946 -249.050449)
			(xy 353.104165 -249.040605) (xy 353.15334 -249.038624) (xy 353.202195 -249.044556) (xy 353.249466 -249.058248)
			(xy 353.293928 -249.079346) (xy 353.334431 -249.107302) (xy 353.369924 -249.141394) (xy 353.399489 -249.180738)
			(xy 353.42236 -249.224315) (xy 353.437944 -249.270996) (xy 353.445839 -249.319573) (xy 353.446334 -249.34418)
			(xy 354.71533 -249.34418) (xy 354.71929 -249.295126) (xy 354.731067 -249.247342) (xy 354.750358 -249.202066)
			(xy 354.776661 -249.16047) (xy 354.809296 -249.123633) (xy 354.847417 -249.092508) (xy 354.890038 -249.067901)
			(xy 354.936054 -249.050449) (xy 354.984273 -249.040605) (xy 355.033448 -249.038624) (xy 355.082303 -249.044556)
			(xy 355.129574 -249.058248) (xy 355.174036 -249.079346) (xy 355.214539 -249.107302) (xy 355.250032 -249.141394)
			(xy 355.279597 -249.180738) (xy 355.302468 -249.224315) (xy 355.318052 -249.270996) (xy 355.325947 -249.319573)
			(xy 355.326442 -249.34418) (xy 356.595438 -249.34418) (xy 356.599398 -249.295126) (xy 356.611175 -249.247342)
			(xy 356.630466 -249.202066) (xy 356.656769 -249.16047) (xy 356.689404 -249.123633) (xy 356.727525 -249.092508)
			(xy 356.770146 -249.067901) (xy 356.816162 -249.050449) (xy 356.864381 -249.040605) (xy 356.913556 -249.038624)
			(xy 356.962411 -249.044556) (xy 357.009682 -249.058248) (xy 357.054144 -249.079346) (xy 357.094647 -249.107302)
			(xy 357.13014 -249.141394) (xy 357.159705 -249.180738) (xy 357.182576 -249.224315) (xy 357.19816 -249.270996)
			(xy 357.206055 -249.319573) (xy 357.20655 -249.34418) (xy 357.206192 -249.36196) (xy 359.396541 -249.36196)
			(xy 359.400571 -249.309462) (xy 359.412568 -249.258194) (xy 359.432251 -249.209359) (xy 359.459157 -249.1641)
			(xy 359.492657 -249.123479) (xy 359.531965 -249.088448) (xy 359.57616 -249.059828) (xy 359.624205 -249.038289)
			(xy 359.674976 -249.024337) (xy 359.727281 -249.018299) (xy 359.779895 -249.020316) (xy 359.831585 -249.03034)
			(xy 359.881138 -249.048138) (xy 359.927394 -249.073291) (xy 359.969268 -249.10521) (xy 360.00578 -249.143148)
			(xy 360.036072 -249.186214) (xy 360.059435 -249.233399) (xy 360.075321 -249.283598) (xy 360.083358 -249.335634)
			(xy 360.083522 -249.34418) (xy 361.289104 -249.34418) (xy 361.293064 -249.295126) (xy 361.304841 -249.247342)
			(xy 361.324132 -249.202066) (xy 361.350435 -249.16047) (xy 361.38307 -249.123633) (xy 361.421191 -249.092508)
			(xy 361.463812 -249.067901) (xy 361.509828 -249.050449) (xy 361.558047 -249.040605) (xy 361.607222 -249.038624)
			(xy 361.656077 -249.044556) (xy 361.703348 -249.058248) (xy 361.74781 -249.079346) (xy 361.788313 -249.107302)
			(xy 361.823806 -249.141394) (xy 361.853371 -249.180738) (xy 361.876242 -249.224315) (xy 361.891826 -249.270996)
			(xy 361.899721 -249.319573) (xy 361.900216 -249.34418) (xy 363.168958 -249.34418) (xy 363.172918 -249.295126)
			(xy 363.184695 -249.247342) (xy 363.203986 -249.202066) (xy 363.230289 -249.16047) (xy 363.262924 -249.123633)
			(xy 363.301045 -249.092508) (xy 363.343666 -249.067901) (xy 363.389682 -249.050449) (xy 363.437901 -249.040605)
			(xy 363.487076 -249.038624) (xy 363.535931 -249.044556) (xy 363.583202 -249.058248) (xy 363.627664 -249.079346)
			(xy 363.668167 -249.107302) (xy 363.70366 -249.141394) (xy 363.733225 -249.180738) (xy 363.756096 -249.224315)
			(xy 363.77168 -249.270996) (xy 363.779575 -249.319573) (xy 363.78007 -249.34418) (xy 365.049066 -249.34418)
			(xy 365.053026 -249.295126) (xy 365.064803 -249.247342) (xy 365.084094 -249.202066) (xy 365.110397 -249.16047)
			(xy 365.143032 -249.123633) (xy 365.181153 -249.092508) (xy 365.223774 -249.067901) (xy 365.26979 -249.050449)
			(xy 365.318009 -249.040605) (xy 365.367184 -249.038624) (xy 365.416039 -249.044556) (xy 365.46331 -249.058248)
			(xy 365.507772 -249.079346) (xy 365.548275 -249.107302) (xy 365.583768 -249.141394) (xy 365.613333 -249.180738)
			(xy 365.636204 -249.224315) (xy 365.651788 -249.270996) (xy 365.659683 -249.319573) (xy 365.660178 -249.34418)
			(xy 366.92892 -249.34418) (xy 366.93288 -249.295126) (xy 366.944657 -249.247342) (xy 366.963948 -249.202066)
			(xy 366.990251 -249.16047) (xy 367.022886 -249.123633) (xy 367.061007 -249.092508) (xy 367.103628 -249.067901)
			(xy 367.149644 -249.050449) (xy 367.197863 -249.040605) (xy 367.247038 -249.038624) (xy 367.295893 -249.044556)
			(xy 367.343164 -249.058248) (xy 367.387626 -249.079346) (xy 367.428129 -249.107302) (xy 367.463622 -249.141394)
			(xy 367.493187 -249.180738) (xy 367.516058 -249.224315) (xy 367.531642 -249.270996) (xy 367.539537 -249.319573)
			(xy 367.540032 -249.34418) (xy 368.809028 -249.34418) (xy 368.812988 -249.295126) (xy 368.824765 -249.247342)
			(xy 368.844056 -249.202066) (xy 368.870359 -249.16047) (xy 368.902994 -249.123633) (xy 368.941115 -249.092508)
			(xy 368.983736 -249.067901) (xy 369.029752 -249.050449) (xy 369.077971 -249.040605) (xy 369.127146 -249.038624)
			(xy 369.176001 -249.044556) (xy 369.223272 -249.058248) (xy 369.267734 -249.079346) (xy 369.308237 -249.107302)
			(xy 369.34373 -249.141394) (xy 369.373295 -249.180738) (xy 369.396166 -249.224315) (xy 369.41175 -249.270996)
			(xy 369.419645 -249.319573) (xy 369.42014 -249.34418) (xy 370.688882 -249.34418) (xy 370.692842 -249.295126)
			(xy 370.704619 -249.247342) (xy 370.72391 -249.202066) (xy 370.750213 -249.16047) (xy 370.782848 -249.123633)
			(xy 370.820969 -249.092508) (xy 370.86359 -249.067901) (xy 370.909606 -249.050449) (xy 370.957825 -249.040605)
			(xy 371.007 -249.038624) (xy 371.055855 -249.044556) (xy 371.103126 -249.058248) (xy 371.147588 -249.079346)
			(xy 371.188091 -249.107302) (xy 371.223584 -249.141394) (xy 371.253149 -249.180738) (xy 371.27602 -249.224315)
			(xy 371.291604 -249.270996) (xy 371.299499 -249.319573) (xy 371.299994 -249.34418) (xy 372.56899 -249.34418)
			(xy 372.57295 -249.295126) (xy 372.584727 -249.247342) (xy 372.604018 -249.202066) (xy 372.630321 -249.16047)
			(xy 372.662956 -249.123633) (xy 372.701077 -249.092508) (xy 372.743698 -249.067901) (xy 372.789714 -249.050449)
			(xy 372.837933 -249.040605) (xy 372.887108 -249.038624) (xy 372.935963 -249.044556) (xy 372.983234 -249.058248)
			(xy 373.027696 -249.079346) (xy 373.068199 -249.107302) (xy 373.103692 -249.141394) (xy 373.133257 -249.180738)
			(xy 373.156128 -249.224315) (xy 373.171712 -249.270996) (xy 373.179607 -249.319573) (xy 373.180102 -249.34418)
			(xy 373.179607 -249.368787) (xy 373.171712 -249.417364) (xy 373.156128 -249.464045) (xy 373.133257 -249.507622)
			(xy 373.103692 -249.546966) (xy 373.068199 -249.581058) (xy 373.027696 -249.609014) (xy 372.983234 -249.630112)
			(xy 372.935963 -249.643804) (xy 372.887108 -249.649736) (xy 372.837933 -249.647755) (xy 372.789714 -249.637911)
			(xy 372.743698 -249.620459) (xy 372.701077 -249.595852) (xy 372.662956 -249.564727) (xy 372.630321 -249.52789)
			(xy 372.604018 -249.486294) (xy 372.584727 -249.441018) (xy 372.57295 -249.393234) (xy 372.56899 -249.34418)
			(xy 371.299994 -249.34418) (xy 371.299499 -249.368787) (xy 371.291604 -249.417364) (xy 371.27602 -249.464045)
			(xy 371.253149 -249.507622) (xy 371.223584 -249.546966) (xy 371.188091 -249.581058) (xy 371.147588 -249.609014)
			(xy 371.103126 -249.630112) (xy 371.055855 -249.643804) (xy 371.007 -249.649736) (xy 370.957825 -249.647755)
			(xy 370.909606 -249.637911) (xy 370.86359 -249.620459) (xy 370.820969 -249.595852) (xy 370.782848 -249.564727)
			(xy 370.750213 -249.52789) (xy 370.72391 -249.486294) (xy 370.704619 -249.441018) (xy 370.692842 -249.393234)
			(xy 370.688882 -249.34418) (xy 369.42014 -249.34418) (xy 369.419645 -249.368787) (xy 369.41175 -249.417364)
			(xy 369.396166 -249.464045) (xy 369.373295 -249.507622) (xy 369.34373 -249.546966) (xy 369.308237 -249.581058)
			(xy 369.267734 -249.609014) (xy 369.223272 -249.630112) (xy 369.176001 -249.643804) (xy 369.127146 -249.649736)
			(xy 369.077971 -249.647755) (xy 369.029752 -249.637911) (xy 368.983736 -249.620459) (xy 368.941115 -249.595852)
			(xy 368.902994 -249.564727) (xy 368.870359 -249.52789) (xy 368.844056 -249.486294) (xy 368.824765 -249.441018)
			(xy 368.812988 -249.393234) (xy 368.809028 -249.34418) (xy 367.540032 -249.34418) (xy 367.539537 -249.368787)
			(xy 367.531642 -249.417364) (xy 367.516058 -249.464045) (xy 367.493187 -249.507622) (xy 367.463622 -249.546966)
			(xy 367.428129 -249.581058) (xy 367.387626 -249.609014) (xy 367.343164 -249.630112) (xy 367.295893 -249.643804)
			(xy 367.247038 -249.649736) (xy 367.197863 -249.647755) (xy 367.149644 -249.637911) (xy 367.103628 -249.620459)
			(xy 367.061007 -249.595852) (xy 367.022886 -249.564727) (xy 366.990251 -249.52789) (xy 366.963948 -249.486294)
			(xy 366.944657 -249.441018) (xy 366.93288 -249.393234) (xy 366.92892 -249.34418) (xy 365.660178 -249.34418)
			(xy 365.659683 -249.368787) (xy 365.651788 -249.417364) (xy 365.636204 -249.464045) (xy 365.613333 -249.507622)
			(xy 365.583768 -249.546966) (xy 365.548275 -249.581058) (xy 365.507772 -249.609014) (xy 365.46331 -249.630112)
			(xy 365.416039 -249.643804) (xy 365.367184 -249.649736) (xy 365.318009 -249.647755) (xy 365.26979 -249.637911)
			(xy 365.223774 -249.620459) (xy 365.181153 -249.595852) (xy 365.143032 -249.564727) (xy 365.110397 -249.52789)
			(xy 365.084094 -249.486294) (xy 365.064803 -249.441018) (xy 365.053026 -249.393234) (xy 365.049066 -249.34418)
			(xy 363.78007 -249.34418) (xy 363.779575 -249.368787) (xy 363.77168 -249.417364) (xy 363.756096 -249.464045)
			(xy 363.733225 -249.507622) (xy 363.70366 -249.546966) (xy 363.668167 -249.581058) (xy 363.627664 -249.609014)
			(xy 363.583202 -249.630112) (xy 363.535931 -249.643804) (xy 363.487076 -249.649736) (xy 363.437901 -249.647755)
			(xy 363.389682 -249.637911) (xy 363.343666 -249.620459) (xy 363.301045 -249.595852) (xy 363.262924 -249.564727)
			(xy 363.230289 -249.52789) (xy 363.203986 -249.486294) (xy 363.184695 -249.441018) (xy 363.172918 -249.393234)
			(xy 363.168958 -249.34418) (xy 361.900216 -249.34418) (xy 361.899721 -249.368787) (xy 361.891826 -249.417364)
			(xy 361.876242 -249.464045) (xy 361.853371 -249.507622) (xy 361.823806 -249.546966) (xy 361.788313 -249.581058)
			(xy 361.74781 -249.609014) (xy 361.703348 -249.630112) (xy 361.656077 -249.643804) (xy 361.607222 -249.649736)
			(xy 361.558047 -249.647755) (xy 361.509828 -249.637911) (xy 361.463812 -249.620459) (xy 361.421191 -249.595852)
			(xy 361.38307 -249.564727) (xy 361.350435 -249.52789) (xy 361.324132 -249.486294) (xy 361.304841 -249.441018)
			(xy 361.293064 -249.393234) (xy 361.289104 -249.34418) (xy 360.083522 -249.34418) (xy 360.083862 -249.36196)
			(xy 360.083358 -249.388286) (xy 360.075321 -249.440322) (xy 360.059435 -249.490521) (xy 360.036072 -249.537706)
			(xy 360.00578 -249.580772) (xy 359.969268 -249.61871) (xy 359.927394 -249.650629) (xy 359.881138 -249.675782)
			(xy 359.831585 -249.69358) (xy 359.779895 -249.703604) (xy 359.727281 -249.705621) (xy 359.674976 -249.699583)
			(xy 359.624205 -249.685631) (xy 359.57616 -249.664092) (xy 359.531965 -249.635472) (xy 359.492657 -249.600441)
			(xy 359.459157 -249.55982) (xy 359.432251 -249.514561) (xy 359.412568 -249.465726) (xy 359.400571 -249.414458)
			(xy 359.396541 -249.36196) (xy 357.206192 -249.36196) (xy 357.206055 -249.368787) (xy 357.19816 -249.417364)
			(xy 357.182576 -249.464045) (xy 357.159705 -249.507622) (xy 357.13014 -249.546966) (xy 357.094647 -249.581058)
			(xy 357.054144 -249.609014) (xy 357.009682 -249.630112) (xy 356.962411 -249.643804) (xy 356.913556 -249.649736)
			(xy 356.864381 -249.647755) (xy 356.816162 -249.637911) (xy 356.770146 -249.620459) (xy 356.727525 -249.595852)
			(xy 356.689404 -249.564727) (xy 356.656769 -249.52789) (xy 356.630466 -249.486294) (xy 356.611175 -249.441018)
			(xy 356.599398 -249.393234) (xy 356.595438 -249.34418) (xy 355.326442 -249.34418) (xy 355.325947 -249.368787)
			(xy 355.318052 -249.417364) (xy 355.302468 -249.464045) (xy 355.279597 -249.507622) (xy 355.250032 -249.546966)
			(xy 355.214539 -249.581058) (xy 355.174036 -249.609014) (xy 355.129574 -249.630112) (xy 355.082303 -249.643804)
			(xy 355.033448 -249.649736) (xy 354.984273 -249.647755) (xy 354.936054 -249.637911) (xy 354.890038 -249.620459)
			(xy 354.847417 -249.595852) (xy 354.809296 -249.564727) (xy 354.776661 -249.52789) (xy 354.750358 -249.486294)
			(xy 354.731067 -249.441018) (xy 354.71929 -249.393234) (xy 354.71533 -249.34418) (xy 353.446334 -249.34418)
			(xy 353.445839 -249.368787) (xy 353.437944 -249.417364) (xy 353.42236 -249.464045) (xy 353.399489 -249.507622)
			(xy 353.369924 -249.546966) (xy 353.334431 -249.581058) (xy 353.293928 -249.609014) (xy 353.249466 -249.630112)
			(xy 353.202195 -249.643804) (xy 353.15334 -249.649736) (xy 353.104165 -249.647755) (xy 353.055946 -249.637911)
			(xy 353.00993 -249.620459) (xy 352.967309 -249.595852) (xy 352.929188 -249.564727) (xy 352.896553 -249.52789)
			(xy 352.87025 -249.486294) (xy 352.850959 -249.441018) (xy 352.839182 -249.393234) (xy 352.835222 -249.34418)
			(xy 351.56648 -249.34418) (xy 351.565985 -249.368787) (xy 351.55809 -249.417364) (xy 351.542506 -249.464045)
			(xy 351.519635 -249.507622) (xy 351.49007 -249.546966) (xy 351.454577 -249.581058) (xy 351.414074 -249.609014)
			(xy 351.369612 -249.630112) (xy 351.322341 -249.643804) (xy 351.273486 -249.649736) (xy 351.224311 -249.647755)
			(xy 351.176092 -249.637911) (xy 351.130076 -249.620459) (xy 351.087455 -249.595852) (xy 351.049334 -249.564727)
			(xy 351.016699 -249.52789) (xy 350.990396 -249.486294) (xy 350.971105 -249.441018) (xy 350.959328 -249.393234)
			(xy 350.955368 -249.34418) (xy 349.686372 -249.34418) (xy 349.685877 -249.368787) (xy 349.677982 -249.417364)
			(xy 349.662398 -249.464045) (xy 349.639527 -249.507622) (xy 349.609962 -249.546966) (xy 349.574469 -249.581058)
			(xy 349.533966 -249.609014) (xy 349.489504 -249.630112) (xy 349.442233 -249.643804) (xy 349.393378 -249.649736)
			(xy 349.344203 -249.647755) (xy 349.295984 -249.637911) (xy 349.249968 -249.620459) (xy 349.207347 -249.595852)
			(xy 349.169226 -249.564727) (xy 349.136591 -249.52789) (xy 349.110288 -249.486294) (xy 349.090997 -249.441018)
			(xy 349.07922 -249.393234) (xy 349.07526 -249.34418) (xy 348.14764 -249.34418) (xy 348.684088 -249.880628)
			(xy 348.71914 -249.884438) (xy 348.73438 -249.874786) (xy 348.754298 -249.862634) (xy 348.79683 -249.843448)
			(xy 348.84164 -249.830444) (xy 348.887835 -249.823881) (xy 348.911164 -249.823478) (xy 348.937156 -249.823958)
			(xy 348.988499 -249.832085) (xy 349.037939 -249.848144) (xy 349.084259 -249.87174) (xy 349.126316 -249.902291)
			(xy 349.163077 -249.939046) (xy 349.193634 -249.981099) (xy 349.217237 -250.027414) (xy 349.233303 -250.076852)
			(xy 349.241438 -250.128195) (xy 349.241872 -250.154186) (xy 349.545414 -250.154186) (xy 349.549374 -250.105132)
			(xy 349.561151 -250.057348) (xy 349.580442 -250.012072) (xy 349.606745 -249.970476) (xy 349.63938 -249.933639)
			(xy 349.677501 -249.902514) (xy 349.720122 -249.877907) (xy 349.766138 -249.860455) (xy 349.814357 -249.850611)
			(xy 349.863532 -249.84863) (xy 349.912387 -249.854562) (xy 349.959658 -249.868254) (xy 350.00412 -249.889352)
			(xy 350.044623 -249.917308) (xy 350.080116 -249.9514) (xy 350.109681 -249.990744) (xy 350.132552 -250.034321)
			(xy 350.148136 -250.081002) (xy 350.156031 -250.129579) (xy 350.156526 -250.154186) (xy 351.425268 -250.154186)
			(xy 351.429228 -250.105132) (xy 351.441005 -250.057348) (xy 351.460296 -250.012072) (xy 351.486599 -249.970476)
			(xy 351.519234 -249.933639) (xy 351.557355 -249.902514) (xy 351.599976 -249.877907) (xy 351.645992 -249.860455)
			(xy 351.694211 -249.850611) (xy 351.743386 -249.84863) (xy 351.792241 -249.854562) (xy 351.839512 -249.868254)
			(xy 351.883974 -249.889352) (xy 351.924477 -249.917308) (xy 351.95997 -249.9514) (xy 351.989535 -249.990744)
			(xy 352.012406 -250.034321) (xy 352.02799 -250.081002) (xy 352.035885 -250.129579) (xy 352.03638 -250.154186)
			(xy 353.305376 -250.154186) (xy 353.309336 -250.105132) (xy 353.321113 -250.057348) (xy 353.340404 -250.012072)
			(xy 353.366707 -249.970476) (xy 353.399342 -249.933639) (xy 353.437463 -249.902514) (xy 353.480084 -249.877907)
			(xy 353.5261 -249.860455) (xy 353.574319 -249.850611) (xy 353.623494 -249.84863) (xy 353.672349 -249.854562)
			(xy 353.71962 -249.868254) (xy 353.764082 -249.889352) (xy 353.804585 -249.917308) (xy 353.840078 -249.9514)
			(xy 353.869643 -249.990744) (xy 353.892514 -250.034321) (xy 353.908098 -250.081002) (xy 353.915993 -250.129579)
			(xy 353.916488 -250.154186) (xy 355.18523 -250.154186) (xy 355.18919 -250.105132) (xy 355.200967 -250.057348)
			(xy 355.220258 -250.012072) (xy 355.246561 -249.970476) (xy 355.279196 -249.933639) (xy 355.317317 -249.902514)
			(xy 355.359938 -249.877907) (xy 355.405954 -249.860455) (xy 355.454173 -249.850611) (xy 355.503348 -249.84863)
			(xy 355.552203 -249.854562) (xy 355.599474 -249.868254) (xy 355.643936 -249.889352) (xy 355.684439 -249.917308)
			(xy 355.719932 -249.9514) (xy 355.749497 -249.990744) (xy 355.772368 -250.034321) (xy 355.787952 -250.081002)
			(xy 355.795847 -250.129579) (xy 355.796342 -250.154186) (xy 357.065338 -250.154186) (xy 357.069298 -250.105132)
			(xy 357.081075 -250.057348) (xy 357.100366 -250.012072) (xy 357.126669 -249.970476) (xy 357.159304 -249.933639)
			(xy 357.197425 -249.902514) (xy 357.240046 -249.877907) (xy 357.286062 -249.860455) (xy 357.334281 -249.850611)
			(xy 357.383456 -249.84863) (xy 357.432311 -249.854562) (xy 357.479582 -249.868254) (xy 357.524044 -249.889352)
			(xy 357.564547 -249.917308) (xy 357.60004 -249.9514) (xy 357.629605 -249.990744) (xy 357.652476 -250.034321)
			(xy 357.66806 -250.081002) (xy 357.675955 -250.129579) (xy 357.67645 -250.154186) (xy 360.81895 -250.154186)
			(xy 360.82291 -250.105132) (xy 360.834687 -250.057348) (xy 360.853978 -250.012072) (xy 360.880281 -249.970476)
			(xy 360.912916 -249.933639) (xy 360.951037 -249.902514) (xy 360.993658 -249.877907) (xy 361.039674 -249.860455)
			(xy 361.087893 -249.850611) (xy 361.137068 -249.84863) (xy 361.185923 -249.854562) (xy 361.233194 -249.868254)
			(xy 361.277656 -249.889352) (xy 361.318159 -249.917308) (xy 361.353652 -249.9514) (xy 361.383217 -249.990744)
			(xy 361.406088 -250.034321) (xy 361.421672 -250.081002) (xy 361.429567 -250.129579) (xy 361.430062 -250.154186)
			(xy 362.699058 -250.154186) (xy 362.703018 -250.105132) (xy 362.714795 -250.057348) (xy 362.734086 -250.012072)
			(xy 362.760389 -249.970476) (xy 362.793024 -249.933639) (xy 362.831145 -249.902514) (xy 362.873766 -249.877907)
			(xy 362.919782 -249.860455) (xy 362.968001 -249.850611) (xy 363.017176 -249.84863) (xy 363.066031 -249.854562)
			(xy 363.113302 -249.868254) (xy 363.157764 -249.889352) (xy 363.198267 -249.917308) (xy 363.23376 -249.9514)
			(xy 363.263325 -249.990744) (xy 363.286196 -250.034321) (xy 363.30178 -250.081002) (xy 363.309675 -250.129579)
			(xy 363.31017 -250.154186) (xy 364.578912 -250.154186) (xy 364.582872 -250.105132) (xy 364.594649 -250.057348)
			(xy 364.61394 -250.012072) (xy 364.640243 -249.970476) (xy 364.672878 -249.933639) (xy 364.710999 -249.902514)
			(xy 364.75362 -249.877907) (xy 364.799636 -249.860455) (xy 364.847855 -249.850611) (xy 364.89703 -249.84863)
			(xy 364.945885 -249.854562) (xy 364.993156 -249.868254) (xy 365.037618 -249.889352) (xy 365.078121 -249.917308)
			(xy 365.113614 -249.9514) (xy 365.143179 -249.990744) (xy 365.16605 -250.034321) (xy 365.181634 -250.081002)
			(xy 365.189529 -250.129579) (xy 365.190024 -250.154186) (xy 366.45902 -250.154186) (xy 366.46298 -250.105132)
			(xy 366.474757 -250.057348) (xy 366.494048 -250.012072) (xy 366.520351 -249.970476) (xy 366.552986 -249.933639)
			(xy 366.591107 -249.902514) (xy 366.633728 -249.877907) (xy 366.679744 -249.860455) (xy 366.727963 -249.850611)
			(xy 366.777138 -249.84863) (xy 366.825993 -249.854562) (xy 366.873264 -249.868254) (xy 366.917726 -249.889352)
			(xy 366.958229 -249.917308) (xy 366.993722 -249.9514) (xy 367.023287 -249.990744) (xy 367.046158 -250.034321)
			(xy 367.061742 -250.081002) (xy 367.069637 -250.129579) (xy 367.070132 -250.154186) (xy 368.338874 -250.154186)
			(xy 368.342834 -250.105132) (xy 368.354611 -250.057348) (xy 368.373902 -250.012072) (xy 368.400205 -249.970476)
			(xy 368.43284 -249.933639) (xy 368.470961 -249.902514) (xy 368.513582 -249.877907) (xy 368.559598 -249.860455)
			(xy 368.607817 -249.850611) (xy 368.656992 -249.84863) (xy 368.705847 -249.854562) (xy 368.753118 -249.868254)
			(xy 368.79758 -249.889352) (xy 368.838083 -249.917308) (xy 368.873576 -249.9514) (xy 368.903141 -249.990744)
			(xy 368.926012 -250.034321) (xy 368.941596 -250.081002) (xy 368.949491 -250.129579) (xy 368.949986 -250.154186)
			(xy 370.218982 -250.154186) (xy 370.222942 -250.105132) (xy 370.234719 -250.057348) (xy 370.25401 -250.012072)
			(xy 370.280313 -249.970476) (xy 370.312948 -249.933639) (xy 370.351069 -249.902514) (xy 370.39369 -249.877907)
			(xy 370.439706 -249.860455) (xy 370.487925 -249.850611) (xy 370.5371 -249.84863) (xy 370.585955 -249.854562)
			(xy 370.633226 -249.868254) (xy 370.677688 -249.889352) (xy 370.718191 -249.917308) (xy 370.753684 -249.9514)
			(xy 370.783249 -249.990744) (xy 370.80612 -250.034321) (xy 370.821704 -250.081002) (xy 370.829599 -250.129579)
			(xy 370.830094 -250.154186) (xy 372.09909 -250.154186) (xy 372.10305 -250.105132) (xy 372.114827 -250.057348)
			(xy 372.134118 -250.012072) (xy 372.160421 -249.970476) (xy 372.193056 -249.933639) (xy 372.231177 -249.902514)
			(xy 372.273798 -249.877907) (xy 372.319814 -249.860455) (xy 372.368033 -249.850611) (xy 372.417208 -249.84863)
			(xy 372.466063 -249.854562) (xy 372.513334 -249.868254) (xy 372.557796 -249.889352) (xy 372.598299 -249.917308)
			(xy 372.633792 -249.9514) (xy 372.663357 -249.990744) (xy 372.686228 -250.034321) (xy 372.701812 -250.081002)
			(xy 372.709707 -250.129579) (xy 372.710202 -250.154186) (xy 372.709707 -250.178793) (xy 372.701812 -250.22737)
			(xy 372.686228 -250.274051) (xy 372.663357 -250.317628) (xy 372.633792 -250.356972) (xy 372.598299 -250.391064)
			(xy 372.557796 -250.41902) (xy 372.513334 -250.440118) (xy 372.466063 -250.45381) (xy 372.417208 -250.459742)
			(xy 372.368033 -250.457761) (xy 372.319814 -250.447917) (xy 372.273798 -250.430465) (xy 372.231177 -250.405858)
			(xy 372.193056 -250.374733) (xy 372.160421 -250.337896) (xy 372.134118 -250.2963) (xy 372.114827 -250.251024)
			(xy 372.10305 -250.20324) (xy 372.09909 -250.154186) (xy 370.830094 -250.154186) (xy 370.829599 -250.178793)
			(xy 370.821704 -250.22737) (xy 370.80612 -250.274051) (xy 370.783249 -250.317628) (xy 370.753684 -250.356972)
			(xy 370.718191 -250.391064) (xy 370.677688 -250.41902) (xy 370.633226 -250.440118) (xy 370.585955 -250.45381)
			(xy 370.5371 -250.459742) (xy 370.487925 -250.457761) (xy 370.439706 -250.447917) (xy 370.39369 -250.430465)
			(xy 370.351069 -250.405858) (xy 370.312948 -250.374733) (xy 370.280313 -250.337896) (xy 370.25401 -250.2963)
			(xy 370.234719 -250.251024) (xy 370.222942 -250.20324) (xy 370.218982 -250.154186) (xy 368.949986 -250.154186)
			(xy 368.949491 -250.178793) (xy 368.941596 -250.22737) (xy 368.926012 -250.274051) (xy 368.903141 -250.317628)
			(xy 368.873576 -250.356972) (xy 368.838083 -250.391064) (xy 368.79758 -250.41902) (xy 368.753118 -250.440118)
			(xy 368.705847 -250.45381) (xy 368.656992 -250.459742) (xy 368.607817 -250.457761) (xy 368.559598 -250.447917)
			(xy 368.513582 -250.430465) (xy 368.470961 -250.405858) (xy 368.43284 -250.374733) (xy 368.400205 -250.337896)
			(xy 368.373902 -250.2963) (xy 368.354611 -250.251024) (xy 368.342834 -250.20324) (xy 368.338874 -250.154186)
			(xy 367.070132 -250.154186) (xy 367.069637 -250.178793) (xy 367.061742 -250.22737) (xy 367.046158 -250.274051)
			(xy 367.023287 -250.317628) (xy 366.993722 -250.356972) (xy 366.958229 -250.391064) (xy 366.917726 -250.41902)
			(xy 366.873264 -250.440118) (xy 366.825993 -250.45381) (xy 366.777138 -250.459742) (xy 366.727963 -250.457761)
			(xy 366.679744 -250.447917) (xy 366.633728 -250.430465) (xy 366.591107 -250.405858) (xy 366.552986 -250.374733)
			(xy 366.520351 -250.337896) (xy 366.494048 -250.2963) (xy 366.474757 -250.251024) (xy 366.46298 -250.20324)
			(xy 366.45902 -250.154186) (xy 365.190024 -250.154186) (xy 365.189529 -250.178793) (xy 365.181634 -250.22737)
			(xy 365.16605 -250.274051) (xy 365.143179 -250.317628) (xy 365.113614 -250.356972) (xy 365.078121 -250.391064)
			(xy 365.037618 -250.41902) (xy 364.993156 -250.440118) (xy 364.945885 -250.45381) (xy 364.89703 -250.459742)
			(xy 364.847855 -250.457761) (xy 364.799636 -250.447917) (xy 364.75362 -250.430465) (xy 364.710999 -250.405858)
			(xy 364.672878 -250.374733) (xy 364.640243 -250.337896) (xy 364.61394 -250.2963) (xy 364.594649 -250.251024)
			(xy 364.582872 -250.20324) (xy 364.578912 -250.154186) (xy 363.31017 -250.154186) (xy 363.309675 -250.178793)
			(xy 363.30178 -250.22737) (xy 363.286196 -250.274051) (xy 363.263325 -250.317628) (xy 363.23376 -250.356972)
			(xy 363.198267 -250.391064) (xy 363.157764 -250.41902) (xy 363.113302 -250.440118) (xy 363.066031 -250.45381)
			(xy 363.017176 -250.459742) (xy 362.968001 -250.457761) (xy 362.919782 -250.447917) (xy 362.873766 -250.430465)
			(xy 362.831145 -250.405858) (xy 362.793024 -250.374733) (xy 362.760389 -250.337896) (xy 362.734086 -250.2963)
			(xy 362.714795 -250.251024) (xy 362.703018 -250.20324) (xy 362.699058 -250.154186) (xy 361.430062 -250.154186)
			(xy 361.429567 -250.178793) (xy 361.421672 -250.22737) (xy 361.406088 -250.274051) (xy 361.383217 -250.317628)
			(xy 361.353652 -250.356972) (xy 361.318159 -250.391064) (xy 361.277656 -250.41902) (xy 361.233194 -250.440118)
			(xy 361.185923 -250.45381) (xy 361.137068 -250.459742) (xy 361.087893 -250.457761) (xy 361.039674 -250.447917)
			(xy 360.993658 -250.430465) (xy 360.951037 -250.405858) (xy 360.912916 -250.374733) (xy 360.880281 -250.337896)
			(xy 360.853978 -250.2963) (xy 360.834687 -250.251024) (xy 360.82291 -250.20324) (xy 360.81895 -250.154186)
			(xy 357.67645 -250.154186) (xy 357.675955 -250.178793) (xy 357.66806 -250.22737) (xy 357.652476 -250.274051)
			(xy 357.629605 -250.317628) (xy 357.60004 -250.356972) (xy 357.564547 -250.391064) (xy 357.524044 -250.41902)
			(xy 357.479582 -250.440118) (xy 357.432311 -250.45381) (xy 357.383456 -250.459742) (xy 357.334281 -250.457761)
			(xy 357.286062 -250.447917) (xy 357.240046 -250.430465) (xy 357.197425 -250.405858) (xy 357.159304 -250.374733)
			(xy 357.126669 -250.337896) (xy 357.100366 -250.2963) (xy 357.081075 -250.251024) (xy 357.069298 -250.20324)
			(xy 357.065338 -250.154186) (xy 355.796342 -250.154186) (xy 355.795847 -250.178793) (xy 355.787952 -250.22737)
			(xy 355.772368 -250.274051) (xy 355.749497 -250.317628) (xy 355.719932 -250.356972) (xy 355.684439 -250.391064)
			(xy 355.643936 -250.41902) (xy 355.599474 -250.440118) (xy 355.552203 -250.45381) (xy 355.503348 -250.459742)
			(xy 355.454173 -250.457761) (xy 355.405954 -250.447917) (xy 355.359938 -250.430465) (xy 355.317317 -250.405858)
			(xy 355.279196 -250.374733) (xy 355.246561 -250.337896) (xy 355.220258 -250.2963) (xy 355.200967 -250.251024)
			(xy 355.18919 -250.20324) (xy 355.18523 -250.154186) (xy 353.916488 -250.154186) (xy 353.915993 -250.178793)
			(xy 353.908098 -250.22737) (xy 353.892514 -250.274051) (xy 353.869643 -250.317628) (xy 353.840078 -250.356972)
			(xy 353.804585 -250.391064) (xy 353.764082 -250.41902) (xy 353.71962 -250.440118) (xy 353.672349 -250.45381)
			(xy 353.623494 -250.459742) (xy 353.574319 -250.457761) (xy 353.5261 -250.447917) (xy 353.480084 -250.430465)
			(xy 353.437463 -250.405858) (xy 353.399342 -250.374733) (xy 353.366707 -250.337896) (xy 353.340404 -250.2963)
			(xy 353.321113 -250.251024) (xy 353.309336 -250.20324) (xy 353.305376 -250.154186) (xy 352.03638 -250.154186)
			(xy 352.035885 -250.178793) (xy 352.02799 -250.22737) (xy 352.012406 -250.274051) (xy 351.989535 -250.317628)
			(xy 351.95997 -250.356972) (xy 351.924477 -250.391064) (xy 351.883974 -250.41902) (xy 351.839512 -250.440118)
			(xy 351.792241 -250.45381) (xy 351.743386 -250.459742) (xy 351.694211 -250.457761) (xy 351.645992 -250.447917)
			(xy 351.599976 -250.430465) (xy 351.557355 -250.405858) (xy 351.519234 -250.374733) (xy 351.486599 -250.337896)
			(xy 351.460296 -250.2963) (xy 351.441005 -250.251024) (xy 351.429228 -250.20324) (xy 351.425268 -250.154186)
			(xy 350.156526 -250.154186) (xy 350.156031 -250.178793) (xy 350.148136 -250.22737) (xy 350.132552 -250.274051)
			(xy 350.109681 -250.317628) (xy 350.080116 -250.356972) (xy 350.044623 -250.391064) (xy 350.00412 -250.41902)
			(xy 349.959658 -250.440118) (xy 349.912387 -250.45381) (xy 349.863532 -250.459742) (xy 349.814357 -250.457761)
			(xy 349.766138 -250.447917) (xy 349.720122 -250.430465) (xy 349.677501 -250.405858) (xy 349.63938 -250.374733)
			(xy 349.606745 -250.337896) (xy 349.580442 -250.2963) (xy 349.561151 -250.251024) (xy 349.549374 -250.20324)
			(xy 349.545414 -250.154186) (xy 349.241872 -250.154186) (xy 349.241448 -250.177512) (xy 349.234852 -250.223696)
			(xy 349.221846 -250.2685) (xy 349.202686 -250.311037) (xy 349.190564 -250.33097) (xy 349.18269 -250.34367)
			(xy 349.182944 -250.373388) (xy 349.19158 -250.38685) (xy 349.198184 -250.394724) (xy 349.477838 -250.674378)
			(xy 349.488252 -250.678188) (xy 349.512499 -250.687839) (xy 349.557546 -250.714184) (xy 349.597461 -250.747799)
			(xy 349.631083 -250.787708) (xy 349.657437 -250.832749) (xy 349.667068 -250.857004) (xy 349.670878 -250.867418)
			(xy 349.963994 -251.160534) (xy 349.971389 -251.167389) (xy 349.989988 -251.175136) (xy 350.000062 -251.17552)
		)
		(stroke
			(width 0)
			(type solid)
		)
		(fill yes)
		(layer "In13.Cu")
		(net "PVDDCR_CPU0_P0")
	)
	(gr_poly
		(pts
			(xy 207.197706 -131.598924) (xy 207.207589 -131.59846) (xy 207.225888 -131.590988) (xy 207.240006 -131.577155)
			(xy 207.247849 -131.559011) (xy 207.248506 -131.54914) (xy 207.249593 -131.520975) (xy 207.259033 -131.465407)
			(xy 207.276543 -131.411833) (xy 207.301744 -131.361417) (xy 207.334087 -131.315257) (xy 207.372869 -131.274357)
			(xy 207.417244 -131.239606) (xy 207.466249 -131.21176) (xy 207.518817 -131.191427) (xy 207.573804 -131.179047)
			(xy 207.630014 -131.17489) (xy 207.686224 -131.179047) (xy 207.741211 -131.191427) (xy 207.793779 -131.21176)
			(xy 207.842784 -131.239606) (xy 207.887159 -131.274357) (xy 207.925941 -131.315257) (xy 207.958284 -131.361417)
			(xy 207.983485 -131.411833) (xy 208.000995 -131.465407) (xy 208.010435 -131.520975) (xy 208.011522 -131.54914)
			(xy 208.012187 -131.559008) (xy 208.02003 -131.577143) (xy 208.034147 -131.590968) (xy 208.052442 -131.59843)
			(xy 208.062322 -131.598924) (xy 208.78292 -131.598924) (xy 208.793256 -131.598444) (xy 208.812266 -131.590321)
			(xy 208.81975 -131.583176) (xy 208.877916 -131.52247) (xy 208.885028 -131.503166) (xy 208.88452 -131.492752)
			(xy 208.884012 -131.46913) (xy 208.884439 -131.438971) (xy 208.89157 -131.379077) (xy 208.905735 -131.320447)
			(xy 208.926736 -131.263903) (xy 208.954277 -131.210241) (xy 208.987972 -131.160213) (xy 209.027348 -131.114521)
			(xy 209.071852 -131.073808) (xy 209.096102 -131.055872) (xy 209.104484 -131.049776) (xy 209.115152 -131.032504)
			(xy 209.129122 -130.940302) (xy 209.124296 -130.920744) (xy 209.1182 -130.912362) (xy 209.10015 -130.88742)
			(xy 209.071493 -130.832932) (xy 209.051964 -130.774547) (xy 209.042071 -130.713782) (xy 209.041492 -130.683)
			(xy 209.041978 -130.655749) (xy 209.049734 -130.601801) (xy 209.065089 -130.549506) (xy 209.087731 -130.499929)
			(xy 209.117197 -130.454079) (xy 209.152888 -130.412888) (xy 209.194079 -130.377197) (xy 209.239929 -130.347731)
			(xy 209.289506 -130.325089) (xy 209.341801 -130.309734) (xy 209.395749 -130.301978) (xy 209.450251 -130.301978)
			(xy 209.504199 -130.309734) (xy 209.556494 -130.325089) (xy 209.606071 -130.347731) (xy 209.651921 -130.377197)
			(xy 209.693112 -130.412888) (xy 209.728803 -130.454079) (xy 209.758269 -130.499929) (xy 209.780911 -130.549506)
			(xy 209.796266 -130.601801) (xy 209.804022 -130.655749) (xy 209.804508 -130.683) (xy 209.804023 -130.710569)
			(xy 209.796087 -130.765133) (xy 209.780382 -130.817986) (xy 209.757233 -130.868029) (xy 209.727124 -130.91422)
			(xy 209.709258 -130.935222) (xy 209.7024 -130.942842) (xy 209.695796 -130.9624) (xy 209.702908 -131.055364)
			(xy 209.712052 -131.073398) (xy 209.719926 -131.080002) (xy 209.743843 -131.100753) (xy 209.786863 -131.147219)
			(xy 209.823777 -131.198667) (xy 209.854016 -131.254303) (xy 209.87711 -131.313263) (xy 209.892703 -131.374635)
			(xy 209.900552 -131.437469) (xy 209.901028 -131.46913) (xy 209.90052 -131.492752) (xy 209.900012 -131.503166)
			(xy 209.907124 -131.52247) (xy 209.96529 -131.583176) (xy 209.972767 -131.590335) (xy 209.991779 -131.59847)
			(xy 210.00212 -131.598924) (xy 210.381596 -131.598924) (xy 210.384644 -131.598924) (xy 210.389308 -131.598513)
			(xy 210.398382 -131.596212) (xy 210.402678 -131.594352) (xy 210.424014 -131.583684) (xy 210.43392 -131.57708)
			(xy 210.43773 -131.573778) (xy 210.44154 -131.569206) (xy 210.442048 -131.568444) (xy 210.453259 -131.55418)
			(xy 210.477413 -131.527104) (xy 210.490308 -131.514342) (xy 210.498455 -131.506458) (xy 210.515351 -131.491338)
			(xy 210.52409 -131.484116) (xy 210.531099 -131.477961) (xy 210.540355 -131.46178) (xy 210.542124 -131.45262)
			(xy 210.54695 -131.422648) (xy 210.548031 -131.413138) (xy 210.54384 -131.394478) (xy 210.538822 -131.386326)
			(xy 210.514732 -131.349603) (xy 210.473095 -131.272267) (xy 210.439286 -131.191202) (xy 210.413636 -131.107199)
			(xy 210.396393 -131.021076) (xy 210.387727 -130.933672) (xy 210.387184 -130.889756) (xy 210.387661 -130.848655)
			(xy 210.395249 -130.766803) (xy 210.410357 -130.686001) (xy 210.432856 -130.606937) (xy 210.462554 -130.530286)
			(xy 210.499197 -130.456703) (xy 210.542473 -130.386814) (xy 210.592013 -130.321216) (xy 210.647394 -130.260469)
			(xy 210.708144 -130.20509) (xy 210.773743 -130.155553) (xy 210.843634 -130.11228) (xy 210.917219 -130.075639)
			(xy 210.993871 -130.045945) (xy 211.072936 -130.023449) (xy 211.153739 -130.008344) (xy 211.235591 -130.000759)
			(xy 211.276692 -130.000248) (xy 211.315176 -130.00067) (xy 211.391855 -130.007345) (xy 211.46767 -130.020621)
			(xy 211.542055 -130.040398) (xy 211.614453 -130.066528) (xy 211.649564 -130.08229) (xy 211.649818 -130.08229)
			(xy 211.657647 -130.085573) (xy 211.67453 -130.087268) (xy 211.691031 -130.083318) (xy 211.698332 -130.078988)
			(xy 211.770468 -130.03276) (xy 211.777421 -130.027902) (xy 211.7879 -130.014574) (xy 211.793473 -129.998563)
			(xy 211.793836 -129.990088) (xy 211.793836 -129.804414) (xy 211.794276 -129.794352) (xy 211.802016 -129.775773)
			(xy 211.808822 -129.768346) (xy 211.988908 -129.58826) (xy 211.994105 -129.58251) (xy 212.001081 -129.568678)
			(xy 212.002624 -129.561082) (xy 212.003386 -129.5527) (xy 212.003386 -123.7869) (xy 212.00237 -123.776232)
			(xy 211.999068 -123.761246) (xy 211.999068 -123.760992) (xy 211.98713 -123.733044) (xy 211.969241 -123.67496)
			(xy 211.958405 -123.615158) (xy 211.954776 -123.554491) (xy 211.958407 -123.493824) (xy 211.969245 -123.434022)
			(xy 211.987137 -123.375939) (xy 211.999068 -123.347988) (xy 212.003386 -123.338082) (xy 212.003386 -122.550428)
			(xy 212.003045 -122.541734) (xy 211.99721 -122.525357) (xy 211.991956 -122.518424) (xy 211.988654 -122.514614)
			(xy 210.907884 -121.433844) (xy 210.901126 -121.427671) (xy 210.884469 -121.420115) (xy 210.875372 -121.419112)
			(xy 210.86826 -121.419112) (xy 210.831684 -121.420382) (xy 210.83143 -121.420382) (xy 210.800135 -121.419881)
			(xy 210.738023 -121.412162) (xy 210.677326 -121.396887) (xy 210.618959 -121.374286) (xy 210.591146 -121.35993)
			(xy 210.586494 -121.357937) (xy 210.576642 -121.355625) (xy 210.571588 -121.355358) (xy 210.275678 -121.355358)
			(xy 210.262978 -121.356882) (xy 210.258406 -121.358406) (xy 210.232309 -121.37066) (xy 210.177947 -121.389869)
			(xy 210.121763 -121.402815) (xy 210.064476 -121.409332) (xy 210.035648 -121.409714) (xy 210.007379 -121.409316)
			(xy 209.951192 -121.403021) (xy 209.896049 -121.390538) (xy 209.842629 -121.37202) (xy 209.816954 -121.360184)
			(xy 209.81178 -121.357922) (xy 209.800756 -121.355484) (xy 209.79511 -121.355358) (xy 206.82077 -121.355358)
			(xy 206.807816 -121.357136) (xy 206.8068 -121.35739) (xy 206.795969 -121.365386) (xy 206.773606 -121.38038)
			(xy 206.762096 -121.387362) (xy 206.759515 -121.392789) (xy 206.756696 -121.404469) (xy 206.756508 -121.410476)
			(xy 206.756508 -121.495312) (xy 206.758032 -121.50725) (xy 206.760503 -121.515402) (xy 206.769978 -121.529546)
			(xy 206.776574 -121.534936) (xy 206.802643 -121.552619) (xy 206.85063 -121.59343) (xy 206.893215 -121.63985)
			(xy 206.929748 -121.691169) (xy 206.95967 -121.746603) (xy 206.982525 -121.805305) (xy 206.997964 -121.866378)
			(xy 207.005749 -121.928889) (xy 207.00619 -121.960386) (xy 207.005688 -121.992347) (xy 206.997677 -122.055765)
			(xy 206.98178 -122.117679) (xy 206.958248 -122.177112) (xy 206.927454 -122.233127) (xy 206.889881 -122.284842)
			(xy 206.846124 -122.331439) (xy 206.796871 -122.372184) (xy 206.7429 -122.406435) (xy 206.685061 -122.433652)
			(xy 206.624268 -122.453405) (xy 206.561478 -122.465383) (xy 206.497682 -122.469397) (xy 206.433886 -122.465383)
			(xy 206.371096 -122.453405) (xy 206.310303 -122.433652) (xy 206.252464 -122.406435) (xy 206.198493 -122.372184)
			(xy 206.14924 -122.331439) (xy 206.105483 -122.284842) (xy 206.06791 -122.233127) (xy 206.037116 -122.177112)
			(xy 206.013584 -122.117679) (xy 205.997687 -122.055765) (xy 205.989676 -121.992347) (xy 205.989174 -121.960386)
			(xy 205.989253 -121.947664) (xy 205.990523 -121.922252) (xy 205.991714 -121.909586) (xy 205.995438 -121.877435)
			(xy 206.009997 -121.81437) (xy 206.03244 -121.753662) (xy 206.062403 -121.696292) (xy 206.099403 -121.643187)
			(xy 206.142841 -121.595204) (xy 206.192016 -121.553121) (xy 206.21879 -121.534936) (xy 206.225392 -121.529551)
			(xy 206.234874 -121.515407) (xy 206.237332 -121.50725) (xy 206.238856 -121.495312) (xy 206.238856 -121.410476)
			(xy 206.238693 -121.404465) (xy 206.235877 -121.392779) (xy 206.233268 -121.387362) (xy 206.221752 -121.380389)
			(xy 206.199388 -121.365396) (xy 206.188564 -121.35739) (xy 206.187548 -121.357136) (xy 206.174594 -121.355358)
			(xy 204.243686 -121.355358) (xy 204.242162 -121.355358) (xy 204.231666 -121.356194) (xy 204.212656 -121.365192)
			(xy 204.198837 -121.381047) (xy 204.195172 -121.390918) (xy 204.195172 -121.391172) (xy 204.16647 -121.483628)
			(xy 204.163537 -121.494833) (xy 204.166994 -121.517709) (xy 204.173074 -121.52757) (xy 204.18298 -121.537476)
			(xy 204.189838 -121.543318) (xy 204.214655 -121.561184) (xy 204.260251 -121.601933) (xy 204.300633 -121.647853)
			(xy 204.335218 -121.698285) (xy 204.363507 -121.752498) (xy 204.385093 -121.809713) (xy 204.399663 -121.869103)
			(xy 204.407008 -121.929811) (xy 204.407516 -121.960386) (xy 204.407014 -121.992347) (xy 204.399003 -122.055765)
			(xy 204.383106 -122.117679) (xy 204.359574 -122.177112) (xy 204.32878 -122.233127) (xy 204.291207 -122.284842)
			(xy 204.24745 -122.331439) (xy 204.198197 -122.372184) (xy 204.144226 -122.406435) (xy 204.086387 -122.433652)
			(xy 204.025594 -122.453405) (xy 203.962804 -122.465383) (xy 203.899008 -122.469397) (xy 203.835212 -122.465383)
			(xy 203.772422 -122.453405) (xy 203.711629 -122.433652) (xy 203.65379 -122.406435) (xy 203.599819 -122.372184)
			(xy 203.550566 -122.331439) (xy 203.506809 -122.284842) (xy 203.469236 -122.233127) (xy 203.438442 -122.177112)
			(xy 203.41491 -122.117679) (xy 203.399013 -122.055765) (xy 203.391002 -121.992347) (xy 203.3905 -121.960386)
			(xy 203.390579 -121.947664) (xy 203.391849 -121.922252) (xy 203.39304 -121.909586) (xy 203.396088 -121.885202)
			(xy 203.400907 -121.855855) (xy 203.416508 -121.798464) (xy 203.438696 -121.743283) (xy 203.467167 -121.691067)
			(xy 203.501532 -121.642526) (xy 203.541323 -121.598324) (xy 203.585997 -121.559064) (xy 203.61021 -121.541794)
			(xy 203.611988 -121.540524) (xy 203.624942 -121.52757) (xy 203.631013 -121.517713) (xy 203.634438 -121.494839)
			(xy 203.631546 -121.483628) (xy 203.602844 -121.391172) (xy 203.602844 -121.390918) (xy 203.599199 -121.381035)
			(xy 203.58538 -121.365168) (xy 203.566356 -121.356177) (xy 203.555854 -121.355358) (xy 203.05395 -121.355358)
			(xy 203.045143 -121.355782) (xy 203.028594 -121.361831) (xy 203.01505 -121.3731) (xy 203.010262 -121.380504)
			(xy 202.965812 -121.455688) (xy 202.962569 -121.461536) (xy 202.958952 -121.474406) (xy 202.9587 -121.481088)
			(xy 202.9587 -121.494296) (xy 202.965304 -121.506234) (xy 202.980517 -121.534659) (xy 203.004446 -121.594526)
			(xy 203.020626 -121.656934) (xy 203.028799 -121.720886) (xy 203.029312 -121.753122) (xy 203.029312 -121.761758)
			(xy 203.02836 -121.792725) (xy 203.019855 -121.854094) (xy 203.003954 -121.913975) (xy 202.980891 -121.971478)
			(xy 202.95101 -122.025753) (xy 202.914754 -122.075992) (xy 202.87266 -122.121452) (xy 202.825352 -122.161458)
			(xy 202.799696 -122.178826) (xy 202.793091 -122.18421) (xy 202.783602 -122.198351) (xy 202.781154 -122.206512)
			(xy 202.77963 -122.21845) (xy 202.77963 -122.304302) (xy 202.781154 -122.31624) (xy 202.78362 -122.324396)
			(xy 202.793084 -122.338554) (xy 202.799696 -122.343926) (xy 202.825761 -122.361611) (xy 202.873738 -122.402426)
			(xy 202.916313 -122.448848) (xy 202.952835 -122.500168) (xy 202.982747 -122.555602) (xy 203.005591 -122.614303)
			(xy 203.021017 -122.675374) (xy 203.028792 -122.737881) (xy 203.029312 -122.769376) (xy 203.02882 -122.801203)
			(xy 203.020878 -122.864361) (xy 203.005116 -122.926033) (xy 202.981779 -122.985256) (xy 202.951233 -123.041104)
			(xy 202.913956 -123.092702) (xy 202.870531 -123.139244) (xy 202.821636 -123.180002) (xy 202.811242 -123.186909)
			(xy 205.993994 -123.186909) (xy 205.993994 -123.122987) (xy 206.002005 -123.059569) (xy 206.017902 -122.997655)
			(xy 206.041434 -122.938222) (xy 206.072228 -122.882207) (xy 206.109801 -122.830492) (xy 206.153558 -122.783895)
			(xy 206.202811 -122.74315) (xy 206.256782 -122.708899) (xy 206.314621 -122.681682) (xy 206.375414 -122.661929)
			(xy 206.438204 -122.649951) (xy 206.502 -122.645938) (xy 206.565796 -122.649951) (xy 206.628586 -122.661929)
			(xy 206.689379 -122.681682) (xy 206.747218 -122.708899) (xy 206.801189 -122.74315) (xy 206.850442 -122.783895)
			(xy 206.894199 -122.830492) (xy 206.931772 -122.882207) (xy 206.946831 -122.9096) (xy 209.414873 -122.9096)
			(xy 209.418887 -122.845803) (xy 209.430865 -122.783012) (xy 209.450618 -122.722218) (xy 209.477835 -122.664378)
			(xy 209.512086 -122.610406) (xy 209.552832 -122.561152) (xy 209.599429 -122.517393) (xy 209.651143 -122.479819)
			(xy 209.707159 -122.449023) (xy 209.766593 -122.42549) (xy 209.828508 -122.409592) (xy 209.891926 -122.401579)
			(xy 209.923888 -122.401076) (xy 209.956269 -122.401598) (xy 210.020507 -122.409813) (xy 210.083181 -122.426124)
			(xy 210.143275 -122.450266) (xy 210.199813 -122.481849) (xy 210.25188 -122.52036) (xy 210.298631 -122.565175)
			(xy 210.319366 -122.590052) (xy 210.326732 -122.598942) (xy 210.347306 -122.608848) (xy 210.449668 -122.608848)
			(xy 210.470242 -122.598942) (xy 210.477608 -122.589798) (xy 210.498355 -122.56483) (xy 210.545165 -122.519849)
			(xy 210.597317 -122.481189) (xy 210.653963 -122.449478) (xy 210.714183 -122.42523) (xy 210.776999 -122.408841)
			(xy 210.841389 -122.400575) (xy 210.873848 -122.40006) (xy 210.905805 -122.400629) (xy 210.969215 -122.408645)
			(xy 211.03112 -122.424545) (xy 211.090544 -122.448077) (xy 211.14655 -122.478872) (xy 211.198256 -122.516442)
			(xy 211.244845 -122.560197) (xy 211.285584 -122.609445) (xy 211.319829 -122.663411) (xy 211.34704 -122.721243)
			(xy 211.36679 -122.78203) (xy 211.378766 -122.844812) (xy 211.382779 -122.9086) (xy 211.378766 -122.972388)
			(xy 211.36679 -123.03517) (xy 211.34704 -123.095957) (xy 211.319829 -123.153789) (xy 211.285584 -123.207755)
			(xy 211.244845 -123.257003) (xy 211.198256 -123.300758) (xy 211.14655 -123.338328) (xy 211.090544 -123.369123)
			(xy 211.03112 -123.392655) (xy 210.969215 -123.408555) (xy 210.905805 -123.416571) (xy 210.873848 -123.417076)
			(xy 210.841466 -123.416581) (xy 210.777228 -123.408359) (xy 210.714554 -123.392042) (xy 210.654461 -123.367894)
			(xy 210.597923 -123.336308) (xy 210.545857 -123.297794) (xy 210.499105 -123.252977) (xy 210.47837 -123.2281)
			(xy 210.471004 -123.21921) (xy 210.45043 -123.209304) (xy 210.348068 -123.209304) (xy 210.327494 -123.21921)
			(xy 210.320128 -123.228354) (xy 210.299349 -123.253295) (xy 210.252546 -123.298279) (xy 210.2004 -123.336943)
			(xy 210.14376 -123.368658) (xy 210.083544 -123.39291) (xy 210.020733 -123.409304) (xy 209.956346 -123.417574)
			(xy 209.923888 -123.418092) (xy 209.891926 -123.417621) (xy 209.828508 -123.409608) (xy 209.766593 -123.39371)
			(xy 209.707159 -123.370177) (xy 209.651143 -123.339381) (xy 209.599429 -123.301807) (xy 209.552832 -123.258048)
			(xy 209.512086 -123.208794) (xy 209.477835 -123.154822) (xy 209.450618 -123.096982) (xy 209.430865 -123.036188)
			(xy 209.418887 -122.973397) (xy 209.414873 -122.9096) (xy 206.946831 -122.9096) (xy 206.962566 -122.938222)
			(xy 206.986098 -122.997655) (xy 207.001995 -123.059569) (xy 207.010006 -123.122987) (xy 207.010508 -123.154948)
			(xy 207.010006 -123.186909) (xy 207.001995 -123.250327) (xy 206.986098 -123.312241) (xy 206.962566 -123.371674)
			(xy 206.931772 -123.427689) (xy 206.894199 -123.479404) (xy 206.850442 -123.526001) (xy 206.801189 -123.566746)
			(xy 206.747218 -123.600997) (xy 206.689379 -123.628214) (xy 206.628586 -123.647967) (xy 206.565796 -123.659945)
			(xy 206.502 -123.663959) (xy 206.438204 -123.659945) (xy 206.375414 -123.647967) (xy 206.314621 -123.628214)
			(xy 206.256782 -123.600997) (xy 206.202811 -123.566746) (xy 206.153558 -123.526001) (xy 206.109801 -123.479404)
			(xy 206.072228 -123.427689) (xy 206.041434 -123.371674) (xy 206.017902 -123.312241) (xy 206.002005 -123.250327)
			(xy 205.993994 -123.186909) (xy 202.811242 -123.186909) (xy 202.795124 -123.19762) (xy 202.790298 -123.200668)
			(xy 202.774804 -123.216162) (xy 202.771296 -123.221944) (xy 202.767167 -123.234817) (xy 202.766676 -123.241562)
			(xy 202.768454 -123.341384) (xy 202.768454 -123.34494) (xy 202.775058 -123.356116) (xy 202.778602 -123.361678)
			(xy 202.78799 -123.370936) (xy 202.7936 -123.374404) (xy 202.793854 -123.374658) (xy 202.82255 -123.391737)
			(xy 202.87562 -123.432274) (xy 202.922931 -123.479403) (xy 202.963672 -123.532316) (xy 202.997142 -123.590103)
			(xy 203.022766 -123.651772) (xy 203.040103 -123.716262) (xy 203.048857 -123.782466) (xy 203.049378 -123.815856)
			(xy 203.048876 -123.847817) (xy 203.040865 -123.911235) (xy 203.024968 -123.973149) (xy 203.001436 -124.032582)
			(xy 202.970642 -124.088597) (xy 202.933069 -124.140312) (xy 202.889312 -124.186909) (xy 202.840059 -124.227654)
			(xy 202.786088 -124.261905) (xy 202.728249 -124.289122) (xy 202.667456 -124.308875) (xy 202.604666 -124.320853)
			(xy 202.54087 -124.324867) (xy 202.477074 -124.320853) (xy 202.414284 -124.308875) (xy 202.353491 -124.289122)
			(xy 202.295652 -124.261905) (xy 202.241681 -124.227654) (xy 202.192428 -124.186909) (xy 202.148671 -124.140312)
			(xy 202.111098 -124.088597) (xy 202.080304 -124.032582) (xy 202.056772 -123.973149) (xy 202.040875 -123.911235)
			(xy 202.032864 -123.847817) (xy 202.032362 -123.815856) (xy 202.032852 -123.784027) (xy 202.04079 -123.720867)
			(xy 202.056549 -123.659191) (xy 202.079882 -123.599964) (xy 202.110425 -123.544113) (xy 202.1477 -123.49251)
			(xy 202.191124 -123.445964) (xy 202.240018 -123.4052) (xy 202.26655 -123.387612) (xy 202.271376 -123.384564)
			(xy 202.28687 -123.36907) (xy 202.290371 -123.363286) (xy 202.294485 -123.350412) (xy 202.294998 -123.34367)
			(xy 202.29322 -123.243848) (xy 202.29322 -123.240292) (xy 202.286616 -123.229116) (xy 202.283071 -123.223555)
			(xy 202.273684 -123.214296) (xy 202.268074 -123.210828) (xy 202.26782 -123.210574) (xy 202.239928 -123.193988)
			(xy 202.188198 -123.154806) (xy 202.141872 -123.109363) (xy 202.101701 -123.058397) (xy 202.068338 -123.002737)
			(xy 202.042325 -122.943285) (xy 202.024084 -122.881008) (xy 202.013911 -122.816916) (xy 202.011972 -122.752051)
			(xy 202.018298 -122.687467) (xy 202.032787 -122.624211) (xy 202.055203 -122.563312) (xy 202.085182 -122.505757)
			(xy 202.122237 -122.452483) (xy 202.165766 -122.404355) (xy 202.215063 -122.362153) (xy 202.241912 -122.343926)
			(xy 202.248511 -122.338539) (xy 202.257986 -122.324393) (xy 202.260454 -122.31624) (xy 202.261978 -122.304302)
			(xy 202.261978 -122.21845) (xy 202.260454 -122.206512) (xy 202.257977 -122.198364) (xy 202.248495 -122.18423)
			(xy 202.241912 -122.178826) (xy 202.215845 -122.161142) (xy 202.167863 -122.120329) (xy 202.125282 -122.073908)
			(xy 202.088754 -122.022589) (xy 202.058837 -121.967155) (xy 202.035987 -121.908453) (xy 202.020553 -121.847381)
			(xy 202.012772 -121.784872) (xy 202.012296 -121.753376) (xy 202.012296 -121.74347) (xy 202.013148 -121.716741)
			(xy 202.019772 -121.663673) (xy 202.025504 -121.637552) (xy 202.034156 -121.603294) (xy 202.059651 -121.537397)
			(xy 202.076304 -121.506234) (xy 202.076558 -121.50598) (xy 202.07957 -121.500139) (xy 202.0828 -121.487404)
			(xy 202.082908 -121.480834) (xy 202.082654 -121.467372) (xy 202.031346 -121.380504) (xy 202.026589 -121.373065)
			(xy 202.013059 -121.36174) (xy 201.996479 -121.355706) (xy 201.987658 -121.355358) (xy 199.452484 -121.355358)
			(xy 199.447912 -121.355612) (xy 199.435468 -121.357664) (xy 199.414705 -121.371929) (xy 199.408288 -121.38279)
			(xy 199.367902 -121.470166) (xy 199.364748 -121.478696) (xy 199.364023 -121.496854) (xy 199.369643 -121.514137)
			(xy 199.375014 -121.521474) (xy 199.37603 -121.522744) (xy 199.39197 -121.54214) (xy 199.418807 -121.584568)
			(xy 199.439413 -121.630347) (xy 199.453378 -121.678568) (xy 199.460426 -121.728274) (xy 199.460866 -121.753376)
			(xy 199.460866 -121.75363) (xy 199.459342 -121.786396) (xy 199.458864 -121.796229) (xy 199.464511 -121.815071)
			(xy 199.476835 -121.8304) (xy 199.494023 -121.839964) (xy 199.513546 -121.842353) (xy 199.532533 -121.837218)
			(xy 199.540622 -121.831608) (xy 199.56398 -121.814588) (xy 199.615057 -121.787551) (xy 199.669831 -121.769124)
			(xy 199.726864 -121.759793) (xy 199.75576 -121.759218) (xy 199.783747 -121.759736) (xy 199.839032 -121.768487)
			(xy 199.892267 -121.785779) (xy 199.94214 -121.811188) (xy 199.987425 -121.844086) (xy 200.027005 -121.883664)
			(xy 200.059905 -121.928948) (xy 200.085315 -121.978821) (xy 200.10261 -122.032055) (xy 200.111363 -122.087339)
			(xy 200.111868 -122.115326) (xy 200.111353 -122.142596) (xy 200.103045 -122.1965) (xy 200.086611 -122.248505)
			(xy 200.062436 -122.297395) (xy 200.031087 -122.342025) (xy 199.993296 -122.38135) (xy 199.971914 -122.398282)
			(xy 199.96277 -122.405394) (xy 199.95261 -122.42546) (xy 199.949308 -122.527568) (xy 199.958706 -122.54865)
			(xy 199.967342 -122.556016) (xy 199.986402 -122.572995) (xy 200.019938 -122.611476) (xy 200.047629 -122.654356)
			(xy 200.068904 -122.700755) (xy 200.083327 -122.749719) (xy 200.090601 -122.800242) (xy 200.09104 -122.825764)
			(xy 200.090542 -122.852413) (xy 200.082599 -122.905117) (xy 200.066889 -122.956047) (xy 200.043763 -123.004068)
			(xy 200.013739 -123.048105) (xy 199.977487 -123.087176) (xy 199.935816 -123.120407) (xy 199.889658 -123.147056)
			(xy 199.840044 -123.166528) (xy 199.788082 -123.178388) (xy 199.734932 -123.182372) (xy 199.681782 -123.178388)
			(xy 199.62982 -123.166528) (xy 199.580206 -123.147056) (xy 199.534048 -123.120407) (xy 199.492377 -123.087176)
			(xy 199.456125 -123.048105) (xy 199.426101 -123.004068) (xy 199.402975 -122.956047) (xy 199.387265 -122.905117)
			(xy 199.379322 -122.852413) (xy 199.378824 -122.825764) (xy 199.37934 -122.798494) (xy 199.387649 -122.744591)
			(xy 199.404084 -122.692587) (xy 199.428259 -122.643698) (xy 199.459608 -122.599068) (xy 199.497399 -122.559743)
			(xy 199.518778 -122.542808) (xy 199.527922 -122.535696) (xy 199.538082 -122.51563) (xy 199.541384 -122.413522)
			(xy 199.531986 -122.39244) (xy 199.52335 -122.385074) (xy 199.503522 -122.367337) (xy 199.468834 -122.327003)
			(xy 199.440529 -122.281959) (xy 199.419237 -122.233207) (xy 199.405432 -122.181831) (xy 199.401938 -122.155458)
			(xy 199.400414 -122.143266) (xy 199.386952 -122.122946) (xy 199.303894 -122.076718) (xy 199.292945 -122.071449)
			(xy 199.268692 -122.070671) (xy 199.257412 -122.075194) (xy 199.233476 -122.086008) (xy 199.183222 -122.101276)
			(xy 199.131273 -122.109008) (xy 199.105012 -122.109484) (xy 199.104758 -122.109484) (xy 199.09155 -122.10923)
			(xy 199.087994 -122.10923) (xy 199.074786 -122.109484) (xy 199.047976 -122.109) (xy 198.994959 -122.100969)
			(xy 198.943743 -122.085091) (xy 198.895482 -122.061723) (xy 198.851264 -122.031392) (xy 198.812085 -121.994783)
			(xy 198.77883 -121.95272) (xy 198.76516 -121.929652) (xy 198.753476 -121.928128) (xy 198.69404 -121.928128)
			(xy 198.68781 -121.92834) (xy 198.675735 -121.931426) (xy 198.670164 -121.934224) (xy 198.650098 -121.944892)
			(xy 198.640192 -121.95175) (xy 198.636128 -121.955306) (xy 198.632572 -121.960132) (xy 198.615742 -121.982812)
			(xy 198.576112 -122.023046) (xy 198.530624 -122.056516) (xy 198.48042 -122.08238) (xy 198.426762 -122.09999)
			(xy 198.370995 -122.108904) (xy 198.342758 -122.109484) (xy 198.32955 -122.10923) (xy 198.325994 -122.10923)
			(xy 198.312786 -122.109484) (xy 198.284802 -122.108962) (xy 198.229524 -122.100205) (xy 198.176296 -122.082907)
			(xy 198.126429 -122.057496) (xy 198.081152 -122.024597) (xy 198.041579 -121.985019) (xy 198.008684 -121.939738)
			(xy 197.983278 -121.889869) (xy 197.965986 -121.836639) (xy 197.957235 -121.78136) (xy 197.956678 -121.753376)
			(xy 197.957227 -121.725687) (xy 197.96584 -121.67098) (xy 197.982809 -121.618264) (xy 198.007725 -121.568806)
			(xy 198.039988 -121.523794) (xy 198.05904 -121.503694) (xy 198.082662 -121.479564) (xy 198.078852 -121.468388)
			(xy 198.051674 -121.409714) (xy 198.051674 -121.409206) (xy 198.039482 -121.383552) (xy 198.039482 -121.383298)
			(xy 198.035403 -121.375877) (xy 198.023289 -121.36406) (xy 198.007982 -121.356839) (xy 197.999604 -121.355612)
			(xy 197.995032 -121.355358) (xy 194.392042 -121.355358) (xy 194.381977 -121.354923) (xy 194.363392 -121.347189)
			(xy 194.355974 -121.340372) (xy 193.890646 -120.875044) (xy 193.884804 -120.869964) (xy 193.878632 -120.865774)
			(xy 193.864557 -120.860854) (xy 193.857118 -120.860312) (xy 193.782696 -120.860566) (xy 193.777663 -120.860702)
			(xy 193.767805 -120.862741) (xy 193.763138 -120.86463) (xy 193.753994 -120.86844) (xy 193.746882 -120.875552)
			(xy 193.728135 -120.893733) (xy 193.685976 -120.92455) (xy 193.639502 -120.948365) (xy 193.589865 -120.964589)
			(xy 193.538296 -120.972817) (xy 193.512186 -120.973342) (xy 193.511932 -120.973342) (xy 193.498724 -120.973088)
			(xy 193.473765 -120.971628) (xy 193.424681 -120.962129) (xy 193.377585 -120.945353) (xy 193.333549 -120.921682)
			(xy 193.293576 -120.891655) (xy 193.258576 -120.855956) (xy 193.229345 -120.815397) (xy 193.206549 -120.770902)
			(xy 193.190707 -120.723483) (xy 193.18218 -120.674221) (xy 193.181224 -120.649238) (xy 193.181224 -120.642126)
			(xy 193.181634 -120.618912) (xy 193.188156 -120.572945) (xy 193.201035 -120.528338) (xy 193.21018 -120.506998)
			(xy 193.213482 -120.499886) (xy 193.21526 -120.484646) (xy 193.213736 -120.477026) (xy 193.21211 -120.469533)
			(xy 193.205006 -120.455953) (xy 193.199766 -120.450356) (xy 193.11112 -120.36171) (xy 193.097411 -120.347769)
			(xy 193.071735 -120.318278) (xy 193.059812 -120.302782) (xy 193.040524 -120.27651) (xy 193.007426 -120.220362)
			(xy 192.993772 -120.190768) (xy 192.991994 -120.18645) (xy 192.989454 -120.181116) (xy 192.984628 -120.176544)
			(xy 192.982088 -120.174258) (xy 192.978437 -120.170964) (xy 192.970125 -120.165714) (xy 192.965578 -120.163844)
			(xy 192.895982 -120.13819) (xy 192.891139 -120.136547) (xy 192.881029 -120.135014) (xy 192.875916 -120.135142)
			(xy 192.86601 -120.13565) (xy 192.856612 -120.140222) (xy 192.833982 -120.150722) (xy 192.786349 -120.165549)
			(xy 192.737029 -120.173047) (xy 192.712086 -120.173496) (xy 192.6861 -120.172985) (xy 192.634768 -120.164853)
			(xy 192.58534 -120.148791) (xy 192.539033 -120.125194) (xy 192.496988 -120.094644) (xy 192.460239 -120.057892)
			(xy 192.429693 -120.015845) (xy 192.406099 -119.969536) (xy 192.390041 -119.920107) (xy 192.381913 -119.868774)
			(xy 192.381378 -119.842788) (xy 192.381469 -119.830038) (xy 192.383375 -119.804609) (xy 192.385188 -119.791988)
			(xy 192.389367 -119.767923) (xy 192.403878 -119.721285) (xy 192.425092 -119.67729) (xy 192.452548 -119.636895)
			(xy 192.485649 -119.600978) (xy 192.523673 -119.570322) (xy 192.565793 -119.545594) (xy 192.611093 -119.527332)
			(xy 192.658588 -119.515933) (xy 192.682876 -119.51335) (xy 192.683384 -119.51335) (xy 192.690401 -119.512368)
			(xy 192.703539 -119.507073) (xy 192.709292 -119.502936) (xy 192.71488 -119.49811) (xy 192.734184 -119.478044)
			(xy 192.735708 -119.476266) (xy 192.741671 -119.468879) (xy 192.74815 -119.45105) (xy 192.747725 -119.432084)
			(xy 192.740453 -119.414562) (xy 192.734184 -119.407432) (xy 192.71488 -119.387366) (xy 192.711686 -119.384164)
			(xy 192.704407 -119.378799) (xy 192.700402 -119.376698) (xy 192.692274 -119.372888) (xy 192.682622 -119.372126)
			(xy 192.658244 -119.369504) (xy 192.610587 -119.357984) (xy 192.565155 -119.339552) (xy 192.522942 -119.314613)
			(xy 192.484875 -119.283714) (xy 192.451788 -119.247532) (xy 192.424408 -119.206861) (xy 192.403333 -119.162592)
			(xy 192.389027 -119.115697) (xy 192.381803 -119.067203) (xy 192.381378 -119.042688) (xy 192.381825 -119.018165)
			(xy 192.38907 -118.969657) (xy 192.4034 -118.922751) (xy 192.4245 -118.878475) (xy 192.451907 -118.837801)
			(xy 192.485021 -118.801621) (xy 192.523115 -118.770728) (xy 192.565354 -118.7458) (xy 192.610811 -118.727384)
			(xy 192.65849 -118.715882) (xy 192.682876 -118.71325) (xy 192.683638 -118.71325) (xy 192.692266 -118.711982)
			(xy 192.707979 -118.704449) (xy 192.714372 -118.698518) (xy 192.71488 -118.69801) (xy 192.73393 -118.678452)
			(xy 192.738308 -118.67371) (xy 192.74474 -118.662525) (xy 192.74663 -118.656354) (xy 192.748558 -118.647808)
			(xy 192.747171 -118.630355) (xy 192.740014 -118.614377) (xy 192.734184 -118.60784) (xy 192.71488 -118.58752)
			(xy 192.711639 -118.584289) (xy 192.704229 -118.578922) (xy 192.700148 -118.576852) (xy 192.692274 -118.573042)
			(xy 192.682622 -118.57228) (xy 192.658242 -118.569659) (xy 192.610583 -118.558139) (xy 192.565146 -118.539708)
			(xy 192.52293 -118.51477) (xy 192.484858 -118.483872) (xy 192.451766 -118.447691) (xy 192.424379 -118.40702)
			(xy 192.403298 -118.362751) (xy 192.388985 -118.315854) (xy 192.381753 -118.267358) (xy 192.381378 -118.242842)
			(xy 192.381828 -118.218321) (xy 192.389079 -118.169818) (xy 192.403412 -118.122917) (xy 192.424515 -118.078648)
			(xy 192.451924 -118.03798) (xy 192.485038 -118.001805) (xy 192.523131 -117.970918) (xy 192.565367 -117.945994)
			(xy 192.610821 -117.92758) (xy 192.658496 -117.916081) (xy 192.682876 -117.913404) (xy 192.683384 -117.913404)
			(xy 192.690402 -117.912423) (xy 192.703543 -117.907133) (xy 192.709292 -117.90299) (xy 192.71488 -117.898164)
			(xy 192.734184 -117.878098) (xy 192.735708 -117.87632) (xy 192.741681 -117.868933) (xy 192.748179 -117.851095)
			(xy 192.747768 -117.832115) (xy 192.740505 -117.814576) (xy 192.734184 -117.807486) (xy 192.71488 -117.78742)
			(xy 192.711684 -117.784221) (xy 192.704403 -117.778859) (xy 192.700402 -117.776752) (xy 192.692274 -117.772942)
			(xy 192.682622 -117.77218) (xy 192.658242 -117.769559) (xy 192.610583 -117.758039) (xy 192.565146 -117.739608)
			(xy 192.52293 -117.71467) (xy 192.484858 -117.683772) (xy 192.451766 -117.647591) (xy 192.424379 -117.60692)
			(xy 192.403298 -117.562651) (xy 192.388985 -117.515754) (xy 192.381753 -117.467258) (xy 192.381378 -117.442742)
			(xy 192.381828 -117.418221) (xy 192.389079 -117.369718) (xy 192.403412 -117.322817) (xy 192.424515 -117.278548)
			(xy 192.451924 -117.23788) (xy 192.485038 -117.201705) (xy 192.523131 -117.170818) (xy 192.565367 -117.145894)
			(xy 192.610821 -117.12748) (xy 192.658496 -117.115981) (xy 192.682876 -117.113304) (xy 192.683384 -117.113304)
			(xy 192.690402 -117.112323) (xy 192.703543 -117.107033) (xy 192.709292 -117.10289) (xy 192.71488 -117.098064)
			(xy 192.734184 -117.077998) (xy 192.735708 -117.07622) (xy 192.741681 -117.068833) (xy 192.748179 -117.050995)
			(xy 192.747768 -117.032015) (xy 192.740505 -117.014476) (xy 192.734184 -117.007386) (xy 192.71488 -116.98732)
			(xy 192.711684 -116.984121) (xy 192.704403 -116.978759) (xy 192.700402 -116.976652) (xy 192.692274 -116.972842)
			(xy 192.682622 -116.97208) (xy 192.658242 -116.969459) (xy 192.610583 -116.957939) (xy 192.565146 -116.939508)
			(xy 192.52293 -116.91457) (xy 192.484858 -116.883672) (xy 192.451766 -116.847491) (xy 192.424379 -116.80682)
			(xy 192.403298 -116.762551) (xy 192.388985 -116.715654) (xy 192.381753 -116.667158) (xy 192.381378 -116.642642)
			(xy 192.381828 -116.618121) (xy 192.389079 -116.569618) (xy 192.403412 -116.522717) (xy 192.424515 -116.478448)
			(xy 192.451924 -116.43778) (xy 192.485038 -116.401605) (xy 192.523131 -116.370718) (xy 192.565367 -116.345794)
			(xy 192.610821 -116.32738) (xy 192.658496 -116.315881) (xy 192.682876 -116.313204) (xy 192.683638 -116.313204)
			(xy 192.692267 -116.311938) (xy 192.707986 -116.304411) (xy 192.714372 -116.298472) (xy 192.71488 -116.297964)
			(xy 192.73393 -116.278406) (xy 192.738304 -116.273662) (xy 192.744726 -116.262474) (xy 192.74663 -116.256308)
			(xy 192.74855 -116.247764) (xy 192.747149 -116.23032) (xy 192.739985 -116.214354) (xy 192.734184 -116.207794)
			(xy 192.71488 -116.187474) (xy 192.711638 -116.184246) (xy 192.704225 -116.178883) (xy 192.700148 -116.176806)
			(xy 192.692274 -116.172996) (xy 192.682622 -116.172234) (xy 192.658244 -116.169612) (xy 192.610587 -116.158092)
			(xy 192.565154 -116.13966) (xy 192.52294 -116.114722) (xy 192.484873 -116.083823) (xy 192.451785 -116.047641)
			(xy 192.424403 -116.00697) (xy 192.403328 -115.962701) (xy 192.389021 -115.915805) (xy 192.381796 -115.867311)
			(xy 192.381378 -115.842796) (xy 192.381824 -115.818273) (xy 192.389068 -115.769763) (xy 192.403397 -115.722856)
			(xy 192.424497 -115.67858) (xy 192.451904 -115.637905) (xy 192.485018 -115.601724) (xy 192.523113 -115.57083)
			(xy 192.565352 -115.545901) (xy 192.61081 -115.527484) (xy 192.658489 -115.515982) (xy 192.682876 -115.513358)
			(xy 192.683638 -115.513358) (xy 192.691576 -115.512166) (xy 192.706203 -115.505577) (xy 192.71234 -115.500404)
			(xy 192.737232 -115.47475) (xy 192.743095 -115.467556) (xy 192.749728 -115.450238) (xy 192.750186 -115.440968)
			(xy 192.750186 -114.664744) (xy 192.75012 -114.660736) (xy 192.748848 -114.65282) (xy 192.747646 -114.648996)
			(xy 192.745739 -114.643568) (xy 192.739831 -114.633697) (xy 192.735962 -114.629438) (xy 192.71488 -114.607594)
			(xy 192.711687 -114.604391) (xy 192.704409 -114.599023) (xy 192.700402 -114.596926) (xy 192.692274 -114.593116)
			(xy 192.682622 -114.592354) (xy 192.658243 -114.589732) (xy 192.610585 -114.578212) (xy 192.56515 -114.559781)
			(xy 192.522936 -114.534843) (xy 192.484866 -114.503944) (xy 192.451777 -114.467763) (xy 192.424393 -114.427091)
			(xy 192.403315 -114.382823) (xy 192.389005 -114.335927) (xy 192.381777 -114.287431) (xy 192.381378 -114.262916)
			(xy 192.381823 -114.238392) (xy 192.389064 -114.18988) (xy 192.403392 -114.142971) (xy 192.42449 -114.098692)
			(xy 192.451897 -114.058014) (xy 192.485011 -114.021831) (xy 192.523106 -113.990935) (xy 192.565346 -113.966004)
			(xy 192.610805 -113.947585) (xy 192.658486 -113.936083) (xy 192.682876 -113.933478) (xy 192.683638 -113.933478)
			(xy 192.692266 -113.932212) (xy 192.707983 -113.924681) (xy 192.714372 -113.918746) (xy 192.71488 -113.918238)
			(xy 192.73393 -113.89868) (xy 192.738301 -113.893934) (xy 192.744718 -113.882745) (xy 192.74663 -113.876582)
			(xy 192.748545 -113.868039) (xy 192.747137 -113.8506) (xy 192.739968 -113.834641) (xy 192.734184 -113.828068)
			(xy 192.71488 -113.807748) (xy 192.71164 -113.804516) (xy 192.704231 -113.799146) (xy 192.700148 -113.79708)
			(xy 192.692274 -113.79327) (xy 192.682622 -113.792508) (xy 192.658244 -113.789886) (xy 192.610589 -113.778366)
			(xy 192.565158 -113.759934) (xy 192.522946 -113.734994) (xy 192.484881 -113.704095) (xy 192.451796 -113.667913)
			(xy 192.424417 -113.627242) (xy 192.403345 -113.582973) (xy 192.389041 -113.536078) (xy 192.38182 -113.487584)
			(xy 192.381378 -113.46307) (xy 192.381826 -113.438548) (xy 192.389073 -113.390042) (xy 192.403405 -113.343138)
			(xy 192.424506 -113.298864) (xy 192.451914 -113.258193) (xy 192.485028 -113.222015) (xy 192.523121 -113.191124)
			(xy 192.565359 -113.166198) (xy 192.610815 -113.147782) (xy 192.658492 -113.136282) (xy 192.682876 -113.133632)
			(xy 192.683384 -113.133632) (xy 192.690401 -113.132649) (xy 192.703537 -113.127353) (xy 192.709292 -113.123218)
			(xy 192.71488 -113.118392) (xy 192.734184 -113.098326) (xy 192.735708 -113.096548) (xy 192.741667 -113.089162)
			(xy 192.74814 -113.071334) (xy 192.74771 -113.052373) (xy 192.740436 -113.034858) (xy 192.734184 -113.027714)
			(xy 192.71488 -113.007648) (xy 192.711685 -113.004447) (xy 192.704405 -112.999083) (xy 192.700402 -112.99698)
			(xy 192.692274 -112.99317) (xy 192.682622 -112.992408) (xy 192.658244 -112.989786) (xy 192.610589 -112.978266)
			(xy 192.565158 -112.959834) (xy 192.522946 -112.934894) (xy 192.484881 -112.903995) (xy 192.451796 -112.867813)
			(xy 192.424417 -112.827142) (xy 192.403345 -112.782873) (xy 192.389041 -112.735978) (xy 192.38182 -112.687484)
			(xy 192.381378 -112.66297) (xy 192.381826 -112.638448) (xy 192.389073 -112.589942) (xy 192.403405 -112.543038)
			(xy 192.424506 -112.498764) (xy 192.451914 -112.458093) (xy 192.485028 -112.421915) (xy 192.523121 -112.391024)
			(xy 192.565359 -112.366098) (xy 192.610815 -112.347682) (xy 192.658492 -112.336182) (xy 192.682876 -112.333532)
			(xy 192.683384 -112.333532) (xy 192.690401 -112.332549) (xy 192.703537 -112.327253) (xy 192.709292 -112.323118)
			(xy 192.71488 -112.318292) (xy 192.734184 -112.298226) (xy 192.735708 -112.296448) (xy 192.741667 -112.289062)
			(xy 192.74814 -112.271234) (xy 192.74771 -112.252273) (xy 192.740436 -112.234758) (xy 192.734184 -112.227614)
			(xy 192.71488 -112.207548) (xy 192.711685 -112.204347) (xy 192.704405 -112.198983) (xy 192.700402 -112.19688)
			(xy 192.692274 -112.19307) (xy 192.682622 -112.192308) (xy 192.658244 -112.189686) (xy 192.610589 -112.178166)
			(xy 192.565158 -112.159734) (xy 192.522946 -112.134794) (xy 192.484881 -112.103895) (xy 192.451796 -112.067713)
			(xy 192.424417 -112.027042) (xy 192.403345 -111.982773) (xy 192.389041 -111.935878) (xy 192.38182 -111.887384)
			(xy 192.381378 -111.86287) (xy 192.381826 -111.838348) (xy 192.389073 -111.789842) (xy 192.403405 -111.742938)
			(xy 192.424506 -111.698664) (xy 192.451914 -111.657993) (xy 192.485028 -111.621815) (xy 192.523121 -111.590924)
			(xy 192.565359 -111.565998) (xy 192.610815 -111.547582) (xy 192.658492 -111.536082) (xy 192.682876 -111.533432)
			(xy 192.683638 -111.533432) (xy 192.692265 -111.532164) (xy 192.707977 -111.524628) (xy 192.714372 -111.5187)
			(xy 192.71488 -111.518192) (xy 192.73393 -111.498634) (xy 192.738306 -111.493891) (xy 192.744735 -111.482705)
			(xy 192.74663 -111.476536) (xy 192.748555 -111.467991) (xy 192.747162 -111.450541) (xy 192.740003 -111.434568)
			(xy 192.734184 -111.428022) (xy 192.71488 -111.407702) (xy 192.711639 -111.404472) (xy 192.704227 -111.399107)
			(xy 192.700148 -111.397034) (xy 192.692274 -111.393224) (xy 192.682622 -111.392462) (xy 192.658243 -111.38984)
			(xy 192.610584 -111.378321) (xy 192.565149 -111.359889) (xy 192.522934 -111.334951) (xy 192.484864 -111.304053)
			(xy 192.451773 -111.267871) (xy 192.424389 -111.2272) (xy 192.40331 -111.182931) (xy 192.388999 -111.136035)
			(xy 192.38177 -111.08754) (xy 192.381378 -111.063024) (xy 192.381822 -111.038499) (xy 192.389063 -110.989987)
			(xy 192.403389 -110.943076) (xy 192.424487 -110.898796) (xy 192.451894 -110.858118) (xy 192.485008 -110.821933)
			(xy 192.523103 -110.791037) (xy 192.565344 -110.766105) (xy 192.610804 -110.747686) (xy 192.658485 -110.736183)
			(xy 192.682876 -110.733586) (xy 192.683384 -110.733586) (xy 192.690402 -110.732604) (xy 192.703541 -110.727313)
			(xy 192.709292 -110.723172) (xy 192.71488 -110.718346) (xy 192.734184 -110.69828) (xy 192.735708 -110.696502)
			(xy 192.741677 -110.689115) (xy 192.748169 -110.67128) (xy 192.747753 -110.652305) (xy 192.740487 -110.634771)
			(xy 192.734184 -110.627668) (xy 192.71488 -110.607602) (xy 192.711639 -110.604372) (xy 192.704227 -110.599007)
			(xy 192.700148 -110.596934) (xy 192.692528 -110.593378) (xy 192.682876 -110.592362) (xy 192.658489 -110.589751)
			(xy 192.610813 -110.578248) (xy 192.565358 -110.559828) (xy 192.523123 -110.534897) (xy 192.485034 -110.504001)
			(xy 192.451927 -110.467817) (xy 192.424527 -110.42714) (xy 192.403436 -110.382862) (xy 192.389117 -110.335955)
			(xy 192.381884 -110.287446) (xy 192.381378 -110.262924) (xy 192.381785 -110.2392) (xy 192.388565 -110.19224)
			(xy 192.401987 -110.146731) (xy 192.421777 -110.103608) (xy 192.447528 -110.063756) (xy 192.478712 -110.027996)
			(xy 192.49644 -110.012226) (xy 192.496948 -110.011718) (xy 192.502784 -110.006227) (xy 192.511056 -109.992514)
			(xy 192.513204 -109.984794) (xy 192.514474 -109.975142) (xy 192.517268 -109.900974) (xy 192.517182 -109.890471)
			(xy 192.509586 -109.870912) (xy 192.502536 -109.863128) (xy 192.312036 -109.672628) (xy 192.306369 -109.667381)
			(xy 192.292665 -109.660274) (xy 192.285112 -109.658658) (xy 192.283334 -109.658404) (xy 192.282572 -109.658404)
			(xy 192.28054 -109.65815) (xy 192.274444 -109.657896) (xy 192.242186 -109.658912) (xy 192.241678 -109.658912)
			(xy 192.195704 -109.66069) (xy 192.186382 -109.662253) (xy 192.169704 -109.671111) (xy 192.163192 -109.677962)
			(xy 192.162938 -109.678216) (xy 192.147169 -109.696) (xy 192.111406 -109.727306) (xy 192.071529 -109.753168)
			(xy 192.028359 -109.773053) (xy 191.982786 -109.786551) (xy 191.935751 -109.793383) (xy 191.911986 -109.793786)
			(xy 191.885998 -109.793302) (xy 191.834662 -109.785169) (xy 191.785231 -109.769105) (xy 191.738922 -109.745506)
			(xy 191.696874 -109.714953) (xy 191.660123 -109.678199) (xy 191.629575 -109.636148) (xy 191.605981 -109.589835)
			(xy 191.589923 -109.540402) (xy 191.581795 -109.489066) (xy 191.581278 -109.463078) (xy 191.581712 -109.439316)
			(xy 191.588556 -109.392288) (xy 191.602057 -109.346722) (xy 191.621938 -109.303556) (xy 191.647789 -109.263677)
			(xy 191.679078 -109.227907) (xy 191.696848 -109.212126) (xy 191.697102 -109.211872) (xy 191.704031 -109.205418)
			(xy 191.712921 -109.188715) (xy 191.714374 -109.17936) (xy 191.716152 -109.133386) (xy 191.716152 -109.132878)
			(xy 191.717168 -109.10062) (xy 191.716914 -109.094524) (xy 191.71666 -109.092492) (xy 191.71666 -109.09173)
			(xy 191.716406 -109.089952) (xy 191.714786 -109.082402) (xy 191.707669 -109.068707) (xy 191.702436 -109.063028)
			(xy 191.511936 -108.872528) (xy 191.506269 -108.867281) (xy 191.492565 -108.860174) (xy 191.485012 -108.858558)
			(xy 191.483234 -108.858304) (xy 191.482472 -108.858304) (xy 191.48044 -108.85805) (xy 191.474344 -108.857796)
			(xy 191.442086 -108.858812) (xy 191.441578 -108.858812) (xy 191.395604 -108.86059) (xy 191.386282 -108.862153)
			(xy 191.369604 -108.871011) (xy 191.363092 -108.877862) (xy 191.362838 -108.878116) (xy 191.347069 -108.8959)
			(xy 191.311306 -108.927206) (xy 191.271429 -108.953068) (xy 191.228259 -108.972953) (xy 191.182686 -108.986451)
			(xy 191.135651 -108.993283) (xy 191.111886 -108.993686) (xy 191.085898 -108.993202) (xy 191.034562 -108.985069)
			(xy 190.985131 -108.969005) (xy 190.938822 -108.945406) (xy 190.896774 -108.914853) (xy 190.860023 -108.878099)
			(xy 190.829475 -108.836048) (xy 190.805881 -108.789735) (xy 190.789823 -108.740302) (xy 190.781695 -108.688966)
			(xy 190.781178 -108.662978) (xy 190.781612 -108.639216) (xy 190.788456 -108.592188) (xy 190.801957 -108.546622)
			(xy 190.821838 -108.503456) (xy 190.847689 -108.463577) (xy 190.878978 -108.427807) (xy 190.896748 -108.412026)
			(xy 190.897002 -108.411772) (xy 190.903802 -108.405375) (xy 190.912671 -108.388964) (xy 190.914274 -108.379768)
			(xy 190.916814 -108.306362) (xy 190.917068 -108.298488) (xy 190.916546 -108.288591) (xy 190.908959 -108.270302)
			(xy 190.902336 -108.262928) (xy 190.711836 -108.072428) (xy 190.70403 -108.065412) (xy 190.684486 -108.057817)
			(xy 190.67399 -108.057696) (xy 190.602108 -108.06049) (xy 190.599568 -108.06049) (xy 190.589181 -108.061399)
			(xy 190.570421 -108.07045) (xy 190.563246 -108.078016) (xy 190.562738 -108.078524) (xy 190.546957 -108.09624)
			(xy 190.511194 -108.127415) (xy 190.471343 -108.15316) (xy 190.428223 -108.172948) (xy 190.382718 -108.186371)
			(xy 190.335762 -108.193155) (xy 190.31204 -108.193586) (xy 190.286049 -108.193106) (xy 190.234707 -108.184979)
			(xy 190.185269 -108.16892) (xy 190.138952 -108.145324) (xy 190.096896 -108.114773) (xy 190.060139 -108.078017)
			(xy 190.029585 -108.035964) (xy 190.005986 -107.989648) (xy 189.989925 -107.94021) (xy 189.981796 -107.888869)
			(xy 189.981332 -107.862878) (xy 189.981743 -107.839156) (xy 189.988528 -107.7922) (xy 190.001957 -107.746697)
			(xy 190.021754 -107.703581) (xy 190.04751 -107.663737) (xy 190.078699 -107.627985) (xy 190.096394 -107.61218)
			(xy 190.096902 -107.611672) (xy 190.104429 -107.604471) (xy 190.113463 -107.585723) (xy 190.114428 -107.57535)
			(xy 190.114428 -107.57281) (xy 190.117222 -107.500928) (xy 190.117126 -107.49043) (xy 190.109512 -107.470888)
			(xy 190.10249 -107.463082) (xy 190.070994 -107.431586) (xy 190.038228 -107.39882) (xy 190.034543 -107.395382)
			(xy 190.026098 -107.389882) (xy 190.021464 -107.387898) (xy 190.013336 -107.384596) (xy 186.742324 -107.384596)
			(xy 186.734958 -107.384342) (xy 186.390534 -107.384342) (xy 186.384946 -107.385866) (xy 186.360938 -107.390832)
			(xy 186.312048 -107.394458) (xy 186.263158 -107.390832) (xy 186.23915 -107.385866) (xy 186.233562 -107.384342)
			(xy 185.889138 -107.384342) (xy 185.881772 -107.384596) (xy 185.162444 -107.384596) (xy 185.155078 -107.384342)
			(xy 184.810654 -107.384342) (xy 184.805066 -107.385866) (xy 184.781058 -107.390832) (xy 184.732168 -107.394458)
			(xy 184.683278 -107.390832) (xy 184.65927 -107.385866) (xy 184.653682 -107.384342) (xy 184.010808 -107.384342)
			(xy 184.00522 -107.385866) (xy 183.981212 -107.390832) (xy 183.932322 -107.394458) (xy 183.883432 -107.390832)
			(xy 183.859424 -107.385866) (xy 183.853836 -107.384342) (xy 183.210708 -107.384342) (xy 183.20512 -107.385612)
			(xy 183.187136 -107.389418) (xy 183.150602 -107.393494) (xy 183.132222 -107.39374) (xy 183.106233 -107.393232)
			(xy 183.054894 -107.385104) (xy 183.005458 -107.369046) (xy 182.959143 -107.345452) (xy 182.91709 -107.314903)
			(xy 182.880332 -107.278152) (xy 182.849777 -107.236103) (xy 182.826175 -107.189792) (xy 182.810108 -107.140359)
			(xy 182.801972 -107.089021) (xy 182.801514 -107.063032) (xy 182.801599 -107.053421) (xy 182.802744 -107.034232)
			(xy 182.8038 -107.024678) (xy 182.8038 -107.024424) (xy 182.80444 -107.013034) (xy 182.796926 -106.991526)
			(xy 182.789322 -106.983022) (xy 182.764684 -106.958384) (xy 182.756448 -106.950972) (xy 182.735652 -106.943391)
			(xy 182.713594 -106.945226) (xy 182.703724 -106.950256) (xy 182.684166 -106.961178) (xy 182.679226 -106.964156)
			(xy 182.670751 -106.971977) (xy 182.667402 -106.976672) (xy 182.662563 -106.984413) (xy 182.658129 -107.00211)
			(xy 182.658766 -107.011216) (xy 182.65902 -107.012994) (xy 182.660804 -107.025426) (xy 182.662709 -107.050473)
			(xy 182.66283 -107.063032) (xy 182.662318 -107.089021) (xy 182.654182 -107.140357) (xy 182.638115 -107.189789)
			(xy 182.614514 -107.2361) (xy 182.583958 -107.278147) (xy 182.547201 -107.314898) (xy 182.505148 -107.345445)
			(xy 182.458833 -107.369039) (xy 182.409398 -107.385096) (xy 182.35806 -107.393223) (xy 182.306083 -107.393218)
			(xy 182.254746 -107.385083) (xy 182.205314 -107.369017) (xy 182.159003 -107.345415) (xy 182.116955 -107.31486)
			(xy 182.080205 -107.278104) (xy 182.049656 -107.236051) (xy 182.026063 -107.189736) (xy 182.010005 -107.140302)
			(xy 182.001878 -107.088963) (xy 182.001882 -107.036986) (xy 182.010017 -106.985649) (xy 182.026082 -106.936217)
			(xy 182.049683 -106.889906) (xy 182.080237 -106.847858) (xy 182.116994 -106.811107) (xy 182.159047 -106.780558)
			(xy 182.20536 -106.756964) (xy 182.254795 -106.740905) (xy 182.306133 -106.732778) (xy 182.332122 -106.732324)
			(xy 182.344681 -106.732442) (xy 182.369727 -106.73435) (xy 182.38216 -106.736134) (xy 182.383938 -106.736388)
			(xy 182.393049 -106.737062) (xy 182.410757 -106.732629) (xy 182.418482 -106.727752) (xy 182.423136 -106.724356)
			(xy 182.43095 -106.715891) (xy 182.433976 -106.710988) (xy 182.444898 -106.69143) (xy 182.449896 -106.681545)
			(xy 182.451756 -106.659496) (xy 182.444176 -106.638708) (xy 182.43677 -106.63047) (xy 182.412132 -106.605832)
			(xy 182.403616 -106.598241) (xy 182.382117 -106.590702) (xy 182.37073 -106.591354) (xy 182.370476 -106.591354)
			(xy 182.360923 -106.592417) (xy 182.341734 -106.593563) (xy 182.332122 -106.59364) (xy 182.306133 -106.593132)
			(xy 182.254794 -106.585004) (xy 182.205358 -106.568946) (xy 182.159043 -106.545352) (xy 182.11699 -106.514803)
			(xy 182.080232 -106.478052) (xy 182.049677 -106.436003) (xy 182.026075 -106.389692) (xy 182.010008 -106.340259)
			(xy 182.001872 -106.288921) (xy 182.001414 -106.262932) (xy 182.002007 -106.23493) (xy 182.011449 -106.179728)
			(xy 182.030053 -106.126904) (xy 182.057286 -106.077967) (xy 182.09237 -106.034314) (xy 182.11292 -106.015282)
			(xy 182.119327 -106.008749) (xy 182.127391 -105.99234) (xy 182.128668 -105.983278) (xy 182.128922 -105.978452)
			(xy 182.128922 -99.81565) (xy 182.128668 -99.810824) (xy 182.127215 -99.800428) (xy 182.117114 -99.782054)
			(xy 182.10911 -99.775264) (xy 182.10403 -99.771962) (xy 182.026814 -99.725734) (xy 182.02146 -99.72311)
			(xy 182.00991 -99.720165) (xy 182.003954 -99.719892) (xy 181.991508 -99.719638) (xy 181.985666 -99.722686)
			(xy 181.957078 -99.738136) (xy 181.896815 -99.762452) (xy 181.833944 -99.77889) (xy 181.769492 -99.787184)
			(xy 181.737 -99.78771) (xy 181.70569 -99.787229) (xy 181.643544 -99.779538) (xy 181.582813 -99.764273)
			(xy 181.524417 -99.741664) (xy 181.46924 -99.712055) (xy 181.418117 -99.675893) (xy 181.371822 -99.633725)
			(xy 181.331057 -99.586192) (xy 181.313328 -99.56038) (xy 181.310534 -99.55657) (xy 181.303626 -99.548844)
			(xy 181.285263 -99.539278) (xy 181.274974 -99.538028) (xy 181.271164 -99.537774) (xy 181.186836 -99.537774)
			(xy 181.183026 -99.538028) (xy 181.172741 -99.539292) (xy 181.154379 -99.548852) (xy 181.147466 -99.55657)
			(xy 181.144672 -99.56038) (xy 181.126958 -99.586201) (xy 181.086187 -99.633729) (xy 181.039887 -99.67589)
			(xy 180.988761 -99.712046) (xy 180.933582 -99.741651) (xy 180.875186 -99.764256) (xy 180.814455 -99.779519)
			(xy 180.75231 -99.787208) (xy 180.68969 -99.787208) (xy 180.627545 -99.779519) (xy 180.566814 -99.764256)
			(xy 180.508418 -99.741651) (xy 180.453239 -99.712046) (xy 180.402113 -99.67589) (xy 180.355813 -99.633729)
			(xy 180.315042 -99.586201) (xy 180.297328 -99.56038) (xy 180.294534 -99.55657) (xy 180.287626 -99.548844)
			(xy 180.269263 -99.539278) (xy 180.258974 -99.538028) (xy 180.255164 -99.537774) (xy 180.170836 -99.537774)
			(xy 180.167026 -99.538028) (xy 180.156741 -99.539292) (xy 180.138379 -99.548852) (xy 180.131466 -99.55657)
			(xy 180.128672 -99.56038) (xy 180.110958 -99.586201) (xy 180.070187 -99.633729) (xy 180.023887 -99.67589)
			(xy 179.972761 -99.712046) (xy 179.917582 -99.741651) (xy 179.859186 -99.764256) (xy 179.798455 -99.779519)
			(xy 179.73631 -99.787208) (xy 179.67369 -99.787208) (xy 179.611545 -99.779519) (xy 179.550814 -99.764256)
			(xy 179.492418 -99.741651) (xy 179.437239 -99.712046) (xy 179.386113 -99.67589) (xy 179.339813 -99.633729)
			(xy 179.299042 -99.586201) (xy 179.281328 -99.56038) (xy 179.278534 -99.55657) (xy 179.271626 -99.548844)
			(xy 179.253263 -99.539278) (xy 179.242974 -99.538028) (xy 179.239164 -99.537774) (xy 179.154836 -99.537774)
			(xy 179.151026 -99.538028) (xy 179.140741 -99.539292) (xy 179.122379 -99.548852) (xy 179.115466 -99.55657)
			(xy 179.112672 -99.56038) (xy 179.094958 -99.586201) (xy 179.054187 -99.633729) (xy 179.007887 -99.67589)
			(xy 178.956761 -99.712046) (xy 178.901582 -99.741651) (xy 178.843186 -99.764256) (xy 178.782455 -99.779519)
			(xy 178.72031 -99.787208) (xy 178.65769 -99.787208) (xy 178.595545 -99.779519) (xy 178.534814 -99.764256)
			(xy 178.476418 -99.741651) (xy 178.421239 -99.712046) (xy 178.370113 -99.67589) (xy 178.323813 -99.633729)
			(xy 178.283042 -99.586201) (xy 178.265328 -99.56038) (xy 178.262534 -99.55657) (xy 178.255626 -99.548844)
			(xy 178.237263 -99.539278) (xy 178.226974 -99.538028) (xy 178.223164 -99.537774) (xy 178.138836 -99.537774)
			(xy 178.135026 -99.538028) (xy 178.124741 -99.539292) (xy 178.106379 -99.548852) (xy 178.099466 -99.55657)
			(xy 178.096672 -99.56038) (xy 178.078958 -99.586201) (xy 178.038187 -99.633729) (xy 177.991887 -99.67589)
			(xy 177.940761 -99.712046) (xy 177.885582 -99.741651) (xy 177.827186 -99.764256) (xy 177.766455 -99.779519)
			(xy 177.70431 -99.787208) (xy 177.64169 -99.787208) (xy 177.579545 -99.779519) (xy 177.518814 -99.764256)
			(xy 177.460418 -99.741651) (xy 177.405239 -99.712046) (xy 177.354113 -99.67589) (xy 177.307813 -99.633729)
			(xy 177.267042 -99.586201) (xy 177.249328 -99.56038) (xy 177.246534 -99.55657) (xy 177.239626 -99.548844)
			(xy 177.221263 -99.539278) (xy 177.210974 -99.538028) (xy 177.207164 -99.537774) (xy 177.122836 -99.537774)
			(xy 177.119026 -99.538028) (xy 177.108741 -99.539292) (xy 177.090379 -99.548852) (xy 177.083466 -99.55657)
			(xy 177.080672 -99.56038) (xy 177.062957 -99.586201) (xy 177.022183 -99.633728) (xy 176.975884 -99.67589)
			(xy 176.924758 -99.712049) (xy 176.86958 -99.741658) (xy 176.811185 -99.764269) (xy 176.750455 -99.77954)
			(xy 176.68831 -99.78724) (xy 176.657 -99.78771) (xy 176.626253 -99.787246) (xy 176.565206 -99.779834)
			(xy 176.505498 -99.765118) (xy 176.447999 -99.743313) (xy 176.393547 -99.714737) (xy 176.342936 -99.679805)
			(xy 176.296905 -99.639029) (xy 176.256124 -99.593001) (xy 176.221188 -99.542394) (xy 176.192607 -99.487945)
			(xy 176.170796 -99.430448) (xy 176.156075 -99.370741) (xy 176.148657 -99.309695) (xy 176.148238 -99.278948)
			(xy 176.148716 -99.247636) (xy 176.156401 -99.185486) (xy 176.171661 -99.12475) (xy 176.194264 -99.066348)
			(xy 176.223869 -99.011164) (xy 176.260027 -98.960034) (xy 176.302191 -98.913731) (xy 176.349722 -98.872957)
			(xy 176.375568 -98.855276) (xy 176.379378 -98.852482) (xy 176.387105 -98.845573) (xy 176.396678 -98.827213)
			(xy 176.39792 -98.816922) (xy 176.398174 -98.813112) (xy 176.398174 -98.728784) (xy 176.39792 -98.724974)
			(xy 176.396645 -98.714696) (xy 176.387066 -98.696355) (xy 176.379378 -98.689414) (xy 176.375568 -98.68662)
			(xy 176.349747 -98.668905) (xy 176.30222 -98.628133) (xy 176.260059 -98.581833) (xy 176.223902 -98.530707)
			(xy 176.194295 -98.475529) (xy 176.171688 -98.417133) (xy 176.156421 -98.356403) (xy 176.148727 -98.294258)
			(xy 176.148238 -98.262948) (xy 176.14874 -98.230971) (xy 176.156755 -98.167521) (xy 176.17266 -98.105576)
			(xy 176.196203 -98.046114) (xy 176.227013 -97.99007) (xy 176.264605 -97.93833) (xy 176.308384 -97.89171)
			(xy 176.357662 -97.850944) (xy 176.41166 -97.816676) (xy 176.469527 -97.789445) (xy 176.530351 -97.769682)
			(xy 176.593172 -97.757699) (xy 176.657 -97.753683) (xy 176.720828 -97.757699) (xy 176.783649 -97.769682)
			(xy 176.844473 -97.789445) (xy 176.90234 -97.816676) (xy 176.956338 -97.850944) (xy 177.005616 -97.89171)
			(xy 177.049395 -97.93833) (xy 177.086987 -97.99007) (xy 177.117797 -98.046114) (xy 177.14134 -98.105576)
			(xy 177.157245 -98.167521) (xy 177.16526 -98.230971) (xy 177.165762 -98.262948) (xy 177.165284 -98.29426)
			(xy 177.157599 -98.356411) (xy 177.14234 -98.417147) (xy 177.119737 -98.475549) (xy 177.090132 -98.530734)
			(xy 177.053974 -98.581864) (xy 177.011811 -98.628167) (xy 176.96428 -98.668942) (xy 176.938432 -98.68662)
			(xy 176.934622 -98.689414) (xy 176.926894 -98.696322) (xy 176.91732 -98.714683) (xy 176.91608 -98.724974)
			(xy 176.915826 -98.728784) (xy 176.915826 -98.813112) (xy 176.91608 -98.816922) (xy 176.917378 -98.827391)
			(xy 176.927202 -98.846034) (xy 176.93513 -98.85299) (xy 176.938432 -98.855276) (xy 176.966248 -98.874418)
			(xy 177.017052 -98.918896) (xy 177.061523 -98.969705) (xy 177.080672 -98.997516) (xy 177.082958 -99.000818)
			(xy 177.089927 -99.008735) (xy 177.108559 -99.018567) (xy 177.119026 -99.019868) (xy 177.122836 -99.020122)
			(xy 177.207164 -99.020122) (xy 177.210974 -99.019868) (xy 177.221165 -99.018621) (xy 177.239377 -99.009181)
			(xy 177.24628 -99.00158) (xy 177.249328 -98.997516) (xy 177.269495 -98.968182) (xy 177.316724 -98.914922)
			(xy 177.370918 -98.868768) (xy 177.431018 -98.830621) (xy 177.463196 -98.815398) (xy 177.46345 -98.815398)
			(xy 177.469325 -98.812524) (xy 177.479478 -98.804288) (xy 177.483516 -98.799142) (xy 177.487326 -98.794062)
			(xy 177.491898 -98.782124) (xy 177.503328 -98.689922) (xy 177.503982 -98.683401) (xy 177.502315 -98.670408)
			(xy 177.500026 -98.664268) (xy 177.500026 -98.664014) (xy 177.497352 -98.658227) (xy 177.489642 -98.648079)
			(xy 177.484786 -98.643948) (xy 177.484532 -98.643694) (xy 177.459123 -98.622972) (xy 177.413324 -98.576054)
			(xy 177.373935 -98.523638) (xy 177.341611 -98.466593) (xy 177.316888 -98.405867) (xy 177.300176 -98.342466)
			(xy 177.291753 -98.277443) (xy 177.291238 -98.24466) (xy 177.291783 -98.211372) (xy 177.300471 -98.145365)
			(xy 177.317693 -98.081054) (xy 177.343155 -98.019539) (xy 177.376421 -97.96187) (xy 177.416925 -97.909032)
			(xy 177.463973 -97.861927) (xy 177.516763 -97.82136) (xy 177.574392 -97.788025) (xy 177.604928 -97.77476)
			(xy 177.61839 -97.769172) (xy 177.635408 -97.745804) (xy 177.64252 -97.640648) (xy 177.642803 -97.631234)
			(xy 177.63724 -97.613252) (xy 177.625549 -97.598502) (xy 177.617628 -97.593404) (xy 177.589491 -97.576183)
			(xy 177.537499 -97.535579) (xy 177.491195 -97.488591) (xy 177.451358 -97.436009) (xy 177.418656 -97.378715)
			(xy 177.39364 -97.317674) (xy 177.37673 -97.253909) (xy 177.368209 -97.188493) (xy 177.367692 -97.155508)
			(xy 177.368194 -97.123547) (xy 177.376205 -97.060129) (xy 177.392102 -96.998215) (xy 177.415634 -96.938782)
			(xy 177.446428 -96.882767) (xy 177.484001 -96.831052) (xy 177.527758 -96.784455) (xy 177.577011 -96.74371)
			(xy 177.630982 -96.709459) (xy 177.688821 -96.682242) (xy 177.749614 -96.662489) (xy 177.812404 -96.650511)
			(xy 177.8762 -96.646498) (xy 177.939996 -96.650511) (xy 178.002786 -96.662489) (xy 178.063579 -96.682242)
			(xy 178.121418 -96.709459) (xy 178.175389 -96.74371) (xy 178.224642 -96.784455) (xy 178.268399 -96.831052)
			(xy 178.305972 -96.882767) (xy 178.336766 -96.938782) (xy 178.360298 -96.998215) (xy 178.376195 -97.060129)
			(xy 178.383745 -97.1199) (xy 179.196038 -97.1199) (xy 179.200051 -97.05611) (xy 179.212027 -96.993326)
			(xy 179.231779 -96.932538) (xy 179.258993 -96.874705) (xy 179.293241 -96.820739) (xy 179.333982 -96.771491)
			(xy 179.380575 -96.727738) (xy 179.432284 -96.690169) (xy 179.488294 -96.659377) (xy 179.547722 -96.635848)
			(xy 179.60963 -96.619953) (xy 179.673042 -96.611942) (xy 179.705 -96.61144) (xy 179.736287 -96.611934)
			(xy 179.79839 -96.619606) (xy 179.85908 -96.634845) (xy 179.91744 -96.657421) (xy 179.972585 -96.686993)
			(xy 180.023683 -96.723112) (xy 180.069958 -96.765233) (xy 180.110711 -96.812717) (xy 180.128418 -96.838516)
			(xy 180.135941 -96.848666) (xy 180.158215 -96.860525) (xy 180.170836 -96.861122) (xy 180.255164 -96.861122)
			(xy 180.26777 -96.860482) (xy 180.290019 -96.848623) (xy 180.297582 -96.838516) (xy 180.315273 -96.812706)
			(xy 180.356034 -96.765228) (xy 180.402315 -96.723113) (xy 180.453415 -96.686996) (xy 180.508562 -96.657424)
			(xy 180.566921 -96.634845) (xy 180.627611 -96.6196) (xy 180.689712 -96.61192) (xy 180.721 -96.61144)
			(xy 180.752964 -96.611846) (xy 180.816388 -96.619858) (xy 180.878308 -96.635756) (xy 180.937747 -96.65929)
			(xy 180.993767 -96.690087) (xy 181.045486 -96.727663) (xy 181.092088 -96.771425) (xy 181.132837 -96.820683)
			(xy 181.167092 -96.874659) (xy 181.194311 -96.932503) (xy 181.214066 -96.993302) (xy 181.226045 -97.056098)
			(xy 181.230059 -97.1199) (xy 181.226045 -97.183702) (xy 181.214066 -97.246498) (xy 181.194311 -97.307297)
			(xy 181.167092 -97.365141) (xy 181.132837 -97.419117) (xy 181.092088 -97.468375) (xy 181.045486 -97.512137)
			(xy 180.993767 -97.549713) (xy 180.937747 -97.58051) (xy 180.878308 -97.604044) (xy 180.816388 -97.619942)
			(xy 180.752964 -97.627954) (xy 180.721 -97.628456) (xy 180.689713 -97.627964) (xy 180.62761 -97.620292)
			(xy 180.56692 -97.605053) (xy 180.50856 -97.582476) (xy 180.453414 -97.552904) (xy 180.402317 -97.516784)
			(xy 180.356042 -97.474664) (xy 180.315289 -97.427179) (xy 180.297582 -97.40138) (xy 180.290039 -97.391247)
			(xy 180.267781 -97.379375) (xy 180.255164 -97.378774) (xy 180.170836 -97.378774) (xy 180.15823 -97.379416)
			(xy 180.135981 -97.391274) (xy 180.128418 -97.40138) (xy 180.110726 -97.427189) (xy 180.069965 -97.474667)
			(xy 180.023684 -97.516783) (xy 179.972585 -97.5529) (xy 179.917438 -97.582471) (xy 179.859079 -97.60505)
			(xy 179.798389 -97.620296) (xy 179.736287 -97.627976) (xy 179.705 -97.628456) (xy 179.673042 -97.627858)
			(xy 179.60963 -97.619847) (xy 179.547722 -97.603952) (xy 179.488294 -97.580423) (xy 179.432284 -97.549631)
			(xy 179.380575 -97.512062) (xy 179.333982 -97.468309) (xy 179.293241 -97.419061) (xy 179.258993 -97.365095)
			(xy 179.231779 -97.307262) (xy 179.212027 -97.246474) (xy 179.200051 -97.18369) (xy 179.196038 -97.1199)
			(xy 178.383745 -97.1199) (xy 178.384206 -97.123547) (xy 178.384708 -97.155508) (xy 178.384165 -97.188775)
			(xy 178.375488 -97.254741) (xy 178.358283 -97.319013) (xy 178.332845 -97.380492) (xy 178.299607 -97.43813)
			(xy 178.259136 -97.490941) (xy 178.212125 -97.538024) (xy 178.159376 -97.578574) (xy 178.10179 -97.611901)
			(xy 178.071272 -97.625154) (xy 178.05781 -97.630742) (xy 178.040792 -97.65411) (xy 178.032664 -97.773744)
			(xy 178.045872 -97.79889) (xy 178.054762 -97.804224) (xy 178.081458 -97.820203) (xy 178.131114 -97.857693)
			(xy 178.175821 -97.900966) (xy 178.195732 -97.924874) (xy 178.19932 -97.929185) (xy 178.208038 -97.936238)
			(xy 178.213004 -97.938844) (xy 178.22291 -97.94367) (xy 178.314096 -97.944686) (xy 178.319357 -97.944433)
			(xy 178.329602 -97.941997) (xy 178.334416 -97.93986) (xy 178.344068 -97.935542) (xy 178.351434 -97.926652)
			(xy 178.372194 -97.902863) (xy 178.418638 -97.86009) (xy 178.470019 -97.823393) (xy 178.525546 -97.793337)
			(xy 178.584366 -97.770384) (xy 178.645574 -97.754888) (xy 178.70823 -97.747086) (xy 178.7398 -97.746566)
			(xy 178.773243 -97.747097) (xy 178.83955 -97.755869) (xy 178.904134 -97.773261) (xy 178.96588 -97.798972)
			(xy 179.02372 -97.83256) (xy 179.076656 -97.873442) (xy 179.123774 -97.920914) (xy 179.144422 -97.947226)
			(xy 179.14493 -97.947734) (xy 179.14493 -97.947988) (xy 179.148519 -97.952298) (xy 179.157237 -97.959349)
			(xy 179.162202 -97.961958) (xy 179.162456 -97.961958) (xy 179.167654 -97.964426) (xy 179.178808 -97.967245)
			(xy 179.184554 -97.967546) (xy 179.265834 -97.968308) (xy 179.27143 -97.968109) (xy 179.282329 -97.965551)
			(xy 179.287424 -97.963228) (xy 179.29733 -97.958656) (xy 179.30495 -97.94875) (xy 179.325668 -97.923189)
			(xy 179.372627 -97.877098) (xy 179.42514 -97.837452) (xy 179.482329 -97.804911) (xy 179.543239 -97.780021)
			(xy 179.60685 -97.763197) (xy 179.672101 -97.754721) (xy 179.705 -97.754186) (xy 179.73631 -97.754667)
			(xy 179.798456 -97.762358) (xy 179.859187 -97.777623) (xy 179.917583 -97.800232) (xy 179.972761 -97.829841)
			(xy 180.023884 -97.866003) (xy 180.070179 -97.90817) (xy 180.110944 -97.955703) (xy 180.128672 -97.981516)
			(xy 180.131466 -97.985326) (xy 180.138374 -97.993052) (xy 180.156736 -98.002618) (xy 180.167026 -98.003868)
			(xy 180.170836 -98.004122) (xy 180.255164 -98.004122) (xy 180.258974 -98.003868) (xy 180.269259 -98.002604)
			(xy 180.287621 -97.993043) (xy 180.294534 -97.985326) (xy 180.297328 -97.981516) (xy 180.315042 -97.955695)
			(xy 180.355813 -97.908167) (xy 180.402113 -97.866006) (xy 180.453239 -97.82985) (xy 180.508418 -97.800245)
			(xy 180.566814 -97.77764) (xy 180.627545 -97.762377) (xy 180.68969 -97.754688) (xy 180.75231 -97.754688)
			(xy 180.814455 -97.762377) (xy 180.875186 -97.77764) (xy 180.933582 -97.800245) (xy 180.988761 -97.82985)
			(xy 181.039887 -97.866006) (xy 181.086187 -97.908167) (xy 181.126958 -97.955695) (xy 181.144672 -97.981516)
			(xy 181.147466 -97.985326) (xy 181.154374 -97.993052) (xy 181.172736 -98.002618) (xy 181.183026 -98.003868)
			(xy 181.186836 -98.004122) (xy 181.271164 -98.004122) (xy 181.274974 -98.003868) (xy 181.285259 -98.002604)
			(xy 181.303621 -97.993043) (xy 181.310534 -97.985326) (xy 181.313328 -97.981516) (xy 181.331043 -97.955695)
			(xy 181.371817 -97.908168) (xy 181.418117 -97.866007) (xy 181.469242 -97.829848) (xy 181.52442 -97.800239)
			(xy 181.582816 -97.777628) (xy 181.643545 -97.762357) (xy 181.70569 -97.754657) (xy 181.737 -97.754186)
			(xy 181.768655 -97.754669) (xy 181.831475 -97.762528) (xy 181.892833 -97.778124) (xy 181.951781 -97.801217)
			(xy 181.979824 -97.815908) (xy 181.986428 -97.818956) (xy 181.990911 -97.820461) (xy 182.000241 -97.822001)
			(xy 182.00497 -97.822004) (xy 182.017416 -97.82175) (xy 182.10403 -97.769934) (xy 182.109364 -97.766378)
			(xy 182.11726 -97.759608) (xy 182.12722 -97.741373) (xy 182.128668 -97.731072) (xy 182.128922 -97.726246)
			(xy 182.128922 -95.62465) (xy 182.128668 -95.619824) (xy 182.127215 -95.609428) (xy 182.117114 -95.591054)
			(xy 182.10911 -95.584264) (xy 182.10403 -95.580962) (xy 182.026814 -95.534734) (xy 182.02146 -95.53211)
			(xy 182.00991 -95.529165) (xy 182.003954 -95.528892) (xy 181.991508 -95.528638) (xy 181.985666 -95.531686)
			(xy 181.957078 -95.547136) (xy 181.896815 -95.571452) (xy 181.833944 -95.58789) (xy 181.769492 -95.596184)
			(xy 181.737 -95.59671) (xy 181.70569 -95.596229) (xy 181.643544 -95.588538) (xy 181.582813 -95.573273)
			(xy 181.524417 -95.550664) (xy 181.46924 -95.521055) (xy 181.418117 -95.484893) (xy 181.371822 -95.442725)
			(xy 181.331057 -95.395192) (xy 181.313328 -95.36938) (xy 181.310534 -95.36557) (xy 181.303626 -95.357844)
			(xy 181.285263 -95.348278) (xy 181.274974 -95.347028) (xy 181.271164 -95.346774) (xy 181.186836 -95.346774)
			(xy 181.183026 -95.347028) (xy 181.172741 -95.348292) (xy 181.154379 -95.357852) (xy 181.147466 -95.36557)
			(xy 181.144672 -95.36938) (xy 181.126958 -95.395201) (xy 181.086187 -95.442729) (xy 181.039887 -95.48489)
			(xy 180.988761 -95.521046) (xy 180.933582 -95.550651) (xy 180.875186 -95.573256) (xy 180.814455 -95.588519)
			(xy 180.75231 -95.596208) (xy 180.68969 -95.596208) (xy 180.627545 -95.588519) (xy 180.566814 -95.573256)
			(xy 180.508418 -95.550651) (xy 180.453239 -95.521046) (xy 180.402113 -95.48489) (xy 180.355813 -95.442729)
			(xy 180.315042 -95.395201) (xy 180.297328 -95.36938) (xy 180.294534 -95.36557) (xy 180.287626 -95.357844)
			(xy 180.269263 -95.348278) (xy 180.258974 -95.347028) (xy 180.255164 -95.346774) (xy 180.170836 -95.346774)
			(xy 180.167026 -95.347028) (xy 180.156741 -95.348292) (xy 180.138379 -95.357852) (xy 180.131466 -95.36557)
			(xy 180.128672 -95.36938) (xy 180.110958 -95.395201) (xy 180.070187 -95.442729) (xy 180.023887 -95.48489)
			(xy 179.972761 -95.521046) (xy 179.917582 -95.550651) (xy 179.859186 -95.573256) (xy 179.798455 -95.588519)
			(xy 179.73631 -95.596208) (xy 179.67369 -95.596208) (xy 179.611545 -95.588519) (xy 179.550814 -95.573256)
			(xy 179.492418 -95.550651) (xy 179.437239 -95.521046) (xy 179.386113 -95.48489) (xy 179.339813 -95.442729)
			(xy 179.299042 -95.395201) (xy 179.281328 -95.36938) (xy 179.278534 -95.36557) (xy 179.271626 -95.357844)
			(xy 179.253263 -95.348278) (xy 179.242974 -95.347028) (xy 179.239164 -95.346774) (xy 179.154836 -95.346774)
			(xy 179.151026 -95.347028) (xy 179.140741 -95.348292) (xy 179.122379 -95.357852) (xy 179.115466 -95.36557)
			(xy 179.112672 -95.36938) (xy 179.094958 -95.395201) (xy 179.054187 -95.442729) (xy 179.007887 -95.48489)
			(xy 178.956761 -95.521046) (xy 178.901582 -95.550651) (xy 178.843186 -95.573256) (xy 178.782455 -95.588519)
			(xy 178.72031 -95.596208) (xy 178.65769 -95.596208) (xy 178.595545 -95.588519) (xy 178.534814 -95.573256)
			(xy 178.476418 -95.550651) (xy 178.421239 -95.521046) (xy 178.370113 -95.48489) (xy 178.323813 -95.442729)
			(xy 178.283042 -95.395201) (xy 178.265328 -95.36938) (xy 178.262534 -95.36557) (xy 178.255626 -95.357844)
			(xy 178.237263 -95.348278) (xy 178.226974 -95.347028) (xy 178.223164 -95.346774) (xy 178.138836 -95.346774)
			(xy 178.135026 -95.347028) (xy 178.124741 -95.348292) (xy 178.106379 -95.357852) (xy 178.099466 -95.36557)
			(xy 178.096672 -95.36938) (xy 178.078958 -95.395201) (xy 178.038187 -95.442729) (xy 177.991887 -95.48489)
			(xy 177.940761 -95.521046) (xy 177.885582 -95.550651) (xy 177.827186 -95.573256) (xy 177.766455 -95.588519)
			(xy 177.70431 -95.596208) (xy 177.64169 -95.596208) (xy 177.579545 -95.588519) (xy 177.518814 -95.573256)
			(xy 177.460418 -95.550651) (xy 177.405239 -95.521046) (xy 177.354113 -95.48489) (xy 177.307813 -95.442729)
			(xy 177.267042 -95.395201) (xy 177.249328 -95.36938) (xy 177.246534 -95.36557) (xy 177.239626 -95.357844)
			(xy 177.221263 -95.348278) (xy 177.210974 -95.347028) (xy 177.207164 -95.346774) (xy 177.122836 -95.346774)
			(xy 177.119026 -95.347028) (xy 177.108741 -95.348292) (xy 177.090379 -95.357852) (xy 177.083466 -95.36557)
			(xy 177.080672 -95.36938) (xy 177.062957 -95.395201) (xy 177.022183 -95.442728) (xy 176.975884 -95.48489)
			(xy 176.924758 -95.521049) (xy 176.86958 -95.550658) (xy 176.811185 -95.573269) (xy 176.750455 -95.58854)
			(xy 176.68831 -95.59624) (xy 176.657 -95.59671) (xy 176.62502 -95.596208) (xy 176.561564 -95.588192)
			(xy 176.499614 -95.572285) (xy 176.440145 -95.54874) (xy 176.384096 -95.517927) (xy 176.332352 -95.480332)
			(xy 176.285727 -95.436549) (xy 176.244957 -95.387267) (xy 176.210686 -95.333263) (xy 176.183453 -95.275391)
			(xy 176.163688 -95.214561) (xy 176.151703 -95.151734) (xy 176.147687 -95.0879) (xy 176.151703 -95.024066)
			(xy 176.163688 -94.961239) (xy 176.183453 -94.900409) (xy 176.210686 -94.842537) (xy 176.244957 -94.788533)
			(xy 176.285727 -94.739251) (xy 176.332352 -94.695468) (xy 176.384096 -94.657873) (xy 176.440145 -94.62706)
			(xy 176.499614 -94.603515) (xy 176.561564 -94.587608) (xy 176.62502 -94.579592) (xy 176.657 -94.579186)
			(xy 176.68831 -94.579667) (xy 176.750456 -94.587358) (xy 176.811187 -94.602623) (xy 176.869583 -94.625232)
			(xy 176.924761 -94.654841) (xy 176.975884 -94.691003) (xy 177.022179 -94.73317) (xy 177.062944 -94.780703)
			(xy 177.080672 -94.806516) (xy 177.083466 -94.810326) (xy 177.090374 -94.818052) (xy 177.108736 -94.827618)
			(xy 177.119026 -94.828868) (xy 177.122836 -94.829122) (xy 177.207164 -94.829122) (xy 177.210974 -94.828868)
			(xy 177.221259 -94.827604) (xy 177.239621 -94.818043) (xy 177.246534 -94.810326) (xy 177.249328 -94.806516)
			(xy 177.267042 -94.780695) (xy 177.307813 -94.733167) (xy 177.354113 -94.691006) (xy 177.405239 -94.65485)
			(xy 177.460418 -94.625245) (xy 177.518814 -94.60264) (xy 177.579545 -94.587377) (xy 177.64169 -94.579688)
			(xy 177.70431 -94.579688) (xy 177.766455 -94.587377) (xy 177.827186 -94.60264) (xy 177.885582 -94.625245)
			(xy 177.940761 -94.65485) (xy 177.991887 -94.691006) (xy 178.038187 -94.733167) (xy 178.078958 -94.780695)
			(xy 178.096672 -94.806516) (xy 178.099466 -94.810326) (xy 178.106374 -94.818052) (xy 178.124736 -94.827618)
			(xy 178.135026 -94.828868) (xy 178.138836 -94.829122) (xy 178.223164 -94.829122) (xy 178.226974 -94.828868)
			(xy 178.237259 -94.827604) (xy 178.255621 -94.818043) (xy 178.262534 -94.810326) (xy 178.265328 -94.806516)
			(xy 178.283042 -94.780695) (xy 178.323813 -94.733167) (xy 178.370113 -94.691006) (xy 178.421239 -94.65485)
			(xy 178.476418 -94.625245) (xy 178.534814 -94.60264) (xy 178.595545 -94.587377) (xy 178.65769 -94.579688)
			(xy 178.72031 -94.579688) (xy 178.782455 -94.587377) (xy 178.843186 -94.60264) (xy 178.901582 -94.625245)
			(xy 178.956761 -94.65485) (xy 179.007887 -94.691006) (xy 179.054187 -94.733167) (xy 179.094958 -94.780695)
			(xy 179.112672 -94.806516) (xy 179.115466 -94.810326) (xy 179.122374 -94.818052) (xy 179.140736 -94.827618)
			(xy 179.151026 -94.828868) (xy 179.154836 -94.829122) (xy 179.239164 -94.829122) (xy 179.242974 -94.828868)
			(xy 179.253259 -94.827604) (xy 179.271621 -94.818043) (xy 179.278534 -94.810326) (xy 179.281328 -94.806516)
			(xy 179.299042 -94.780695) (xy 179.339813 -94.733167) (xy 179.386113 -94.691006) (xy 179.437239 -94.65485)
			(xy 179.492418 -94.625245) (xy 179.550814 -94.60264) (xy 179.611545 -94.587377) (xy 179.67369 -94.579688)
			(xy 179.73631 -94.579688) (xy 179.798455 -94.587377) (xy 179.859186 -94.60264) (xy 179.917582 -94.625245)
			(xy 179.972761 -94.65485) (xy 180.023887 -94.691006) (xy 180.070187 -94.733167) (xy 180.110958 -94.780695)
			(xy 180.128672 -94.806516) (xy 180.131466 -94.810326) (xy 180.138374 -94.818052) (xy 180.156736 -94.827618)
			(xy 180.167026 -94.828868) (xy 180.170836 -94.829122) (xy 180.255164 -94.829122) (xy 180.258974 -94.828868)
			(xy 180.269259 -94.827604) (xy 180.287621 -94.818043) (xy 180.294534 -94.810326) (xy 180.297328 -94.806516)
			(xy 180.315042 -94.780695) (xy 180.355813 -94.733167) (xy 180.402113 -94.691006) (xy 180.453239 -94.65485)
			(xy 180.508418 -94.625245) (xy 180.566814 -94.60264) (xy 180.627545 -94.587377) (xy 180.68969 -94.579688)
			(xy 180.75231 -94.579688) (xy 180.814455 -94.587377) (xy 180.875186 -94.60264) (xy 180.933582 -94.625245)
			(xy 180.988761 -94.65485) (xy 181.039887 -94.691006) (xy 181.086187 -94.733167) (xy 181.126958 -94.780695)
			(xy 181.144672 -94.806516) (xy 181.147466 -94.810326) (xy 181.154374 -94.818052) (xy 181.172736 -94.827618)
			(xy 181.183026 -94.828868) (xy 181.186836 -94.829122) (xy 181.271164 -94.829122) (xy 181.274974 -94.828868)
			(xy 181.285259 -94.827604) (xy 181.303621 -94.818043) (xy 181.310534 -94.810326) (xy 181.313328 -94.806516)
			(xy 181.331043 -94.780695) (xy 181.371817 -94.733168) (xy 181.418117 -94.691007) (xy 181.469242 -94.654848)
			(xy 181.52442 -94.625239) (xy 181.582816 -94.602628) (xy 181.643545 -94.587357) (xy 181.70569 -94.579657)
			(xy 181.737 -94.579186) (xy 181.768655 -94.579669) (xy 181.831475 -94.587528) (xy 181.892833 -94.603124)
			(xy 181.951781 -94.626217) (xy 181.979824 -94.640908) (xy 181.986428 -94.643956) (xy 181.990911 -94.645461)
			(xy 182.000241 -94.647001) (xy 182.00497 -94.647004) (xy 182.017416 -94.64675) (xy 182.10403 -94.594934)
			(xy 182.109364 -94.591378) (xy 182.11726 -94.584608) (xy 182.12722 -94.566373) (xy 182.128668 -94.556072)
			(xy 182.128922 -94.551246) (xy 182.128922 -94.22765) (xy 182.128668 -94.222824) (xy 182.127215 -94.212428)
			(xy 182.117114 -94.194054) (xy 182.10911 -94.187264) (xy 182.10403 -94.183962) (xy 182.026814 -94.137734)
			(xy 182.02146 -94.13511) (xy 182.00991 -94.132165) (xy 182.003954 -94.131892) (xy 181.991508 -94.131638)
			(xy 181.985666 -94.134686) (xy 181.957078 -94.150136) (xy 181.896815 -94.174452) (xy 181.833944 -94.19089)
			(xy 181.769492 -94.199184) (xy 181.737 -94.19971) (xy 181.706771 -94.199278) (xy 181.646739 -94.192118)
			(xy 181.587978 -94.177898) (xy 181.531314 -94.156819) (xy 181.477545 -94.129178) (xy 181.427429 -94.095363)
			(xy 181.38167 -94.05585) (xy 181.340913 -94.011197) (xy 181.32298 -93.986858) (xy 181.32298 -93.98635)
			(xy 181.316122 -93.976952) (xy 181.291484 -93.96603) (xy 181.190392 -93.97619) (xy 181.181624 -93.97735)
			(xy 181.165651 -93.984924) (xy 181.153235 -93.997507) (xy 181.149244 -94.0054) (xy 181.149244 -94.005654)
			(xy 181.135415 -94.034907) (xy 181.10142 -94.089964) (xy 181.060717 -94.140264) (xy 181.013962 -94.184995)
			(xy 180.961912 -94.223434) (xy 180.905406 -94.254961) (xy 180.845357 -94.279067) (xy 180.782737 -94.295361)
			(xy 180.718555 -94.303581) (xy 180.686202 -94.304104) (xy 180.652868 -94.303581) (xy 180.586773 -94.294871)
			(xy 180.522382 -94.2776) (xy 180.460799 -94.252065) (xy 180.40308 -94.218703) (xy 180.350215 -94.178085)
			(xy 180.30311 -94.130909) (xy 180.262572 -94.077983) (xy 180.245512 -94.049342) (xy 180.239416 -94.038674)
			(xy 180.219096 -94.025466) (xy 180.113178 -94.01429) (xy 180.090318 -94.022926) (xy 180.08219 -94.03207)
			(xy 180.061491 -94.054284) (xy 180.015677 -94.094135) (xy 179.965447 -94.128251) (xy 179.911514 -94.156146)
			(xy 179.854645 -94.177426) (xy 179.795647 -94.191786) (xy 179.73536 -94.199024) (xy 179.705 -94.199456)
			(xy 179.673332 -94.198955) (xy 179.61049 -94.191058) (xy 179.549115 -94.175422) (xy 179.490154 -94.152291)
			(xy 179.434519 -94.122021) (xy 179.383071 -94.085081) (xy 179.336606 -94.042041) (xy 179.315872 -94.0181)
			(xy 179.307236 -94.00794) (xy 179.28336 -93.998796) (xy 179.185062 -94.012004) (xy 179.176636 -94.013488)
			(xy 179.161399 -94.021248) (xy 179.149553 -94.033579) (xy 179.145692 -94.041214) (xy 179.131821 -94.070366)
			(xy 179.097774 -94.125219) (xy 179.057057 -94.175321) (xy 179.010326 -94.219866) (xy 178.958332 -94.258138)
			(xy 178.901912 -94.28952) (xy 178.841973 -94.313507) (xy 178.77948 -94.329715) (xy 178.715438 -94.337882)
			(xy 178.683158 -94.338394) (xy 178.6512 -94.33789) (xy 178.587787 -94.329874) (xy 178.525879 -94.313974)
			(xy 178.466452 -94.290441) (xy 178.410443 -94.259646) (xy 178.358735 -94.222074) (xy 178.312144 -94.178317)
			(xy 178.271403 -94.129067) (xy 178.237156 -94.075099) (xy 178.209943 -94.017265) (xy 178.190193 -93.956476)
			(xy 178.178217 -93.893691) (xy 178.174203 -93.8299) (xy 178.178217 -93.766109) (xy 178.190193 -93.703324)
			(xy 178.209943 -93.642535) (xy 178.237156 -93.584701) (xy 178.271403 -93.530733) (xy 178.312144 -93.481483)
			(xy 178.358735 -93.437726) (xy 178.410443 -93.400154) (xy 178.466452 -93.369359) (xy 178.525879 -93.345826)
			(xy 178.587787 -93.329926) (xy 178.6512 -93.32191) (xy 178.683158 -93.321378) (xy 178.714824 -93.321883)
			(xy 178.777661 -93.329787) (xy 178.839032 -93.345428) (xy 178.897987 -93.368565) (xy 178.953615 -93.39884)
			(xy 179.005056 -93.435785) (xy 179.051513 -93.478828) (xy 179.072286 -93.502734) (xy 179.080922 -93.512894)
			(xy 179.104798 -93.522038) (xy 179.203096 -93.50883) (xy 179.211528 -93.507353) (xy 179.22678 -93.499604)
			(xy 179.238644 -93.487277) (xy 179.242466 -93.47962) (xy 179.256335 -93.450465) (xy 179.290379 -93.395605)
			(xy 179.331093 -93.345497) (xy 179.377823 -93.300945) (xy 179.429817 -93.262667) (xy 179.486238 -93.231278)
			(xy 179.546178 -93.207283) (xy 179.608673 -93.191069) (xy 179.672718 -93.182897) (xy 179.705 -93.18244)
			(xy 179.738333 -93.182963) (xy 179.804427 -93.191674) (xy 179.868817 -93.208946) (xy 179.930398 -93.234483)
			(xy 179.988114 -93.267847) (xy 180.040976 -93.308466) (xy 180.088078 -93.355644) (xy 180.128612 -93.408572)
			(xy 180.14569 -93.437202) (xy 180.151786 -93.44787) (xy 180.172106 -93.461078) (xy 180.278024 -93.472254)
			(xy 180.300884 -93.463618) (xy 180.309012 -93.454474) (xy 180.329713 -93.432262) (xy 180.375528 -93.392416)
			(xy 180.425759 -93.358304) (xy 180.479692 -93.330411) (xy 180.53656 -93.309135) (xy 180.595557 -93.294776)
			(xy 180.655843 -93.287539) (xy 180.686202 -93.287088) (xy 180.716281 -93.28753) (xy 180.776018 -93.294625)
			(xy 180.834501 -93.308717) (xy 180.890914 -93.329608) (xy 180.94447 -93.357006) (xy 180.99442 -93.39053)
			(xy 181.040068 -93.429711) (xy 181.080776 -93.474003) (xy 181.098698 -93.498162) (xy 181.106572 -93.509338)
			(xy 181.131464 -93.520514) (xy 181.246018 -93.509084) (xy 181.268116 -93.49359) (xy 181.27091 -93.48724)
			(xy 181.284482 -93.457415) (xy 181.318191 -93.401222) (xy 181.358839 -93.349826) (xy 181.405755 -93.304077)
			(xy 181.458158 -93.264736) (xy 181.515182 -93.232453) (xy 181.575881 -93.207765) (xy 181.639249 -93.191079)
			(xy 181.704236 -93.182673) (xy 181.737 -93.182186) (xy 181.768655 -93.182669) (xy 181.831475 -93.190528)
			(xy 181.892833 -93.206124) (xy 181.951781 -93.229217) (xy 181.979824 -93.243908) (xy 181.986428 -93.246956)
			(xy 181.990911 -93.248461) (xy 182.000241 -93.250001) (xy 182.00497 -93.250004) (xy 182.017416 -93.24975)
			(xy 182.10403 -93.197934) (xy 182.109364 -93.194378) (xy 182.11726 -93.187608) (xy 182.12722 -93.169373)
			(xy 182.128668 -93.159072) (xy 182.128922 -93.154246) (xy 182.128922 -92.64015) (xy 182.128668 -92.632022)
			(xy 182.128668 -92.060522) (xy 182.128922 -92.052648) (xy 182.128922 -91.265248) (xy 182.128668 -91.257374)
			(xy 182.128668 -88.42375) (xy 182.128419 -88.416336) (xy 182.124165 -88.402133) (xy 182.120286 -88.39581)
			(xy 182.11673 -88.390222) (xy 182.1053 -88.380824) (xy 182.098188 -88.377776) (xy 182.070467 -88.3654)
			(xy 182.017924 -88.334989) (xy 181.969373 -88.29854) (xy 181.925506 -88.256572) (xy 181.886946 -88.20968)
			(xy 181.854241 -88.158533) (xy 181.840632 -88.131396) (xy 181.836242 -88.123126) (xy 181.822692 -88.110228)
			(xy 181.814216 -88.10625) (xy 181.785768 -88.09482) (xy 181.77698 -88.091711) (xy 181.758357 -88.09132)
			(xy 181.749446 -88.094058) (xy 181.72163 -88.103653) (xy 181.664347 -88.117117) (xy 181.605894 -88.123887)
			(xy 181.576472 -88.124284) (xy 181.576218 -88.124284) (xy 181.544238 -88.123804) (xy 181.480781 -88.11579)
			(xy 181.418829 -88.099885) (xy 181.359359 -88.076341) (xy 181.303309 -88.045529) (xy 181.251563 -88.007935)
			(xy 181.204936 -87.964152) (xy 181.164165 -87.91487) (xy 181.129893 -87.860866) (xy 181.102659 -87.802993)
			(xy 181.082894 -87.742163) (xy 181.070908 -87.679335) (xy 181.066892 -87.6155) (xy 181.070908 -87.551665)
			(xy 181.082894 -87.488837) (xy 181.102659 -87.428007) (xy 181.129893 -87.370134) (xy 181.164165 -87.31613)
			(xy 181.204936 -87.266848) (xy 181.251563 -87.223065) (xy 181.303309 -87.185471) (xy 181.359359 -87.154659)
			(xy 181.418829 -87.131115) (xy 181.480781 -87.11521) (xy 181.544238 -87.107196) (xy 181.576218 -87.10676)
			(xy 181.60645 -87.10719) (xy 181.666488 -87.114352) (xy 181.725253 -87.128587) (xy 181.781914 -87.149692)
			(xy 181.835671 -87.177369) (xy 181.885766 -87.211228) (xy 181.93149 -87.25079) (xy 181.952138 -87.272876)
			(xy 181.96251 -87.283465) (xy 181.987941 -87.298669) (xy 182.016664 -87.305937) (xy 182.046265 -87.304658)
			(xy 182.074254 -87.294939) (xy 182.098278 -87.277598) (xy 182.116316 -87.254094) (xy 182.126852 -87.226402)
			(xy 182.128414 -87.211662) (xy 182.128668 -87.208106) (xy 182.128668 -86.410038) (xy 182.127447 -86.401435)
			(xy 182.12004 -86.385729) (xy 182.11419 -86.379304) (xy 179.217066 -83.482434) (xy 179.213337 -83.478911)
			(xy 179.204763 -83.47328) (xy 179.200048 -83.471258) (xy 179.192174 -83.467956) (xy 175.87087 -83.467956)
			(xy 175.862742 -83.467702) (xy 175.76546 -83.467702) (xy 175.755393 -83.467271) (xy 175.736799 -83.459547)
			(xy 175.729392 -83.452716) (xy 175.659034 -83.382358) (xy 175.654716 -83.378294) (xy 169.306494 -77.030072)
			(xy 169.302176 -77.0255) (xy 169.232072 -76.955396) (xy 169.225219 -76.948001) (xy 169.217474 -76.929402)
			(xy 169.217086 -76.919328) (xy 169.217086 -76.822046) (xy 169.216832 -76.813918) (xy 169.216832 -72.95769)
			(xy 169.215618 -72.949084) (xy 169.208219 -72.93337) (xy 169.202354 -72.926956) (xy 167.268906 -70.993508)
			(xy 167.265177 -70.989984) (xy 167.256605 -70.984349) (xy 167.251888 -70.982332) (xy 167.243252 -70.978776)
			(xy 152.26411 -70.978776) (xy 152.255418 -70.979121) (xy 152.239049 -70.984966) (xy 152.232106 -70.990206)
			(xy 152.228296 -70.993508) (xy 152.20696 -71.014844) (xy 152.203442 -71.018577) (xy 152.19782 -71.027154)
			(xy 152.195784 -71.031862) (xy 152.192228 -71.040498) (xy 152.192228 -72.4675) (xy 156.642059 -72.4675)
			(xy 156.646073 -72.403703) (xy 156.658051 -72.340911) (xy 156.677803 -72.280116) (xy 156.70502 -72.222276)
			(xy 156.739271 -72.168303) (xy 156.780016 -72.119048) (xy 156.826612 -72.075288) (xy 156.878326 -72.037713)
			(xy 156.934342 -72.006916) (xy 156.993775 -71.983381) (xy 157.055689 -71.967481) (xy 157.119108 -71.959466)
			(xy 157.15107 -71.958962) (xy 157.182357 -71.959437) (xy 157.244459 -71.967115) (xy 157.305149 -71.98236)
			(xy 157.363507 -72.004941) (xy 157.418652 -72.034515) (xy 157.469749 -72.070636) (xy 157.516025 -72.112756)
			(xy 157.55678 -72.16024) (xy 157.574488 -72.186038) (xy 157.582043 -72.196161) (xy 157.604292 -72.208037)
			(xy 157.616906 -72.208644) (xy 157.701234 -72.208644) (xy 157.713837 -72.207977) (xy 157.736085 -72.196136)
			(xy 157.743652 -72.186038) (xy 157.761368 -72.16025) (xy 157.802134 -72.112787) (xy 157.848416 -72.070686)
			(xy 157.899515 -72.034582) (xy 157.954657 -72.005021) (xy 158.013011 -71.98245) (xy 158.073693 -71.967211)
			(xy 158.135787 -71.959533) (xy 158.198353 -71.959533) (xy 158.260447 -71.967211) (xy 158.321129 -71.98245)
			(xy 158.379483 -72.005021) (xy 158.434625 -72.034582) (xy 158.485724 -72.070686) (xy 158.532006 -72.112787)
			(xy 158.572772 -72.16025) (xy 158.590488 -72.186038) (xy 158.598043 -72.196161) (xy 158.620292 -72.208037)
			(xy 158.632906 -72.208644) (xy 158.717234 -72.208644) (xy 158.729837 -72.207977) (xy 158.752085 -72.196136)
			(xy 158.759652 -72.186038) (xy 158.777369 -72.160247) (xy 158.818126 -72.112768) (xy 158.864403 -72.070651)
			(xy 158.915499 -72.034532) (xy 158.970642 -72.004958) (xy 159.028998 -71.982376) (xy 159.089684 -71.967128)
			(xy 159.151784 -71.959444) (xy 159.18307 -71.958962) (xy 159.215032 -71.959501) (xy 159.278451 -71.967509)
			(xy 159.340367 -71.983403) (xy 159.399803 -72.006932) (xy 159.45582 -72.037726) (xy 159.507537 -72.075297)
			(xy 159.554136 -72.119054) (xy 159.594884 -72.168307) (xy 159.629137 -72.222278) (xy 159.646009 -72.258131)
			(xy 159.894264 -72.258131) (xy 159.894264 -72.194209) (xy 159.902275 -72.130791) (xy 159.918172 -72.068877)
			(xy 159.941704 -72.009444) (xy 159.972498 -71.953429) (xy 160.010071 -71.901714) (xy 160.053828 -71.855117)
			(xy 160.103081 -71.814372) (xy 160.157052 -71.780121) (xy 160.214891 -71.752904) (xy 160.275684 -71.733151)
			(xy 160.338474 -71.721173) (xy 160.40227 -71.71716) (xy 160.466066 -71.721173) (xy 160.528856 -71.733151)
			(xy 160.589649 -71.752904) (xy 160.647488 -71.780121) (xy 160.701459 -71.814372) (xy 160.750712 -71.855117)
			(xy 160.794469 -71.901714) (xy 160.832042 -71.953429) (xy 160.862836 -72.009444) (xy 160.886368 -72.068877)
			(xy 160.902265 -72.130791) (xy 160.910276 -72.194209) (xy 160.910778 -72.22617) (xy 160.910276 -72.258131)
			(xy 160.902265 -72.321549) (xy 160.886368 -72.383463) (xy 160.862836 -72.442896) (xy 160.832042 -72.498911)
			(xy 160.794469 -72.550626) (xy 160.750712 -72.597223) (xy 160.701459 -72.637968) (xy 160.647488 -72.672219)
			(xy 160.589649 -72.699436) (xy 160.528856 -72.719189) (xy 160.466066 -72.731167) (xy 160.40227 -72.735181)
			(xy 160.338474 -72.731167) (xy 160.275684 -72.719189) (xy 160.214891 -72.699436) (xy 160.157052 -72.672219)
			(xy 160.103081 -72.637968) (xy 160.053828 -72.597223) (xy 160.010071 -72.550626) (xy 159.972498 -72.498911)
			(xy 159.941704 -72.442896) (xy 159.918172 -72.383463) (xy 159.902275 -72.321549) (xy 159.894264 -72.258131)
			(xy 159.646009 -72.258131) (xy 159.656355 -72.280117) (xy 159.676109 -72.340912) (xy 159.688088 -72.403703)
			(xy 159.692102 -72.4675) (xy 159.688088 -72.531297) (xy 159.676109 -72.594088) (xy 159.656355 -72.654883)
			(xy 159.629137 -72.712722) (xy 159.594884 -72.766693) (xy 159.554136 -72.815946) (xy 159.507537 -72.859703)
			(xy 159.45582 -72.897274) (xy 159.399803 -72.928068) (xy 159.340367 -72.951597) (xy 159.278451 -72.967491)
			(xy 159.215032 -72.975499) (xy 159.18307 -72.975978) (xy 159.151782 -72.975499) (xy 159.08968 -72.967824)
			(xy 159.028989 -72.952582) (xy 158.97063 -72.930003) (xy 158.915484 -72.900429) (xy 158.864387 -72.864308)
			(xy 158.818112 -72.822186) (xy 158.777359 -72.774701) (xy 158.759652 -72.748902) (xy 158.752141 -72.738741)
			(xy 158.729858 -72.726887) (xy 158.717234 -72.726296) (xy 158.632906 -72.726296) (xy 158.620302 -72.72695)
			(xy 158.598056 -72.738803) (xy 158.590488 -72.748902) (xy 158.572772 -72.77469) (xy 158.532006 -72.822153)
			(xy 158.485724 -72.864254) (xy 158.434625 -72.900358) (xy 158.379483 -72.929919) (xy 158.321129 -72.95249)
			(xy 158.260447 -72.967729) (xy 158.198353 -72.975407) (xy 158.135787 -72.975407) (xy 158.073693 -72.967729)
			(xy 158.013011 -72.95249) (xy 157.954657 -72.929919) (xy 157.899515 -72.900358) (xy 157.848416 -72.864254)
			(xy 157.802134 -72.822153) (xy 157.761368 -72.77469) (xy 157.743652 -72.748902) (xy 157.736141 -72.738741)
			(xy 157.713858 -72.726887) (xy 157.701234 -72.726296) (xy 157.616906 -72.726296) (xy 157.604302 -72.72695)
			(xy 157.582056 -72.738803) (xy 157.574488 -72.748902) (xy 157.556758 -72.774683) (xy 157.516001 -72.822161)
			(xy 157.469726 -72.864278) (xy 157.418632 -72.900396) (xy 157.363491 -72.929971) (xy 157.305137 -72.952555)
			(xy 157.244453 -72.967806) (xy 157.182356 -72.975494) (xy 157.15107 -72.975978) (xy 157.119108 -72.975534)
			(xy 157.055689 -72.967519) (xy 156.993775 -72.951619) (xy 156.934342 -72.928084) (xy 156.878326 -72.897287)
			(xy 156.826612 -72.859712) (xy 156.780016 -72.815952) (xy 156.739271 -72.766697) (xy 156.70502 -72.712724)
			(xy 156.677803 -72.654884) (xy 156.658051 -72.594089) (xy 156.646073 -72.531297) (xy 156.642059 -72.4675)
			(xy 152.192228 -72.4675) (xy 152.192228 -75.481434) (xy 163.774372 -75.481434) (xy 163.778443 -75.425812)
			(xy 163.790569 -75.371375) (xy 163.810492 -75.319284) (xy 163.837788 -75.270649) (xy 163.871874 -75.226506)
			(xy 163.912023 -75.187797) (xy 163.957381 -75.155346) (xy 164.006981 -75.129845) (xy 164.059765 -75.111838)
			(xy 164.114608 -75.101708) (xy 164.170342 -75.099671) (xy 164.225779 -75.105771) (xy 164.279736 -75.119877)
			(xy 164.331065 -75.141689) (xy 164.378671 -75.170743) (xy 164.421539 -75.206418) (xy 164.458756 -75.247955)
			(xy 164.489529 -75.294468) (xy 164.513201 -75.344965) (xy 164.529269 -75.398372) (xy 164.537389 -75.453548)
			(xy 164.537898 -75.481434) (xy 164.537389 -75.50932) (xy 164.529269 -75.564496) (xy 164.513201 -75.617903)
			(xy 164.489529 -75.6684) (xy 164.458756 -75.714913) (xy 164.421539 -75.75645) (xy 164.378671 -75.792125)
			(xy 164.331065 -75.821179) (xy 164.279736 -75.842991) (xy 164.225779 -75.857097) (xy 164.170342 -75.863197)
			(xy 164.114608 -75.86116) (xy 164.059765 -75.85103) (xy 164.006981 -75.833023) (xy 163.957381 -75.807522)
			(xy 163.912023 -75.775071) (xy 163.871874 -75.736362) (xy 163.837788 -75.692219) (xy 163.810492 -75.643584)
			(xy 163.790569 -75.591493) (xy 163.778443 -75.537056) (xy 163.774372 -75.481434) (xy 152.192228 -75.481434)
			(xy 152.192228 -76.781406) (xy 160.604452 -76.781406) (xy 160.608523 -76.725784) (xy 160.620649 -76.671347)
			(xy 160.640572 -76.619256) (xy 160.667868 -76.570621) (xy 160.701954 -76.526478) (xy 160.742103 -76.487769)
			(xy 160.787461 -76.455318) (xy 160.837061 -76.429817) (xy 160.889845 -76.41181) (xy 160.944688 -76.40168)
			(xy 161.000422 -76.399643) (xy 161.055859 -76.405743) (xy 161.109816 -76.419849) (xy 161.161145 -76.441661)
			(xy 161.208751 -76.470715) (xy 161.251619 -76.50639) (xy 161.288836 -76.547927) (xy 161.319609 -76.59444)
			(xy 161.343281 -76.644937) (xy 161.359349 -76.698344) (xy 161.367469 -76.75352) (xy 161.367978 -76.781406)
			(xy 161.367469 -76.809292) (xy 161.359349 -76.864468) (xy 161.343281 -76.917875) (xy 161.319609 -76.968372)
			(xy 161.288836 -77.014885) (xy 161.251619 -77.056422) (xy 161.208751 -77.092097) (xy 161.161145 -77.121151)
			(xy 161.109816 -77.142963) (xy 161.055859 -77.157069) (xy 161.000422 -77.163169) (xy 160.944688 -77.161132)
			(xy 160.889845 -77.151002) (xy 160.837061 -77.132995) (xy 160.787461 -77.107494) (xy 160.742103 -77.075043)
			(xy 160.701954 -77.036334) (xy 160.667868 -76.992191) (xy 160.640572 -76.943556) (xy 160.620649 -76.891465)
			(xy 160.608523 -76.837028) (xy 160.604452 -76.781406) (xy 152.192228 -76.781406) (xy 152.192228 -77.587813)
			(xy 158.616136 -77.587813) (xy 158.616136 -77.523891) (xy 158.624147 -77.460473) (xy 158.640044 -77.398559)
			(xy 158.663576 -77.339126) (xy 158.69437 -77.283111) (xy 158.731943 -77.231396) (xy 158.7757 -77.184799)
			(xy 158.824953 -77.144054) (xy 158.878924 -77.109803) (xy 158.936763 -77.082586) (xy 158.997556 -77.062833)
			(xy 159.060346 -77.050855) (xy 159.124142 -77.046842) (xy 159.187938 -77.050855) (xy 159.250728 -77.062833)
			(xy 159.311521 -77.082586) (xy 159.36936 -77.109803) (xy 159.423331 -77.144054) (xy 159.472584 -77.184799)
			(xy 159.516341 -77.231396) (xy 159.553914 -77.283111) (xy 159.584708 -77.339126) (xy 159.60824 -77.398559)
			(xy 159.624137 -77.460473) (xy 159.632148 -77.523891) (xy 159.63265 -77.555852) (xy 159.632148 -77.587813)
			(xy 159.624137 -77.651231) (xy 159.60824 -77.713145) (xy 159.584708 -77.772578) (xy 159.553914 -77.828593)
			(xy 159.516341 -77.880308) (xy 159.472584 -77.926905) (xy 159.423331 -77.96765) (xy 159.36936 -78.001901)
			(xy 159.311521 -78.029118) (xy 159.250728 -78.048871) (xy 159.187938 -78.060849) (xy 159.124142 -78.064863)
			(xy 159.060346 -78.060849) (xy 158.997556 -78.048871) (xy 158.936763 -78.029118) (xy 158.878924 -78.001901)
			(xy 158.824953 -77.96765) (xy 158.7757 -77.926905) (xy 158.731943 -77.880308) (xy 158.69437 -77.828593)
			(xy 158.663576 -77.772578) (xy 158.640044 -77.713145) (xy 158.624147 -77.651231) (xy 158.616136 -77.587813)
			(xy 152.192228 -77.587813) (xy 152.192228 -79.097081) (xy 162.603428 -79.097081) (xy 162.603428 -79.033159)
			(xy 162.611439 -78.969741) (xy 162.627336 -78.907827) (xy 162.650868 -78.848394) (xy 162.681662 -78.792379)
			(xy 162.719235 -78.740664) (xy 162.762992 -78.694067) (xy 162.812245 -78.653322) (xy 162.866216 -78.619071)
			(xy 162.924055 -78.591854) (xy 162.984848 -78.572101) (xy 163.047638 -78.560123) (xy 163.111434 -78.55611)
			(xy 163.17523 -78.560123) (xy 163.23802 -78.572101) (xy 163.298813 -78.591854) (xy 163.356652 -78.619071)
			(xy 163.410623 -78.653322) (xy 163.459876 -78.694067) (xy 163.503633 -78.740664) (xy 163.541206 -78.792379)
			(xy 163.572 -78.848394) (xy 163.595532 -78.907827) (xy 163.611429 -78.969741) (xy 163.61944 -79.033159)
			(xy 163.619942 -79.06512) (xy 163.61944 -79.097081) (xy 163.611429 -79.160499) (xy 163.595532 -79.222413)
			(xy 163.572 -79.281846) (xy 163.541206 -79.337861) (xy 163.503633 -79.389576) (xy 163.459876 -79.436173)
			(xy 163.410623 -79.476918) (xy 163.356652 -79.511169) (xy 163.298813 -79.538386) (xy 163.23802 -79.558139)
			(xy 163.17523 -79.570117) (xy 163.111434 -79.574131) (xy 163.047638 -79.570117) (xy 162.984848 -79.558139)
			(xy 162.924055 -79.538386) (xy 162.866216 -79.511169) (xy 162.812245 -79.476918) (xy 162.762992 -79.436173)
			(xy 162.719235 -79.389576) (xy 162.681662 -79.337861) (xy 162.650868 -79.281846) (xy 162.627336 -79.222413)
			(xy 162.611439 -79.160499) (xy 162.603428 -79.097081) (xy 152.192228 -79.097081) (xy 152.192228 -82.080354)
			(xy 152.19299 -82.088736) (xy 152.194509 -82.096338) (xy 152.201502 -82.110166) (xy 152.206706 -82.115914)
			(xy 152.535339 -82.444547) (xy 162.309296 -82.444547) (xy 162.309296 -82.380625) (xy 162.317307 -82.317207)
			(xy 162.333204 -82.255293) (xy 162.356736 -82.19586) (xy 162.38753 -82.139845) (xy 162.425103 -82.08813)
			(xy 162.46886 -82.041533) (xy 162.518113 -82.000788) (xy 162.572084 -81.966537) (xy 162.629923 -81.93932)
			(xy 162.690716 -81.919567) (xy 162.753506 -81.907589) (xy 162.817302 -81.903576) (xy 162.881098 -81.907589)
			(xy 162.943888 -81.919567) (xy 163.004681 -81.93932) (xy 163.06252 -81.966537) (xy 163.116491 -82.000788)
			(xy 163.165744 -82.041533) (xy 163.209501 -82.08813) (xy 163.247074 -82.139845) (xy 163.277868 -82.19586)
			(xy 163.3014 -82.255293) (xy 163.317297 -82.317207) (xy 163.325308 -82.380625) (xy 163.32581 -82.412586)
			(xy 163.325308 -82.444547) (xy 163.317297 -82.507965) (xy 163.3014 -82.569879) (xy 163.277868 -82.629312)
			(xy 163.247074 -82.685327) (xy 163.209501 -82.737042) (xy 163.165744 -82.783639) (xy 163.116491 -82.824384)
			(xy 163.06252 -82.858635) (xy 163.004681 -82.885852) (xy 162.943888 -82.905605) (xy 162.881098 -82.917583)
			(xy 162.817302 -82.921597) (xy 162.753506 -82.917583) (xy 162.690716 -82.905605) (xy 162.629923 -82.885852)
			(xy 162.572084 -82.858635) (xy 162.518113 -82.824384) (xy 162.46886 -82.783639) (xy 162.425103 -82.737042)
			(xy 162.38753 -82.685327) (xy 162.356736 -82.629312) (xy 162.333204 -82.569879) (xy 162.317307 -82.507965)
			(xy 162.309296 -82.444547) (xy 152.535339 -82.444547) (xy 153.054515 -82.963723) (xy 167.111166 -82.963723)
			(xy 167.111166 -82.899801) (xy 167.119177 -82.836383) (xy 167.135074 -82.774469) (xy 167.158606 -82.715036)
			(xy 167.1894 -82.659021) (xy 167.226973 -82.607306) (xy 167.27073 -82.560709) (xy 167.319983 -82.519964)
			(xy 167.373954 -82.485713) (xy 167.431793 -82.458496) (xy 167.492586 -82.438743) (xy 167.555376 -82.426765)
			(xy 167.619172 -82.422752) (xy 167.682968 -82.426765) (xy 167.745758 -82.438743) (xy 167.806551 -82.458496)
			(xy 167.86439 -82.485713) (xy 167.918361 -82.519964) (xy 167.967614 -82.560709) (xy 168.011371 -82.607306)
			(xy 168.048944 -82.659021) (xy 168.079738 -82.715036) (xy 168.10327 -82.774469) (xy 168.119167 -82.836383)
			(xy 168.127178 -82.899801) (xy 168.12768 -82.931762) (xy 168.127178 -82.963723) (xy 168.119167 -83.027141)
			(xy 168.10327 -83.089055) (xy 168.079738 -83.148488) (xy 168.048944 -83.204503) (xy 168.011371 -83.256218)
			(xy 167.967614 -83.302815) (xy 167.918361 -83.34356) (xy 167.86439 -83.377811) (xy 167.806551 -83.405028)
			(xy 167.745758 -83.424781) (xy 167.682968 -83.436759) (xy 167.619172 -83.440773) (xy 167.555376 -83.436759)
			(xy 167.492586 -83.424781) (xy 167.431793 -83.405028) (xy 167.373954 -83.377811) (xy 167.319983 -83.34356)
			(xy 167.27073 -83.302815) (xy 167.226973 -83.256218) (xy 167.1894 -83.204503) (xy 167.158606 -83.148488)
			(xy 167.135074 -83.089055) (xy 167.119177 -83.027141) (xy 167.111166 -82.963723) (xy 153.054515 -82.963723)
			(xy 154.287685 -84.196893) (xy 157.374584 -84.196893) (xy 157.374584 -84.132971) (xy 157.382595 -84.069553)
			(xy 157.398492 -84.007639) (xy 157.422024 -83.948206) (xy 157.452818 -83.892191) (xy 157.490391 -83.840476)
			(xy 157.534148 -83.793879) (xy 157.583401 -83.753134) (xy 157.637372 -83.718883) (xy 157.695211 -83.691666)
			(xy 157.756004 -83.671913) (xy 157.818794 -83.659935) (xy 157.88259 -83.655922) (xy 157.946386 -83.659935)
			(xy 158.009176 -83.671913) (xy 158.069969 -83.691666) (xy 158.127808 -83.718883) (xy 158.181779 -83.753134)
			(xy 158.231032 -83.793879) (xy 158.274789 -83.840476) (xy 158.312362 -83.892191) (xy 158.343156 -83.948206)
			(xy 158.358954 -83.988105) (xy 158.594546 -83.988105) (xy 158.594546 -83.924183) (xy 158.602557 -83.860765)
			(xy 158.618454 -83.798851) (xy 158.641986 -83.739418) (xy 158.67278 -83.683403) (xy 158.710353 -83.631688)
			(xy 158.75411 -83.585091) (xy 158.803363 -83.544346) (xy 158.857334 -83.510095) (xy 158.915173 -83.482878)
			(xy 158.975966 -83.463125) (xy 159.038756 -83.451147) (xy 159.102552 -83.447134) (xy 159.166348 -83.451147)
			(xy 159.229138 -83.463125) (xy 159.289931 -83.482878) (xy 159.34777 -83.510095) (xy 159.401741 -83.544346)
			(xy 159.450994 -83.585091) (xy 159.494751 -83.631688) (xy 159.532324 -83.683403) (xy 159.563118 -83.739418)
			(xy 159.58665 -83.798851) (xy 159.602547 -83.860765) (xy 159.610558 -83.924183) (xy 159.61106 -83.956144)
			(xy 159.610558 -83.988105) (xy 159.602547 -84.051523) (xy 159.58665 -84.113437) (xy 159.563118 -84.17287)
			(xy 159.532324 -84.228885) (xy 159.494751 -84.2806) (xy 159.450994 -84.327197) (xy 159.401741 -84.367942)
			(xy 159.34777 -84.402193) (xy 159.289931 -84.42941) (xy 159.229138 -84.449163) (xy 159.166348 -84.461141)
			(xy 159.102552 -84.465155) (xy 159.038756 -84.461141) (xy 158.975966 -84.449163) (xy 158.915173 -84.42941)
			(xy 158.857334 -84.402193) (xy 158.803363 -84.367942) (xy 158.75411 -84.327197) (xy 158.710353 -84.2806)
			(xy 158.67278 -84.228885) (xy 158.641986 -84.17287) (xy 158.618454 -84.113437) (xy 158.602557 -84.051523)
			(xy 158.594546 -83.988105) (xy 158.358954 -83.988105) (xy 158.366688 -84.007639) (xy 158.382585 -84.069553)
			(xy 158.390596 -84.132971) (xy 158.391098 -84.164932) (xy 158.390596 -84.196893) (xy 158.382585 -84.260311)
			(xy 158.366688 -84.322225) (xy 158.343156 -84.381658) (xy 158.312362 -84.437673) (xy 158.274789 -84.489388)
			(xy 158.231032 -84.535985) (xy 158.181779 -84.57673) (xy 158.127808 -84.610981) (xy 158.069969 -84.638198)
			(xy 158.009176 -84.657951) (xy 157.946386 -84.669929) (xy 157.88259 -84.673943) (xy 157.818794 -84.669929)
			(xy 157.756004 -84.657951) (xy 157.695211 -84.638198) (xy 157.637372 -84.610981) (xy 157.583401 -84.57673)
			(xy 157.534148 -84.535985) (xy 157.490391 -84.489388) (xy 157.452818 -84.437673) (xy 157.422024 -84.381658)
			(xy 157.398492 -84.322225) (xy 157.382595 -84.260311) (xy 157.374584 -84.196893) (xy 154.287685 -84.196893)
			(xy 156.812953 -86.722161) (xy 159.94227 -86.722161) (xy 159.94227 -86.658239) (xy 159.950281 -86.594821)
			(xy 159.966178 -86.532907) (xy 159.98971 -86.473474) (xy 160.020504 -86.417459) (xy 160.058077 -86.365744)
			(xy 160.101834 -86.319147) (xy 160.151087 -86.278402) (xy 160.205058 -86.244151) (xy 160.262897 -86.216934)
			(xy 160.32369 -86.197181) (xy 160.38648 -86.185203) (xy 160.450276 -86.18119) (xy 160.514072 -86.185203)
			(xy 160.576862 -86.197181) (xy 160.637655 -86.216934) (xy 160.695494 -86.244151) (xy 160.749465 -86.278402)
			(xy 160.798718 -86.319147) (xy 160.842475 -86.365744) (xy 160.880048 -86.417459) (xy 160.910842 -86.473474)
			(xy 160.934374 -86.532907) (xy 160.950271 -86.594821) (xy 160.958282 -86.658239) (xy 160.958784 -86.6902)
			(xy 160.958282 -86.722161) (xy 160.950271 -86.785579) (xy 160.936609 -86.83879) (xy 166.853362 -86.83879)
			(xy 166.853864 -86.806829) (xy 166.861875 -86.743411) (xy 166.877772 -86.681497) (xy 166.901304 -86.622064)
			(xy 166.932098 -86.566049) (xy 166.969671 -86.514334) (xy 167.013428 -86.467737) (xy 167.062681 -86.426992)
			(xy 167.116652 -86.392741) (xy 167.174491 -86.365524) (xy 167.235284 -86.345771) (xy 167.298074 -86.333793)
			(xy 167.36187 -86.32978) (xy 167.425666 -86.333793) (xy 167.488456 -86.345771) (xy 167.549249 -86.365524)
			(xy 167.607088 -86.392741) (xy 167.661059 -86.426992) (xy 167.710312 -86.467737) (xy 167.754069 -86.514334)
			(xy 167.791642 -86.566049) (xy 167.822436 -86.622064) (xy 167.845968 -86.681497) (xy 167.861865 -86.743411)
			(xy 167.869876 -86.806829) (xy 167.870378 -86.83879) (xy 167.869969 -86.868403) (xy 167.863091 -86.927228)
			(xy 167.856662 -86.956138) (xy 167.854621 -86.966895) (xy 167.85883 -86.988356) (xy 167.86479 -86.99754)
			(xy 167.909494 -87.05977) (xy 167.91621 -87.068346) (xy 167.935039 -87.079261) (xy 167.945816 -87.080852)
			(xy 167.946324 -87.080852) (xy 167.979211 -87.08444) (xy 168.043724 -87.099093) (xy 168.10579 -87.121993)
			(xy 168.16436 -87.152752) (xy 168.218445 -87.190851) (xy 168.267129 -87.235644) (xy 168.309591 -87.286375)
			(xy 168.345111 -87.342186) (xy 168.359582 -87.371936) (xy 168.365057 -87.382357) (xy 168.383463 -87.396997)
			(xy 168.406457 -87.401936) (xy 168.418002 -87.399622) (xy 168.448422 -87.392459) (xy 168.510451 -87.38482)
			(xy 168.5417 -87.384382) (xy 168.541954 -87.384382) (xy 168.573328 -87.384865) (xy 168.6356 -87.392585)
			(xy 168.696448 -87.407912) (xy 168.754946 -87.430615) (xy 168.810204 -87.460347) (xy 168.861381 -87.496655)
			(xy 168.884854 -87.517478) (xy 168.891878 -87.523288) (xy 168.908781 -87.53007) (xy 168.917874 -87.530686)
			(xy 168.948354 -87.531448) (xy 168.957442 -87.531368) (xy 168.974629 -87.525496) (xy 168.981882 -87.520018)
			(xy 169.009269 -87.498333) (xy 169.06885 -87.461863) (xy 169.132856 -87.433879) (xy 169.200087 -87.414908)
			(xy 169.26928 -87.405305) (xy 169.304208 -87.404702) (xy 169.336169 -87.405184) (xy 169.399588 -87.413197)
			(xy 169.461502 -87.429095) (xy 169.520936 -87.452627) (xy 169.576951 -87.483423) (xy 169.628665 -87.520996)
			(xy 169.675263 -87.564754) (xy 169.716008 -87.614008) (xy 169.750259 -87.66798) (xy 169.777476 -87.725819)
			(xy 169.797229 -87.786613) (xy 169.79942 -87.7981) (xy 170.207237 -87.7981) (xy 170.211251 -87.734311)
			(xy 170.223227 -87.671527) (xy 170.242978 -87.61074) (xy 170.270192 -87.552907) (xy 170.304439 -87.498941)
			(xy 170.34518 -87.449693) (xy 170.391773 -87.40594) (xy 170.443481 -87.368371) (xy 170.49949 -87.337579)
			(xy 170.558917 -87.314049) (xy 170.620825 -87.298154) (xy 170.684236 -87.290142) (xy 170.716194 -87.28964)
			(xy 170.746915 -87.290108) (xy 170.807909 -87.297507) (xy 170.867568 -87.312198) (xy 170.925023 -87.333968)
			(xy 170.979438 -87.362498) (xy 171.004992 -87.379556) (xy 171.013677 -87.384949) (xy 171.033694 -87.38901)
			(xy 171.053711 -87.384949) (xy 171.062396 -87.379556) (xy 171.08795 -87.362498) (xy 171.142365 -87.333967)
			(xy 171.19982 -87.312196) (xy 171.259479 -87.297504) (xy 171.320473 -87.290104) (xy 171.381915 -87.290104)
			(xy 171.442909 -87.297504) (xy 171.502568 -87.312196) (xy 171.560023 -87.333967) (xy 171.614438 -87.362498)
			(xy 171.639992 -87.379556) (xy 171.648677 -87.384949) (xy 171.668694 -87.38901) (xy 171.688711 -87.384949)
			(xy 171.697396 -87.379556) (xy 171.72295 -87.362499) (xy 171.777365 -87.333967) (xy 171.83482 -87.312196)
			(xy 171.894479 -87.297503) (xy 171.955473 -87.290103) (xy 171.986194 -87.28964) (xy 172.01816 -87.290025)
			(xy 172.081587 -87.298037) (xy 172.14351 -87.313935) (xy 172.202952 -87.337469) (xy 172.258975 -87.368268)
			(xy 172.310697 -87.405845) (xy 172.357301 -87.449609) (xy 172.398053 -87.498869) (xy 172.432309 -87.552847)
			(xy 172.45953 -87.610694) (xy 172.479286 -87.671496) (xy 172.491265 -87.734295) (xy 172.49528 -87.7981)
			(xy 172.491265 -87.861905) (xy 172.479286 -87.924704) (xy 172.478572 -87.9269) (xy 175.670694 -87.9269)
			(xy 175.674709 -87.863102) (xy 175.686687 -87.80031) (xy 175.706442 -87.739515) (xy 175.73366 -87.681675)
			(xy 175.767914 -87.627703) (xy 175.808662 -87.57845) (xy 175.855262 -87.534692) (xy 175.90698 -87.497121)
			(xy 175.962998 -87.466328) (xy 176.022435 -87.442799) (xy 176.084351 -87.426905) (xy 176.147772 -87.418897)
			(xy 176.179734 -87.418418) (xy 176.212589 -87.418944) (xy 176.277749 -87.427419) (xy 176.341277 -87.444211)
			(xy 176.402114 -87.469041) (xy 176.45925 -87.501495) (xy 176.511733 -87.541033) (xy 176.558689 -87.586998)
			(xy 176.599339 -87.638625) (xy 176.616614 -87.666576) (xy 176.623726 -87.678768) (xy 176.648364 -87.691976)
			(xy 176.76622 -87.686642) (xy 176.789334 -87.671148) (xy 176.79543 -87.658448) (xy 176.807469 -87.63448)
			(xy 176.837194 -87.589836) (xy 176.872878 -87.549793) (xy 176.913816 -87.515142) (xy 176.959203 -87.486564)
			(xy 177.008145 -87.464623) (xy 177.059676 -87.449751) (xy 177.112783 -87.442241) (xy 177.1396 -87.441786)
			(xy 177.139854 -87.441786) (xy 177.153939 -87.441884) (xy 177.182035 -87.44392) (xy 177.195988 -87.44585)
			(xy 177.204517 -87.446817) (xy 177.221388 -87.443705) (xy 177.229008 -87.439754) (xy 177.254916 -87.424768)
			(xy 177.262311 -87.420061) (xy 177.27362 -87.406687) (xy 177.277014 -87.398606) (xy 177.288368 -87.370034)
			(xy 177.316901 -87.315574) (xy 177.351794 -87.264954) (xy 177.392539 -87.218911) (xy 177.438539 -87.178119)
			(xy 177.489124 -87.143173) (xy 177.543554 -87.114584) (xy 177.601035 -87.092769) (xy 177.660728 -87.078046)
			(xy 177.721761 -87.07063) (xy 177.752502 -87.070184) (xy 177.783114 -87.070614) (xy 177.843894 -87.077983)
			(xy 177.903351 -87.092591) (xy 177.960627 -87.114226) (xy 178.014892 -87.142576) (xy 178.065365 -87.177232)
			(xy 178.111316 -87.217693) (xy 178.152081 -87.263374) (xy 178.187071 -87.313615) (xy 178.201828 -87.34044)
			(xy 178.207717 -87.350231) (xy 178.226054 -87.363812) (xy 178.237134 -87.366602) (xy 178.326034 -87.383874)
			(xy 178.348132 -87.378032) (xy 178.357022 -87.370412) (xy 178.38 -87.351529) (xy 178.429587 -87.318685)
			(xy 178.482669 -87.291855) (xy 178.538522 -87.271408) (xy 178.596379 -87.257623) (xy 178.655451 -87.250688)
			(xy 178.68519 -87.25027) (xy 178.685444 -87.25027) (xy 178.720074 -87.250813) (xy 178.788695 -87.260199)
			(xy 178.855405 -87.278818) (xy 178.918969 -87.306325) (xy 178.978207 -87.34221) (xy 179.005484 -87.363554)
			(xy 179.014351 -87.370122) (xy 179.035683 -87.375668) (xy 179.05737 -87.371733) (xy 179.066698 -87.36584)
			(xy 179.092476 -87.348276) (xy 179.147499 -87.318888) (xy 179.205701 -87.296443) (xy 179.266209 -87.281278)
			(xy 179.328117 -87.27362) (xy 179.359306 -87.27313) (xy 179.391269 -87.273556) (xy 179.454691 -87.281569)
			(xy 179.516609 -87.297468) (xy 179.576046 -87.321001) (xy 179.632065 -87.351798) (xy 179.683782 -87.389374)
			(xy 179.730382 -87.433134) (xy 179.77113 -87.482391) (xy 179.805384 -87.536366) (xy 179.832602 -87.594208)
			(xy 179.852356 -87.655006) (xy 179.864335 -87.7178) (xy 179.868349 -87.7816) (xy 179.864335 -87.8454)
			(xy 179.852356 -87.908194) (xy 179.832602 -87.968992) (xy 179.805384 -88.026834) (xy 179.77113 -88.080809)
			(xy 179.730382 -88.130066) (xy 179.683782 -88.173826) (xy 179.632065 -88.211402) (xy 179.576046 -88.242199)
			(xy 179.516609 -88.265732) (xy 179.454691 -88.281631) (xy 179.391269 -88.289644) (xy 179.359306 -88.290146)
			(xy 179.324677 -88.289571) (xy 179.256057 -88.280192) (xy 179.189348 -88.26158) (xy 179.125784 -88.234081)
			(xy 179.066544 -88.198202) (xy 179.039266 -88.176862) (xy 179.030427 -88.17025) (xy 179.009078 -88.164715)
			(xy 178.987381 -88.16867) (xy 178.978052 -88.174576) (xy 178.952261 -88.19212) (xy 178.897241 -88.221511)
			(xy 178.839043 -88.24396) (xy 178.778538 -88.25913) (xy 178.716633 -88.266793) (xy 178.685444 -88.267286)
			(xy 178.654832 -88.266834) (xy 178.594052 -88.25947) (xy 178.534595 -88.244866) (xy 178.47732 -88.223235)
			(xy 178.423053 -88.194887) (xy 178.37258 -88.160234) (xy 178.326629 -88.119775) (xy 178.285865 -88.074095)
			(xy 178.250875 -88.023854) (xy 178.236118 -87.99703) (xy 178.230216 -87.987249) (xy 178.211888 -87.973664)
			(xy 178.200812 -87.970868) (xy 178.111912 -87.953596) (xy 178.089814 -87.959438) (xy 178.080924 -87.967058)
			(xy 178.057925 -87.985915) (xy 178.008344 -88.018763) (xy 177.955266 -88.045597) (xy 177.899417 -88.066049)
			(xy 177.841563 -88.079839) (xy 177.782494 -88.086779) (xy 177.752756 -88.0872) (xy 177.752502 -88.0872)
			(xy 177.72392 -88.086785) (xy 177.667118 -88.080355) (xy 177.611392 -88.067608) (xy 177.557443 -88.048705)
			(xy 177.531522 -88.036654) (xy 177.523547 -88.033193) (xy 177.506265 -88.031387) (xy 177.49774 -88.033098)
			(xy 177.468784 -88.039956) (xy 177.460451 -88.042274) (xy 177.445914 -88.051632) (xy 177.440336 -88.058244)
			(xy 177.422146 -88.080673) (xy 177.380116 -88.120273) (xy 177.332603 -88.153094) (xy 177.280691 -88.178388)
			(xy 177.225562 -88.195578) (xy 177.168473 -88.204273) (xy 177.1396 -88.204802) (xy 177.110683 -88.204283)
			(xy 177.053512 -88.195554) (xy 176.998313 -88.178296) (xy 176.946352 -88.152904) (xy 176.898818 -88.119961)
			(xy 176.8568 -88.080221) (xy 176.83861 -88.057736) (xy 176.83861 -88.057482) (xy 176.832611 -88.050534)
			(xy 176.816956 -88.040982) (xy 176.798946 -88.037524) (xy 176.789842 -88.038686) (xy 176.701704 -88.053926)
			(xy 176.692722 -88.055849) (xy 176.676874 -88.065105) (xy 176.665329 -88.079371) (xy 176.66208 -88.087962)
			(xy 176.651536 -88.11792) (xy 176.624077 -88.175188) (xy 176.589701 -88.228591) (xy 176.548942 -88.277298)
			(xy 176.502435 -88.32055) (xy 176.450904 -88.357674) (xy 176.395152 -88.388093) (xy 176.336045 -88.411332)
			(xy 176.274505 -88.42703) (xy 176.211489 -88.434943) (xy 176.179734 -88.435434) (xy 176.147772 -88.434903)
			(xy 176.084351 -88.426895) (xy 176.022435 -88.411001) (xy 175.962998 -88.387472) (xy 175.90698 -88.356679)
			(xy 175.855262 -88.319108) (xy 175.808662 -88.27535) (xy 175.767914 -88.226097) (xy 175.73366 -88.172125)
			(xy 175.706442 -88.114285) (xy 175.686687 -88.05349) (xy 175.674709 -87.990698) (xy 175.670694 -87.9269)
			(xy 172.478572 -87.9269) (xy 172.45953 -87.985506) (xy 172.432309 -88.043353) (xy 172.398053 -88.097331)
			(xy 172.357301 -88.146591) (xy 172.310697 -88.190355) (xy 172.258975 -88.227932) (xy 172.202952 -88.258731)
			(xy 172.14351 -88.282265) (xy 172.081587 -88.298163) (xy 172.01816 -88.306175) (xy 171.986194 -88.306656)
			(xy 171.955473 -88.306195) (xy 171.894479 -88.298794) (xy 171.83482 -88.284102) (xy 171.777365 -88.262331)
			(xy 171.72295 -88.233798) (xy 171.697396 -88.21674) (xy 171.688711 -88.211347) (xy 171.668694 -88.207286)
			(xy 171.648677 -88.211347) (xy 171.639992 -88.21674) (xy 171.614438 -88.233798) (xy 171.560023 -88.262329)
			(xy 171.502568 -88.2841) (xy 171.442909 -88.298792) (xy 171.381915 -88.306192) (xy 171.320473 -88.306192)
			(xy 171.259479 -88.298792) (xy 171.19982 -88.2841) (xy 171.142365 -88.262329) (xy 171.08795 -88.233798)
			(xy 171.062396 -88.21674) (xy 171.053711 -88.211347) (xy 171.033694 -88.207286) (xy 171.013677 -88.211347)
			(xy 171.004992 -88.21674) (xy 170.979441 -88.233802) (xy 170.925025 -88.262333) (xy 170.867569 -88.284103)
			(xy 170.80791 -88.298795) (xy 170.746915 -88.306194) (xy 170.716194 -88.306656) (xy 170.684236 -88.306058)
			(xy 170.620825 -88.298046) (xy 170.558917 -88.282151) (xy 170.49949 -88.258621) (xy 170.443481 -88.227829)
			(xy 170.391773 -88.19026) (xy 170.34518 -88.146507) (xy 170.304439 -88.097259) (xy 170.270192 -88.043293)
			(xy 170.242978 -87.98546) (xy 170.223227 -87.924673) (xy 170.211251 -87.861889) (xy 170.207237 -87.7981)
			(xy 169.79942 -87.7981) (xy 169.809207 -87.849403) (xy 169.813221 -87.9132) (xy 169.809207 -87.976997)
			(xy 169.797229 -88.039787) (xy 169.777476 -88.100581) (xy 169.750259 -88.15842) (xy 169.716008 -88.212392)
			(xy 169.675263 -88.261646) (xy 169.628665 -88.305404) (xy 169.576951 -88.342977) (xy 169.520936 -88.373773)
			(xy 169.461502 -88.397305) (xy 169.399588 -88.413203) (xy 169.336169 -88.421216) (xy 169.304208 -88.421718)
			(xy 169.272833 -88.421258) (xy 169.21056 -88.413534) (xy 169.149712 -88.398202) (xy 169.091214 -88.375495)
			(xy 169.035957 -88.345759) (xy 168.98478 -88.309446) (xy 168.961308 -88.288622) (xy 168.954295 -88.282797)
			(xy 168.937384 -88.276024) (xy 168.928288 -88.275414) (xy 168.897808 -88.274652) (xy 168.888722 -88.274763)
			(xy 168.871535 -88.280613) (xy 168.86428 -88.286082) (xy 168.836906 -88.307785) (xy 168.777322 -88.344252)
			(xy 168.713312 -88.372232) (xy 168.646078 -88.391199) (xy 168.576883 -88.400797) (xy 168.541954 -88.401398)
			(xy 168.509906 -88.400956) (xy 168.446319 -88.392896) (xy 168.384249 -88.37691) (xy 168.324679 -88.353251)
			(xy 168.268555 -88.322294) (xy 168.216765 -88.284529) (xy 168.170132 -88.240557) (xy 168.129393 -88.191073)
			(xy 168.095196 -88.136862) (xy 168.081198 -88.108028) (xy 168.075632 -88.097664) (xy 168.057272 -88.083012)
			(xy 168.034312 -88.078046) (xy 168.022778 -88.080342) (xy 167.992355 -88.087492) (xy 167.930328 -88.095139)
			(xy 167.89908 -88.095582) (xy 167.898826 -88.095582) (xy 167.868093 -88.095138) (xy 167.807076 -88.087732)
			(xy 167.747397 -88.073024) (xy 167.689925 -88.05123) (xy 167.6355 -88.022667) (xy 167.584915 -87.987751)
			(xy 167.538907 -87.946993) (xy 167.498149 -87.900985) (xy 167.463233 -87.8504) (xy 167.43467 -87.795975)
			(xy 167.412876 -87.738503) (xy 167.398168 -87.678824) (xy 167.390762 -87.617807) (xy 167.390318 -87.587074)
			(xy 167.390738 -87.557461) (xy 167.397609 -87.498636) (xy 167.404034 -87.469726) (xy 167.406098 -87.458972)
			(xy 167.401873 -87.437507) (xy 167.395906 -87.428324) (xy 167.351202 -87.366094) (xy 167.344475 -87.357528)
			(xy 167.325655 -87.346606) (xy 167.31488 -87.345012) (xy 167.314372 -87.345012) (xy 167.283254 -87.341538)
			(xy 167.222101 -87.328096) (xy 167.163061 -87.307246) (xy 167.10703 -87.279302) (xy 167.054855 -87.244688)
			(xy 167.007326 -87.203927) (xy 166.965164 -87.157638) (xy 166.929006 -87.106521) (xy 166.8994 -87.05135)
			(xy 166.876794 -86.99296) (xy 166.861531 -86.932236) (xy 166.853842 -86.870096) (xy 166.853362 -86.83879)
			(xy 160.936609 -86.83879) (xy 160.934374 -86.847493) (xy 160.910842 -86.906926) (xy 160.880048 -86.962941)
			(xy 160.842475 -87.014656) (xy 160.798718 -87.061253) (xy 160.749465 -87.101998) (xy 160.695494 -87.136249)
			(xy 160.637655 -87.163466) (xy 160.576862 -87.183219) (xy 160.514072 -87.195197) (xy 160.450276 -87.199211)
			(xy 160.38648 -87.195197) (xy 160.32369 -87.183219) (xy 160.262897 -87.163466) (xy 160.205058 -87.136249)
			(xy 160.151087 -87.101998) (xy 160.101834 -87.061253) (xy 160.058077 -87.014656) (xy 160.020504 -86.962941)
			(xy 159.98971 -86.906926) (xy 159.966178 -86.847493) (xy 159.950281 -86.785579) (xy 159.94227 -86.722161)
			(xy 156.812953 -86.722161) (xy 157.910022 -87.81923) (xy 157.919082 -87.827299) (xy 157.942149 -87.834708)
			(xy 157.954218 -87.833454) (xy 158.04261 -87.818976) (xy 158.047944 -87.81796) (xy 158.057342 -87.811102)
			(xy 158.062251 -87.807309) (xy 158.070216 -87.797804) (xy 158.07309 -87.792306) (xy 158.08738 -87.764209)
			(xy 158.121896 -87.71146) (xy 158.162669 -87.663383) (xy 158.209073 -87.620717) (xy 158.260397 -87.584117)
			(xy 158.315854 -87.554143) (xy 158.37459 -87.531257) (xy 158.435706 -87.515809) (xy 158.498263 -87.508037)
			(xy 158.529782 -87.507572) (xy 158.536132 -87.507572) (xy 158.546199 -87.507142) (xy 158.564792 -87.499417)
			(xy 158.5722 -87.492586) (xy 158.612332 -87.44966) (xy 158.624524 -87.436706) (xy 158.628057 -87.432735)
			(xy 158.633556 -87.423641) (xy 158.635446 -87.418672) (xy 158.638748 -87.40902) (xy 158.637986 -87.398098)
			(xy 158.636462 -87.357966) (xy 158.63694 -87.326423) (xy 158.644747 -87.263822) (xy 158.660238 -87.202668)
			(xy 158.683174 -87.1439) (xy 158.713203 -87.088419) (xy 158.749864 -87.03708) (xy 158.792594 -86.990669)
			(xy 158.840736 -86.9499) (xy 158.893552 -86.915399) (xy 158.950229 -86.887695) (xy 159.009898 -86.867215)
			(xy 159.071642 -86.854273) (xy 159.134512 -86.849068) (xy 159.197544 -86.851679) (xy 159.259769 -86.862066)
			(xy 159.320231 -86.880071) (xy 159.378001 -86.905416) (xy 159.432193 -86.937712) (xy 159.481974 -86.976463)
			(xy 159.52658 -87.021074) (xy 159.565325 -87.07086) (xy 159.597614 -87.125056) (xy 159.622951 -87.18283)
			(xy 159.640948 -87.243294) (xy 159.651328 -87.30552) (xy 159.653931 -87.368552) (xy 159.648718 -87.431422)
			(xy 159.635768 -87.493164) (xy 159.61528 -87.55283) (xy 159.58757 -87.609504) (xy 159.553062 -87.662315)
			(xy 159.512287 -87.710452) (xy 159.465871 -87.753176) (xy 159.414526 -87.789831) (xy 159.359042 -87.819853)
			(xy 159.300271 -87.842782) (xy 159.239115 -87.858265) (xy 159.176513 -87.866064) (xy 159.14497 -87.866474)
			(xy 159.138366 -87.866474) (xy 159.128209 -87.86692) (xy 159.109474 -87.874775) (xy 159.102044 -87.881714)
			(xy 159.07385 -87.91194) (xy 159.07385 -87.912448) (xy 159.050228 -87.93734) (xy 159.046688 -87.941307)
			(xy 159.041174 -87.950396) (xy 159.039306 -87.955374) (xy 159.036004 -87.965026) (xy 159.036766 -87.975948)
			(xy 159.03829 -88.01608) (xy 159.037812 -88.047595) (xy 159.030015 -88.110142) (xy 159.01455 -88.171246)
			(xy 158.991654 -88.229971) (xy 158.961678 -88.285417) (xy 158.925082 -88.336736) (xy 158.882426 -88.383139)
			(xy 158.834363 -88.423918) (xy 158.781631 -88.458445) (xy 158.753556 -88.472772) (xy 158.748061 -88.47565)
			(xy 158.73855 -88.483609) (xy 158.73476 -88.48852) (xy 158.727902 -88.497918) (xy 158.726886 -88.503252)
			(xy 158.712408 -88.591644) (xy 158.71106 -88.603263) (xy 158.717823 -88.625625) (xy 158.725362 -88.63457)
			(xy 158.801308 -88.710262) (xy 161.2519 -91.161108) (xy 161.259121 -91.167587) (xy 161.277013 -91.17504)
			(xy 161.286698 -91.175586) (xy 161.286952 -91.175586) (xy 161.287714 -91.175586) (xy 161.322004 -91.16187)
			(xy 161.3281 -91.156536) (xy 161.351573 -91.135713) (xy 161.40275 -91.099402) (xy 161.458007 -91.069668)
			(xy 161.516505 -91.046962) (xy 161.577353 -91.03163) (xy 161.639625 -91.023906) (xy 161.671 -91.02344)
			(xy 161.701731 -91.023886) (xy 161.762745 -91.031295) (xy 161.822421 -91.046004) (xy 161.879889 -91.0678)
			(xy 161.93431 -91.096365) (xy 161.984891 -91.131281) (xy 162.030894 -91.17204) (xy 162.071649 -91.218047)
			(xy 162.10656 -91.268631) (xy 162.135119 -91.323055) (xy 162.15691 -91.380525) (xy 162.171614 -91.440202)
			(xy 162.179017 -91.501217) (xy 162.179508 -91.531948) (xy 162.179098 -91.558829) (xy 162.286182 -91.558829)
			(xy 162.286182 -91.494907) (xy 162.294193 -91.431489) (xy 162.31009 -91.369575) (xy 162.333622 -91.310142)
			(xy 162.364416 -91.254127) (xy 162.401989 -91.202412) (xy 162.445746 -91.155815) (xy 162.494999 -91.11507)
			(xy 162.54897 -91.080819) (xy 162.606809 -91.053602) (xy 162.667602 -91.033849) (xy 162.730392 -91.021871)
			(xy 162.794188 -91.017858) (xy 162.857984 -91.021871) (xy 162.920774 -91.033849) (xy 162.981567 -91.053602)
			(xy 163.039406 -91.080819) (xy 163.093377 -91.11507) (xy 163.14263 -91.155815) (xy 163.186387 -91.202412)
			(xy 163.22396 -91.254127) (xy 163.254754 -91.310142) (xy 163.278286 -91.369575) (xy 163.294183 -91.431489)
			(xy 163.302194 -91.494907) (xy 163.302696 -91.526868) (xy 163.302194 -91.558829) (xy 163.294183 -91.622247)
			(xy 163.28476 -91.658948) (xy 180.338982 -91.658948) (xy 180.343053 -91.603326) (xy 180.355179 -91.548889)
			(xy 180.375102 -91.496798) (xy 180.402398 -91.448163) (xy 180.436484 -91.40402) (xy 180.476633 -91.365311)
			(xy 180.521991 -91.33286) (xy 180.571591 -91.307359) (xy 180.624375 -91.289352) (xy 180.679218 -91.279222)
			(xy 180.734952 -91.277185) (xy 180.790389 -91.283285) (xy 180.844346 -91.297391) (xy 180.895675 -91.319203)
			(xy 180.943281 -91.348257) (xy 180.986149 -91.383932) (xy 181.023366 -91.425469) (xy 181.054139 -91.471982)
			(xy 181.077811 -91.522479) (xy 181.093879 -91.575886) (xy 181.101999 -91.631062) (xy 181.102508 -91.658948)
			(xy 181.101999 -91.686834) (xy 181.093879 -91.74201) (xy 181.077811 -91.795417) (xy 181.054139 -91.845914)
			(xy 181.023366 -91.892427) (xy 180.986149 -91.933964) (xy 180.943281 -91.969639) (xy 180.895675 -91.998693)
			(xy 180.844346 -92.020505) (xy 180.790389 -92.034611) (xy 180.734952 -92.040711) (xy 180.679218 -92.038674)
			(xy 180.624375 -92.028544) (xy 180.571591 -92.010537) (xy 180.521991 -91.985036) (xy 180.476633 -91.952585)
			(xy 180.436484 -91.913876) (xy 180.402398 -91.869733) (xy 180.375102 -91.821098) (xy 180.355179 -91.769007)
			(xy 180.343053 -91.71457) (xy 180.338982 -91.658948) (xy 163.28476 -91.658948) (xy 163.278286 -91.684161)
			(xy 163.254754 -91.743594) (xy 163.22396 -91.799609) (xy 163.186387 -91.851324) (xy 163.14263 -91.897921)
			(xy 163.093377 -91.938666) (xy 163.039406 -91.972917) (xy 162.981567 -92.000134) (xy 162.920774 -92.019887)
			(xy 162.857984 -92.031865) (xy 162.794188 -92.035879) (xy 162.730392 -92.031865) (xy 162.667602 -92.019887)
			(xy 162.606809 -92.000134) (xy 162.54897 -91.972917) (xy 162.494999 -91.938666) (xy 162.445746 -91.897921)
			(xy 162.401989 -91.851324) (xy 162.364416 -91.799609) (xy 162.333622 -91.743594) (xy 162.31009 -91.684161)
			(xy 162.294193 -91.622247) (xy 162.286182 -91.558829) (xy 162.179098 -91.558829) (xy 162.179019 -91.563983)
			(xy 162.170965 -91.627545) (xy 162.15499 -91.689591) (xy 162.131348 -91.74914) (xy 162.100412 -91.805246)
			(xy 162.062674 -91.857023) (xy 162.041078 -91.88069) (xy 162.03422 -91.888056) (xy 162.027108 -91.905836)
			(xy 162.027362 -91.91625) (xy 162.027458 -91.920395) (xy 162.028864 -91.928566) (xy 162.030156 -91.932506)
			(xy 162.03041 -91.933014) (xy 162.032018 -91.936994) (xy 162.036359 -91.944398) (xy 162.039046 -91.947746)
			(xy 162.042094 -91.951302) (xy 162.054032 -91.96324) (xy 162.10534 -92.014294) (xy 162.108896 -92.018104)
			(xy 162.243008 -92.152216) (xy 162.250921 -92.159306) (xy 162.270736 -92.166908) (xy 162.281362 -92.166948)
			(xy 162.306 -92.16644) (xy 162.336731 -92.166886) (xy 162.397745 -92.174295) (xy 162.457421 -92.189004)
			(xy 162.514889 -92.2108) (xy 162.56931 -92.239365) (xy 162.619891 -92.274281) (xy 162.665894 -92.31504)
			(xy 162.706573 -92.360961) (xy 172.422306 -92.360961) (xy 172.422306 -92.297039) (xy 172.430317 -92.233621)
			(xy 172.446214 -92.171707) (xy 172.469746 -92.112274) (xy 172.50054 -92.056259) (xy 172.538113 -92.004544)
			(xy 172.58187 -91.957947) (xy 172.631123 -91.917202) (xy 172.685094 -91.882951) (xy 172.742933 -91.855734)
			(xy 172.803726 -91.835981) (xy 172.866516 -91.824003) (xy 172.930312 -91.81999) (xy 172.994108 -91.824003)
			(xy 173.056898 -91.835981) (xy 173.117691 -91.855734) (xy 173.17553 -91.882951) (xy 173.229501 -91.917202)
			(xy 173.278754 -91.957947) (xy 173.322511 -92.004544) (xy 173.360084 -92.056259) (xy 173.390878 -92.112274)
			(xy 173.41441 -92.171707) (xy 173.430307 -92.233621) (xy 173.438318 -92.297039) (xy 173.43882 -92.329)
			(xy 173.438318 -92.360961) (xy 173.430307 -92.424379) (xy 173.41441 -92.486293) (xy 173.411419 -92.493846)
			(xy 176.428652 -92.493846) (xy 176.432723 -92.438224) (xy 176.444849 -92.383787) (xy 176.464772 -92.331696)
			(xy 176.492068 -92.283061) (xy 176.526154 -92.238918) (xy 176.566303 -92.200209) (xy 176.611661 -92.167758)
			(xy 176.661261 -92.142257) (xy 176.714045 -92.12425) (xy 176.768888 -92.11412) (xy 176.824622 -92.112083)
			(xy 176.880059 -92.118183) (xy 176.934016 -92.132289) (xy 176.985345 -92.154101) (xy 177.032951 -92.183155)
			(xy 177.075819 -92.21883) (xy 177.113036 -92.260367) (xy 177.143809 -92.30688) (xy 177.167481 -92.357377)
			(xy 177.183549 -92.410784) (xy 177.191669 -92.46596) (xy 177.192178 -92.493846) (xy 177.191669 -92.521732)
			(xy 177.183549 -92.576908) (xy 177.167481 -92.630315) (xy 177.143809 -92.680812) (xy 177.113036 -92.727325)
			(xy 177.075819 -92.768862) (xy 177.032951 -92.804537) (xy 176.985345 -92.833591) (xy 176.934016 -92.855403)
			(xy 176.880059 -92.869509) (xy 176.824622 -92.875609) (xy 176.768888 -92.873572) (xy 176.714045 -92.863442)
			(xy 176.661261 -92.845435) (xy 176.611661 -92.819934) (xy 176.566303 -92.787483) (xy 176.526154 -92.748774)
			(xy 176.492068 -92.704631) (xy 176.464772 -92.655996) (xy 176.444849 -92.603905) (xy 176.432723 -92.549468)
			(xy 176.428652 -92.493846) (xy 173.411419 -92.493846) (xy 173.390878 -92.545726) (xy 173.360084 -92.601741)
			(xy 173.322511 -92.653456) (xy 173.278754 -92.700053) (xy 173.229501 -92.740798) (xy 173.17553 -92.775049)
			(xy 173.117691 -92.802266) (xy 173.056898 -92.822019) (xy 172.994108 -92.833997) (xy 172.930312 -92.838011)
			(xy 172.866516 -92.833997) (xy 172.803726 -92.822019) (xy 172.742933 -92.802266) (xy 172.685094 -92.775049)
			(xy 172.631123 -92.740798) (xy 172.58187 -92.700053) (xy 172.538113 -92.653456) (xy 172.50054 -92.601741)
			(xy 172.469746 -92.545726) (xy 172.446214 -92.486293) (xy 172.430317 -92.424379) (xy 172.422306 -92.360961)
			(xy 162.706573 -92.360961) (xy 162.706649 -92.361047) (xy 162.74156 -92.411631) (xy 162.770119 -92.466055)
			(xy 162.79191 -92.523525) (xy 162.806614 -92.583202) (xy 162.814017 -92.644217) (xy 162.814508 -92.674948)
			(xy 162.814 -92.699586) (xy 162.813998 -92.71022) (xy 162.8216 -92.730054) (xy 162.828732 -92.73794)
			(xy 162.962844 -92.872052) (xy 162.9664 -92.875608) (xy 163.908692 -93.8179) (xy 170.382238 -93.8179)
			(xy 170.386251 -93.75411) (xy 170.398227 -93.691326) (xy 170.417979 -93.630538) (xy 170.445193 -93.572705)
			(xy 170.479441 -93.518739) (xy 170.520182 -93.469491) (xy 170.566775 -93.425738) (xy 170.618484 -93.388169)
			(xy 170.674494 -93.357377) (xy 170.733922 -93.333848) (xy 170.79583 -93.317953) (xy 170.859242 -93.309942)
			(xy 170.8912 -93.30944) (xy 170.922487 -93.309934) (xy 170.98459 -93.317606) (xy 171.04528 -93.332845)
			(xy 171.10364 -93.355421) (xy 171.158785 -93.384993) (xy 171.209883 -93.421112) (xy 171.256158 -93.463233)
			(xy 171.296911 -93.510717) (xy 171.314618 -93.536516) (xy 171.322141 -93.546666) (xy 171.344415 -93.558525)
			(xy 171.357036 -93.559122) (xy 171.441364 -93.559122) (xy 171.45397 -93.558482) (xy 171.476219 -93.546623)
			(xy 171.483782 -93.536516) (xy 171.501498 -93.510728) (xy 171.542264 -93.463265) (xy 171.588546 -93.421164)
			(xy 171.639645 -93.38506) (xy 171.694787 -93.355499) (xy 171.753141 -93.332928) (xy 171.813823 -93.317689)
			(xy 171.875917 -93.310011) (xy 171.938483 -93.310011) (xy 172.000577 -93.317689) (xy 172.061259 -93.332928)
			(xy 172.119613 -93.355499) (xy 172.174755 -93.38506) (xy 172.225854 -93.421164) (xy 172.272136 -93.463265)
			(xy 172.312902 -93.510728) (xy 172.330618 -93.536516) (xy 172.338141 -93.546666) (xy 172.360415 -93.558525)
			(xy 172.373036 -93.559122) (xy 172.457364 -93.559122) (xy 172.46997 -93.558482) (xy 172.492219 -93.546623)
			(xy 172.499782 -93.536516) (xy 172.517498 -93.510728) (xy 172.558264 -93.463265) (xy 172.604546 -93.421164)
			(xy 172.655645 -93.38506) (xy 172.710787 -93.355499) (xy 172.769141 -93.332928) (xy 172.829823 -93.317689)
			(xy 172.891917 -93.310011) (xy 172.954483 -93.310011) (xy 173.016577 -93.317689) (xy 173.077259 -93.332928)
			(xy 173.135613 -93.355499) (xy 173.190755 -93.38506) (xy 173.241854 -93.421164) (xy 173.288136 -93.463265)
			(xy 173.328902 -93.510728) (xy 173.346618 -93.536516) (xy 173.354141 -93.546666) (xy 173.376415 -93.558525)
			(xy 173.389036 -93.559122) (xy 173.473364 -93.559122) (xy 173.48597 -93.558482) (xy 173.508219 -93.546623)
			(xy 173.515782 -93.536516) (xy 173.533473 -93.510706) (xy 173.574234 -93.463228) (xy 173.620515 -93.421113)
			(xy 173.671615 -93.384996) (xy 173.726762 -93.355424) (xy 173.785121 -93.332845) (xy 173.845811 -93.3176)
			(xy 173.907912 -93.30992) (xy 173.9392 -93.30944) (xy 173.971164 -93.309846) (xy 174.034588 -93.317858)
			(xy 174.096508 -93.333756) (xy 174.155947 -93.35729) (xy 174.211967 -93.388087) (xy 174.263686 -93.425663)
			(xy 174.310288 -93.469425) (xy 174.351037 -93.518683) (xy 174.385292 -93.572659) (xy 174.412511 -93.630503)
			(xy 174.422316 -93.660679) (xy 176.375308 -93.660679) (xy 176.375308 -93.596757) (xy 176.383319 -93.533339)
			(xy 176.399216 -93.471425) (xy 176.422748 -93.411992) (xy 176.453542 -93.355977) (xy 176.491115 -93.304262)
			(xy 176.534872 -93.257665) (xy 176.584125 -93.21692) (xy 176.638096 -93.182669) (xy 176.695935 -93.155452)
			(xy 176.756728 -93.135699) (xy 176.819518 -93.123721) (xy 176.883314 -93.119708) (xy 176.94711 -93.123721)
			(xy 177.0099 -93.135699) (xy 177.070693 -93.155452) (xy 177.128532 -93.182669) (xy 177.182503 -93.21692)
			(xy 177.231756 -93.257665) (xy 177.275513 -93.304262) (xy 177.313086 -93.355977) (xy 177.34388 -93.411992)
			(xy 177.367412 -93.471425) (xy 177.383309 -93.533339) (xy 177.39132 -93.596757) (xy 177.391822 -93.628718)
			(xy 177.39132 -93.660679) (xy 177.383309 -93.724097) (xy 177.367412 -93.786011) (xy 177.34388 -93.845444)
			(xy 177.313086 -93.901459) (xy 177.275513 -93.953174) (xy 177.231756 -93.999771) (xy 177.182503 -94.040516)
			(xy 177.128532 -94.074767) (xy 177.070693 -94.101984) (xy 177.0099 -94.121737) (xy 176.94711 -94.133715)
			(xy 176.883314 -94.137729) (xy 176.819518 -94.133715) (xy 176.756728 -94.121737) (xy 176.695935 -94.101984)
			(xy 176.638096 -94.074767) (xy 176.584125 -94.040516) (xy 176.534872 -93.999771) (xy 176.491115 -93.953174)
			(xy 176.453542 -93.901459) (xy 176.422748 -93.845444) (xy 176.399216 -93.786011) (xy 176.383319 -93.724097)
			(xy 176.375308 -93.660679) (xy 174.422316 -93.660679) (xy 174.432266 -93.691302) (xy 174.444245 -93.754098)
			(xy 174.448259 -93.8179) (xy 174.444245 -93.881702) (xy 174.432266 -93.944498) (xy 174.412511 -94.005297)
			(xy 174.385292 -94.063141) (xy 174.351037 -94.117117) (xy 174.310288 -94.166375) (xy 174.263686 -94.210137)
			(xy 174.211967 -94.247713) (xy 174.155947 -94.27851) (xy 174.096508 -94.302044) (xy 174.034588 -94.317942)
			(xy 173.971164 -94.325954) (xy 173.9392 -94.326456) (xy 173.907913 -94.325964) (xy 173.84581 -94.318292)
			(xy 173.78512 -94.303053) (xy 173.72676 -94.280476) (xy 173.671614 -94.250904) (xy 173.620517 -94.214784)
			(xy 173.574242 -94.172664) (xy 173.533489 -94.125179) (xy 173.515782 -94.09938) (xy 173.508239 -94.089247)
			(xy 173.485981 -94.077375) (xy 173.473364 -94.076774) (xy 173.389036 -94.076774) (xy 173.37643 -94.077416)
			(xy 173.354181 -94.089274) (xy 173.346618 -94.09938) (xy 173.328902 -94.125168) (xy 173.288136 -94.172631)
			(xy 173.241854 -94.214732) (xy 173.190755 -94.250836) (xy 173.135613 -94.280397) (xy 173.077259 -94.302968)
			(xy 173.016577 -94.318207) (xy 172.954483 -94.325885) (xy 172.891917 -94.325885) (xy 172.829823 -94.318207)
			(xy 172.769141 -94.302968) (xy 172.710787 -94.280397) (xy 172.655645 -94.250836) (xy 172.604546 -94.214732)
			(xy 172.558264 -94.172631) (xy 172.517498 -94.125168) (xy 172.499782 -94.09938) (xy 172.492239 -94.089247)
			(xy 172.469981 -94.077375) (xy 172.457364 -94.076774) (xy 172.373036 -94.076774) (xy 172.36043 -94.077416)
			(xy 172.338181 -94.089274) (xy 172.330618 -94.09938) (xy 172.312902 -94.125168) (xy 172.272136 -94.172631)
			(xy 172.225854 -94.214732) (xy 172.174755 -94.250836) (xy 172.119613 -94.280397) (xy 172.061259 -94.302968)
			(xy 172.000577 -94.318207) (xy 171.938483 -94.325885) (xy 171.875917 -94.325885) (xy 171.813823 -94.318207)
			(xy 171.753141 -94.302968) (xy 171.694787 -94.280397) (xy 171.639645 -94.250836) (xy 171.588546 -94.214732)
			(xy 171.542264 -94.172631) (xy 171.501498 -94.125168) (xy 171.483782 -94.09938) (xy 171.476239 -94.089247)
			(xy 171.453981 -94.077375) (xy 171.441364 -94.076774) (xy 171.357036 -94.076774) (xy 171.34443 -94.077416)
			(xy 171.322181 -94.089274) (xy 171.314618 -94.09938) (xy 171.296926 -94.125189) (xy 171.256165 -94.172667)
			(xy 171.209884 -94.214783) (xy 171.158785 -94.2509) (xy 171.103638 -94.280471) (xy 171.045279 -94.30305)
			(xy 170.984589 -94.318296) (xy 170.922487 -94.325976) (xy 170.8912 -94.326456) (xy 170.859242 -94.325858)
			(xy 170.79583 -94.317847) (xy 170.733922 -94.301952) (xy 170.674494 -94.278423) (xy 170.618484 -94.247631)
			(xy 170.566775 -94.210062) (xy 170.520182 -94.166309) (xy 170.479441 -94.117061) (xy 170.445193 -94.063095)
			(xy 170.417979 -94.005262) (xy 170.398227 -93.944474) (xy 170.386251 -93.88169) (xy 170.382238 -93.8179)
			(xy 163.908692 -93.8179) (xy 164.586158 -94.495366) (xy 164.626036 -94.49689) (xy 164.641022 -94.483682)
			(xy 164.664147 -94.46437) (xy 164.714138 -94.430739) (xy 164.767749 -94.403246) (xy 164.824232 -94.382274)
			(xy 164.882796 -94.368118) (xy 164.942621 -94.360975) (xy 164.972746 -94.360492) (xy 164.973 -94.360492)
			(xy 165.003731 -94.360956) (xy 165.064745 -94.368365) (xy 165.124421 -94.383073) (xy 165.181889 -94.404868)
			(xy 165.236311 -94.433431) (xy 165.286893 -94.468345) (xy 165.332898 -94.509102) (xy 165.373655 -94.555107)
			(xy 165.408569 -94.605689) (xy 165.437132 -94.660111) (xy 165.458927 -94.717579) (xy 165.473635 -94.777255)
			(xy 165.481044 -94.838269) (xy 165.481508 -94.869) (xy 165.481508 -94.869254) (xy 165.481087 -94.899384)
			(xy 165.473974 -94.959224) (xy 165.45983 -95.017801) (xy 165.438854 -95.074293) (xy 165.411341 -95.127906)
			(xy 165.377677 -95.177886) (xy 165.358318 -95.200978) (xy 165.34511 -95.215964) (xy 165.346634 -95.255842)
			(xy 165.401752 -95.31096) (xy 167.953942 -95.31096) (xy 167.958013 -95.255338) (xy 167.970139 -95.200901)
			(xy 167.990062 -95.14881) (xy 168.017358 -95.100175) (xy 168.051444 -95.056032) (xy 168.091593 -95.017323)
			(xy 168.136951 -94.984872) (xy 168.186551 -94.959371) (xy 168.239335 -94.941364) (xy 168.294178 -94.931234)
			(xy 168.349912 -94.929197) (xy 168.405349 -94.935297) (xy 168.459306 -94.949403) (xy 168.510635 -94.971215)
			(xy 168.558241 -95.000269) (xy 168.601109 -95.035944) (xy 168.638326 -95.077481) (xy 168.669099 -95.123994)
			(xy 168.692771 -95.174491) (xy 168.708839 -95.227898) (xy 168.716959 -95.283074) (xy 168.717468 -95.31096)
			(xy 168.716959 -95.338846) (xy 168.708839 -95.394022) (xy 168.692771 -95.447429) (xy 168.669099 -95.497926)
			(xy 168.638326 -95.544439) (xy 168.601109 -95.585976) (xy 168.558241 -95.621651) (xy 168.510635 -95.650705)
			(xy 168.459306 -95.672517) (xy 168.405349 -95.686623) (xy 168.349912 -95.692723) (xy 168.294178 -95.690686)
			(xy 168.239335 -95.680556) (xy 168.186551 -95.662549) (xy 168.136951 -95.637048) (xy 168.091593 -95.604597)
			(xy 168.051444 -95.565888) (xy 168.017358 -95.521745) (xy 167.990062 -95.47311) (xy 167.970139 -95.421019)
			(xy 167.958013 -95.366582) (xy 167.953942 -95.31096) (xy 165.401752 -95.31096) (xy 166.160153 -96.069361)
			(xy 171.195994 -96.069361) (xy 171.195994 -96.005439) (xy 171.204005 -95.942021) (xy 171.219902 -95.880107)
			(xy 171.243434 -95.820674) (xy 171.274228 -95.764659) (xy 171.311801 -95.712944) (xy 171.355558 -95.666347)
			(xy 171.404811 -95.625602) (xy 171.458782 -95.591351) (xy 171.516621 -95.564134) (xy 171.577414 -95.544381)
			(xy 171.640204 -95.532403) (xy 171.704 -95.52839) (xy 171.767796 -95.532403) (xy 171.830586 -95.544381)
			(xy 171.891379 -95.564134) (xy 171.949218 -95.591351) (xy 172.003189 -95.625602) (xy 172.052442 -95.666347)
			(xy 172.096199 -95.712944) (xy 172.133772 -95.764659) (xy 172.164566 -95.820674) (xy 172.188098 -95.880107)
			(xy 172.203995 -95.942021) (xy 172.211097 -95.998241) (xy 173.532794 -95.998241) (xy 173.532794 -95.934319)
			(xy 173.540805 -95.870901) (xy 173.556702 -95.808987) (xy 173.580234 -95.749554) (xy 173.611028 -95.693539)
			(xy 173.648601 -95.641824) (xy 173.692358 -95.595227) (xy 173.741611 -95.554482) (xy 173.795582 -95.520231)
			(xy 173.853421 -95.493014) (xy 173.914214 -95.473261) (xy 173.977004 -95.461283) (xy 174.0408 -95.45727)
			(xy 174.104596 -95.461283) (xy 174.167386 -95.473261) (xy 174.228179 -95.493014) (xy 174.286018 -95.520231)
			(xy 174.339989 -95.554482) (xy 174.389242 -95.595227) (xy 174.432999 -95.641824) (xy 174.470572 -95.693539)
			(xy 174.501366 -95.749554) (xy 174.524898 -95.808987) (xy 174.540795 -95.870901) (xy 174.548806 -95.934319)
			(xy 174.549308 -95.96628) (xy 174.548806 -95.998241) (xy 174.540795 -96.061659) (xy 174.524898 -96.123573)
			(xy 174.501366 -96.183006) (xy 174.470572 -96.239021) (xy 174.432999 -96.290736) (xy 174.389242 -96.337333)
			(xy 174.339989 -96.378078) (xy 174.286018 -96.412329) (xy 174.228179 -96.439546) (xy 174.167386 -96.459299)
			(xy 174.104596 -96.471277) (xy 174.0408 -96.475291) (xy 173.977004 -96.471277) (xy 173.914214 -96.459299)
			(xy 173.853421 -96.439546) (xy 173.795582 -96.412329) (xy 173.741611 -96.378078) (xy 173.692358 -96.337333)
			(xy 173.648601 -96.290736) (xy 173.611028 -96.239021) (xy 173.580234 -96.183006) (xy 173.556702 -96.123573)
			(xy 173.540805 -96.061659) (xy 173.532794 -95.998241) (xy 172.211097 -95.998241) (xy 172.212006 -96.005439)
			(xy 172.212508 -96.0374) (xy 172.212006 -96.069361) (xy 172.203995 -96.132779) (xy 172.188098 -96.194693)
			(xy 172.164566 -96.254126) (xy 172.133772 -96.310141) (xy 172.096199 -96.361856) (xy 172.052442 -96.408453)
			(xy 172.003189 -96.449198) (xy 171.949218 -96.483449) (xy 171.891379 -96.510666) (xy 171.830586 -96.530419)
			(xy 171.767796 -96.542397) (xy 171.704 -96.546411) (xy 171.640204 -96.542397) (xy 171.577414 -96.530419)
			(xy 171.516621 -96.510666) (xy 171.458782 -96.483449) (xy 171.404811 -96.449198) (xy 171.355558 -96.408453)
			(xy 171.311801 -96.361856) (xy 171.274228 -96.310141) (xy 171.243434 -96.254126) (xy 171.219902 -96.194693)
			(xy 171.204005 -96.132779) (xy 171.195994 -96.069361) (xy 166.160153 -96.069361) (xy 166.684706 -96.593914)
			(xy 166.694099 -96.602318) (xy 166.71822 -96.609521) (xy 166.73068 -96.60763) (xy 166.813992 -96.590358)
			(xy 166.820032 -96.58892) (xy 166.831215 -96.583534) (xy 166.83609 -96.57969) (xy 166.84117 -96.575626)
			(xy 166.848282 -96.56572) (xy 166.850822 -96.55937) (xy 166.862351 -96.531186) (xy 166.89119 -96.477552)
			(xy 166.92623 -96.427747) (xy 166.96697 -96.382486) (xy 167.012825 -96.342416) (xy 167.063138 -96.308111)
			(xy 167.11719 -96.280062) (xy 167.174205 -96.258672) (xy 167.233368 -96.244247) (xy 167.29383 -96.236993)
			(xy 167.324278 -96.236536) (xy 167.353609 -96.236983) (xy 167.411875 -96.243792) (xy 167.468972 -96.257254)
			(xy 167.524143 -96.277189) (xy 167.550592 -96.289876) (xy 167.558466 -96.292924) (xy 167.589324 -96.302859)
			(xy 167.648431 -96.329485) (xy 167.703673 -96.363409) (xy 167.754154 -96.404081) (xy 167.799055 -96.450841)
			(xy 167.837646 -96.502929) (xy 167.869302 -96.559502) (xy 167.893509 -96.61964) (xy 167.909873 -96.682368)
			(xy 167.91813 -96.746667) (xy 167.918638 -96.77908) (xy 167.918135 -96.810995) (xy 167.910138 -96.874324)
			(xy 167.89428 -96.936154) (xy 167.870811 -96.995513) (xy 167.840098 -97.05147) (xy 167.802626 -97.103144)
			(xy 167.758982 -97.149724) (xy 167.756348 -97.151909) (xy 170.383194 -97.151909) (xy 170.383194 -97.087987)
			(xy 170.391205 -97.024569) (xy 170.407102 -96.962655) (xy 170.430634 -96.903222) (xy 170.461428 -96.847207)
			(xy 170.499001 -96.795492) (xy 170.542758 -96.748895) (xy 170.592011 -96.70815) (xy 170.645982 -96.673899)
			(xy 170.703821 -96.646682) (xy 170.764614 -96.626929) (xy 170.827404 -96.614951) (xy 170.8912 -96.610938)
			(xy 170.954996 -96.614951) (xy 170.997614 -96.623081) (xy 172.415194 -96.623081) (xy 172.415194 -96.559159)
			(xy 172.423205 -96.495741) (xy 172.439102 -96.433827) (xy 172.462634 -96.374394) (xy 172.493428 -96.318379)
			(xy 172.531001 -96.266664) (xy 172.574758 -96.220067) (xy 172.624011 -96.179322) (xy 172.677982 -96.145071)
			(xy 172.735821 -96.117854) (xy 172.796614 -96.098101) (xy 172.859404 -96.086123) (xy 172.9232 -96.08211)
			(xy 172.986996 -96.086123) (xy 173.049786 -96.098101) (xy 173.110579 -96.117854) (xy 173.168418 -96.145071)
			(xy 173.222389 -96.179322) (xy 173.271642 -96.220067) (xy 173.315399 -96.266664) (xy 173.352972 -96.318379)
			(xy 173.383766 -96.374394) (xy 173.407298 -96.433827) (xy 173.423195 -96.495741) (xy 173.431206 -96.559159)
			(xy 173.431708 -96.59112) (xy 173.431206 -96.623081) (xy 173.423195 -96.686499) (xy 173.407298 -96.748413)
			(xy 173.383766 -96.807846) (xy 173.352972 -96.863861) (xy 173.315399 -96.915576) (xy 173.271642 -96.962173)
			(xy 173.222389 -97.002918) (xy 173.168418 -97.037169) (xy 173.110579 -97.064386) (xy 173.049786 -97.084139)
			(xy 172.986996 -97.096117) (xy 172.9232 -97.100131) (xy 172.859404 -97.096117) (xy 172.796614 -97.084139)
			(xy 172.735821 -97.064386) (xy 172.677982 -97.037169) (xy 172.624011 -97.002918) (xy 172.574758 -96.962173)
			(xy 172.531001 -96.915576) (xy 172.493428 -96.863861) (xy 172.462634 -96.807846) (xy 172.439102 -96.748413)
			(xy 172.423205 -96.686499) (xy 172.415194 -96.623081) (xy 170.997614 -96.623081) (xy 171.017786 -96.626929)
			(xy 171.078579 -96.646682) (xy 171.136418 -96.673899) (xy 171.190389 -96.70815) (xy 171.239642 -96.748895)
			(xy 171.283399 -96.795492) (xy 171.320972 -96.847207) (xy 171.351766 -96.903222) (xy 171.375298 -96.962655)
			(xy 171.391195 -97.024569) (xy 171.399206 -97.087987) (xy 171.399708 -97.119948) (xy 171.39931 -97.1453)
			(xy 175.132038 -97.1453) (xy 175.136051 -97.08151) (xy 175.148027 -97.018726) (xy 175.167779 -96.957938)
			(xy 175.194993 -96.900105) (xy 175.229241 -96.846139) (xy 175.269982 -96.796891) (xy 175.316575 -96.753138)
			(xy 175.368284 -96.715569) (xy 175.424294 -96.684777) (xy 175.483722 -96.661248) (xy 175.54563 -96.645353)
			(xy 175.609042 -96.637342) (xy 175.641 -96.63684) (xy 175.6715 -96.637236) (xy 175.732062 -96.644538)
			(xy 175.791315 -96.659038) (xy 175.848406 -96.680525) (xy 175.902514 -96.708692) (xy 175.952862 -96.743134)
			(xy 175.998724 -96.783355) (xy 176.039443 -96.828776) (xy 176.057306 -96.853502) (xy 176.057306 -96.853756)
			(xy 176.065122 -96.863627) (xy 176.087644 -96.874816) (xy 176.100232 -96.875092) (xy 176.197514 -96.872552)
			(xy 176.219612 -96.860106) (xy 176.22647 -96.849184) (xy 176.24399 -96.82229) (xy 176.284739 -96.772696)
			(xy 176.331403 -96.728623) (xy 176.383241 -96.690771) (xy 176.439429 -96.659741) (xy 176.499074 -96.636026)
			(xy 176.561229 -96.620004) (xy 176.624907 -96.611929) (xy 176.657 -96.61144) (xy 176.688964 -96.611846)
			(xy 176.752388 -96.619858) (xy 176.814308 -96.635756) (xy 176.873747 -96.65929) (xy 176.929767 -96.690087)
			(xy 176.981486 -96.727663) (xy 177.028088 -96.771425) (xy 177.068837 -96.820683) (xy 177.103092 -96.874659)
			(xy 177.130311 -96.932503) (xy 177.150066 -96.993302) (xy 177.162045 -97.056098) (xy 177.166059 -97.1199)
			(xy 177.162045 -97.183702) (xy 177.150066 -97.246498) (xy 177.130311 -97.307297) (xy 177.103092 -97.365141)
			(xy 177.068837 -97.419117) (xy 177.028088 -97.468375) (xy 176.981486 -97.512137) (xy 176.929767 -97.549713)
			(xy 176.873747 -97.58051) (xy 176.814308 -97.604044) (xy 176.752388 -97.619942) (xy 176.688964 -97.627954)
			(xy 176.657 -97.628456) (xy 176.6265 -97.628061) (xy 176.565937 -97.620759) (xy 176.506685 -97.60626)
			(xy 176.449594 -97.584772) (xy 176.395485 -97.556605) (xy 176.345138 -97.522163) (xy 176.299275 -97.481942)
			(xy 176.258557 -97.43652) (xy 176.240694 -97.411794) (xy 176.240694 -97.41154) (xy 176.232879 -97.401668)
			(xy 176.210356 -97.39048) (xy 176.197768 -97.390204) (xy 176.100486 -97.392744) (xy 176.078388 -97.40519)
			(xy 176.07153 -97.416112) (xy 176.054008 -97.443005) (xy 176.01326 -97.492599) (xy 175.966597 -97.536672)
			(xy 175.914759 -97.574525) (xy 175.858571 -97.605555) (xy 175.798925 -97.62927) (xy 175.73677 -97.645292)
			(xy 175.673093 -97.653367) (xy 175.641 -97.653856) (xy 175.609042 -97.653258) (xy 175.54563 -97.645247)
			(xy 175.483722 -97.629352) (xy 175.424294 -97.605823) (xy 175.368284 -97.575031) (xy 175.316575 -97.537462)
			(xy 175.269982 -97.493709) (xy 175.229241 -97.444461) (xy 175.194993 -97.390495) (xy 175.167779 -97.332662)
			(xy 175.148027 -97.271874) (xy 175.136051 -97.20909) (xy 175.132038 -97.1453) (xy 171.39931 -97.1453)
			(xy 171.399206 -97.151909) (xy 171.391195 -97.215327) (xy 171.375298 -97.277241) (xy 171.351766 -97.336674)
			(xy 171.320972 -97.392689) (xy 171.283399 -97.444404) (xy 171.239642 -97.491001) (xy 171.190389 -97.531746)
			(xy 171.136418 -97.565997) (xy 171.078579 -97.593214) (xy 171.017786 -97.612967) (xy 170.954996 -97.624945)
			(xy 170.8912 -97.628959) (xy 170.827404 -97.624945) (xy 170.764614 -97.612967) (xy 170.703821 -97.593214)
			(xy 170.645982 -97.565997) (xy 170.592011 -97.531746) (xy 170.542758 -97.491001) (xy 170.499001 -97.444404)
			(xy 170.461428 -97.392689) (xy 170.430634 -97.336674) (xy 170.407102 -97.277241) (xy 170.391205 -97.215327)
			(xy 170.383194 -97.151909) (xy 167.756348 -97.151909) (xy 167.709853 -97.190476) (xy 167.656011 -97.224761)
			(xy 167.598303 -97.25204) (xy 167.537634 -97.271883) (xy 167.506396 -97.278444) (xy 167.49141 -97.281238)
			(xy 167.469312 -97.302828) (xy 167.461946 -97.338896) (xy 167.460064 -97.35136) (xy 167.467244 -97.37549)
			(xy 167.475662 -97.38487) (xy 167.950853 -97.860061) (xy 168.932854 -97.860061) (xy 168.932854 -97.796139)
			(xy 168.940865 -97.732721) (xy 168.956762 -97.670807) (xy 168.980294 -97.611374) (xy 169.011088 -97.555359)
			(xy 169.048661 -97.503644) (xy 169.092418 -97.457047) (xy 169.141671 -97.416302) (xy 169.195642 -97.382051)
			(xy 169.253481 -97.354834) (xy 169.314274 -97.335081) (xy 169.377064 -97.323103) (xy 169.44086 -97.31909)
			(xy 169.504656 -97.323103) (xy 169.567446 -97.335081) (xy 169.628239 -97.354834) (xy 169.686078 -97.382051)
			(xy 169.740049 -97.416302) (xy 169.789302 -97.457047) (xy 169.833059 -97.503644) (xy 169.870632 -97.555359)
			(xy 169.901426 -97.611374) (xy 169.924958 -97.670807) (xy 169.940855 -97.732721) (xy 169.948866 -97.796139)
			(xy 169.949368 -97.8281) (xy 169.948866 -97.860061) (xy 169.940855 -97.923479) (xy 169.924958 -97.985393)
			(xy 169.901426 -98.044826) (xy 169.870632 -98.100841) (xy 169.833059 -98.152556) (xy 169.789302 -98.199153)
			(xy 169.740049 -98.239898) (xy 169.714935 -98.255836) (xy 175.27092 -98.255836) (xy 175.274991 -98.200214)
			(xy 175.287117 -98.145777) (xy 175.30704 -98.093686) (xy 175.334336 -98.045051) (xy 175.368422 -98.000908)
			(xy 175.408571 -97.962199) (xy 175.453929 -97.929748) (xy 175.503529 -97.904247) (xy 175.556313 -97.88624)
			(xy 175.611156 -97.87611) (xy 175.66689 -97.874073) (xy 175.722327 -97.880173) (xy 175.776284 -97.894279)
			(xy 175.827613 -97.916091) (xy 175.875219 -97.945145) (xy 175.918087 -97.98082) (xy 175.955304 -98.022357)
			(xy 175.986077 -98.06887) (xy 176.009749 -98.119367) (xy 176.025817 -98.172774) (xy 176.033937 -98.22795)
			(xy 176.034446 -98.255836) (xy 176.033937 -98.283722) (xy 176.025817 -98.338898) (xy 176.009749 -98.392305)
			(xy 175.986077 -98.442802) (xy 175.955304 -98.489315) (xy 175.918087 -98.530852) (xy 175.875219 -98.566527)
			(xy 175.827613 -98.595581) (xy 175.776284 -98.617393) (xy 175.722327 -98.631499) (xy 175.66689 -98.637599)
			(xy 175.611156 -98.635562) (xy 175.556313 -98.625432) (xy 175.503529 -98.607425) (xy 175.453929 -98.581924)
			(xy 175.408571 -98.549473) (xy 175.368422 -98.510764) (xy 175.334336 -98.466621) (xy 175.30704 -98.417986)
			(xy 175.287117 -98.365895) (xy 175.274991 -98.311458) (xy 175.27092 -98.255836) (xy 169.714935 -98.255836)
			(xy 169.686078 -98.274149) (xy 169.628239 -98.301366) (xy 169.567446 -98.321119) (xy 169.504656 -98.333097)
			(xy 169.44086 -98.337111) (xy 169.377064 -98.333097) (xy 169.314274 -98.321119) (xy 169.253481 -98.301366)
			(xy 169.195642 -98.274149) (xy 169.141671 -98.239898) (xy 169.092418 -98.199153) (xy 169.048661 -98.152556)
			(xy 169.011088 -98.100841) (xy 168.980294 -98.044826) (xy 168.956762 -97.985393) (xy 168.940865 -97.923479)
			(xy 168.932854 -97.860061) (xy 167.950853 -97.860061) (xy 168.058846 -97.968054) (xy 168.062656 -97.971864)
			(xy 168.133014 -98.042222) (xy 168.139866 -98.049618) (xy 168.147606 -98.068217) (xy 168.148 -98.07829)
			(xy 168.148 -99.2789) (xy 170.052038 -99.2789) (xy 170.056051 -99.21511) (xy 170.068027 -99.152326)
			(xy 170.087779 -99.091538) (xy 170.114993 -99.033705) (xy 170.149241 -98.979739) (xy 170.189982 -98.930491)
			(xy 170.236575 -98.886738) (xy 170.288284 -98.849169) (xy 170.344294 -98.818377) (xy 170.403722 -98.794848)
			(xy 170.46563 -98.778953) (xy 170.529042 -98.770942) (xy 170.561 -98.77044) (xy 170.592287 -98.770934)
			(xy 170.65439 -98.778606) (xy 170.71508 -98.793845) (xy 170.77344 -98.816421) (xy 170.828585 -98.845993)
			(xy 170.879683 -98.882112) (xy 170.925958 -98.924233) (xy 170.966711 -98.971717) (xy 170.984418 -98.997516)
			(xy 170.991941 -99.007666) (xy 171.014215 -99.019525) (xy 171.026836 -99.020122) (xy 171.111164 -99.020122)
			(xy 171.12377 -99.019482) (xy 171.146019 -99.007623) (xy 171.153582 -98.997516) (xy 171.171298 -98.971728)
			(xy 171.212064 -98.924265) (xy 171.258346 -98.882164) (xy 171.309445 -98.84606) (xy 171.364587 -98.816499)
			(xy 171.422941 -98.793928) (xy 171.483623 -98.778689) (xy 171.545717 -98.771011) (xy 171.608283 -98.771011)
			(xy 171.670377 -98.778689) (xy 171.731059 -98.793928) (xy 171.789413 -98.816499) (xy 171.844555 -98.84606)
			(xy 171.895654 -98.882164) (xy 171.941936 -98.924265) (xy 171.982702 -98.971728) (xy 172.000418 -98.997516)
			(xy 172.007941 -99.007666) (xy 172.030215 -99.019525) (xy 172.042836 -99.020122) (xy 172.127164 -99.020122)
			(xy 172.13977 -99.019482) (xy 172.162019 -99.007623) (xy 172.169582 -98.997516) (xy 172.187298 -98.971728)
			(xy 172.228064 -98.924265) (xy 172.274346 -98.882164) (xy 172.325445 -98.84606) (xy 172.380587 -98.816499)
			(xy 172.438941 -98.793928) (xy 172.499623 -98.778689) (xy 172.561717 -98.771011) (xy 172.624283 -98.771011)
			(xy 172.686377 -98.778689) (xy 172.747059 -98.793928) (xy 172.805413 -98.816499) (xy 172.860555 -98.84606)
			(xy 172.911654 -98.882164) (xy 172.957936 -98.924265) (xy 172.998702 -98.971728) (xy 173.016418 -98.997516)
			(xy 173.023941 -99.007666) (xy 173.046215 -99.019525) (xy 173.058836 -99.020122) (xy 173.143164 -99.020122)
			(xy 173.15577 -99.019482) (xy 173.178019 -99.007623) (xy 173.185582 -98.997516) (xy 173.203273 -98.971706)
			(xy 173.244034 -98.924228) (xy 173.290315 -98.882113) (xy 173.341415 -98.845996) (xy 173.396562 -98.816424)
			(xy 173.454921 -98.793845) (xy 173.515611 -98.7786) (xy 173.577712 -98.77092) (xy 173.609 -98.77044)
			(xy 173.643158 -98.771004) (xy 173.710859 -98.780146) (xy 173.776728 -98.798266) (xy 173.839579 -98.825038)
			(xy 173.898283 -98.85998) (xy 173.951782 -98.902463) (xy 173.999115 -98.951724) (xy 174.019718 -98.978974)
			(xy 174.027338 -98.989388) (xy 174.050198 -99.00031) (xy 174.160434 -98.995484) (xy 174.182278 -98.982276)
			(xy 174.188882 -98.971354) (xy 174.206187 -98.943517) (xy 174.246819 -98.892085) (xy 174.293723 -98.846301)
			(xy 174.346121 -98.806923) (xy 174.403145 -98.774605) (xy 174.463849 -98.749882) (xy 174.527227 -98.733164)
			(xy 174.592227 -98.724729) (xy 174.625 -98.724212) (xy 174.656962 -98.724674) (xy 174.720383 -98.732686)
			(xy 174.782299 -98.748583) (xy 174.841735 -98.772115) (xy 174.897752 -98.802911) (xy 174.949468 -98.840485)
			(xy 174.996067 -98.884245) (xy 175.036814 -98.933499) (xy 175.071067 -98.987473) (xy 175.098285 -99.045313)
			(xy 175.118038 -99.106109) (xy 175.130017 -99.168902) (xy 175.134031 -99.2327) (xy 175.130017 -99.296498)
			(xy 175.118038 -99.359291) (xy 175.098285 -99.420087) (xy 175.071067 -99.477927) (xy 175.036814 -99.531901)
			(xy 174.996067 -99.581155) (xy 174.949468 -99.624915) (xy 174.897752 -99.662489) (xy 174.841735 -99.693285)
			(xy 174.782299 -99.716817) (xy 174.720383 -99.732714) (xy 174.656962 -99.740726) (xy 174.625 -99.741228)
			(xy 174.590843 -99.740637) (xy 174.523145 -99.731496) (xy 174.457278 -99.713378) (xy 174.394427 -99.686611)
			(xy 174.335724 -99.651674) (xy 174.282223 -99.609196) (xy 174.234887 -99.559941) (xy 174.214282 -99.532694)
			(xy 174.206662 -99.52228) (xy 174.183802 -99.511358) (xy 174.073566 -99.516184) (xy 174.051722 -99.529392)
			(xy 174.045118 -99.540314) (xy 174.027802 -99.568143) (xy 173.987172 -99.619577) (xy 173.940271 -99.665363)
			(xy 173.887874 -99.704742) (xy 173.830852 -99.737061) (xy 173.770149 -99.761785) (xy 173.706772 -99.778503)
			(xy 173.641772 -99.786939) (xy 173.609 -99.787456) (xy 173.577713 -99.786964) (xy 173.51561 -99.779292)
			(xy 173.45492 -99.764053) (xy 173.39656 -99.741476) (xy 173.341414 -99.711904) (xy 173.290317 -99.675784)
			(xy 173.244042 -99.633664) (xy 173.203289 -99.586179) (xy 173.185582 -99.56038) (xy 173.178039 -99.550247)
			(xy 173.155781 -99.538375) (xy 173.143164 -99.537774) (xy 173.058836 -99.537774) (xy 173.04623 -99.538416)
			(xy 173.023981 -99.550274) (xy 173.016418 -99.56038) (xy 172.998702 -99.586168) (xy 172.957936 -99.633631)
			(xy 172.911654 -99.675732) (xy 172.860555 -99.711836) (xy 172.805413 -99.741397) (xy 172.747059 -99.763968)
			(xy 172.686377 -99.779207) (xy 172.624283 -99.786885) (xy 172.561717 -99.786885) (xy 172.499623 -99.779207)
			(xy 172.438941 -99.763968) (xy 172.380587 -99.741397) (xy 172.325445 -99.711836) (xy 172.274346 -99.675732)
			(xy 172.228064 -99.633631) (xy 172.187298 -99.586168) (xy 172.169582 -99.56038) (xy 172.162039 -99.550247)
			(xy 172.139781 -99.538375) (xy 172.127164 -99.537774) (xy 172.042836 -99.537774) (xy 172.03023 -99.538416)
			(xy 172.007981 -99.550274) (xy 172.000418 -99.56038) (xy 171.982702 -99.586168) (xy 171.941936 -99.633631)
			(xy 171.895654 -99.675732) (xy 171.844555 -99.711836) (xy 171.789413 -99.741397) (xy 171.731059 -99.763968)
			(xy 171.670377 -99.779207) (xy 171.608283 -99.786885) (xy 171.545717 -99.786885) (xy 171.483623 -99.779207)
			(xy 171.422941 -99.763968) (xy 171.364587 -99.741397) (xy 171.309445 -99.711836) (xy 171.258346 -99.675732)
			(xy 171.212064 -99.633631) (xy 171.171298 -99.586168) (xy 171.153582 -99.56038) (xy 171.146039 -99.550247)
			(xy 171.123781 -99.538375) (xy 171.111164 -99.537774) (xy 171.026836 -99.537774) (xy 171.01423 -99.538416)
			(xy 170.991981 -99.550274) (xy 170.984418 -99.56038) (xy 170.966726 -99.586189) (xy 170.925965 -99.633667)
			(xy 170.879684 -99.675783) (xy 170.828585 -99.7119) (xy 170.773438 -99.741471) (xy 170.715079 -99.76405)
			(xy 170.654389 -99.779296) (xy 170.592287 -99.786976) (xy 170.561 -99.787456) (xy 170.529042 -99.786858)
			(xy 170.46563 -99.778847) (xy 170.403722 -99.762952) (xy 170.344294 -99.739423) (xy 170.288284 -99.708631)
			(xy 170.236575 -99.671062) (xy 170.189982 -99.627309) (xy 170.149241 -99.578061) (xy 170.114993 -99.524095)
			(xy 170.087779 -99.466262) (xy 170.068027 -99.405474) (xy 170.056051 -99.34269) (xy 170.052038 -99.2789)
			(xy 168.148 -99.2789) (xy 168.148 -101.102946) (xy 170.244322 -101.102946) (xy 170.244322 -101.048454)
			(xy 170.252077 -100.994516) (xy 170.267428 -100.94223) (xy 170.290064 -100.892661) (xy 170.319523 -100.846818)
			(xy 170.355206 -100.805633) (xy 170.396387 -100.769946) (xy 170.442228 -100.740482) (xy 170.491794 -100.717841)
			(xy 170.544078 -100.702485) (xy 170.598016 -100.694725) (xy 170.625262 -100.694236) (xy 170.652701 -100.694652)
			(xy 170.707016 -100.702497) (xy 170.759645 -100.718045) (xy 170.809503 -100.740976) (xy 170.85556 -100.770816)
			(xy 170.896865 -100.806948) (xy 170.932565 -100.848627) (xy 170.961923 -100.894992) (xy 170.984333 -100.945086)
			(xy 170.992292 -100.97135) (xy 170.996594 -100.984786) (xy 171.011489 -101.008735) (xy 171.032362 -101.027702)
			(xy 171.057624 -101.040241) (xy 171.085352 -101.045399) (xy 171.113433 -101.042782) (xy 171.139731 -101.03259)
			(xy 171.162241 -101.015598) (xy 171.171108 -101.004624) (xy 171.191759 -100.978132) (xy 171.238933 -100.930313)
			(xy 171.291992 -100.88912) (xy 171.350012 -100.855271) (xy 171.411983 -100.829355) (xy 171.476827 -100.811823)
			(xy 171.543414 -100.80298) (xy 171.577 -100.80244) (xy 171.608964 -100.802846) (xy 171.672388 -100.810858)
			(xy 171.734308 -100.826756) (xy 171.793747 -100.85029) (xy 171.849767 -100.881087) (xy 171.901486 -100.918663)
			(xy 171.948088 -100.962425) (xy 171.988837 -101.011683) (xy 172.023092 -101.065659) (xy 172.050311 -101.123503)
			(xy 172.070066 -101.184302) (xy 172.082045 -101.247098) (xy 172.086059 -101.3109) (xy 172.082045 -101.374702)
			(xy 172.070066 -101.437498) (xy 172.050311 -101.498297) (xy 172.023092 -101.556141) (xy 171.988837 -101.610117)
			(xy 171.948088 -101.659375) (xy 171.901486 -101.703137) (xy 171.849767 -101.740713) (xy 171.793747 -101.77151)
			(xy 171.734308 -101.795044) (xy 171.672388 -101.810942) (xy 171.608964 -101.818954) (xy 171.577 -101.819456)
			(xy 171.544412 -101.818995) (xy 171.479771 -101.810668) (xy 171.416724 -101.794149) (xy 171.356304 -101.769709)
			(xy 171.299502 -101.73775) (xy 171.247249 -101.698796) (xy 171.200402 -101.653483) (xy 171.159728 -101.602557)
			(xy 171.125895 -101.546851) (xy 171.099457 -101.487279) (xy 171.080848 -101.424816) (xy 171.075096 -101.392736)
			(xy 171.072304 -101.378918) (xy 171.060267 -101.35344) (xy 171.041728 -101.33222) (xy 171.018097 -101.316872)
			(xy 170.991171 -101.308563) (xy 170.963001 -101.307926) (xy 170.935728 -101.31501) (xy 170.911427 -101.329275)
			(xy 170.90136 -101.339142) (xy 170.883301 -101.357476) (xy 170.843081 -101.389581) (xy 170.798912 -101.415991)
			(xy 170.751596 -101.436228) (xy 170.70199 -101.449925) (xy 170.650993 -101.456833) (xy 170.625262 -101.457252)
			(xy 170.598016 -101.456675) (xy 170.544078 -101.448915) (xy 170.491794 -101.433559) (xy 170.442228 -101.410918)
			(xy 170.396387 -101.381454) (xy 170.355206 -101.345767) (xy 170.319523 -101.304582) (xy 170.290064 -101.258739)
			(xy 170.267428 -101.20917) (xy 170.252077 -101.156884) (xy 170.244322 -101.102946) (xy 168.148 -101.102946)
			(xy 168.148 -101.868943) (xy 172.196754 -101.868943) (xy 172.196754 -101.805021) (xy 172.204765 -101.741603)
			(xy 172.220662 -101.679689) (xy 172.244194 -101.620256) (xy 172.274988 -101.564241) (xy 172.312561 -101.512526)
			(xy 172.356318 -101.465929) (xy 172.405571 -101.425184) (xy 172.459542 -101.390933) (xy 172.517381 -101.363716)
			(xy 172.578174 -101.343963) (xy 172.640964 -101.331985) (xy 172.70476 -101.327972) (xy 172.768556 -101.331985)
			(xy 172.831346 -101.343963) (xy 172.892139 -101.363716) (xy 172.949978 -101.390933) (xy 173.003949 -101.425184)
			(xy 173.053202 -101.465929) (xy 173.096959 -101.512526) (xy 173.134532 -101.564241) (xy 173.165326 -101.620256)
			(xy 173.188858 -101.679689) (xy 173.204755 -101.741603) (xy 173.212766 -101.805021) (xy 173.213268 -101.836982)
			(xy 173.212766 -101.868943) (xy 173.204755 -101.932361) (xy 173.188858 -101.994275) (xy 173.165326 -102.053708)
			(xy 173.134532 -102.109723) (xy 173.096959 -102.161438) (xy 173.053204 -102.208033) (xy 173.42967 -102.208033)
			(xy 173.42967 -102.144111) (xy 173.437681 -102.080693) (xy 173.453578 -102.018779) (xy 173.47711 -101.959346)
			(xy 173.507904 -101.903331) (xy 173.545477 -101.851616) (xy 173.589234 -101.805019) (xy 173.638487 -101.764274)
			(xy 173.692458 -101.730023) (xy 173.750297 -101.702806) (xy 173.81109 -101.683053) (xy 173.87388 -101.671075)
			(xy 173.937676 -101.667062) (xy 174.001472 -101.671075) (xy 174.064262 -101.683053) (xy 174.125055 -101.702806)
			(xy 174.182894 -101.730023) (xy 174.236865 -101.764274) (xy 174.286118 -101.805019) (xy 174.329875 -101.851616)
			(xy 174.367448 -101.903331) (xy 174.398242 -101.959346) (xy 174.421774 -102.018779) (xy 174.437671 -102.080693)
			(xy 174.437939 -102.082811) (xy 174.778664 -102.082811) (xy 174.778664 -102.018889) (xy 174.786675 -101.955471)
			(xy 174.802572 -101.893557) (xy 174.826104 -101.834124) (xy 174.856898 -101.778109) (xy 174.894471 -101.726394)
			(xy 174.938228 -101.679797) (xy 174.987481 -101.639052) (xy 175.041452 -101.604801) (xy 175.099291 -101.577584)
			(xy 175.160084 -101.557831) (xy 175.222874 -101.545853) (xy 175.28667 -101.54184) (xy 175.350466 -101.545853)
			(xy 175.413256 -101.557831) (xy 175.474049 -101.577584) (xy 175.531888 -101.604801) (xy 175.585859 -101.639052)
			(xy 175.635112 -101.679797) (xy 175.678869 -101.726394) (xy 175.716442 -101.778109) (xy 175.747236 -101.834124)
			(xy 175.770768 -101.893557) (xy 175.786665 -101.955471) (xy 175.787189 -101.959621) (xy 178.180994 -101.959621)
			(xy 178.180994 -101.895699) (xy 178.189005 -101.832281) (xy 178.204902 -101.770367) (xy 178.228434 -101.710934)
			(xy 178.259228 -101.654919) (xy 178.296801 -101.603204) (xy 178.340558 -101.556607) (xy 178.389811 -101.515862)
			(xy 178.443782 -101.481611) (xy 178.501621 -101.454394) (xy 178.562414 -101.434641) (xy 178.625204 -101.422663)
			(xy 178.689 -101.41865) (xy 178.752796 -101.422663) (xy 178.815586 -101.434641) (xy 178.876379 -101.454394)
			(xy 178.934218 -101.481611) (xy 178.988189 -101.515862) (xy 179.037442 -101.556607) (xy 179.081199 -101.603204)
			(xy 179.118772 -101.654919) (xy 179.149566 -101.710934) (xy 179.173098 -101.770367) (xy 179.188995 -101.832281)
			(xy 179.197006 -101.895699) (xy 179.197508 -101.92766) (xy 179.197006 -101.959621) (xy 179.188995 -102.023039)
			(xy 179.173098 -102.084953) (xy 179.149566 -102.144386) (xy 179.118772 -102.200401) (xy 179.081199 -102.252116)
			(xy 179.037442 -102.298713) (xy 178.988189 -102.339458) (xy 178.934218 -102.373709) (xy 178.876379 -102.400926)
			(xy 178.815586 -102.420679) (xy 178.752796 -102.432657) (xy 178.689 -102.436671) (xy 178.625204 -102.432657)
			(xy 178.562414 -102.420679) (xy 178.501621 -102.400926) (xy 178.443782 -102.373709) (xy 178.389811 -102.339458)
			(xy 178.340558 -102.298713) (xy 178.296801 -102.252116) (xy 178.259228 -102.200401) (xy 178.228434 -102.144386)
			(xy 178.204902 -102.084953) (xy 178.189005 -102.023039) (xy 178.180994 -101.959621) (xy 175.787189 -101.959621)
			(xy 175.794676 -102.018889) (xy 175.795178 -102.05085) (xy 175.794676 -102.082811) (xy 175.786665 -102.146229)
			(xy 175.770768 -102.208143) (xy 175.747236 -102.267576) (xy 175.716442 -102.323591) (xy 175.678869 -102.375306)
			(xy 175.635112 -102.421903) (xy 175.585859 -102.462648) (xy 175.531888 -102.496899) (xy 175.474049 -102.524116)
			(xy 175.413256 -102.543869) (xy 175.350466 -102.555847) (xy 175.28667 -102.559861) (xy 175.222874 -102.555847)
			(xy 175.160084 -102.543869) (xy 175.099291 -102.524116) (xy 175.041452 -102.496899) (xy 174.987481 -102.462648)
			(xy 174.938228 -102.421903) (xy 174.894471 -102.375306) (xy 174.856898 -102.323591) (xy 174.826104 -102.267576)
			(xy 174.802572 -102.208143) (xy 174.786675 -102.146229) (xy 174.778664 -102.082811) (xy 174.437939 -102.082811)
			(xy 174.445682 -102.144111) (xy 174.446184 -102.176072) (xy 174.445682 -102.208033) (xy 174.437671 -102.271451)
			(xy 174.421774 -102.333365) (xy 174.398242 -102.392798) (xy 174.367448 -102.448813) (xy 174.329875 -102.500528)
			(xy 174.286118 -102.547125) (xy 174.236865 -102.58787) (xy 174.182894 -102.622121) (xy 174.125055 -102.649338)
			(xy 174.064262 -102.669091) (xy 174.001472 -102.681069) (xy 173.937676 -102.685083) (xy 173.87388 -102.681069)
			(xy 173.81109 -102.669091) (xy 173.750297 -102.649338) (xy 173.692458 -102.622121) (xy 173.638487 -102.58787)
			(xy 173.589234 -102.547125) (xy 173.545477 -102.500528) (xy 173.507904 -102.448813) (xy 173.47711 -102.392798)
			(xy 173.453578 -102.333365) (xy 173.437681 -102.271451) (xy 173.42967 -102.208033) (xy 173.053204 -102.208033)
			(xy 173.053202 -102.208035) (xy 173.003949 -102.24878) (xy 172.949978 -102.283031) (xy 172.892139 -102.310248)
			(xy 172.831346 -102.330001) (xy 172.768556 -102.341979) (xy 172.70476 -102.345993) (xy 172.640964 -102.341979)
			(xy 172.578174 -102.330001) (xy 172.517381 -102.310248) (xy 172.459542 -102.283031) (xy 172.405571 -102.24878)
			(xy 172.356318 -102.208035) (xy 172.312561 -102.161438) (xy 172.274988 -102.109723) (xy 172.244194 -102.053708)
			(xy 172.220662 -101.994275) (xy 172.204765 -101.932361) (xy 172.196754 -101.868943) (xy 168.148 -101.868943)
			(xy 168.148 -103.029512) (xy 174.433228 -103.029512) (xy 174.437299 -102.97389) (xy 174.449425 -102.919453)
			(xy 174.469348 -102.867362) (xy 174.496644 -102.818727) (xy 174.53073 -102.774584) (xy 174.570879 -102.735875)
			(xy 174.616237 -102.703424) (xy 174.665837 -102.677923) (xy 174.718621 -102.659916) (xy 174.773464 -102.649786)
			(xy 174.829198 -102.647749) (xy 174.884635 -102.653849) (xy 174.938592 -102.667955) (xy 174.989921 -102.689767)
			(xy 175.037527 -102.718821) (xy 175.080395 -102.754496) (xy 175.117612 -102.796033) (xy 175.148385 -102.842546)
			(xy 175.16052 -102.868433) (xy 179.47233 -102.868433) (xy 179.47233 -102.804511) (xy 179.480341 -102.741093)
			(xy 179.496238 -102.679179) (xy 179.51977 -102.619746) (xy 179.550564 -102.563731) (xy 179.588137 -102.512016)
			(xy 179.631894 -102.465419) (xy 179.681147 -102.424674) (xy 179.735118 -102.390423) (xy 179.792957 -102.363206)
			(xy 179.85375 -102.343453) (xy 179.91654 -102.331475) (xy 179.980336 -102.327462) (xy 180.044132 -102.331475)
			(xy 180.106922 -102.343453) (xy 180.167715 -102.363206) (xy 180.225554 -102.390423) (xy 180.279525 -102.424674)
			(xy 180.328778 -102.465419) (xy 180.372535 -102.512016) (xy 180.410108 -102.563731) (xy 180.440902 -102.619746)
			(xy 180.464434 -102.679179) (xy 180.480331 -102.741093) (xy 180.488342 -102.804511) (xy 180.488844 -102.836472)
			(xy 180.488342 -102.868433) (xy 180.480331 -102.931851) (xy 180.464434 -102.993765) (xy 180.440902 -103.053198)
			(xy 180.410108 -103.109213) (xy 180.372535 -103.160928) (xy 180.328778 -103.207525) (xy 180.279525 -103.24827)
			(xy 180.225554 -103.282521) (xy 180.167715 -103.309738) (xy 180.106922 -103.329491) (xy 180.044132 -103.341469)
			(xy 179.980336 -103.345483) (xy 179.91654 -103.341469) (xy 179.85375 -103.329491) (xy 179.792957 -103.309738)
			(xy 179.735118 -103.282521) (xy 179.681147 -103.24827) (xy 179.631894 -103.207525) (xy 179.588137 -103.160928)
			(xy 179.550564 -103.109213) (xy 179.51977 -103.053198) (xy 179.496238 -102.993765) (xy 179.480341 -102.931851)
			(xy 179.47233 -102.868433) (xy 175.16052 -102.868433) (xy 175.172057 -102.893043) (xy 175.188125 -102.94645)
			(xy 175.196245 -103.001626) (xy 175.196754 -103.029512) (xy 175.196245 -103.057398) (xy 175.188125 -103.112574)
			(xy 175.172057 -103.165981) (xy 175.148385 -103.216478) (xy 175.117612 -103.262991) (xy 175.080395 -103.304528)
			(xy 175.037527 -103.340203) (xy 174.989921 -103.369257) (xy 174.938592 -103.391069) (xy 174.884635 -103.405175)
			(xy 174.829198 -103.411275) (xy 174.773464 -103.409238) (xy 174.718621 -103.399108) (xy 174.665837 -103.381101)
			(xy 174.616237 -103.3556) (xy 174.570879 -103.323149) (xy 174.53073 -103.28444) (xy 174.496644 -103.240297)
			(xy 174.469348 -103.191662) (xy 174.449425 -103.139571) (xy 174.437299 -103.085134) (xy 174.433228 -103.029512)
			(xy 168.148 -103.029512) (xy 168.148 -103.593646) (xy 168.148275 -103.600968) (xy 168.152409 -103.615018)
			(xy 168.156128 -103.621332) (xy 168.160192 -103.627428) (xy 168.171114 -103.636826) (xy 168.177972 -103.639874)
			(xy 168.20736 -103.653647) (xy 168.262687 -103.687576) (xy 168.313247 -103.72827) (xy 168.358217 -103.775067)
			(xy 168.396866 -103.827207) (xy 168.428565 -103.883841) (xy 168.452799 -103.944049) (xy 168.458857 -103.96728)
			(xy 172.30293 -103.96728) (xy 172.307001 -103.911658) (xy 172.319127 -103.857221) (xy 172.33905 -103.80513)
			(xy 172.366346 -103.756495) (xy 172.400432 -103.712352) (xy 172.440581 -103.673643) (xy 172.485939 -103.641192)
			(xy 172.535539 -103.615691) (xy 172.588323 -103.597684) (xy 172.643166 -103.587554) (xy 172.6989 -103.585517)
			(xy 172.754337 -103.591617) (xy 172.808294 -103.605723) (xy 172.859623 -103.627535) (xy 172.907229 -103.656589)
			(xy 172.950097 -103.692264) (xy 172.987314 -103.733801) (xy 173.018087 -103.780314) (xy 173.041759 -103.830811)
			(xy 173.057827 -103.884218) (xy 173.065947 -103.939394) (xy 173.066456 -103.96728) (xy 173.065947 -103.995166)
			(xy 173.057827 -104.050342) (xy 173.041759 -104.103749) (xy 173.018087 -104.154246) (xy 172.987314 -104.200759)
			(xy 172.950097 -104.242296) (xy 172.907229 -104.277971) (xy 172.906131 -104.278641) (xy 174.56632 -104.278641)
			(xy 174.56632 -104.214719) (xy 174.574331 -104.151301) (xy 174.590228 -104.089387) (xy 174.61376 -104.029954)
			(xy 174.644554 -103.973939) (xy 174.682127 -103.922224) (xy 174.725884 -103.875627) (xy 174.775137 -103.834882)
			(xy 174.829108 -103.800631) (xy 174.886947 -103.773414) (xy 174.94774 -103.753661) (xy 175.01053 -103.741683)
			(xy 175.074326 -103.73767) (xy 175.138122 -103.741683) (xy 175.200912 -103.753661) (xy 175.261705 -103.773414)
			(xy 175.319544 -103.800631) (xy 175.373515 -103.834882) (xy 175.422768 -103.875627) (xy 175.466525 -103.922224)
			(xy 175.504098 -103.973939) (xy 175.534892 -104.029954) (xy 175.558424 -104.089387) (xy 175.574321 -104.151301)
			(xy 175.582332 -104.214719) (xy 175.582834 -104.24668) (xy 175.582332 -104.278641) (xy 175.574321 -104.342059)
			(xy 175.558424 -104.403973) (xy 175.534892 -104.463406) (xy 175.504098 -104.519421) (xy 175.466525 -104.571136)
			(xy 175.422768 -104.617733) (xy 175.373515 -104.658478) (xy 175.319544 -104.692729) (xy 175.261705 -104.719946)
			(xy 175.200912 -104.739699) (xy 175.138122 -104.751677) (xy 175.074326 -104.755691) (xy 175.01053 -104.751677)
			(xy 174.94774 -104.739699) (xy 174.886947 -104.719946) (xy 174.829108 -104.692729) (xy 174.775137 -104.658478)
			(xy 174.725884 -104.617733) (xy 174.682127 -104.571136) (xy 174.644554 -104.519421) (xy 174.61376 -104.463406)
			(xy 174.590228 -104.403973) (xy 174.574331 -104.342059) (xy 174.56632 -104.278641) (xy 172.906131 -104.278641)
			(xy 172.859623 -104.307025) (xy 172.808294 -104.328837) (xy 172.754337 -104.342943) (xy 172.6989 -104.349043)
			(xy 172.643166 -104.347006) (xy 172.588323 -104.336876) (xy 172.535539 -104.318869) (xy 172.485939 -104.293368)
			(xy 172.440581 -104.260917) (xy 172.400432 -104.222208) (xy 172.366346 -104.178065) (xy 172.33905 -104.12943)
			(xy 172.319127 -104.077339) (xy 172.307001 -104.022902) (xy 172.30293 -103.96728) (xy 168.458857 -103.96728)
			(xy 168.469175 -104.006851) (xy 168.477424 -104.071227) (xy 168.477946 -104.103678) (xy 168.477454 -104.135506)
			(xy 168.469512 -104.198664) (xy 168.45375 -104.260337) (xy 168.430415 -104.319561) (xy 168.39987 -104.375409)
			(xy 168.362594 -104.427009) (xy 168.31917 -104.473553) (xy 168.270276 -104.514314) (xy 168.243758 -104.531922)
			(xy 168.235884 -104.537002) (xy 168.217596 -104.56164) (xy 168.21277 -104.571292) (xy 168.205404 -104.595676)
			(xy 168.203243 -104.60471) (xy 168.2048 -104.623204) (xy 168.208452 -104.631744) (xy 168.220401 -104.657697)
			(xy 168.237257 -104.712289) (xy 168.245776 -104.768785) (xy 168.246298 -104.797352) (xy 168.245839 -104.823924)
			(xy 168.238458 -104.876553) (xy 168.223833 -104.927645) (xy 168.208832 -104.961393) (xy 175.84394 -104.961393)
			(xy 175.84394 -104.897471) (xy 175.851951 -104.834053) (xy 175.867848 -104.772139) (xy 175.89138 -104.712706)
			(xy 175.922174 -104.656691) (xy 175.959747 -104.604976) (xy 176.003504 -104.558379) (xy 176.052757 -104.517634)
			(xy 176.106728 -104.483383) (xy 176.164567 -104.456166) (xy 176.22536 -104.436413) (xy 176.28815 -104.424435)
			(xy 176.351946 -104.420422) (xy 176.415742 -104.424435) (xy 176.478532 -104.436413) (xy 176.539325 -104.456166)
			(xy 176.597164 -104.483383) (xy 176.651135 -104.517634) (xy 176.700388 -104.558379) (xy 176.744145 -104.604976)
			(xy 176.781718 -104.656691) (xy 176.812512 -104.712706) (xy 176.836044 -104.772139) (xy 176.851941 -104.834053)
			(xy 176.859952 -104.897471) (xy 176.860454 -104.929432) (xy 176.859952 -104.961393) (xy 176.851941 -105.024811)
			(xy 176.836044 -105.086725) (xy 176.812512 -105.146158) (xy 176.781718 -105.202173) (xy 176.744145 -105.253888)
			(xy 176.700388 -105.300485) (xy 176.651135 -105.34123) (xy 176.597164 -105.375481) (xy 176.539325 -105.402698)
			(xy 176.478532 -105.422451) (xy 176.415742 -105.434429) (xy 176.351946 -105.438443) (xy 176.28815 -105.434429)
			(xy 176.22536 -105.422451) (xy 176.164567 -105.402698) (xy 176.106728 -105.375481) (xy 176.052757 -105.34123)
			(xy 176.003504 -105.300485) (xy 175.959747 -105.253888) (xy 175.922174 -105.202173) (xy 175.89138 -105.146158)
			(xy 175.867848 -105.086725) (xy 175.851951 -105.024811) (xy 175.84394 -104.961393) (xy 168.208832 -104.961393)
			(xy 168.202247 -104.976208) (xy 168.174119 -105.021298) (xy 168.157398 -105.041954) (xy 168.153079 -105.048542)
			(xy 168.148311 -105.063546) (xy 168.148 -105.071418) (xy 168.148 -105.588562) (xy 168.148 -105.589578)
			(xy 168.148482 -105.597354) (xy 168.153532 -105.612086) (xy 168.157906 -105.618534) (xy 168.16475 -105.626992)
			(xy 168.1837 -105.637639) (xy 168.194482 -105.639108) (xy 168.225855 -105.642208) (xy 168.287547 -105.65519)
			(xy 168.347162 -105.675699) (xy 168.403783 -105.70342) (xy 168.456544 -105.737929) (xy 168.504633 -105.778696)
			(xy 168.547313 -105.825096) (xy 168.583929 -105.876416) (xy 168.61392 -105.931869) (xy 168.636825 -105.990605)
			(xy 168.652293 -106.051721) (xy 168.660087 -106.114281) (xy 168.660087 -106.177325) (xy 168.652292 -106.239885)
			(xy 168.636823 -106.301001) (xy 168.613917 -106.359737) (xy 168.603379 -106.379221) (xy 169.676566 -106.379221)
			(xy 169.676566 -106.315299) (xy 169.684577 -106.251881) (xy 169.700474 -106.189967) (xy 169.724006 -106.130534)
			(xy 169.7548 -106.074519) (xy 169.792373 -106.022804) (xy 169.83613 -105.976207) (xy 169.885383 -105.935462)
			(xy 169.939354 -105.901211) (xy 169.997193 -105.873994) (xy 170.057986 -105.854241) (xy 170.120776 -105.842263)
			(xy 170.184572 -105.83825) (xy 170.248368 -105.842263) (xy 170.311158 -105.854241) (xy 170.371951 -105.873994)
			(xy 170.42979 -105.901211) (xy 170.483761 -105.935462) (xy 170.533014 -105.976207) (xy 170.576771 -106.022804)
			(xy 170.614344 -106.074519) (xy 170.645138 -106.130534) (xy 170.66867 -106.189967) (xy 170.684567 -106.251881)
			(xy 170.685959 -106.2629) (xy 175.664425 -106.2629) (xy 175.668407 -106.209757) (xy 175.680266 -106.157801)
			(xy 175.699735 -106.108192) (xy 175.72638 -106.062039) (xy 175.759607 -106.020373) (xy 175.798672 -105.984124)
			(xy 175.842703 -105.954102) (xy 175.890717 -105.930978) (xy 175.941641 -105.915268) (xy 175.994338 -105.907323)
			(xy 176.020984 -105.906824) (xy 176.049104 -105.907335) (xy 176.104647 -105.916174) (xy 176.158109 -105.933632)
			(xy 176.208162 -105.959278) (xy 176.253562 -105.992473) (xy 176.29318 -106.032391) (xy 176.310036 -106.054906)
			(xy 176.318201 -106.065605) (xy 176.339095 -106.082561) (xy 176.363689 -106.093477) (xy 176.39028 -106.097597)
			(xy 176.417025 -106.094636) (xy 176.44207 -106.084798) (xy 176.463681 -106.068765) (xy 176.472342 -106.058462)
			(xy 176.488106 -106.039147) (xy 176.524458 -106.00503) (xy 176.56552 -105.976758) (xy 176.610363 -105.954972)
			(xy 176.657968 -105.940167) (xy 176.707257 -105.932678) (xy 176.732184 -105.932224) (xy 176.758177 -105.932642)
			(xy 176.809522 -105.940772) (xy 176.858963 -105.956834) (xy 176.905283 -105.980434) (xy 176.947341 -106.010989)
			(xy 176.984101 -106.047747) (xy 177.014658 -106.089803) (xy 177.038259 -106.136122) (xy 177.054324 -106.185562)
			(xy 177.062457 -106.236907) (xy 177.062457 -106.288893) (xy 177.054324 -106.340238) (xy 177.038259 -106.389678)
			(xy 177.014658 -106.435997) (xy 176.984101 -106.478053) (xy 176.947341 -106.514811) (xy 176.905283 -106.545366)
			(xy 176.858963 -106.568966) (xy 176.809522 -106.585028) (xy 176.758177 -106.593158) (xy 176.732184 -106.59364)
			(xy 176.707255 -106.593203) (xy 176.657962 -106.585723) (xy 176.610352 -106.570921) (xy 176.565508 -106.549132)
			(xy 176.524446 -106.520852) (xy 176.488101 -106.486723) (xy 176.472342 -106.467402) (xy 176.463657 -106.457117)
			(xy 176.442062 -106.441067) (xy 176.417024 -106.431216) (xy 176.390281 -106.42825) (xy 176.363693 -106.432376)
			(xy 176.339106 -106.443305) (xy 176.318229 -106.460279) (xy 176.310036 -106.470958) (xy 176.293184 -106.493475)
			(xy 176.253563 -106.533387) (xy 176.208161 -106.566577) (xy 176.158107 -106.592218) (xy 176.104645 -106.609674)
			(xy 176.049104 -106.618511) (xy 176.020984 -106.61904) (xy 175.994338 -106.618477) (xy 175.941641 -106.610532)
			(xy 175.890717 -106.594822) (xy 175.842703 -106.571698) (xy 175.798672 -106.541676) (xy 175.759607 -106.505427)
			(xy 175.72638 -106.463761) (xy 175.699735 -106.417608) (xy 175.680266 -106.367999) (xy 175.668407 -106.316043)
			(xy 175.664425 -106.2629) (xy 170.685959 -106.2629) (xy 170.692578 -106.315299) (xy 170.69308 -106.34726)
			(xy 170.692578 -106.379221) (xy 170.684567 -106.442639) (xy 170.66867 -106.504553) (xy 170.645138 -106.563986)
			(xy 170.614344 -106.620001) (xy 170.576771 -106.671716) (xy 170.533014 -106.718313) (xy 170.483761 -106.759058)
			(xy 170.42979 -106.793309) (xy 170.371951 -106.820526) (xy 170.311158 -106.840279) (xy 170.248368 -106.852257)
			(xy 170.184572 -106.856271) (xy 170.120776 -106.852257) (xy 170.057986 -106.840279) (xy 169.997193 -106.820526)
			(xy 169.939354 -106.793309) (xy 169.885383 -106.759058) (xy 169.83613 -106.718313) (xy 169.792373 -106.671716)
			(xy 169.7548 -106.620001) (xy 169.724006 -106.563986) (xy 169.700474 -106.504553) (xy 169.684577 -106.442639)
			(xy 169.676566 -106.379221) (xy 168.603379 -106.379221) (xy 168.583926 -106.415189) (xy 168.547309 -106.466509)
			(xy 168.504628 -106.512908) (xy 168.456539 -106.553674) (xy 168.403778 -106.588183) (xy 168.347156 -106.615904)
			(xy 168.287541 -106.636412) (xy 168.225848 -106.649393) (xy 168.194482 -106.652568) (xy 168.183683 -106.65399)
			(xy 168.164705 -106.664636) (xy 168.157906 -106.673142) (xy 168.1535 -106.679573) (xy 168.148457 -106.694316)
			(xy 168.148 -106.702098) (xy 168.148 -107.089019) (xy 178.001932 -107.089019) (xy 178.001932 -107.037045)
			(xy 178.010062 -106.98571) (xy 178.026123 -106.93628) (xy 178.049719 -106.88997) (xy 178.080269 -106.847922)
			(xy 178.11702 -106.811171) (xy 178.159068 -106.780621) (xy 178.205378 -106.757025) (xy 178.254808 -106.740964)
			(xy 178.306143 -106.732834) (xy 178.358117 -106.732834) (xy 178.409452 -106.740964) (xy 178.458882 -106.757025)
			(xy 178.505192 -106.780621) (xy 178.54724 -106.811171) (xy 178.583991 -106.847922) (xy 178.614541 -106.88997)
			(xy 178.638137 -106.93628) (xy 178.654198 -106.98571) (xy 178.662328 -107.037045) (xy 178.662838 -107.063032)
			(xy 178.662328 -107.089019) (xy 180.401978 -107.089019) (xy 180.401978 -107.037045) (xy 180.410108 -106.98571)
			(xy 180.426169 -106.93628) (xy 180.449765 -106.88997) (xy 180.480315 -106.847922) (xy 180.517066 -106.811171)
			(xy 180.559114 -106.780621) (xy 180.605424 -106.757025) (xy 180.654854 -106.740964) (xy 180.706189 -106.732834)
			(xy 180.758163 -106.732834) (xy 180.809498 -106.740964) (xy 180.858928 -106.757025) (xy 180.905238 -106.780621)
			(xy 180.947286 -106.811171) (xy 180.984037 -106.847922) (xy 181.014587 -106.88997) (xy 181.038183 -106.93628)
			(xy 181.054244 -106.98571) (xy 181.062374 -107.037045) (xy 181.062884 -107.063032) (xy 181.062374 -107.089019)
			(xy 181.054244 -107.140354) (xy 181.038183 -107.189784) (xy 181.014587 -107.236094) (xy 180.984037 -107.278142)
			(xy 180.947286 -107.314893) (xy 180.905238 -107.345443) (xy 180.858928 -107.369039) (xy 180.809498 -107.3851)
			(xy 180.758163 -107.39323) (xy 180.706189 -107.39323) (xy 180.654854 -107.3851) (xy 180.605424 -107.369039)
			(xy 180.559114 -107.345443) (xy 180.517066 -107.314893) (xy 180.480315 -107.278142) (xy 180.449765 -107.236094)
			(xy 180.426169 -107.189784) (xy 180.410108 -107.140354) (xy 180.401978 -107.089019) (xy 178.662328 -107.089019)
			(xy 178.654198 -107.140354) (xy 178.638137 -107.189784) (xy 178.614541 -107.236094) (xy 178.583991 -107.278142)
			(xy 178.54724 -107.314893) (xy 178.505192 -107.345443) (xy 178.458882 -107.369039) (xy 178.409452 -107.3851)
			(xy 178.358117 -107.39323) (xy 178.306143 -107.39323) (xy 178.254808 -107.3851) (xy 178.205378 -107.369039)
			(xy 178.159068 -107.345443) (xy 178.11702 -107.314893) (xy 178.080269 -107.278142) (xy 178.049719 -107.236094)
			(xy 178.026123 -107.189784) (xy 178.010062 -107.140354) (xy 178.001932 -107.089019) (xy 168.148 -107.089019)
			(xy 168.148 -107.592368) (xy 168.148254 -107.59821) (xy 168.149362 -107.605352) (xy 168.15503 -107.618639)
			(xy 168.15943 -107.624372) (xy 168.182036 -107.648756) (xy 168.184994 -107.651848) (xy 168.191766 -107.657076)
			(xy 168.195498 -107.65917) (xy 168.203118 -107.663234) (xy 168.207436 -107.663742) (xy 168.240245 -107.66816)
			(xy 168.304424 -107.6844) (xy 168.365955 -107.708825) (xy 168.395142 -107.724448) (xy 168.421404 -107.739548)
			(xy 168.470478 -107.775071) (xy 168.51498 -107.816177) (xy 168.554277 -107.862284) (xy 168.571418 -107.887262)
			(xy 168.576942 -107.894848) (xy 168.592186 -107.905768) (xy 168.601136 -107.908598) (xy 168.613074 -107.910122)
			(xy 168.698926 -107.910122) (xy 168.710864 -107.908598) (xy 168.719016 -107.906126) (xy 168.733161 -107.896653)
			(xy 168.73855 -107.890056) (xy 168.756232 -107.863986) (xy 168.797043 -107.815998) (xy 168.843462 -107.773412)
			(xy 168.894781 -107.736878) (xy 168.950215 -107.706955) (xy 169.008917 -107.6841) (xy 169.069991 -107.668663)
			(xy 169.132503 -107.660878) (xy 169.164 -107.66044) (xy 169.195531 -107.660914) (xy 169.25811 -107.668706)
			(xy 169.319246 -107.684172) (xy 169.378003 -107.707073) (xy 169.433479 -107.73706) (xy 169.484825 -107.773671)
			(xy 169.531253 -107.816347) (xy 169.572052 -107.864433) (xy 169.589704 -107.890564) (xy 169.589958 -107.891072)
			(xy 169.593484 -107.896092) (xy 169.602468 -107.904442) (xy 169.607738 -107.907582) (xy 169.607992 -107.907582)
			(xy 169.613562 -107.910382) (xy 169.625638 -107.913462) (xy 169.631868 -107.913678) (xy 169.716196 -107.91444)
			(xy 169.728388 -107.91317) (xy 169.737484 -107.910646) (xy 169.753016 -107.899943) (xy 169.758614 -107.892342)
			(xy 169.758868 -107.892088) (xy 169.758868 -107.891834) (xy 169.776655 -107.866423) (xy 169.817448 -107.819698)
			(xy 169.86362 -107.778279) (xy 169.914486 -107.742781) (xy 169.969291 -107.713733) (xy 170.027221 -107.691563)
			(xy 170.087418 -107.676603) (xy 170.148986 -107.669072) (xy 170.18 -107.668568) (xy 170.210732 -107.669032)
			(xy 170.271746 -107.67644) (xy 170.331424 -107.691149) (xy 170.388893 -107.712944) (xy 170.443316 -107.741506)
			(xy 170.4939 -107.77642) (xy 170.539906 -107.817177) (xy 170.580665 -107.863181) (xy 170.598395 -107.888865)
			(xy 178.802032 -107.888865) (xy 178.802032 -107.836891) (xy 178.810162 -107.785556) (xy 178.826223 -107.736126)
			(xy 178.849819 -107.689816) (xy 178.880369 -107.647768) (xy 178.91712 -107.611017) (xy 178.959168 -107.580467)
			(xy 179.005478 -107.556871) (xy 179.054908 -107.54081) (xy 179.106243 -107.53268) (xy 179.158217 -107.53268)
			(xy 179.209552 -107.54081) (xy 179.258982 -107.556871) (xy 179.305292 -107.580467) (xy 179.34734 -107.611017)
			(xy 179.384091 -107.647768) (xy 179.414641 -107.689816) (xy 179.438237 -107.736126) (xy 179.454298 -107.785556)
			(xy 179.462428 -107.836891) (xy 179.462938 -107.862878) (xy 179.462428 -107.888865) (xy 179.602132 -107.888865)
			(xy 179.602132 -107.836891) (xy 179.610262 -107.785556) (xy 179.626323 -107.736126) (xy 179.649919 -107.689816)
			(xy 179.680469 -107.647768) (xy 179.71722 -107.611017) (xy 179.759268 -107.580467) (xy 179.805578 -107.556871)
			(xy 179.855008 -107.54081) (xy 179.906343 -107.53268) (xy 179.958317 -107.53268) (xy 180.009652 -107.54081)
			(xy 180.059082 -107.556871) (xy 180.105392 -107.580467) (xy 180.14744 -107.611017) (xy 180.184191 -107.647768)
			(xy 180.214741 -107.689816) (xy 180.238337 -107.736126) (xy 180.254398 -107.785556) (xy 180.262528 -107.836891)
			(xy 180.263038 -107.862878) (xy 180.262528 -107.888865) (xy 181.202078 -107.888865) (xy 181.202078 -107.836891)
			(xy 181.210208 -107.785556) (xy 181.226269 -107.736126) (xy 181.249865 -107.689816) (xy 181.280415 -107.647768)
			(xy 181.317166 -107.611017) (xy 181.359214 -107.580467) (xy 181.405524 -107.556871) (xy 181.454954 -107.54081)
			(xy 181.506289 -107.53268) (xy 181.558263 -107.53268) (xy 181.609598 -107.54081) (xy 181.659028 -107.556871)
			(xy 181.705338 -107.580467) (xy 181.747386 -107.611017) (xy 181.784137 -107.647768) (xy 181.814687 -107.689816)
			(xy 181.838283 -107.736126) (xy 181.854344 -107.785556) (xy 181.862474 -107.836891) (xy 181.862984 -107.862878)
			(xy 181.862474 -107.888865) (xy 182.001924 -107.888865) (xy 182.001924 -107.836891) (xy 182.010054 -107.785556)
			(xy 182.026115 -107.736126) (xy 182.049711 -107.689816) (xy 182.080261 -107.647768) (xy 182.117012 -107.611017)
			(xy 182.15906 -107.580467) (xy 182.20537 -107.556871) (xy 182.2548 -107.54081) (xy 182.306135 -107.53268)
			(xy 182.358109 -107.53268) (xy 182.409444 -107.54081) (xy 182.458874 -107.556871) (xy 182.505184 -107.580467)
			(xy 182.547232 -107.611017) (xy 182.583983 -107.647768) (xy 182.614533 -107.689816) (xy 182.638129 -107.736126)
			(xy 182.65419 -107.785556) (xy 182.66232 -107.836891) (xy 182.66283 -107.862878) (xy 182.66232 -107.888865)
			(xy 182.802024 -107.888865) (xy 182.802024 -107.836891) (xy 182.810154 -107.785556) (xy 182.826215 -107.736126)
			(xy 182.849811 -107.689816) (xy 182.880361 -107.647768) (xy 182.917112 -107.611017) (xy 182.95916 -107.580467)
			(xy 183.00547 -107.556871) (xy 183.0549 -107.54081) (xy 183.106235 -107.53268) (xy 183.158209 -107.53268)
			(xy 183.209544 -107.54081) (xy 183.258974 -107.556871) (xy 183.305284 -107.580467) (xy 183.347332 -107.611017)
			(xy 183.384083 -107.647768) (xy 183.414633 -107.689816) (xy 183.438229 -107.736126) (xy 183.45429 -107.785556)
			(xy 183.46242 -107.836891) (xy 183.46293 -107.862878) (xy 183.46242 -107.888865) (xy 183.602124 -107.888865)
			(xy 183.602124 -107.836891) (xy 183.610254 -107.785556) (xy 183.626315 -107.736126) (xy 183.649911 -107.689816)
			(xy 183.680461 -107.647768) (xy 183.717212 -107.611017) (xy 183.75926 -107.580467) (xy 183.80557 -107.556871)
			(xy 183.855 -107.54081) (xy 183.906335 -107.53268) (xy 183.958309 -107.53268) (xy 184.009644 -107.54081)
			(xy 184.059074 -107.556871) (xy 184.105384 -107.580467) (xy 184.147432 -107.611017) (xy 184.184183 -107.647768)
			(xy 184.214733 -107.689816) (xy 184.238329 -107.736126) (xy 184.25439 -107.785556) (xy 184.26252 -107.836891)
			(xy 184.26303 -107.862878) (xy 184.26252 -107.888865) (xy 184.40197 -107.888865) (xy 184.40197 -107.836891)
			(xy 184.4101 -107.785556) (xy 184.426161 -107.736126) (xy 184.449757 -107.689816) (xy 184.480307 -107.647768)
			(xy 184.517058 -107.611017) (xy 184.559106 -107.580467) (xy 184.605416 -107.556871) (xy 184.654846 -107.54081)
			(xy 184.706181 -107.53268) (xy 184.758155 -107.53268) (xy 184.80949 -107.54081) (xy 184.85892 -107.556871)
			(xy 184.90523 -107.580467) (xy 184.947278 -107.611017) (xy 184.984029 -107.647768) (xy 185.014579 -107.689816)
			(xy 185.038175 -107.736126) (xy 185.054236 -107.785556) (xy 185.062366 -107.836891) (xy 185.062876 -107.862878)
			(xy 185.062366 -107.888865) (xy 185.98185 -107.888865) (xy 185.98185 -107.836891) (xy 185.98998 -107.785556)
			(xy 186.006041 -107.736126) (xy 186.029637 -107.689816) (xy 186.060187 -107.647768) (xy 186.096938 -107.611017)
			(xy 186.138986 -107.580467) (xy 186.185296 -107.556871) (xy 186.234726 -107.54081) (xy 186.286061 -107.53268)
			(xy 186.338035 -107.53268) (xy 186.38937 -107.54081) (xy 186.4388 -107.556871) (xy 186.48511 -107.580467)
			(xy 186.527158 -107.611017) (xy 186.563909 -107.647768) (xy 186.594459 -107.689816) (xy 186.618055 -107.736126)
			(xy 186.634116 -107.785556) (xy 186.642246 -107.836891) (xy 186.642756 -107.862878) (xy 186.642246 -107.888865)
			(xy 186.781696 -107.888865) (xy 186.781696 -107.836891) (xy 186.789826 -107.785556) (xy 186.805887 -107.736126)
			(xy 186.829483 -107.689816) (xy 186.860033 -107.647768) (xy 186.896784 -107.611017) (xy 186.938832 -107.580467)
			(xy 186.985142 -107.556871) (xy 187.034572 -107.54081) (xy 187.085907 -107.53268) (xy 187.137881 -107.53268)
			(xy 187.189216 -107.54081) (xy 187.238646 -107.556871) (xy 187.284956 -107.580467) (xy 187.327004 -107.611017)
			(xy 187.363755 -107.647768) (xy 187.394305 -107.689816) (xy 187.417901 -107.736126) (xy 187.433962 -107.785556)
			(xy 187.442092 -107.836891) (xy 187.442602 -107.862878) (xy 187.442092 -107.888865) (xy 187.581796 -107.888865)
			(xy 187.581796 -107.836891) (xy 187.589926 -107.785556) (xy 187.605987 -107.736126) (xy 187.629583 -107.689816)
			(xy 187.660133 -107.647768) (xy 187.696884 -107.611017) (xy 187.738932 -107.580467) (xy 187.785242 -107.556871)
			(xy 187.834672 -107.54081) (xy 187.886007 -107.53268) (xy 187.937981 -107.53268) (xy 187.989316 -107.54081)
			(xy 188.038746 -107.556871) (xy 188.085056 -107.580467) (xy 188.127104 -107.611017) (xy 188.163855 -107.647768)
			(xy 188.194405 -107.689816) (xy 188.218001 -107.736126) (xy 188.234062 -107.785556) (xy 188.242192 -107.836891)
			(xy 188.242702 -107.862878) (xy 188.242192 -107.888865) (xy 188.381896 -107.888865) (xy 188.381896 -107.836891)
			(xy 188.390026 -107.785556) (xy 188.406087 -107.736126) (xy 188.429683 -107.689816) (xy 188.460233 -107.647768)
			(xy 188.496984 -107.611017) (xy 188.539032 -107.580467) (xy 188.585342 -107.556871) (xy 188.634772 -107.54081)
			(xy 188.686107 -107.53268) (xy 188.738081 -107.53268) (xy 188.789416 -107.54081) (xy 188.838846 -107.556871)
			(xy 188.885156 -107.580467) (xy 188.927204 -107.611017) (xy 188.963955 -107.647768) (xy 188.994505 -107.689816)
			(xy 189.018101 -107.736126) (xy 189.034162 -107.785556) (xy 189.042292 -107.836891) (xy 189.042802 -107.862878)
			(xy 189.042292 -107.888865) (xy 189.181742 -107.888865) (xy 189.181742 -107.836891) (xy 189.189872 -107.785556)
			(xy 189.205933 -107.736126) (xy 189.229529 -107.689816) (xy 189.260079 -107.647768) (xy 189.29683 -107.611017)
			(xy 189.338878 -107.580467) (xy 189.385188 -107.556871) (xy 189.434618 -107.54081) (xy 189.485953 -107.53268)
			(xy 189.537927 -107.53268) (xy 189.589262 -107.54081) (xy 189.638692 -107.556871) (xy 189.685002 -107.580467)
			(xy 189.72705 -107.611017) (xy 189.763801 -107.647768) (xy 189.794351 -107.689816) (xy 189.817947 -107.736126)
			(xy 189.834008 -107.785556) (xy 189.842138 -107.836891) (xy 189.842648 -107.862878) (xy 189.842138 -107.888865)
			(xy 189.834008 -107.9402) (xy 189.817947 -107.98963) (xy 189.794351 -108.03594) (xy 189.763801 -108.077988)
			(xy 189.72705 -108.114739) (xy 189.685002 -108.145289) (xy 189.638692 -108.168885) (xy 189.589262 -108.184946)
			(xy 189.537927 -108.193076) (xy 189.485953 -108.193076) (xy 189.434618 -108.184946) (xy 189.385188 -108.168885)
			(xy 189.338878 -108.145289) (xy 189.29683 -108.114739) (xy 189.260079 -108.077988) (xy 189.229529 -108.03594)
			(xy 189.205933 -107.98963) (xy 189.189872 -107.9402) (xy 189.181742 -107.888865) (xy 189.042292 -107.888865)
			(xy 189.034162 -107.9402) (xy 189.018101 -107.98963) (xy 188.994505 -108.03594) (xy 188.963955 -108.077988)
			(xy 188.927204 -108.114739) (xy 188.885156 -108.145289) (xy 188.838846 -108.168885) (xy 188.789416 -108.184946)
			(xy 188.738081 -108.193076) (xy 188.686107 -108.193076) (xy 188.634772 -108.184946) (xy 188.585342 -108.168885)
			(xy 188.539032 -108.145289) (xy 188.496984 -108.114739) (xy 188.460233 -108.077988) (xy 188.429683 -108.03594)
			(xy 188.406087 -107.98963) (xy 188.390026 -107.9402) (xy 188.381896 -107.888865) (xy 188.242192 -107.888865)
			(xy 188.234062 -107.9402) (xy 188.218001 -107.98963) (xy 188.194405 -108.03594) (xy 188.163855 -108.077988)
			(xy 188.127104 -108.114739) (xy 188.085056 -108.145289) (xy 188.038746 -108.168885) (xy 187.989316 -108.184946)
			(xy 187.937981 -108.193076) (xy 187.886007 -108.193076) (xy 187.834672 -108.184946) (xy 187.785242 -108.168885)
			(xy 187.738932 -108.145289) (xy 187.696884 -108.114739) (xy 187.660133 -108.077988) (xy 187.629583 -108.03594)
			(xy 187.605987 -107.98963) (xy 187.589926 -107.9402) (xy 187.581796 -107.888865) (xy 187.442092 -107.888865)
			(xy 187.433962 -107.9402) (xy 187.417901 -107.98963) (xy 187.394305 -108.03594) (xy 187.363755 -108.077988)
			(xy 187.327004 -108.114739) (xy 187.284956 -108.145289) (xy 187.238646 -108.168885) (xy 187.189216 -108.184946)
			(xy 187.137881 -108.193076) (xy 187.085907 -108.193076) (xy 187.034572 -108.184946) (xy 186.985142 -108.168885)
			(xy 186.938832 -108.145289) (xy 186.896784 -108.114739) (xy 186.860033 -108.077988) (xy 186.829483 -108.03594)
			(xy 186.805887 -107.98963) (xy 186.789826 -107.9402) (xy 186.781696 -107.888865) (xy 186.642246 -107.888865)
			(xy 186.634116 -107.9402) (xy 186.618055 -107.98963) (xy 186.594459 -108.03594) (xy 186.563909 -108.077988)
			(xy 186.527158 -108.114739) (xy 186.48511 -108.145289) (xy 186.4388 -108.168885) (xy 186.38937 -108.184946)
			(xy 186.338035 -108.193076) (xy 186.286061 -108.193076) (xy 186.234726 -108.184946) (xy 186.185296 -108.168885)
			(xy 186.138986 -108.145289) (xy 186.096938 -108.114739) (xy 186.060187 -108.077988) (xy 186.029637 -108.03594)
			(xy 186.006041 -107.98963) (xy 185.98998 -107.9402) (xy 185.98185 -107.888865) (xy 185.062366 -107.888865)
			(xy 185.054236 -107.9402) (xy 185.038175 -107.98963) (xy 185.014579 -108.03594) (xy 184.984029 -108.077988)
			(xy 184.947278 -108.114739) (xy 184.90523 -108.145289) (xy 184.85892 -108.168885) (xy 184.80949 -108.184946)
			(xy 184.758155 -108.193076) (xy 184.706181 -108.193076) (xy 184.654846 -108.184946) (xy 184.605416 -108.168885)
			(xy 184.559106 -108.145289) (xy 184.517058 -108.114739) (xy 184.480307 -108.077988) (xy 184.449757 -108.03594)
			(xy 184.426161 -107.98963) (xy 184.4101 -107.9402) (xy 184.40197 -107.888865) (xy 184.26252 -107.888865)
			(xy 184.25439 -107.9402) (xy 184.238329 -107.98963) (xy 184.214733 -108.03594) (xy 184.184183 -108.077988)
			(xy 184.147432 -108.114739) (xy 184.105384 -108.145289) (xy 184.059074 -108.168885) (xy 184.009644 -108.184946)
			(xy 183.958309 -108.193076) (xy 183.906335 -108.193076) (xy 183.855 -108.184946) (xy 183.80557 -108.168885)
			(xy 183.75926 -108.145289) (xy 183.717212 -108.114739) (xy 183.680461 -108.077988) (xy 183.649911 -108.03594)
			(xy 183.626315 -107.98963) (xy 183.610254 -107.9402) (xy 183.602124 -107.888865) (xy 183.46242 -107.888865)
			(xy 183.45429 -107.9402) (xy 183.438229 -107.98963) (xy 183.414633 -108.03594) (xy 183.384083 -108.077988)
			(xy 183.347332 -108.114739) (xy 183.305284 -108.145289) (xy 183.258974 -108.168885) (xy 183.209544 -108.184946)
			(xy 183.158209 -108.193076) (xy 183.106235 -108.193076) (xy 183.0549 -108.184946) (xy 183.00547 -108.168885)
			(xy 182.95916 -108.145289) (xy 182.917112 -108.114739) (xy 182.880361 -108.077988) (xy 182.849811 -108.03594)
			(xy 182.826215 -107.98963) (xy 182.810154 -107.9402) (xy 182.802024 -107.888865) (xy 182.66232 -107.888865)
			(xy 182.65419 -107.9402) (xy 182.638129 -107.98963) (xy 182.614533 -108.03594) (xy 182.583983 -108.077988)
			(xy 182.547232 -108.114739) (xy 182.505184 -108.145289) (xy 182.458874 -108.168885) (xy 182.409444 -108.184946)
			(xy 182.358109 -108.193076) (xy 182.306135 -108.193076) (xy 182.2548 -108.184946) (xy 182.20537 -108.168885)
			(xy 182.15906 -108.145289) (xy 182.117012 -108.114739) (xy 182.080261 -108.077988) (xy 182.049711 -108.03594)
			(xy 182.026115 -107.98963) (xy 182.010054 -107.9402) (xy 182.001924 -107.888865) (xy 181.862474 -107.888865)
			(xy 181.854344 -107.9402) (xy 181.838283 -107.98963) (xy 181.814687 -108.03594) (xy 181.784137 -108.077988)
			(xy 181.747386 -108.114739) (xy 181.705338 -108.145289) (xy 181.659028 -108.168885) (xy 181.609598 -108.184946)
			(xy 181.558263 -108.193076) (xy 181.506289 -108.193076) (xy 181.454954 -108.184946) (xy 181.405524 -108.168885)
			(xy 181.359214 -108.145289) (xy 181.317166 -108.114739) (xy 181.280415 -108.077988) (xy 181.249865 -108.03594)
			(xy 181.226269 -107.98963) (xy 181.210208 -107.9402) (xy 181.202078 -107.888865) (xy 180.262528 -107.888865)
			(xy 180.254398 -107.9402) (xy 180.238337 -107.98963) (xy 180.214741 -108.03594) (xy 180.184191 -108.077988)
			(xy 180.14744 -108.114739) (xy 180.105392 -108.145289) (xy 180.059082 -108.168885) (xy 180.009652 -108.184946)
			(xy 179.958317 -108.193076) (xy 179.906343 -108.193076) (xy 179.855008 -108.184946) (xy 179.805578 -108.168885)
			(xy 179.759268 -108.145289) (xy 179.71722 -108.114739) (xy 179.680469 -108.077988) (xy 179.649919 -108.03594)
			(xy 179.626323 -107.98963) (xy 179.610262 -107.9402) (xy 179.602132 -107.888865) (xy 179.462428 -107.888865)
			(xy 179.454298 -107.9402) (xy 179.438237 -107.98963) (xy 179.414641 -108.03594) (xy 179.384091 -108.077988)
			(xy 179.34734 -108.114739) (xy 179.305292 -108.145289) (xy 179.258982 -108.168885) (xy 179.209552 -108.184946)
			(xy 179.158217 -108.193076) (xy 179.106243 -108.193076) (xy 179.054908 -108.184946) (xy 179.005478 -108.168885)
			(xy 178.959168 -108.145289) (xy 178.91712 -108.114739) (xy 178.880369 -108.077988) (xy 178.849819 -108.03594)
			(xy 178.826223 -107.98963) (xy 178.810162 -107.9402) (xy 178.802032 -107.888865) (xy 170.598395 -107.888865)
			(xy 170.615582 -107.913763) (xy 170.644147 -107.968185) (xy 170.665944 -108.025653) (xy 170.680655 -108.08533)
			(xy 170.688066 -108.146344) (xy 170.688508 -108.177076) (xy 170.68805 -108.208057) (xy 170.68053 -108.269561)
			(xy 170.665598 -108.329697) (xy 170.643475 -108.387575) (xy 170.614488 -108.442339) (xy 170.579067 -108.493179)
			(xy 170.537735 -108.539341) (xy 170.491105 -108.580144) (xy 170.46575 -108.597954) (xy 170.456098 -108.60659)
			(xy 170.45178 -108.611416) (xy 170.448732 -108.618274) (xy 170.446623 -108.623222) (xy 170.444318 -108.633726)
			(xy 170.44416 -108.639102) (xy 170.44416 -108.688965) (xy 177.202086 -108.688965) (xy 177.202086 -108.636991)
			(xy 177.210216 -108.585656) (xy 177.226277 -108.536226) (xy 177.249873 -108.489916) (xy 177.280423 -108.447868)
			(xy 177.317174 -108.411117) (xy 177.359222 -108.380567) (xy 177.405532 -108.356971) (xy 177.454962 -108.34091)
			(xy 177.506297 -108.33278) (xy 177.558271 -108.33278) (xy 177.609606 -108.34091) (xy 177.659036 -108.356971)
			(xy 177.705346 -108.380567) (xy 177.747394 -108.411117) (xy 177.784145 -108.447868) (xy 177.814695 -108.489916)
			(xy 177.838291 -108.536226) (xy 177.854352 -108.585656) (xy 177.862482 -108.636991) (xy 177.862992 -108.662978)
			(xy 177.862482 -108.688965) (xy 178.001932 -108.688965) (xy 178.001932 -108.636991) (xy 178.010062 -108.585656)
			(xy 178.026123 -108.536226) (xy 178.049719 -108.489916) (xy 178.080269 -108.447868) (xy 178.11702 -108.411117)
			(xy 178.159068 -108.380567) (xy 178.205378 -108.356971) (xy 178.254808 -108.34091) (xy 178.306143 -108.33278)
			(xy 178.358117 -108.33278) (xy 178.409452 -108.34091) (xy 178.458882 -108.356971) (xy 178.505192 -108.380567)
			(xy 178.54724 -108.411117) (xy 178.583991 -108.447868) (xy 178.614541 -108.489916) (xy 178.638137 -108.536226)
			(xy 178.654198 -108.585656) (xy 178.662328 -108.636991) (xy 178.662838 -108.662978) (xy 178.662328 -108.688965)
			(xy 178.802032 -108.688965) (xy 178.802032 -108.636991) (xy 178.810162 -108.585656) (xy 178.826223 -108.536226)
			(xy 178.849819 -108.489916) (xy 178.880369 -108.447868) (xy 178.91712 -108.411117) (xy 178.959168 -108.380567)
			(xy 179.005478 -108.356971) (xy 179.054908 -108.34091) (xy 179.106243 -108.33278) (xy 179.158217 -108.33278)
			(xy 179.209552 -108.34091) (xy 179.258982 -108.356971) (xy 179.305292 -108.380567) (xy 179.34734 -108.411117)
			(xy 179.384091 -108.447868) (xy 179.414641 -108.489916) (xy 179.438237 -108.536226) (xy 179.454298 -108.585656)
			(xy 179.462428 -108.636991) (xy 179.462938 -108.662978) (xy 179.462428 -108.688965) (xy 179.602132 -108.688965)
			(xy 179.602132 -108.636991) (xy 179.610262 -108.585656) (xy 179.626323 -108.536226) (xy 179.649919 -108.489916)
			(xy 179.680469 -108.447868) (xy 179.71722 -108.411117) (xy 179.759268 -108.380567) (xy 179.805578 -108.356971)
			(xy 179.855008 -108.34091) (xy 179.906343 -108.33278) (xy 179.958317 -108.33278) (xy 180.009652 -108.34091)
			(xy 180.059082 -108.356971) (xy 180.105392 -108.380567) (xy 180.14744 -108.411117) (xy 180.184191 -108.447868)
			(xy 180.214741 -108.489916) (xy 180.238337 -108.536226) (xy 180.254398 -108.585656) (xy 180.262528 -108.636991)
			(xy 180.263038 -108.662978) (xy 180.262528 -108.688965) (xy 180.401978 -108.688965) (xy 180.401978 -108.636991)
			(xy 180.410108 -108.585656) (xy 180.426169 -108.536226) (xy 180.449765 -108.489916) (xy 180.480315 -108.447868)
			(xy 180.517066 -108.411117) (xy 180.559114 -108.380567) (xy 180.605424 -108.356971) (xy 180.654854 -108.34091)
			(xy 180.706189 -108.33278) (xy 180.758163 -108.33278) (xy 180.809498 -108.34091) (xy 180.858928 -108.356971)
			(xy 180.905238 -108.380567) (xy 180.947286 -108.411117) (xy 180.984037 -108.447868) (xy 181.014587 -108.489916)
			(xy 181.038183 -108.536226) (xy 181.054244 -108.585656) (xy 181.062374 -108.636991) (xy 181.062884 -108.662978)
			(xy 181.062374 -108.688965) (xy 181.202078 -108.688965) (xy 181.202078 -108.636991) (xy 181.210208 -108.585656)
			(xy 181.226269 -108.536226) (xy 181.249865 -108.489916) (xy 181.280415 -108.447868) (xy 181.317166 -108.411117)
			(xy 181.359214 -108.380567) (xy 181.405524 -108.356971) (xy 181.454954 -108.34091) (xy 181.506289 -108.33278)
			(xy 181.558263 -108.33278) (xy 181.609598 -108.34091) (xy 181.659028 -108.356971) (xy 181.705338 -108.380567)
			(xy 181.747386 -108.411117) (xy 181.784137 -108.447868) (xy 181.814687 -108.489916) (xy 181.838283 -108.536226)
			(xy 181.854344 -108.585656) (xy 181.862474 -108.636991) (xy 181.862984 -108.662978) (xy 181.862474 -108.688965)
			(xy 182.001924 -108.688965) (xy 182.001924 -108.636991) (xy 182.010054 -108.585656) (xy 182.026115 -108.536226)
			(xy 182.049711 -108.489916) (xy 182.080261 -108.447868) (xy 182.117012 -108.411117) (xy 182.15906 -108.380567)
			(xy 182.20537 -108.356971) (xy 182.2548 -108.34091) (xy 182.306135 -108.33278) (xy 182.358109 -108.33278)
			(xy 182.409444 -108.34091) (xy 182.458874 -108.356971) (xy 182.505184 -108.380567) (xy 182.547232 -108.411117)
			(xy 182.583983 -108.447868) (xy 182.614533 -108.489916) (xy 182.638129 -108.536226) (xy 182.65419 -108.585656)
			(xy 182.66232 -108.636991) (xy 182.66283 -108.662978) (xy 182.66232 -108.688965) (xy 182.802024 -108.688965)
			(xy 182.802024 -108.636991) (xy 182.810154 -108.585656) (xy 182.826215 -108.536226) (xy 182.849811 -108.489916)
			(xy 182.880361 -108.447868) (xy 182.917112 -108.411117) (xy 182.95916 -108.380567) (xy 183.00547 -108.356971)
			(xy 183.0549 -108.34091) (xy 183.106235 -108.33278) (xy 183.158209 -108.33278) (xy 183.209544 -108.34091)
			(xy 183.258974 -108.356971) (xy 183.305284 -108.380567) (xy 183.347332 -108.411117) (xy 183.384083 -108.447868)
			(xy 183.414633 -108.489916) (xy 183.438229 -108.536226) (xy 183.45429 -108.585656) (xy 183.46242 -108.636991)
			(xy 183.46293 -108.662978) (xy 183.46242 -108.688965) (xy 183.602124 -108.688965) (xy 183.602124 -108.636991)
			(xy 183.610254 -108.585656) (xy 183.626315 -108.536226) (xy 183.649911 -108.489916) (xy 183.680461 -108.447868)
			(xy 183.717212 -108.411117) (xy 183.75926 -108.380567) (xy 183.80557 -108.356971) (xy 183.855 -108.34091)
			(xy 183.906335 -108.33278) (xy 183.958309 -108.33278) (xy 184.009644 -108.34091) (xy 184.059074 -108.356971)
			(xy 184.105384 -108.380567) (xy 184.147432 -108.411117) (xy 184.184183 -108.447868) (xy 184.214733 -108.489916)
			(xy 184.238329 -108.536226) (xy 184.25439 -108.585656) (xy 184.26252 -108.636991) (xy 184.26303 -108.662978)
			(xy 184.26252 -108.688965) (xy 184.40197 -108.688965) (xy 184.40197 -108.636991) (xy 184.4101 -108.585656)
			(xy 184.426161 -108.536226) (xy 184.449757 -108.489916) (xy 184.480307 -108.447868) (xy 184.517058 -108.411117)
			(xy 184.559106 -108.380567) (xy 184.605416 -108.356971) (xy 184.654846 -108.34091) (xy 184.706181 -108.33278)
			(xy 184.758155 -108.33278) (xy 184.80949 -108.34091) (xy 184.85892 -108.356971) (xy 184.90523 -108.380567)
			(xy 184.947278 -108.411117) (xy 184.984029 -108.447868) (xy 185.014579 -108.489916) (xy 185.038175 -108.536226)
			(xy 185.054236 -108.585656) (xy 185.062366 -108.636991) (xy 185.062876 -108.662978) (xy 185.062366 -108.688965)
			(xy 185.98185 -108.688965) (xy 185.98185 -108.636991) (xy 185.98998 -108.585656) (xy 186.006041 -108.536226)
			(xy 186.029637 -108.489916) (xy 186.060187 -108.447868) (xy 186.096938 -108.411117) (xy 186.138986 -108.380567)
			(xy 186.185296 -108.356971) (xy 186.234726 -108.34091) (xy 186.286061 -108.33278) (xy 186.338035 -108.33278)
			(xy 186.38937 -108.34091) (xy 186.4388 -108.356971) (xy 186.48511 -108.380567) (xy 186.527158 -108.411117)
			(xy 186.563909 -108.447868) (xy 186.594459 -108.489916) (xy 186.618055 -108.536226) (xy 186.634116 -108.585656)
			(xy 186.642246 -108.636991) (xy 186.642756 -108.662978) (xy 186.642246 -108.688965) (xy 186.781696 -108.688965)
			(xy 186.781696 -108.636991) (xy 186.789826 -108.585656) (xy 186.805887 -108.536226) (xy 186.829483 -108.489916)
			(xy 186.860033 -108.447868) (xy 186.896784 -108.411117) (xy 186.938832 -108.380567) (xy 186.985142 -108.356971)
			(xy 187.034572 -108.34091) (xy 187.085907 -108.33278) (xy 187.137881 -108.33278) (xy 187.189216 -108.34091)
			(xy 187.238646 -108.356971) (xy 187.284956 -108.380567) (xy 187.327004 -108.411117) (xy 187.363755 -108.447868)
			(xy 187.394305 -108.489916) (xy 187.417901 -108.536226) (xy 187.433962 -108.585656) (xy 187.442092 -108.636991)
			(xy 187.442602 -108.662978) (xy 187.442092 -108.688965) (xy 187.581796 -108.688965) (xy 187.581796 -108.636991)
			(xy 187.589926 -108.585656) (xy 187.605987 -108.536226) (xy 187.629583 -108.489916) (xy 187.660133 -108.447868)
			(xy 187.696884 -108.411117) (xy 187.738932 -108.380567) (xy 187.785242 -108.356971) (xy 187.834672 -108.34091)
			(xy 187.886007 -108.33278) (xy 187.937981 -108.33278) (xy 187.989316 -108.34091) (xy 188.038746 -108.356971)
			(xy 188.085056 -108.380567) (xy 188.127104 -108.411117) (xy 188.163855 -108.447868) (xy 188.194405 -108.489916)
			(xy 188.218001 -108.536226) (xy 188.234062 -108.585656) (xy 188.242192 -108.636991) (xy 188.242702 -108.662978)
			(xy 188.242192 -108.688965) (xy 188.381896 -108.688965) (xy 188.381896 -108.636991) (xy 188.390026 -108.585656)
			(xy 188.406087 -108.536226) (xy 188.429683 -108.489916) (xy 188.460233 -108.447868) (xy 188.496984 -108.411117)
			(xy 188.539032 -108.380567) (xy 188.585342 -108.356971) (xy 188.634772 -108.34091) (xy 188.686107 -108.33278)
			(xy 188.738081 -108.33278) (xy 188.789416 -108.34091) (xy 188.838846 -108.356971) (xy 188.885156 -108.380567)
			(xy 188.927204 -108.411117) (xy 188.963955 -108.447868) (xy 188.994505 -108.489916) (xy 189.018101 -108.536226)
			(xy 189.034162 -108.585656) (xy 189.042292 -108.636991) (xy 189.042802 -108.662978) (xy 189.042292 -108.688965)
			(xy 189.181742 -108.688965) (xy 189.181742 -108.636991) (xy 189.189872 -108.585656) (xy 189.205933 -108.536226)
			(xy 189.229529 -108.489916) (xy 189.260079 -108.447868) (xy 189.29683 -108.411117) (xy 189.338878 -108.380567)
			(xy 189.385188 -108.356971) (xy 189.434618 -108.34091) (xy 189.485953 -108.33278) (xy 189.537927 -108.33278)
			(xy 189.589262 -108.34091) (xy 189.638692 -108.356971) (xy 189.685002 -108.380567) (xy 189.72705 -108.411117)
			(xy 189.763801 -108.447868) (xy 189.794351 -108.489916) (xy 189.817947 -108.536226) (xy 189.834008 -108.585656)
			(xy 189.842138 -108.636991) (xy 189.842648 -108.662978) (xy 189.842138 -108.688965) (xy 189.981842 -108.688965)
			(xy 189.981842 -108.636991) (xy 189.989972 -108.585656) (xy 190.006033 -108.536226) (xy 190.029629 -108.489916)
			(xy 190.060179 -108.447868) (xy 190.09693 -108.411117) (xy 190.138978 -108.380567) (xy 190.185288 -108.356971)
			(xy 190.234718 -108.34091) (xy 190.286053 -108.33278) (xy 190.338027 -108.33278) (xy 190.389362 -108.34091)
			(xy 190.438792 -108.356971) (xy 190.485102 -108.380567) (xy 190.52715 -108.411117) (xy 190.563901 -108.447868)
			(xy 190.594451 -108.489916) (xy 190.618047 -108.536226) (xy 190.634108 -108.585656) (xy 190.642238 -108.636991)
			(xy 190.642748 -108.662978) (xy 190.642238 -108.688965) (xy 190.634108 -108.7403) (xy 190.618047 -108.78973)
			(xy 190.594451 -108.83604) (xy 190.563901 -108.878088) (xy 190.52715 -108.914839) (xy 190.485102 -108.945389)
			(xy 190.438792 -108.968985) (xy 190.389362 -108.985046) (xy 190.338027 -108.993176) (xy 190.286053 -108.993176)
			(xy 190.234718 -108.985046) (xy 190.185288 -108.968985) (xy 190.138978 -108.945389) (xy 190.09693 -108.914839)
			(xy 190.060179 -108.878088) (xy 190.029629 -108.83604) (xy 190.006033 -108.78973) (xy 189.989972 -108.7403)
			(xy 189.981842 -108.688965) (xy 189.842138 -108.688965) (xy 189.834008 -108.7403) (xy 189.817947 -108.78973)
			(xy 189.794351 -108.83604) (xy 189.763801 -108.878088) (xy 189.72705 -108.914839) (xy 189.685002 -108.945389)
			(xy 189.638692 -108.968985) (xy 189.589262 -108.985046) (xy 189.537927 -108.993176) (xy 189.485953 -108.993176)
			(xy 189.434618 -108.985046) (xy 189.385188 -108.968985) (xy 189.338878 -108.945389) (xy 189.29683 -108.914839)
			(xy 189.260079 -108.878088) (xy 189.229529 -108.83604) (xy 189.205933 -108.78973) (xy 189.189872 -108.7403)
			(xy 189.181742 -108.688965) (xy 189.042292 -108.688965) (xy 189.034162 -108.7403) (xy 189.018101 -108.78973)
			(xy 188.994505 -108.83604) (xy 188.963955 -108.878088) (xy 188.927204 -108.914839) (xy 188.885156 -108.945389)
			(xy 188.838846 -108.968985) (xy 188.789416 -108.985046) (xy 188.738081 -108.993176) (xy 188.686107 -108.993176)
			(xy 188.634772 -108.985046) (xy 188.585342 -108.968985) (xy 188.539032 -108.945389) (xy 188.496984 -108.914839)
			(xy 188.460233 -108.878088) (xy 188.429683 -108.83604) (xy 188.406087 -108.78973) (xy 188.390026 -108.7403)
			(xy 188.381896 -108.688965) (xy 188.242192 -108.688965) (xy 188.234062 -108.7403) (xy 188.218001 -108.78973)
			(xy 188.194405 -108.83604) (xy 188.163855 -108.878088) (xy 188.127104 -108.914839) (xy 188.085056 -108.945389)
			(xy 188.038746 -108.968985) (xy 187.989316 -108.985046) (xy 187.937981 -108.993176) (xy 187.886007 -108.993176)
			(xy 187.834672 -108.985046) (xy 187.785242 -108.968985) (xy 187.738932 -108.945389) (xy 187.696884 -108.914839)
			(xy 187.660133 -108.878088) (xy 187.629583 -108.83604) (xy 187.605987 -108.78973) (xy 187.589926 -108.7403)
			(xy 187.581796 -108.688965) (xy 187.442092 -108.688965) (xy 187.433962 -108.7403) (xy 187.417901 -108.78973)
			(xy 187.394305 -108.83604) (xy 187.363755 -108.878088) (xy 187.327004 -108.914839) (xy 187.284956 -108.945389)
			(xy 187.238646 -108.968985) (xy 187.189216 -108.985046) (xy 187.137881 -108.993176) (xy 187.085907 -108.993176)
			(xy 187.034572 -108.985046) (xy 186.985142 -108.968985) (xy 186.938832 -108.945389) (xy 186.896784 -108.914839)
			(xy 186.860033 -108.878088) (xy 186.829483 -108.83604) (xy 186.805887 -108.78973) (xy 186.789826 -108.7403)
			(xy 186.781696 -108.688965) (xy 186.642246 -108.688965) (xy 186.634116 -108.7403) (xy 186.618055 -108.78973)
			(xy 186.594459 -108.83604) (xy 186.563909 -108.878088) (xy 186.527158 -108.914839) (xy 186.48511 -108.945389)
			(xy 186.4388 -108.968985) (xy 186.38937 -108.985046) (xy 186.338035 -108.993176) (xy 186.286061 -108.993176)
			(xy 186.234726 -108.985046) (xy 186.185296 -108.968985) (xy 186.138986 -108.945389) (xy 186.096938 -108.914839)
			(xy 186.060187 -108.878088) (xy 186.029637 -108.83604) (xy 186.006041 -108.78973) (xy 185.98998 -108.7403)
			(xy 185.98185 -108.688965) (xy 185.062366 -108.688965) (xy 185.054236 -108.7403) (xy 185.038175 -108.78973)
			(xy 185.014579 -108.83604) (xy 184.984029 -108.878088) (xy 184.947278 -108.914839) (xy 184.90523 -108.945389)
			(xy 184.85892 -108.968985) (xy 184.80949 -108.985046) (xy 184.758155 -108.993176) (xy 184.706181 -108.993176)
			(xy 184.654846 -108.985046) (xy 184.605416 -108.968985) (xy 184.559106 -108.945389) (xy 184.517058 -108.914839)
			(xy 184.480307 -108.878088) (xy 184.449757 -108.83604) (xy 184.426161 -108.78973) (xy 184.4101 -108.7403)
			(xy 184.40197 -108.688965) (xy 184.26252 -108.688965) (xy 184.25439 -108.7403) (xy 184.238329 -108.78973)
			(xy 184.214733 -108.83604) (xy 184.184183 -108.878088) (xy 184.147432 -108.914839) (xy 184.105384 -108.945389)
			(xy 184.059074 -108.968985) (xy 184.009644 -108.985046) (xy 183.958309 -108.993176) (xy 183.906335 -108.993176)
			(xy 183.855 -108.985046) (xy 183.80557 -108.968985) (xy 183.75926 -108.945389) (xy 183.717212 -108.914839)
			(xy 183.680461 -108.878088) (xy 183.649911 -108.83604) (xy 183.626315 -108.78973) (xy 183.610254 -108.7403)
			(xy 183.602124 -108.688965) (xy 183.46242 -108.688965) (xy 183.45429 -108.7403) (xy 183.438229 -108.78973)
			(xy 183.414633 -108.83604) (xy 183.384083 -108.878088) (xy 183.347332 -108.914839) (xy 183.305284 -108.945389)
			(xy 183.258974 -108.968985) (xy 183.209544 -108.985046) (xy 183.158209 -108.993176) (xy 183.106235 -108.993176)
			(xy 183.0549 -108.985046) (xy 183.00547 -108.968985) (xy 182.95916 -108.945389) (xy 182.917112 -108.914839)
			(xy 182.880361 -108.878088) (xy 182.849811 -108.83604) (xy 182.826215 -108.78973) (xy 182.810154 -108.7403)
			(xy 182.802024 -108.688965) (xy 182.66232 -108.688965) (xy 182.65419 -108.7403) (xy 182.638129 -108.78973)
			(xy 182.614533 -108.83604) (xy 182.583983 -108.878088) (xy 182.547232 -108.914839) (xy 182.505184 -108.945389)
			(xy 182.458874 -108.968985) (xy 182.409444 -108.985046) (xy 182.358109 -108.993176) (xy 182.306135 -108.993176)
			(xy 182.2548 -108.985046) (xy 182.20537 -108.968985) (xy 182.15906 -108.945389) (xy 182.117012 -108.914839)
			(xy 182.080261 -108.878088) (xy 182.049711 -108.83604) (xy 182.026115 -108.78973) (xy 182.010054 -108.7403)
			(xy 182.001924 -108.688965) (xy 181.862474 -108.688965) (xy 181.854344 -108.7403) (xy 181.838283 -108.78973)
			(xy 181.814687 -108.83604) (xy 181.784137 -108.878088) (xy 181.747386 -108.914839) (xy 181.705338 -108.945389)
			(xy 181.659028 -108.968985) (xy 181.609598 -108.985046) (xy 181.558263 -108.993176) (xy 181.506289 -108.993176)
			(xy 181.454954 -108.985046) (xy 181.405524 -108.968985) (xy 181.359214 -108.945389) (xy 181.317166 -108.914839)
			(xy 181.280415 -108.878088) (xy 181.249865 -108.83604) (xy 181.226269 -108.78973) (xy 181.210208 -108.7403)
			(xy 181.202078 -108.688965) (xy 181.062374 -108.688965) (xy 181.054244 -108.7403) (xy 181.038183 -108.78973)
			(xy 181.014587 -108.83604) (xy 180.984037 -108.878088) (xy 180.947286 -108.914839) (xy 180.905238 -108.945389)
			(xy 180.858928 -108.968985) (xy 180.809498 -108.985046) (xy 180.758163 -108.993176) (xy 180.706189 -108.993176)
			(xy 180.654854 -108.985046) (xy 180.605424 -108.968985) (xy 180.559114 -108.945389) (xy 180.517066 -108.914839)
			(xy 180.480315 -108.878088) (xy 180.449765 -108.83604) (xy 180.426169 -108.78973) (xy 180.410108 -108.7403)
			(xy 180.401978 -108.688965) (xy 180.262528 -108.688965) (xy 180.254398 -108.7403) (xy 180.238337 -108.78973)
			(xy 180.214741 -108.83604) (xy 180.184191 -108.878088) (xy 180.14744 -108.914839) (xy 180.105392 -108.945389)
			(xy 180.059082 -108.968985) (xy 180.009652 -108.985046) (xy 179.958317 -108.993176) (xy 179.906343 -108.993176)
			(xy 179.855008 -108.985046) (xy 179.805578 -108.968985) (xy 179.759268 -108.945389) (xy 179.71722 -108.914839)
			(xy 179.680469 -108.878088) (xy 179.649919 -108.83604) (xy 179.626323 -108.78973) (xy 179.610262 -108.7403)
			(xy 179.602132 -108.688965) (xy 179.462428 -108.688965) (xy 179.454298 -108.7403) (xy 179.438237 -108.78973)
			(xy 179.414641 -108.83604) (xy 179.384091 -108.878088) (xy 179.34734 -108.914839) (xy 179.305292 -108.945389)
			(xy 179.258982 -108.968985) (xy 179.209552 -108.985046) (xy 179.158217 -108.993176) (xy 179.106243 -108.993176)
			(xy 179.054908 -108.985046) (xy 179.005478 -108.968985) (xy 178.959168 -108.945389) (xy 178.91712 -108.914839)
			(xy 178.880369 -108.878088) (xy 178.849819 -108.83604) (xy 178.826223 -108.78973) (xy 178.810162 -108.7403)
			(xy 178.802032 -108.688965) (xy 178.662328 -108.688965) (xy 178.654198 -108.7403) (xy 178.638137 -108.78973)
			(xy 178.614541 -108.83604) (xy 178.583991 -108.878088) (xy 178.54724 -108.914839) (xy 178.505192 -108.945389)
			(xy 178.458882 -108.968985) (xy 178.409452 -108.985046) (xy 178.358117 -108.993176) (xy 178.306143 -108.993176)
			(xy 178.254808 -108.985046) (xy 178.205378 -108.968985) (xy 178.159068 -108.945389) (xy 178.11702 -108.914839)
			(xy 178.080269 -108.878088) (xy 178.049719 -108.83604) (xy 178.026123 -108.78973) (xy 178.010062 -108.7403)
			(xy 178.001932 -108.688965) (xy 177.862482 -108.688965) (xy 177.854352 -108.7403) (xy 177.838291 -108.78973)
			(xy 177.814695 -108.83604) (xy 177.784145 -108.878088) (xy 177.747394 -108.914839) (xy 177.705346 -108.945389)
			(xy 177.659036 -108.968985) (xy 177.609606 -108.985046) (xy 177.558271 -108.993176) (xy 177.506297 -108.993176)
			(xy 177.454962 -108.985046) (xy 177.405532 -108.968985) (xy 177.359222 -108.945389) (xy 177.317174 -108.914839)
			(xy 177.280423 -108.878088) (xy 177.249873 -108.83604) (xy 177.226277 -108.78973) (xy 177.210216 -108.7403)
			(xy 177.202086 -108.688965) (xy 170.44416 -108.688965) (xy 170.44416 -108.717842) (xy 170.44543 -108.72851)
			(xy 170.447716 -108.739178) (xy 170.451018 -108.749592) (xy 170.454574 -108.757212) (xy 170.467782 -108.766102)
			(xy 170.49382 -108.784572) (xy 170.541526 -108.826995) (xy 170.583547 -108.875055) (xy 170.619221 -108.927997)
			(xy 170.647987 -108.984989) (xy 170.669394 -109.045133) (xy 170.683103 -109.107483) (xy 170.686476 -109.139228)
			(xy 170.688 -109.1565) (xy 170.688762 -109.185456) (xy 170.688318 -109.215807) (xy 170.681087 -109.276076)
			(xy 170.666735 -109.335056) (xy 170.645465 -109.391909) (xy 170.61758 -109.445826) (xy 170.588214 -109.489065)
			(xy 176.401986 -109.489065) (xy 176.401986 -109.437091) (xy 176.410116 -109.385756) (xy 176.426177 -109.336326)
			(xy 176.449773 -109.290016) (xy 176.480323 -109.247968) (xy 176.517074 -109.211217) (xy 176.559122 -109.180667)
			(xy 176.605432 -109.157071) (xy 176.654862 -109.14101) (xy 176.706197 -109.13288) (xy 176.758171 -109.13288)
			(xy 176.809506 -109.14101) (xy 176.858936 -109.157071) (xy 176.905246 -109.180667) (xy 176.947294 -109.211217)
			(xy 176.984045 -109.247968) (xy 177.014595 -109.290016) (xy 177.038191 -109.336326) (xy 177.054252 -109.385756)
			(xy 177.062382 -109.437091) (xy 177.062892 -109.463078) (xy 177.062382 -109.489065) (xy 177.202086 -109.489065)
			(xy 177.202086 -109.437091) (xy 177.210216 -109.385756) (xy 177.226277 -109.336326) (xy 177.249873 -109.290016)
			(xy 177.280423 -109.247968) (xy 177.317174 -109.211217) (xy 177.359222 -109.180667) (xy 177.405532 -109.157071)
			(xy 177.454962 -109.14101) (xy 177.506297 -109.13288) (xy 177.558271 -109.13288) (xy 177.609606 -109.14101)
			(xy 177.659036 -109.157071) (xy 177.705346 -109.180667) (xy 177.747394 -109.211217) (xy 177.784145 -109.247968)
			(xy 177.814695 -109.290016) (xy 177.838291 -109.336326) (xy 177.854352 -109.385756) (xy 177.862482 -109.437091)
			(xy 177.862992 -109.463078) (xy 177.862482 -109.489065) (xy 178.001932 -109.489065) (xy 178.001932 -109.437091)
			(xy 178.010062 -109.385756) (xy 178.026123 -109.336326) (xy 178.049719 -109.290016) (xy 178.080269 -109.247968)
			(xy 178.11702 -109.211217) (xy 178.159068 -109.180667) (xy 178.205378 -109.157071) (xy 178.254808 -109.14101)
			(xy 178.306143 -109.13288) (xy 178.358117 -109.13288) (xy 178.409452 -109.14101) (xy 178.458882 -109.157071)
			(xy 178.505192 -109.180667) (xy 178.54724 -109.211217) (xy 178.583991 -109.247968) (xy 178.614541 -109.290016)
			(xy 178.638137 -109.336326) (xy 178.654198 -109.385756) (xy 178.662328 -109.437091) (xy 178.662838 -109.463078)
			(xy 178.662328 -109.489065) (xy 178.802032 -109.489065) (xy 178.802032 -109.437091) (xy 178.810162 -109.385756)
			(xy 178.826223 -109.336326) (xy 178.849819 -109.290016) (xy 178.880369 -109.247968) (xy 178.91712 -109.211217)
			(xy 178.959168 -109.180667) (xy 179.005478 -109.157071) (xy 179.054908 -109.14101) (xy 179.106243 -109.13288)
			(xy 179.158217 -109.13288) (xy 179.209552 -109.14101) (xy 179.258982 -109.157071) (xy 179.305292 -109.180667)
			(xy 179.34734 -109.211217) (xy 179.384091 -109.247968) (xy 179.414641 -109.290016) (xy 179.438237 -109.336326)
			(xy 179.454298 -109.385756) (xy 179.462428 -109.437091) (xy 179.462938 -109.463078) (xy 179.462428 -109.489065)
			(xy 179.602132 -109.489065) (xy 179.602132 -109.437091) (xy 179.610262 -109.385756) (xy 179.626323 -109.336326)
			(xy 179.649919 -109.290016) (xy 179.680469 -109.247968) (xy 179.71722 -109.211217) (xy 179.759268 -109.180667)
			(xy 179.805578 -109.157071) (xy 179.855008 -109.14101) (xy 179.906343 -109.13288) (xy 179.958317 -109.13288)
			(xy 180.009652 -109.14101) (xy 180.059082 -109.157071) (xy 180.105392 -109.180667) (xy 180.14744 -109.211217)
			(xy 180.184191 -109.247968) (xy 180.214741 -109.290016) (xy 180.238337 -109.336326) (xy 180.254398 -109.385756)
			(xy 180.262528 -109.437091) (xy 180.263038 -109.463078) (xy 180.262528 -109.489065) (xy 180.401978 -109.489065)
			(xy 180.401978 -109.437091) (xy 180.410108 -109.385756) (xy 180.426169 -109.336326) (xy 180.449765 -109.290016)
			(xy 180.480315 -109.247968) (xy 180.517066 -109.211217) (xy 180.559114 -109.180667) (xy 180.605424 -109.157071)
			(xy 180.654854 -109.14101) (xy 180.706189 -109.13288) (xy 180.758163 -109.13288) (xy 180.809498 -109.14101)
			(xy 180.858928 -109.157071) (xy 180.905238 -109.180667) (xy 180.947286 -109.211217) (xy 180.984037 -109.247968)
			(xy 181.014587 -109.290016) (xy 181.038183 -109.336326) (xy 181.054244 -109.385756) (xy 181.062374 -109.437091)
			(xy 181.062884 -109.463078) (xy 181.062374 -109.489065) (xy 181.202078 -109.489065) (xy 181.202078 -109.437091)
			(xy 181.210208 -109.385756) (xy 181.226269 -109.336326) (xy 181.249865 -109.290016) (xy 181.280415 -109.247968)
			(xy 181.317166 -109.211217) (xy 181.359214 -109.180667) (xy 181.405524 -109.157071) (xy 181.454954 -109.14101)
			(xy 181.506289 -109.13288) (xy 181.558263 -109.13288) (xy 181.609598 -109.14101) (xy 181.659028 -109.157071)
			(xy 181.705338 -109.180667) (xy 181.747386 -109.211217) (xy 181.784137 -109.247968) (xy 181.814687 -109.290016)
			(xy 181.838283 -109.336326) (xy 181.854344 -109.385756) (xy 181.862474 -109.437091) (xy 181.862984 -109.463078)
			(xy 181.862474 -109.489065) (xy 182.001924 -109.489065) (xy 182.001924 -109.437091) (xy 182.010054 -109.385756)
			(xy 182.026115 -109.336326) (xy 182.049711 -109.290016) (xy 182.080261 -109.247968) (xy 182.117012 -109.211217)
			(xy 182.15906 -109.180667) (xy 182.20537 -109.157071) (xy 182.2548 -109.14101) (xy 182.306135 -109.13288)
			(xy 182.358109 -109.13288) (xy 182.409444 -109.14101) (xy 182.458874 -109.157071) (xy 182.505184 -109.180667)
			(xy 182.547232 -109.211217) (xy 182.583983 -109.247968) (xy 182.614533 -109.290016) (xy 182.638129 -109.336326)
			(xy 182.65419 -109.385756) (xy 182.66232 -109.437091) (xy 182.66283 -109.463078) (xy 182.66232 -109.489065)
			(xy 182.802024 -109.489065) (xy 182.802024 -109.437091) (xy 182.810154 -109.385756) (xy 182.826215 -109.336326)
			(xy 182.849811 -109.290016) (xy 182.880361 -109.247968) (xy 182.917112 -109.211217) (xy 182.95916 -109.180667)
			(xy 183.00547 -109.157071) (xy 183.0549 -109.14101) (xy 183.106235 -109.13288) (xy 183.158209 -109.13288)
			(xy 183.209544 -109.14101) (xy 183.258974 -109.157071) (xy 183.305284 -109.180667) (xy 183.347332 -109.211217)
			(xy 183.384083 -109.247968) (xy 183.414633 -109.290016) (xy 183.438229 -109.336326) (xy 183.45429 -109.385756)
			(xy 183.46242 -109.437091) (xy 183.46293 -109.463078) (xy 183.46242 -109.489065) (xy 183.602124 -109.489065)
			(xy 183.602124 -109.437091) (xy 183.610254 -109.385756) (xy 183.626315 -109.336326) (xy 183.649911 -109.290016)
			(xy 183.680461 -109.247968) (xy 183.717212 -109.211217) (xy 183.75926 -109.180667) (xy 183.80557 -109.157071)
			(xy 183.855 -109.14101) (xy 183.906335 -109.13288) (xy 183.958309 -109.13288) (xy 184.009644 -109.14101)
			(xy 184.059074 -109.157071) (xy 184.105384 -109.180667) (xy 184.147432 -109.211217) (xy 184.184183 -109.247968)
			(xy 184.214733 -109.290016) (xy 184.238329 -109.336326) (xy 184.25439 -109.385756) (xy 184.26252 -109.437091)
			(xy 184.26303 -109.463078) (xy 184.26252 -109.489065) (xy 184.40197 -109.489065) (xy 184.40197 -109.437091)
			(xy 184.4101 -109.385756) (xy 184.426161 -109.336326) (xy 184.449757 -109.290016) (xy 184.480307 -109.247968)
			(xy 184.517058 -109.211217) (xy 184.559106 -109.180667) (xy 184.605416 -109.157071) (xy 184.654846 -109.14101)
			(xy 184.706181 -109.13288) (xy 184.758155 -109.13288) (xy 184.80949 -109.14101) (xy 184.85892 -109.157071)
			(xy 184.90523 -109.180667) (xy 184.947278 -109.211217) (xy 184.984029 -109.247968) (xy 185.014579 -109.290016)
			(xy 185.038175 -109.336326) (xy 185.054236 -109.385756) (xy 185.062366 -109.437091) (xy 185.062876 -109.463078)
			(xy 185.062366 -109.489065) (xy 185.98185 -109.489065) (xy 185.98185 -109.437091) (xy 185.98998 -109.385756)
			(xy 186.006041 -109.336326) (xy 186.029637 -109.290016) (xy 186.060187 -109.247968) (xy 186.096938 -109.211217)
			(xy 186.138986 -109.180667) (xy 186.185296 -109.157071) (xy 186.234726 -109.14101) (xy 186.286061 -109.13288)
			(xy 186.338035 -109.13288) (xy 186.38937 -109.14101) (xy 186.4388 -109.157071) (xy 186.48511 -109.180667)
			(xy 186.527158 -109.211217) (xy 186.563909 -109.247968) (xy 186.594459 -109.290016) (xy 186.618055 -109.336326)
			(xy 186.634116 -109.385756) (xy 186.642246 -109.437091) (xy 186.642756 -109.463078) (xy 186.642246 -109.489065)
			(xy 186.781696 -109.489065) (xy 186.781696 -109.437091) (xy 186.789826 -109.385756) (xy 186.805887 -109.336326)
			(xy 186.829483 -109.290016) (xy 186.860033 -109.247968) (xy 186.896784 -109.211217) (xy 186.938832 -109.180667)
			(xy 186.985142 -109.157071) (xy 187.034572 -109.14101) (xy 187.085907 -109.13288) (xy 187.137881 -109.13288)
			(xy 187.189216 -109.14101) (xy 187.238646 -109.157071) (xy 187.284956 -109.180667) (xy 187.327004 -109.211217)
			(xy 187.363755 -109.247968) (xy 187.394305 -109.290016) (xy 187.417901 -109.336326) (xy 187.433962 -109.385756)
			(xy 187.442092 -109.437091) (xy 187.442602 -109.463078) (xy 187.442092 -109.489065) (xy 187.581796 -109.489065)
			(xy 187.581796 -109.437091) (xy 187.589926 -109.385756) (xy 187.605987 -109.336326) (xy 187.629583 -109.290016)
			(xy 187.660133 -109.247968) (xy 187.696884 -109.211217) (xy 187.738932 -109.180667) (xy 187.785242 -109.157071)
			(xy 187.834672 -109.14101) (xy 187.886007 -109.13288) (xy 187.937981 -109.13288) (xy 187.989316 -109.14101)
			(xy 188.038746 -109.157071) (xy 188.085056 -109.180667) (xy 188.127104 -109.211217) (xy 188.163855 -109.247968)
			(xy 188.194405 -109.290016) (xy 188.218001 -109.336326) (xy 188.234062 -109.385756) (xy 188.242192 -109.437091)
			(xy 188.242702 -109.463078) (xy 188.242192 -109.489065) (xy 188.381896 -109.489065) (xy 188.381896 -109.437091)
			(xy 188.390026 -109.385756) (xy 188.406087 -109.336326) (xy 188.429683 -109.290016) (xy 188.460233 -109.247968)
			(xy 188.496984 -109.211217) (xy 188.539032 -109.180667) (xy 188.585342 -109.157071) (xy 188.634772 -109.14101)
			(xy 188.686107 -109.13288) (xy 188.738081 -109.13288) (xy 188.789416 -109.14101) (xy 188.838846 -109.157071)
			(xy 188.885156 -109.180667) (xy 188.927204 -109.211217) (xy 188.963955 -109.247968) (xy 188.994505 -109.290016)
			(xy 189.018101 -109.336326) (xy 189.034162 -109.385756) (xy 189.042292 -109.437091) (xy 189.042802 -109.463078)
			(xy 189.042292 -109.489065) (xy 189.181742 -109.489065) (xy 189.181742 -109.437091) (xy 189.189872 -109.385756)
			(xy 189.205933 -109.336326) (xy 189.229529 -109.290016) (xy 189.260079 -109.247968) (xy 189.29683 -109.211217)
			(xy 189.338878 -109.180667) (xy 189.385188 -109.157071) (xy 189.434618 -109.14101) (xy 189.485953 -109.13288)
			(xy 189.537927 -109.13288) (xy 189.589262 -109.14101) (xy 189.638692 -109.157071) (xy 189.685002 -109.180667)
			(xy 189.72705 -109.211217) (xy 189.763801 -109.247968) (xy 189.794351 -109.290016) (xy 189.817947 -109.336326)
			(xy 189.834008 -109.385756) (xy 189.842138 -109.437091) (xy 189.842648 -109.463078) (xy 189.842138 -109.489065)
			(xy 189.981842 -109.489065) (xy 189.981842 -109.437091) (xy 189.989972 -109.385756) (xy 190.006033 -109.336326)
			(xy 190.029629 -109.290016) (xy 190.060179 -109.247968) (xy 190.09693 -109.211217) (xy 190.138978 -109.180667)
			(xy 190.185288 -109.157071) (xy 190.234718 -109.14101) (xy 190.286053 -109.13288) (xy 190.338027 -109.13288)
			(xy 190.389362 -109.14101) (xy 190.438792 -109.157071) (xy 190.485102 -109.180667) (xy 190.52715 -109.211217)
			(xy 190.563901 -109.247968) (xy 190.594451 -109.290016) (xy 190.618047 -109.336326) (xy 190.634108 -109.385756)
			(xy 190.642238 -109.437091) (xy 190.642748 -109.463078) (xy 190.642238 -109.489065) (xy 190.781688 -109.489065)
			(xy 190.781688 -109.437091) (xy 190.789818 -109.385756) (xy 190.805879 -109.336326) (xy 190.829475 -109.290016)
			(xy 190.860025 -109.247968) (xy 190.896776 -109.211217) (xy 190.938824 -109.180667) (xy 190.985134 -109.157071)
			(xy 191.034564 -109.14101) (xy 191.085899 -109.13288) (xy 191.137873 -109.13288) (xy 191.189208 -109.14101)
			(xy 191.238638 -109.157071) (xy 191.284948 -109.180667) (xy 191.326996 -109.211217) (xy 191.363747 -109.247968)
			(xy 191.394297 -109.290016) (xy 191.417893 -109.336326) (xy 191.433954 -109.385756) (xy 191.442084 -109.437091)
			(xy 191.442594 -109.463078) (xy 191.442084 -109.489065) (xy 191.433954 -109.5404) (xy 191.417893 -109.58983)
			(xy 191.394297 -109.63614) (xy 191.363747 -109.678188) (xy 191.326996 -109.714939) (xy 191.284948 -109.745489)
			(xy 191.238638 -109.769085) (xy 191.189208 -109.785146) (xy 191.137873 -109.793276) (xy 191.085899 -109.793276)
			(xy 191.034564 -109.785146) (xy 190.985134 -109.769085) (xy 190.938824 -109.745489) (xy 190.896776 -109.714939)
			(xy 190.860025 -109.678188) (xy 190.829475 -109.63614) (xy 190.805879 -109.58983) (xy 190.789818 -109.5404)
			(xy 190.781688 -109.489065) (xy 190.642238 -109.489065) (xy 190.634108 -109.5404) (xy 190.618047 -109.58983)
			(xy 190.594451 -109.63614) (xy 190.563901 -109.678188) (xy 190.52715 -109.714939) (xy 190.485102 -109.745489)
			(xy 190.438792 -109.769085) (xy 190.389362 -109.785146) (xy 190.338027 -109.793276) (xy 190.286053 -109.793276)
			(xy 190.234718 -109.785146) (xy 190.185288 -109.769085) (xy 190.138978 -109.745489) (xy 190.09693 -109.714939)
			(xy 190.060179 -109.678188) (xy 190.029629 -109.63614) (xy 190.006033 -109.58983) (xy 189.989972 -109.5404)
			(xy 189.981842 -109.489065) (xy 189.842138 -109.489065) (xy 189.834008 -109.5404) (xy 189.817947 -109.58983)
			(xy 189.794351 -109.63614) (xy 189.763801 -109.678188) (xy 189.72705 -109.714939) (xy 189.685002 -109.745489)
			(xy 189.638692 -109.769085) (xy 189.589262 -109.785146) (xy 189.537927 -109.793276) (xy 189.485953 -109.793276)
			(xy 189.434618 -109.785146) (xy 189.385188 -109.769085) (xy 189.338878 -109.745489) (xy 189.29683 -109.714939)
			(xy 189.260079 -109.678188) (xy 189.229529 -109.63614) (xy 189.205933 -109.58983) (xy 189.189872 -109.5404)
			(xy 189.181742 -109.489065) (xy 189.042292 -109.489065) (xy 189.034162 -109.5404) (xy 189.018101 -109.58983)
			(xy 188.994505 -109.63614) (xy 188.963955 -109.678188) (xy 188.927204 -109.714939) (xy 188.885156 -109.745489)
			(xy 188.838846 -109.769085) (xy 188.789416 -109.785146) (xy 188.738081 -109.793276) (xy 188.686107 -109.793276)
			(xy 188.634772 -109.785146) (xy 188.585342 -109.769085) (xy 188.539032 -109.745489) (xy 188.496984 -109.714939)
			(xy 188.460233 -109.678188) (xy 188.429683 -109.63614) (xy 188.406087 -109.58983) (xy 188.390026 -109.5404)
			(xy 188.381896 -109.489065) (xy 188.242192 -109.489065) (xy 188.234062 -109.5404) (xy 188.218001 -109.58983)
			(xy 188.194405 -109.63614) (xy 188.163855 -109.678188) (xy 188.127104 -109.714939) (xy 188.085056 -109.745489)
			(xy 188.038746 -109.769085) (xy 187.989316 -109.785146) (xy 187.937981 -109.793276) (xy 187.886007 -109.793276)
			(xy 187.834672 -109.785146) (xy 187.785242 -109.769085) (xy 187.738932 -109.745489) (xy 187.696884 -109.714939)
			(xy 187.660133 -109.678188) (xy 187.629583 -109.63614) (xy 187.605987 -109.58983) (xy 187.589926 -109.5404)
			(xy 187.581796 -109.489065) (xy 187.442092 -109.489065) (xy 187.433962 -109.5404) (xy 187.417901 -109.58983)
			(xy 187.394305 -109.63614) (xy 187.363755 -109.678188) (xy 187.327004 -109.714939) (xy 187.284956 -109.745489)
			(xy 187.238646 -109.769085) (xy 187.189216 -109.785146) (xy 187.137881 -109.793276) (xy 187.085907 -109.793276)
			(xy 187.034572 -109.785146) (xy 186.985142 -109.769085) (xy 186.938832 -109.745489) (xy 186.896784 -109.714939)
			(xy 186.860033 -109.678188) (xy 186.829483 -109.63614) (xy 186.805887 -109.58983) (xy 186.789826 -109.5404)
			(xy 186.781696 -109.489065) (xy 186.642246 -109.489065) (xy 186.634116 -109.5404) (xy 186.618055 -109.58983)
			(xy 186.594459 -109.63614) (xy 186.563909 -109.678188) (xy 186.527158 -109.714939) (xy 186.48511 -109.745489)
			(xy 186.4388 -109.769085) (xy 186.38937 -109.785146) (xy 186.338035 -109.793276) (xy 186.286061 -109.793276)
			(xy 186.234726 -109.785146) (xy 186.185296 -109.769085) (xy 186.138986 -109.745489) (xy 186.096938 -109.714939)
			(xy 186.060187 -109.678188) (xy 186.029637 -109.63614) (xy 186.006041 -109.58983) (xy 185.98998 -109.5404)
			(xy 185.98185 -109.489065) (xy 185.062366 -109.489065) (xy 185.054236 -109.5404) (xy 185.038175 -109.58983)
			(xy 185.014579 -109.63614) (xy 184.984029 -109.678188) (xy 184.947278 -109.714939) (xy 184.90523 -109.745489)
			(xy 184.85892 -109.769085) (xy 184.80949 -109.785146) (xy 184.758155 -109.793276) (xy 184.706181 -109.793276)
			(xy 184.654846 -109.785146) (xy 184.605416 -109.769085) (xy 184.559106 -109.745489) (xy 184.517058 -109.714939)
			(xy 184.480307 -109.678188) (xy 184.449757 -109.63614) (xy 184.426161 -109.58983) (xy 184.4101 -109.5404)
			(xy 184.40197 -109.489065) (xy 184.26252 -109.489065) (xy 184.25439 -109.5404) (xy 184.238329 -109.58983)
			(xy 184.214733 -109.63614) (xy 184.184183 -109.678188) (xy 184.147432 -109.714939) (xy 184.105384 -109.745489)
			(xy 184.059074 -109.769085) (xy 184.009644 -109.785146) (xy 183.958309 -109.793276) (xy 183.906335 -109.793276)
			(xy 183.855 -109.785146) (xy 183.80557 -109.769085) (xy 183.75926 -109.745489) (xy 183.717212 -109.714939)
			(xy 183.680461 -109.678188) (xy 183.649911 -109.63614) (xy 183.626315 -109.58983) (xy 183.610254 -109.5404)
			(xy 183.602124 -109.489065) (xy 183.46242 -109.489065) (xy 183.45429 -109.5404) (xy 183.438229 -109.58983)
			(xy 183.414633 -109.63614) (xy 183.384083 -109.678188) (xy 183.347332 -109.714939) (xy 183.305284 -109.745489)
			(xy 183.258974 -109.769085) (xy 183.209544 -109.785146) (xy 183.158209 -109.793276) (xy 183.106235 -109.793276)
			(xy 183.0549 -109.785146) (xy 183.00547 -109.769085) (xy 182.95916 -109.745489) (xy 182.917112 -109.714939)
			(xy 182.880361 -109.678188) (xy 182.849811 -109.63614) (xy 182.826215 -109.58983) (xy 182.810154 -109.5404)
			(xy 182.802024 -109.489065) (xy 182.66232 -109.489065) (xy 182.65419 -109.5404) (xy 182.638129 -109.58983)
			(xy 182.614533 -109.63614) (xy 182.583983 -109.678188) (xy 182.547232 -109.714939) (xy 182.505184 -109.745489)
			(xy 182.458874 -109.769085) (xy 182.409444 -109.785146) (xy 182.358109 -109.793276) (xy 182.306135 -109.793276)
			(xy 182.2548 -109.785146) (xy 182.20537 -109.769085) (xy 182.15906 -109.745489) (xy 182.117012 -109.714939)
			(xy 182.080261 -109.678188) (xy 182.049711 -109.63614) (xy 182.026115 -109.58983) (xy 182.010054 -109.5404)
			(xy 182.001924 -109.489065) (xy 181.862474 -109.489065) (xy 181.854344 -109.5404) (xy 181.838283 -109.58983)
			(xy 181.814687 -109.63614) (xy 181.784137 -109.678188) (xy 181.747386 -109.714939) (xy 181.705338 -109.745489)
			(xy 181.659028 -109.769085) (xy 181.609598 -109.785146) (xy 181.558263 -109.793276) (xy 181.506289 -109.793276)
			(xy 181.454954 -109.785146) (xy 181.405524 -109.769085) (xy 181.359214 -109.745489) (xy 181.317166 -109.714939)
			(xy 181.280415 -109.678188) (xy 181.249865 -109.63614) (xy 181.226269 -109.58983) (xy 181.210208 -109.5404)
			(xy 181.202078 -109.489065) (xy 181.062374 -109.489065) (xy 181.054244 -109.5404) (xy 181.038183 -109.58983)
			(xy 181.014587 -109.63614) (xy 180.984037 -109.678188) (xy 180.947286 -109.714939) (xy 180.905238 -109.745489)
			(xy 180.858928 -109.769085) (xy 180.809498 -109.785146) (xy 180.758163 -109.793276) (xy 180.706189 -109.793276)
			(xy 180.654854 -109.785146) (xy 180.605424 -109.769085) (xy 180.559114 -109.745489) (xy 180.517066 -109.714939)
			(xy 180.480315 -109.678188) (xy 180.449765 -109.63614) (xy 180.426169 -109.58983) (xy 180.410108 -109.5404)
			(xy 180.401978 -109.489065) (xy 180.262528 -109.489065) (xy 180.254398 -109.5404) (xy 180.238337 -109.58983)
			(xy 180.214741 -109.63614) (xy 180.184191 -109.678188) (xy 180.14744 -109.714939) (xy 180.105392 -109.745489)
			(xy 180.059082 -109.769085) (xy 180.009652 -109.785146) (xy 179.958317 -109.793276) (xy 179.906343 -109.793276)
			(xy 179.855008 -109.785146) (xy 179.805578 -109.769085) (xy 179.759268 -109.745489) (xy 179.71722 -109.714939)
			(xy 179.680469 -109.678188) (xy 179.649919 -109.63614) (xy 179.626323 -109.58983) (xy 179.610262 -109.5404)
			(xy 179.602132 -109.489065) (xy 179.462428 -109.489065) (xy 179.454298 -109.5404) (xy 179.438237 -109.58983)
			(xy 179.414641 -109.63614) (xy 179.384091 -109.678188) (xy 179.34734 -109.714939) (xy 179.305292 -109.745489)
			(xy 179.258982 -109.769085) (xy 179.209552 -109.785146) (xy 179.158217 -109.793276) (xy 179.106243 -109.793276)
			(xy 179.054908 -109.785146) (xy 179.005478 -109.769085) (xy 178.959168 -109.745489) (xy 178.91712 -109.714939)
			(xy 178.880369 -109.678188) (xy 178.849819 -109.63614) (xy 178.826223 -109.58983) (xy 178.810162 -109.5404)
			(xy 178.802032 -109.489065) (xy 178.662328 -109.489065) (xy 178.654198 -109.5404) (xy 178.638137 -109.58983)
			(xy 178.614541 -109.63614) (xy 178.583991 -109.678188) (xy 178.54724 -109.714939) (xy 178.505192 -109.745489)
			(xy 178.458882 -109.769085) (xy 178.409452 -109.785146) (xy 178.358117 -109.793276) (xy 178.306143 -109.793276)
			(xy 178.254808 -109.785146) (xy 178.205378 -109.769085) (xy 178.159068 -109.745489) (xy 178.11702 -109.714939)
			(xy 178.080269 -109.678188) (xy 178.049719 -109.63614) (xy 178.026123 -109.58983) (xy 178.010062 -109.5404)
			(xy 178.001932 -109.489065) (xy 177.862482 -109.489065) (xy 177.854352 -109.5404) (xy 177.838291 -109.58983)
			(xy 177.814695 -109.63614) (xy 177.784145 -109.678188) (xy 177.747394 -109.714939) (xy 177.705346 -109.745489)
			(xy 177.659036 -109.769085) (xy 177.609606 -109.785146) (xy 177.558271 -109.793276) (xy 177.506297 -109.793276)
			(xy 177.454962 -109.785146) (xy 177.405532 -109.769085) (xy 177.359222 -109.745489) (xy 177.317174 -109.714939)
			(xy 177.280423 -109.678188) (xy 177.249873 -109.63614) (xy 177.226277 -109.58983) (xy 177.210216 -109.5404)
			(xy 177.202086 -109.489065) (xy 177.062382 -109.489065) (xy 177.054252 -109.5404) (xy 177.038191 -109.58983)
			(xy 177.014595 -109.63614) (xy 176.984045 -109.678188) (xy 176.947294 -109.714939) (xy 176.905246 -109.745489)
			(xy 176.858936 -109.769085) (xy 176.809506 -109.785146) (xy 176.758171 -109.793276) (xy 176.706197 -109.793276)
			(xy 176.654862 -109.785146) (xy 176.605432 -109.769085) (xy 176.559122 -109.745489) (xy 176.517074 -109.714939)
			(xy 176.480323 -109.678188) (xy 176.449773 -109.63614) (xy 176.426177 -109.58983) (xy 176.410116 -109.5404)
			(xy 176.401986 -109.489065) (xy 170.588214 -109.489065) (xy 170.583476 -109.496041) (xy 170.543639 -109.541841)
			(xy 170.498633 -109.582574) (xy 170.474132 -109.600492) (xy 170.468798 -109.604556) (xy 170.462194 -109.611922)
			(xy 170.44797 -109.638338) (xy 170.445388 -109.643765) (xy 170.442565 -109.655445) (xy 170.442382 -109.661452)
			(xy 170.442382 -109.72038) (xy 170.442596 -109.72661) (xy 170.445684 -109.738683) (xy 170.448478 -109.744256)
			(xy 170.459146 -109.764322) (xy 170.46575 -109.774228) (xy 170.469306 -109.778038) (xy 170.474386 -109.781594)
			(xy 170.499546 -109.800054) (xy 170.545611 -109.842153) (xy 170.586183 -109.889569) (xy 170.620652 -109.94159)
			(xy 170.648501 -109.997435) (xy 170.669312 -110.056268) (xy 170.682773 -110.117203) (xy 170.688681 -110.179327)
			(xy 170.686948 -110.241707) (xy 170.679796 -110.288911) (xy 178.001932 -110.288911) (xy 178.001932 -110.236937)
			(xy 178.010062 -110.185602) (xy 178.026123 -110.136172) (xy 178.049719 -110.089862) (xy 178.080269 -110.047814)
			(xy 178.11702 -110.011063) (xy 178.159068 -109.980513) (xy 178.205378 -109.956917) (xy 178.254808 -109.940856)
			(xy 178.306143 -109.932726) (xy 178.358117 -109.932726) (xy 178.409452 -109.940856) (xy 178.458882 -109.956917)
			(xy 178.505192 -109.980513) (xy 178.54724 -110.011063) (xy 178.583991 -110.047814) (xy 178.614541 -110.089862)
			(xy 178.638137 -110.136172) (xy 178.654198 -110.185602) (xy 178.662328 -110.236937) (xy 178.662838 -110.262924)
			(xy 178.662328 -110.288911) (xy 178.802032 -110.288911) (xy 178.802032 -110.236937) (xy 178.810162 -110.185602)
			(xy 178.826223 -110.136172) (xy 178.849819 -110.089862) (xy 178.880369 -110.047814) (xy 178.91712 -110.011063)
			(xy 178.959168 -109.980513) (xy 179.005478 -109.956917) (xy 179.054908 -109.940856) (xy 179.106243 -109.932726)
			(xy 179.158217 -109.932726) (xy 179.209552 -109.940856) (xy 179.258982 -109.956917) (xy 179.305292 -109.980513)
			(xy 179.34734 -110.011063) (xy 179.384091 -110.047814) (xy 179.414641 -110.089862) (xy 179.438237 -110.136172)
			(xy 179.454298 -110.185602) (xy 179.462428 -110.236937) (xy 179.462938 -110.262924) (xy 179.462428 -110.288911)
			(xy 179.602132 -110.288911) (xy 179.602132 -110.236937) (xy 179.610262 -110.185602) (xy 179.626323 -110.136172)
			(xy 179.649919 -110.089862) (xy 179.680469 -110.047814) (xy 179.71722 -110.011063) (xy 179.759268 -109.980513)
			(xy 179.805578 -109.956917) (xy 179.855008 -109.940856) (xy 179.906343 -109.932726) (xy 179.958317 -109.932726)
			(xy 180.009652 -109.940856) (xy 180.059082 -109.956917) (xy 180.105392 -109.980513) (xy 180.14744 -110.011063)
			(xy 180.184191 -110.047814) (xy 180.214741 -110.089862) (xy 180.238337 -110.136172) (xy 180.254398 -110.185602)
			(xy 180.262528 -110.236937) (xy 180.263038 -110.262924) (xy 180.262528 -110.288911) (xy 180.401978 -110.288911)
			(xy 180.401978 -110.236937) (xy 180.410108 -110.185602) (xy 180.426169 -110.136172) (xy 180.449765 -110.089862)
			(xy 180.480315 -110.047814) (xy 180.517066 -110.011063) (xy 180.559114 -109.980513) (xy 180.605424 -109.956917)
			(xy 180.654854 -109.940856) (xy 180.706189 -109.932726) (xy 180.758163 -109.932726) (xy 180.809498 -109.940856)
			(xy 180.858928 -109.956917) (xy 180.905238 -109.980513) (xy 180.947286 -110.011063) (xy 180.984037 -110.047814)
			(xy 181.014587 -110.089862) (xy 181.038183 -110.136172) (xy 181.054244 -110.185602) (xy 181.062374 -110.236937)
			(xy 181.062884 -110.262924) (xy 181.062374 -110.288911) (xy 181.202078 -110.288911) (xy 181.202078 -110.236937)
			(xy 181.210208 -110.185602) (xy 181.226269 -110.136172) (xy 181.249865 -110.089862) (xy 181.280415 -110.047814)
			(xy 181.317166 -110.011063) (xy 181.359214 -109.980513) (xy 181.405524 -109.956917) (xy 181.454954 -109.940856)
			(xy 181.506289 -109.932726) (xy 181.558263 -109.932726) (xy 181.609598 -109.940856) (xy 181.659028 -109.956917)
			(xy 181.705338 -109.980513) (xy 181.747386 -110.011063) (xy 181.784137 -110.047814) (xy 181.814687 -110.089862)
			(xy 181.838283 -110.136172) (xy 181.854344 -110.185602) (xy 181.862474 -110.236937) (xy 181.862984 -110.262924)
			(xy 181.862474 -110.288911) (xy 182.001924 -110.288911) (xy 182.001924 -110.236937) (xy 182.010054 -110.185602)
			(xy 182.026115 -110.136172) (xy 182.049711 -110.089862) (xy 182.080261 -110.047814) (xy 182.117012 -110.011063)
			(xy 182.15906 -109.980513) (xy 182.20537 -109.956917) (xy 182.2548 -109.940856) (xy 182.306135 -109.932726)
			(xy 182.358109 -109.932726) (xy 182.409444 -109.940856) (xy 182.458874 -109.956917) (xy 182.505184 -109.980513)
			(xy 182.547232 -110.011063) (xy 182.583983 -110.047814) (xy 182.614533 -110.089862) (xy 182.638129 -110.136172)
			(xy 182.65419 -110.185602) (xy 182.66232 -110.236937) (xy 182.66283 -110.262924) (xy 182.66232 -110.288911)
			(xy 182.802024 -110.288911) (xy 182.802024 -110.236937) (xy 182.810154 -110.185602) (xy 182.826215 -110.136172)
			(xy 182.849811 -110.089862) (xy 182.880361 -110.047814) (xy 182.917112 -110.011063) (xy 182.95916 -109.980513)
			(xy 183.00547 -109.956917) (xy 183.0549 -109.940856) (xy 183.106235 -109.932726) (xy 183.158209 -109.932726)
			(xy 183.209544 -109.940856) (xy 183.258974 -109.956917) (xy 183.305284 -109.980513) (xy 183.347332 -110.011063)
			(xy 183.384083 -110.047814) (xy 183.414633 -110.089862) (xy 183.438229 -110.136172) (xy 183.45429 -110.185602)
			(xy 183.46242 -110.236937) (xy 183.46293 -110.262924) (xy 183.46242 -110.288911) (xy 183.602124 -110.288911)
			(xy 183.602124 -110.236937) (xy 183.610254 -110.185602) (xy 183.626315 -110.136172) (xy 183.649911 -110.089862)
			(xy 183.680461 -110.047814) (xy 183.717212 -110.011063) (xy 183.75926 -109.980513) (xy 183.80557 -109.956917)
			(xy 183.855 -109.940856) (xy 183.906335 -109.932726) (xy 183.958309 -109.932726) (xy 184.009644 -109.940856)
			(xy 184.059074 -109.956917) (xy 184.105384 -109.980513) (xy 184.147432 -110.011063) (xy 184.184183 -110.047814)
			(xy 184.214733 -110.089862) (xy 184.238329 -110.136172) (xy 184.25439 -110.185602) (xy 184.26252 -110.236937)
			(xy 184.26303 -110.262924) (xy 184.26252 -110.288911) (xy 184.40197 -110.288911) (xy 184.40197 -110.236937)
			(xy 184.4101 -110.185602) (xy 184.426161 -110.136172) (xy 184.449757 -110.089862) (xy 184.480307 -110.047814)
			(xy 184.517058 -110.011063) (xy 184.559106 -109.980513) (xy 184.605416 -109.956917) (xy 184.654846 -109.940856)
			(xy 184.706181 -109.932726) (xy 184.758155 -109.932726) (xy 184.80949 -109.940856) (xy 184.85892 -109.956917)
			(xy 184.90523 -109.980513) (xy 184.947278 -110.011063) (xy 184.984029 -110.047814) (xy 185.014579 -110.089862)
			(xy 185.038175 -110.136172) (xy 185.054236 -110.185602) (xy 185.062366 -110.236937) (xy 185.062876 -110.262924)
			(xy 185.062366 -110.288911) (xy 185.98185 -110.288911) (xy 185.98185 -110.236937) (xy 185.98998 -110.185602)
			(xy 186.006041 -110.136172) (xy 186.029637 -110.089862) (xy 186.060187 -110.047814) (xy 186.096938 -110.011063)
			(xy 186.138986 -109.980513) (xy 186.185296 -109.956917) (xy 186.234726 -109.940856) (xy 186.286061 -109.932726)
			(xy 186.338035 -109.932726) (xy 186.38937 -109.940856) (xy 186.4388 -109.956917) (xy 186.48511 -109.980513)
			(xy 186.527158 -110.011063) (xy 186.563909 -110.047814) (xy 186.594459 -110.089862) (xy 186.618055 -110.136172)
			(xy 186.634116 -110.185602) (xy 186.642246 -110.236937) (xy 186.642756 -110.262924) (xy 186.642246 -110.288911)
			(xy 186.781696 -110.288911) (xy 186.781696 -110.236937) (xy 186.789826 -110.185602) (xy 186.805887 -110.136172)
			(xy 186.829483 -110.089862) (xy 186.860033 -110.047814) (xy 186.896784 -110.011063) (xy 186.938832 -109.980513)
			(xy 186.985142 -109.956917) (xy 187.034572 -109.940856) (xy 187.085907 -109.932726) (xy 187.137881 -109.932726)
			(xy 187.189216 -109.940856) (xy 187.238646 -109.956917) (xy 187.284956 -109.980513) (xy 187.327004 -110.011063)
			(xy 187.363755 -110.047814) (xy 187.394305 -110.089862) (xy 187.417901 -110.136172) (xy 187.433962 -110.185602)
			(xy 187.442092 -110.236937) (xy 187.442602 -110.262924) (xy 187.442092 -110.288911) (xy 187.581796 -110.288911)
			(xy 187.581796 -110.236937) (xy 187.589926 -110.185602) (xy 187.605987 -110.136172) (xy 187.629583 -110.089862)
			(xy 187.660133 -110.047814) (xy 187.696884 -110.011063) (xy 187.738932 -109.980513) (xy 187.785242 -109.956917)
			(xy 187.834672 -109.940856) (xy 187.886007 -109.932726) (xy 187.937981 -109.932726) (xy 187.989316 -109.940856)
			(xy 188.038746 -109.956917) (xy 188.085056 -109.980513) (xy 188.127104 -110.011063) (xy 188.163855 -110.047814)
			(xy 188.194405 -110.089862) (xy 188.218001 -110.136172) (xy 188.234062 -110.185602) (xy 188.242192 -110.236937)
			(xy 188.242702 -110.262924) (xy 188.242192 -110.288911) (xy 188.381896 -110.288911) (xy 188.381896 -110.236937)
			(xy 188.390026 -110.185602) (xy 188.406087 -110.136172) (xy 188.429683 -110.089862) (xy 188.460233 -110.047814)
			(xy 188.496984 -110.011063) (xy 188.539032 -109.980513) (xy 188.585342 -109.956917) (xy 188.634772 -109.940856)
			(xy 188.686107 -109.932726) (xy 188.738081 -109.932726) (xy 188.789416 -109.940856) (xy 188.838846 -109.956917)
			(xy 188.885156 -109.980513) (xy 188.927204 -110.011063) (xy 188.963955 -110.047814) (xy 188.994505 -110.089862)
			(xy 189.018101 -110.136172) (xy 189.034162 -110.185602) (xy 189.042292 -110.236937) (xy 189.042802 -110.262924)
			(xy 189.042292 -110.288911) (xy 189.181742 -110.288911) (xy 189.181742 -110.236937) (xy 189.189872 -110.185602)
			(xy 189.205933 -110.136172) (xy 189.229529 -110.089862) (xy 189.260079 -110.047814) (xy 189.29683 -110.011063)
			(xy 189.338878 -109.980513) (xy 189.385188 -109.956917) (xy 189.434618 -109.940856) (xy 189.485953 -109.932726)
			(xy 189.537927 -109.932726) (xy 189.589262 -109.940856) (xy 189.638692 -109.956917) (xy 189.685002 -109.980513)
			(xy 189.72705 -110.011063) (xy 189.763801 -110.047814) (xy 189.794351 -110.089862) (xy 189.817947 -110.136172)
			(xy 189.834008 -110.185602) (xy 189.842138 -110.236937) (xy 189.842648 -110.262924) (xy 189.842138 -110.288911)
			(xy 189.981842 -110.288911) (xy 189.981842 -110.236937) (xy 189.989972 -110.185602) (xy 190.006033 -110.136172)
			(xy 190.029629 -110.089862) (xy 190.060179 -110.047814) (xy 190.09693 -110.011063) (xy 190.138978 -109.980513)
			(xy 190.185288 -109.956917) (xy 190.234718 -109.940856) (xy 190.286053 -109.932726) (xy 190.338027 -109.932726)
			(xy 190.389362 -109.940856) (xy 190.438792 -109.956917) (xy 190.485102 -109.980513) (xy 190.52715 -110.011063)
			(xy 190.563901 -110.047814) (xy 190.594451 -110.089862) (xy 190.618047 -110.136172) (xy 190.634108 -110.185602)
			(xy 190.642238 -110.236937) (xy 190.642748 -110.262924) (xy 190.642238 -110.288911) (xy 190.781688 -110.288911)
			(xy 190.781688 -110.236937) (xy 190.789818 -110.185602) (xy 190.805879 -110.136172) (xy 190.829475 -110.089862)
			(xy 190.860025 -110.047814) (xy 190.896776 -110.011063) (xy 190.938824 -109.980513) (xy 190.985134 -109.956917)
			(xy 191.034564 -109.940856) (xy 191.085899 -109.932726) (xy 191.137873 -109.932726) (xy 191.189208 -109.940856)
			(xy 191.238638 -109.956917) (xy 191.284948 -109.980513) (xy 191.326996 -110.011063) (xy 191.363747 -110.047814)
			(xy 191.394297 -110.089862) (xy 191.417893 -110.136172) (xy 191.433954 -110.185602) (xy 191.442084 -110.236937)
			(xy 191.442594 -110.262924) (xy 191.442084 -110.288911) (xy 191.581788 -110.288911) (xy 191.581788 -110.236937)
			(xy 191.589918 -110.185602) (xy 191.605979 -110.136172) (xy 191.629575 -110.089862) (xy 191.660125 -110.047814)
			(xy 191.696876 -110.011063) (xy 191.738924 -109.980513) (xy 191.785234 -109.956917) (xy 191.834664 -109.940856)
			(xy 191.885999 -109.932726) (xy 191.937973 -109.932726) (xy 191.989308 -109.940856) (xy 192.038738 -109.956917)
			(xy 192.085048 -109.980513) (xy 192.127096 -110.011063) (xy 192.163847 -110.047814) (xy 192.194397 -110.089862)
			(xy 192.217993 -110.136172) (xy 192.234054 -110.185602) (xy 192.242184 -110.236937) (xy 192.242694 -110.262924)
			(xy 192.242184 -110.288911) (xy 192.234054 -110.340246) (xy 192.217993 -110.389676) (xy 192.194397 -110.435986)
			(xy 192.163847 -110.478034) (xy 192.127096 -110.514785) (xy 192.085048 -110.545335) (xy 192.038738 -110.568931)
			(xy 191.989308 -110.584992) (xy 191.937973 -110.593122) (xy 191.885999 -110.593122) (xy 191.834664 -110.584992)
			(xy 191.785234 -110.568931) (xy 191.738924 -110.545335) (xy 191.696876 -110.514785) (xy 191.660125 -110.478034)
			(xy 191.629575 -110.435986) (xy 191.605979 -110.389676) (xy 191.589918 -110.340246) (xy 191.581788 -110.288911)
			(xy 191.442084 -110.288911) (xy 191.433954 -110.340246) (xy 191.417893 -110.389676) (xy 191.394297 -110.435986)
			(xy 191.363747 -110.478034) (xy 191.326996 -110.514785) (xy 191.284948 -110.545335) (xy 191.238638 -110.568931)
			(xy 191.189208 -110.584992) (xy 191.137873 -110.593122) (xy 191.085899 -110.593122) (xy 191.034564 -110.584992)
			(xy 190.985134 -110.568931) (xy 190.938824 -110.545335) (xy 190.896776 -110.514785) (xy 190.860025 -110.478034)
			(xy 190.829475 -110.435986) (xy 190.805879 -110.389676) (xy 190.789818 -110.340246) (xy 190.781688 -110.288911)
			(xy 190.642238 -110.288911) (xy 190.634108 -110.340246) (xy 190.618047 -110.389676) (xy 190.594451 -110.435986)
			(xy 190.563901 -110.478034) (xy 190.52715 -110.514785) (xy 190.485102 -110.545335) (xy 190.438792 -110.568931)
			(xy 190.389362 -110.584992) (xy 190.338027 -110.593122) (xy 190.286053 -110.593122) (xy 190.234718 -110.584992)
			(xy 190.185288 -110.568931) (xy 190.138978 -110.545335) (xy 190.09693 -110.514785) (xy 190.060179 -110.478034)
			(xy 190.029629 -110.435986) (xy 190.006033 -110.389676) (xy 189.989972 -110.340246) (xy 189.981842 -110.288911)
			(xy 189.842138 -110.288911) (xy 189.834008 -110.340246) (xy 189.817947 -110.389676) (xy 189.794351 -110.435986)
			(xy 189.763801 -110.478034) (xy 189.72705 -110.514785) (xy 189.685002 -110.545335) (xy 189.638692 -110.568931)
			(xy 189.589262 -110.584992) (xy 189.537927 -110.593122) (xy 189.485953 -110.593122) (xy 189.434618 -110.584992)
			(xy 189.385188 -110.568931) (xy 189.338878 -110.545335) (xy 189.29683 -110.514785) (xy 189.260079 -110.478034)
			(xy 189.229529 -110.435986) (xy 189.205933 -110.389676) (xy 189.189872 -110.340246) (xy 189.181742 -110.288911)
			(xy 189.042292 -110.288911) (xy 189.034162 -110.340246) (xy 189.018101 -110.389676) (xy 188.994505 -110.435986)
			(xy 188.963955 -110.478034) (xy 188.927204 -110.514785) (xy 188.885156 -110.545335) (xy 188.838846 -110.568931)
			(xy 188.789416 -110.584992) (xy 188.738081 -110.593122) (xy 188.686107 -110.593122) (xy 188.634772 -110.584992)
			(xy 188.585342 -110.568931) (xy 188.539032 -110.545335) (xy 188.496984 -110.514785) (xy 188.460233 -110.478034)
			(xy 188.429683 -110.435986) (xy 188.406087 -110.389676) (xy 188.390026 -110.340246) (xy 188.381896 -110.288911)
			(xy 188.242192 -110.288911) (xy 188.234062 -110.340246) (xy 188.218001 -110.389676) (xy 188.194405 -110.435986)
			(xy 188.163855 -110.478034) (xy 188.127104 -110.514785) (xy 188.085056 -110.545335) (xy 188.038746 -110.568931)
			(xy 187.989316 -110.584992) (xy 187.937981 -110.593122) (xy 187.886007 -110.593122) (xy 187.834672 -110.584992)
			(xy 187.785242 -110.568931) (xy 187.738932 -110.545335) (xy 187.696884 -110.514785) (xy 187.660133 -110.478034)
			(xy 187.629583 -110.435986) (xy 187.605987 -110.389676) (xy 187.589926 -110.340246) (xy 187.581796 -110.288911)
			(xy 187.442092 -110.288911) (xy 187.433962 -110.340246) (xy 187.417901 -110.389676) (xy 187.394305 -110.435986)
			(xy 187.363755 -110.478034) (xy 187.327004 -110.514785) (xy 187.284956 -110.545335) (xy 187.238646 -110.568931)
			(xy 187.189216 -110.584992) (xy 187.137881 -110.593122) (xy 187.085907 -110.593122) (xy 187.034572 -110.584992)
			(xy 186.985142 -110.568931) (xy 186.938832 -110.545335) (xy 186.896784 -110.514785) (xy 186.860033 -110.478034)
			(xy 186.829483 -110.435986) (xy 186.805887 -110.389676) (xy 186.789826 -110.340246) (xy 186.781696 -110.288911)
			(xy 186.642246 -110.288911) (xy 186.634116 -110.340246) (xy 186.618055 -110.389676) (xy 186.594459 -110.435986)
			(xy 186.563909 -110.478034) (xy 186.527158 -110.514785) (xy 186.48511 -110.545335) (xy 186.4388 -110.568931)
			(xy 186.38937 -110.584992) (xy 186.338035 -110.593122) (xy 186.286061 -110.593122) (xy 186.234726 -110.584992)
			(xy 186.185296 -110.568931) (xy 186.138986 -110.545335) (xy 186.096938 -110.514785) (xy 186.060187 -110.478034)
			(xy 186.029637 -110.435986) (xy 186.006041 -110.389676) (xy 185.98998 -110.340246) (xy 185.98185 -110.288911)
			(xy 185.062366 -110.288911) (xy 185.054236 -110.340246) (xy 185.038175 -110.389676) (xy 185.014579 -110.435986)
			(xy 184.984029 -110.478034) (xy 184.947278 -110.514785) (xy 184.90523 -110.545335) (xy 184.85892 -110.568931)
			(xy 184.80949 -110.584992) (xy 184.758155 -110.593122) (xy 184.706181 -110.593122) (xy 184.654846 -110.584992)
			(xy 184.605416 -110.568931) (xy 184.559106 -110.545335) (xy 184.517058 -110.514785) (xy 184.480307 -110.478034)
			(xy 184.449757 -110.435986) (xy 184.426161 -110.389676) (xy 184.4101 -110.340246) (xy 184.40197 -110.288911)
			(xy 184.26252 -110.288911) (xy 184.25439 -110.340246) (xy 184.238329 -110.389676) (xy 184.214733 -110.435986)
			(xy 184.184183 -110.478034) (xy 184.147432 -110.514785) (xy 184.105384 -110.545335) (xy 184.059074 -110.568931)
			(xy 184.009644 -110.584992) (xy 183.958309 -110.593122) (xy 183.906335 -110.593122) (xy 183.855 -110.584992)
			(xy 183.80557 -110.568931) (xy 183.75926 -110.545335) (xy 183.717212 -110.514785) (xy 183.680461 -110.478034)
			(xy 183.649911 -110.435986) (xy 183.626315 -110.389676) (xy 183.610254 -110.340246) (xy 183.602124 -110.288911)
			(xy 183.46242 -110.288911) (xy 183.45429 -110.340246) (xy 183.438229 -110.389676) (xy 183.414633 -110.435986)
			(xy 183.384083 -110.478034) (xy 183.347332 -110.514785) (xy 183.305284 -110.545335) (xy 183.258974 -110.568931)
			(xy 183.209544 -110.584992) (xy 183.158209 -110.593122) (xy 183.106235 -110.593122) (xy 183.0549 -110.584992)
			(xy 183.00547 -110.568931) (xy 182.95916 -110.545335) (xy 182.917112 -110.514785) (xy 182.880361 -110.478034)
			(xy 182.849811 -110.435986) (xy 182.826215 -110.389676) (xy 182.810154 -110.340246) (xy 182.802024 -110.288911)
			(xy 182.66232 -110.288911) (xy 182.65419 -110.340246) (xy 182.638129 -110.389676) (xy 182.614533 -110.435986)
			(xy 182.583983 -110.478034) (xy 182.547232 -110.514785) (xy 182.505184 -110.545335) (xy 182.458874 -110.568931)
			(xy 182.409444 -110.584992) (xy 182.358109 -110.593122) (xy 182.306135 -110.593122) (xy 182.2548 -110.584992)
			(xy 182.20537 -110.568931) (xy 182.15906 -110.545335) (xy 182.117012 -110.514785) (xy 182.080261 -110.478034)
			(xy 182.049711 -110.435986) (xy 182.026115 -110.389676) (xy 182.010054 -110.340246) (xy 182.001924 -110.288911)
			(xy 181.862474 -110.288911) (xy 181.854344 -110.340246) (xy 181.838283 -110.389676) (xy 181.814687 -110.435986)
			(xy 181.784137 -110.478034) (xy 181.747386 -110.514785) (xy 181.705338 -110.545335) (xy 181.659028 -110.568931)
			(xy 181.609598 -110.584992) (xy 181.558263 -110.593122) (xy 181.506289 -110.593122) (xy 181.454954 -110.584992)
			(xy 181.405524 -110.568931) (xy 181.359214 -110.545335) (xy 181.317166 -110.514785) (xy 181.280415 -110.478034)
			(xy 181.249865 -110.435986) (xy 181.226269 -110.389676) (xy 181.210208 -110.340246) (xy 181.202078 -110.288911)
			(xy 181.062374 -110.288911) (xy 181.054244 -110.340246) (xy 181.038183 -110.389676) (xy 181.014587 -110.435986)
			(xy 180.984037 -110.478034) (xy 180.947286 -110.514785) (xy 180.905238 -110.545335) (xy 180.858928 -110.568931)
			(xy 180.809498 -110.584992) (xy 180.758163 -110.593122) (xy 180.706189 -110.593122) (xy 180.654854 -110.584992)
			(xy 180.605424 -110.568931) (xy 180.559114 -110.545335) (xy 180.517066 -110.514785) (xy 180.480315 -110.478034)
			(xy 180.449765 -110.435986) (xy 180.426169 -110.389676) (xy 180.410108 -110.340246) (xy 180.401978 -110.288911)
			(xy 180.262528 -110.288911) (xy 180.254398 -110.340246) (xy 180.238337 -110.389676) (xy 180.214741 -110.435986)
			(xy 180.184191 -110.478034) (xy 180.14744 -110.514785) (xy 180.105392 -110.545335) (xy 180.059082 -110.568931)
			(xy 180.009652 -110.584992) (xy 179.958317 -110.593122) (xy 179.906343 -110.593122) (xy 179.855008 -110.584992)
			(xy 179.805578 -110.568931) (xy 179.759268 -110.545335) (xy 179.71722 -110.514785) (xy 179.680469 -110.478034)
			(xy 179.649919 -110.435986) (xy 179.626323 -110.389676) (xy 179.610262 -110.340246) (xy 179.602132 -110.288911)
			(xy 179.462428 -110.288911) (xy 179.454298 -110.340246) (xy 179.438237 -110.389676) (xy 179.414641 -110.435986)
			(xy 179.384091 -110.478034) (xy 179.34734 -110.514785) (xy 179.305292 -110.545335) (xy 179.258982 -110.568931)
			(xy 179.209552 -110.584992) (xy 179.158217 -110.593122) (xy 179.106243 -110.593122) (xy 179.054908 -110.584992)
			(xy 179.005478 -110.568931) (xy 178.959168 -110.545335) (xy 178.91712 -110.514785) (xy 178.880369 -110.478034)
			(xy 178.849819 -110.435986) (xy 178.826223 -110.389676) (xy 178.810162 -110.340246) (xy 178.802032 -110.288911)
			(xy 178.662328 -110.288911) (xy 178.654198 -110.340246) (xy 178.638137 -110.389676) (xy 178.614541 -110.435986)
			(xy 178.583991 -110.478034) (xy 178.54724 -110.514785) (xy 178.505192 -110.545335) (xy 178.458882 -110.568931)
			(xy 178.409452 -110.584992) (xy 178.358117 -110.593122) (xy 178.306143 -110.593122) (xy 178.254808 -110.584992)
			(xy 178.205378 -110.568931) (xy 178.159068 -110.545335) (xy 178.11702 -110.514785) (xy 178.080269 -110.478034)
			(xy 178.049719 -110.435986) (xy 178.026123 -110.389676) (xy 178.010062 -110.340246) (xy 178.001932 -110.288911)
			(xy 170.679796 -110.288911) (xy 170.6776 -110.303408) (xy 170.660778 -110.363502) (xy 170.636733 -110.421088)
			(xy 170.605827 -110.475302) (xy 170.568523 -110.525329) (xy 170.525381 -110.570419) (xy 170.501564 -110.590584)
			(xy 170.491198 -110.598945) (xy 170.469723 -110.6147) (xy 170.458638 -110.62208) (xy 170.45212 -110.627424)
			(xy 170.442776 -110.64144) (xy 170.44035 -110.649512) (xy 170.438826 -110.66145) (xy 170.438826 -110.747302)
			(xy 170.44035 -110.75924) (xy 170.442821 -110.767392) (xy 170.452296 -110.781536) (xy 170.458892 -110.786926)
			(xy 170.484957 -110.804611) (xy 170.532934 -110.845425) (xy 170.57551 -110.891847) (xy 170.612032 -110.943168)
			(xy 170.641944 -110.998602) (xy 170.664788 -111.057303) (xy 170.672798 -111.089011) (xy 176.401986 -111.089011)
			(xy 176.401986 -111.037037) (xy 176.410116 -110.985702) (xy 176.426177 -110.936272) (xy 176.449773 -110.889962)
			(xy 176.480323 -110.847914) (xy 176.517074 -110.811163) (xy 176.559122 -110.780613) (xy 176.605432 -110.757017)
			(xy 176.654862 -110.740956) (xy 176.706197 -110.732826) (xy 176.758171 -110.732826) (xy 176.809506 -110.740956)
			(xy 176.858936 -110.757017) (xy 176.905246 -110.780613) (xy 176.947294 -110.811163) (xy 176.984045 -110.847914)
			(xy 177.014595 -110.889962) (xy 177.038191 -110.936272) (xy 177.054252 -110.985702) (xy 177.062382 -111.037037)
			(xy 177.062892 -111.063024) (xy 177.062382 -111.089011) (xy 177.202086 -111.089011) (xy 177.202086 -111.037037)
			(xy 177.210216 -110.985702) (xy 177.226277 -110.936272) (xy 177.249873 -110.889962) (xy 177.280423 -110.847914)
			(xy 177.317174 -110.811163) (xy 177.359222 -110.780613) (xy 177.405532 -110.757017) (xy 177.454962 -110.740956)
			(xy 177.506297 -110.732826) (xy 177.558271 -110.732826) (xy 177.609606 -110.740956) (xy 177.659036 -110.757017)
			(xy 177.705346 -110.780613) (xy 177.747394 -110.811163) (xy 177.784145 -110.847914) (xy 177.814695 -110.889962)
			(xy 177.838291 -110.936272) (xy 177.854352 -110.985702) (xy 177.862482 -111.037037) (xy 177.862992 -111.063024)
			(xy 177.862482 -111.089011) (xy 178.001932 -111.089011) (xy 178.001932 -111.037037) (xy 178.010062 -110.985702)
			(xy 178.026123 -110.936272) (xy 178.049719 -110.889962) (xy 178.080269 -110.847914) (xy 178.11702 -110.811163)
			(xy 178.159068 -110.780613) (xy 178.205378 -110.757017) (xy 178.254808 -110.740956) (xy 178.306143 -110.732826)
			(xy 178.358117 -110.732826) (xy 178.409452 -110.740956) (xy 178.458882 -110.757017) (xy 178.505192 -110.780613)
			(xy 178.54724 -110.811163) (xy 178.583991 -110.847914) (xy 178.614541 -110.889962) (xy 178.638137 -110.936272)
			(xy 178.654198 -110.985702) (xy 178.662328 -111.037037) (xy 178.662838 -111.063024) (xy 178.662328 -111.089011)
			(xy 178.802032 -111.089011) (xy 178.802032 -111.037037) (xy 178.810162 -110.985702) (xy 178.826223 -110.936272)
			(xy 178.849819 -110.889962) (xy 178.880369 -110.847914) (xy 178.91712 -110.811163) (xy 178.959168 -110.780613)
			(xy 179.005478 -110.757017) (xy 179.054908 -110.740956) (xy 179.106243 -110.732826) (xy 179.158217 -110.732826)
			(xy 179.209552 -110.740956) (xy 179.258982 -110.757017) (xy 179.305292 -110.780613) (xy 179.34734 -110.811163)
			(xy 179.384091 -110.847914) (xy 179.414641 -110.889962) (xy 179.438237 -110.936272) (xy 179.454298 -110.985702)
			(xy 179.462428 -111.037037) (xy 179.462938 -111.063024) (xy 179.462428 -111.089011) (xy 179.602132 -111.089011)
			(xy 179.602132 -111.037037) (xy 179.610262 -110.985702) (xy 179.626323 -110.936272) (xy 179.649919 -110.889962)
			(xy 179.680469 -110.847914) (xy 179.71722 -110.811163) (xy 179.759268 -110.780613) (xy 179.805578 -110.757017)
			(xy 179.855008 -110.740956) (xy 179.906343 -110.732826) (xy 179.958317 -110.732826) (xy 180.009652 -110.740956)
			(xy 180.059082 -110.757017) (xy 180.105392 -110.780613) (xy 180.14744 -110.811163) (xy 180.184191 -110.847914)
			(xy 180.214741 -110.889962) (xy 180.238337 -110.936272) (xy 180.254398 -110.985702) (xy 180.262528 -111.037037)
			(xy 180.263038 -111.063024) (xy 180.262528 -111.089011) (xy 180.401978 -111.089011) (xy 180.401978 -111.037037)
			(xy 180.410108 -110.985702) (xy 180.426169 -110.936272) (xy 180.449765 -110.889962) (xy 180.480315 -110.847914)
			(xy 180.517066 -110.811163) (xy 180.559114 -110.780613) (xy 180.605424 -110.757017) (xy 180.654854 -110.740956)
			(xy 180.706189 -110.732826) (xy 180.758163 -110.732826) (xy 180.809498 -110.740956) (xy 180.858928 -110.757017)
			(xy 180.905238 -110.780613) (xy 180.947286 -110.811163) (xy 180.984037 -110.847914) (xy 181.014587 -110.889962)
			(xy 181.038183 -110.936272) (xy 181.054244 -110.985702) (xy 181.062374 -111.037037) (xy 181.062884 -111.063024)
			(xy 181.062374 -111.089011) (xy 181.202078 -111.089011) (xy 181.202078 -111.037037) (xy 181.210208 -110.985702)
			(xy 181.226269 -110.936272) (xy 181.249865 -110.889962) (xy 181.280415 -110.847914) (xy 181.317166 -110.811163)
			(xy 181.359214 -110.780613) (xy 181.405524 -110.757017) (xy 181.454954 -110.740956) (xy 181.506289 -110.732826)
			(xy 181.558263 -110.732826) (xy 181.609598 -110.740956) (xy 181.659028 -110.757017) (xy 181.705338 -110.780613)
			(xy 181.747386 -110.811163) (xy 181.784137 -110.847914) (xy 181.814687 -110.889962) (xy 181.838283 -110.936272)
			(xy 181.854344 -110.985702) (xy 181.862474 -111.037037) (xy 181.862984 -111.063024) (xy 181.862474 -111.089011)
			(xy 182.001924 -111.089011) (xy 182.001924 -111.037037) (xy 182.010054 -110.985702) (xy 182.026115 -110.936272)
			(xy 182.049711 -110.889962) (xy 182.080261 -110.847914) (xy 182.117012 -110.811163) (xy 182.15906 -110.780613)
			(xy 182.20537 -110.757017) (xy 182.2548 -110.740956) (xy 182.306135 -110.732826) (xy 182.358109 -110.732826)
			(xy 182.409444 -110.740956) (xy 182.458874 -110.757017) (xy 182.505184 -110.780613) (xy 182.547232 -110.811163)
			(xy 182.583983 -110.847914) (xy 182.614533 -110.889962) (xy 182.638129 -110.936272) (xy 182.65419 -110.985702)
			(xy 182.66232 -111.037037) (xy 182.66283 -111.063024) (xy 182.66232 -111.089011) (xy 182.802024 -111.089011)
			(xy 182.802024 -111.037037) (xy 182.810154 -110.985702) (xy 182.826215 -110.936272) (xy 182.849811 -110.889962)
			(xy 182.880361 -110.847914) (xy 182.917112 -110.811163) (xy 182.95916 -110.780613) (xy 183.00547 -110.757017)
			(xy 183.0549 -110.740956) (xy 183.106235 -110.732826) (xy 183.158209 -110.732826) (xy 183.209544 -110.740956)
			(xy 183.258974 -110.757017) (xy 183.305284 -110.780613) (xy 183.347332 -110.811163) (xy 183.384083 -110.847914)
			(xy 183.414633 -110.889962) (xy 183.438229 -110.936272) (xy 183.45429 -110.985702) (xy 183.46242 -111.037037)
			(xy 183.46293 -111.063024) (xy 183.46242 -111.089011) (xy 183.602124 -111.089011) (xy 183.602124 -111.037037)
			(xy 183.610254 -110.985702) (xy 183.626315 -110.936272) (xy 183.649911 -110.889962) (xy 183.680461 -110.847914)
			(xy 183.717212 -110.811163) (xy 183.75926 -110.780613) (xy 183.80557 -110.757017) (xy 183.855 -110.740956)
			(xy 183.906335 -110.732826) (xy 183.958309 -110.732826) (xy 184.009644 -110.740956) (xy 184.059074 -110.757017)
			(xy 184.105384 -110.780613) (xy 184.147432 -110.811163) (xy 184.184183 -110.847914) (xy 184.214733 -110.889962)
			(xy 184.238329 -110.936272) (xy 184.25439 -110.985702) (xy 184.26252 -111.037037) (xy 184.26303 -111.063024)
			(xy 184.26252 -111.089011) (xy 184.40197 -111.089011) (xy 184.40197 -111.037037) (xy 184.4101 -110.985702)
			(xy 184.426161 -110.936272) (xy 184.449757 -110.889962) (xy 184.480307 -110.847914) (xy 184.517058 -110.811163)
			(xy 184.559106 -110.780613) (xy 184.605416 -110.757017) (xy 184.654846 -110.740956) (xy 184.706181 -110.732826)
			(xy 184.758155 -110.732826) (xy 184.80949 -110.740956) (xy 184.85892 -110.757017) (xy 184.90523 -110.780613)
			(xy 184.947278 -110.811163) (xy 184.984029 -110.847914) (xy 185.014579 -110.889962) (xy 185.038175 -110.936272)
			(xy 185.054236 -110.985702) (xy 185.062366 -111.037037) (xy 185.062876 -111.063024) (xy 185.062366 -111.089011)
			(xy 185.98185 -111.089011) (xy 185.98185 -111.037037) (xy 185.98998 -110.985702) (xy 186.006041 -110.936272)
			(xy 186.029637 -110.889962) (xy 186.060187 -110.847914) (xy 186.096938 -110.811163) (xy 186.138986 -110.780613)
			(xy 186.185296 -110.757017) (xy 186.234726 -110.740956) (xy 186.286061 -110.732826) (xy 186.338035 -110.732826)
			(xy 186.38937 -110.740956) (xy 186.4388 -110.757017) (xy 186.48511 -110.780613) (xy 186.527158 -110.811163)
			(xy 186.563909 -110.847914) (xy 186.594459 -110.889962) (xy 186.618055 -110.936272) (xy 186.634116 -110.985702)
			(xy 186.642246 -111.037037) (xy 186.642756 -111.063024) (xy 186.642246 -111.089011) (xy 186.781696 -111.089011)
			(xy 186.781696 -111.037037) (xy 186.789826 -110.985702) (xy 186.805887 -110.936272) (xy 186.829483 -110.889962)
			(xy 186.860033 -110.847914) (xy 186.896784 -110.811163) (xy 186.938832 -110.780613) (xy 186.985142 -110.757017)
			(xy 187.034572 -110.740956) (xy 187.085907 -110.732826) (xy 187.137881 -110.732826) (xy 187.189216 -110.740956)
			(xy 187.238646 -110.757017) (xy 187.284956 -110.780613) (xy 187.327004 -110.811163) (xy 187.363755 -110.847914)
			(xy 187.394305 -110.889962) (xy 187.417901 -110.936272) (xy 187.433962 -110.985702) (xy 187.442092 -111.037037)
			(xy 187.442602 -111.063024) (xy 187.442092 -111.089011) (xy 187.581796 -111.089011) (xy 187.581796 -111.037037)
			(xy 187.589926 -110.985702) (xy 187.605987 -110.936272) (xy 187.629583 -110.889962) (xy 187.660133 -110.847914)
			(xy 187.696884 -110.811163) (xy 187.738932 -110.780613) (xy 187.785242 -110.757017) (xy 187.834672 -110.740956)
			(xy 187.886007 -110.732826) (xy 187.937981 -110.732826) (xy 187.989316 -110.740956) (xy 188.038746 -110.757017)
			(xy 188.085056 -110.780613) (xy 188.127104 -110.811163) (xy 188.163855 -110.847914) (xy 188.194405 -110.889962)
			(xy 188.218001 -110.936272) (xy 188.234062 -110.985702) (xy 188.242192 -111.037037) (xy 188.242702 -111.063024)
			(xy 188.242192 -111.089011) (xy 188.381896 -111.089011) (xy 188.381896 -111.037037) (xy 188.390026 -110.985702)
			(xy 188.406087 -110.936272) (xy 188.429683 -110.889962) (xy 188.460233 -110.847914) (xy 188.496984 -110.811163)
			(xy 188.539032 -110.780613) (xy 188.585342 -110.757017) (xy 188.634772 -110.740956) (xy 188.686107 -110.732826)
			(xy 188.738081 -110.732826) (xy 188.789416 -110.740956) (xy 188.838846 -110.757017) (xy 188.885156 -110.780613)
			(xy 188.927204 -110.811163) (xy 188.963955 -110.847914) (xy 188.994505 -110.889962) (xy 189.018101 -110.936272)
			(xy 189.034162 -110.985702) (xy 189.042292 -111.037037) (xy 189.042802 -111.063024) (xy 189.042292 -111.089011)
			(xy 189.181742 -111.089011) (xy 189.181742 -111.037037) (xy 189.189872 -110.985702) (xy 189.205933 -110.936272)
			(xy 189.229529 -110.889962) (xy 189.260079 -110.847914) (xy 189.29683 -110.811163) (xy 189.338878 -110.780613)
			(xy 189.385188 -110.757017) (xy 189.434618 -110.740956) (xy 189.485953 -110.732826) (xy 189.537927 -110.732826)
			(xy 189.589262 -110.740956) (xy 189.638692 -110.757017) (xy 189.685002 -110.780613) (xy 189.72705 -110.811163)
			(xy 189.763801 -110.847914) (xy 189.794351 -110.889962) (xy 189.817947 -110.936272) (xy 189.834008 -110.985702)
			(xy 189.842138 -111.037037) (xy 189.842648 -111.063024) (xy 189.842138 -111.089011) (xy 189.981842 -111.089011)
			(xy 189.981842 -111.037037) (xy 189.989972 -110.985702) (xy 190.006033 -110.936272) (xy 190.029629 -110.889962)
			(xy 190.060179 -110.847914) (xy 190.09693 -110.811163) (xy 190.138978 -110.780613) (xy 190.185288 -110.757017)
			(xy 190.234718 -110.740956) (xy 190.286053 -110.732826) (xy 190.338027 -110.732826) (xy 190.389362 -110.740956)
			(xy 190.438792 -110.757017) (xy 190.485102 -110.780613) (xy 190.52715 -110.811163) (xy 190.563901 -110.847914)
			(xy 190.594451 -110.889962) (xy 190.618047 -110.936272) (xy 190.634108 -110.985702) (xy 190.642238 -111.037037)
			(xy 190.642748 -111.063024) (xy 190.642238 -111.089011) (xy 190.781688 -111.089011) (xy 190.781688 -111.037037)
			(xy 190.789818 -110.985702) (xy 190.805879 -110.936272) (xy 190.829475 -110.889962) (xy 190.860025 -110.847914)
			(xy 190.896776 -110.811163) (xy 190.938824 -110.780613) (xy 190.985134 -110.757017) (xy 191.034564 -110.740956)
			(xy 191.085899 -110.732826) (xy 191.137873 -110.732826) (xy 191.189208 -110.740956) (xy 191.238638 -110.757017)
			(xy 191.284948 -110.780613) (xy 191.326996 -110.811163) (xy 191.363747 -110.847914) (xy 191.394297 -110.889962)
			(xy 191.417893 -110.936272) (xy 191.433954 -110.985702) (xy 191.442084 -111.037037) (xy 191.442594 -111.063024)
			(xy 191.442084 -111.089011) (xy 191.581788 -111.089011) (xy 191.581788 -111.037037) (xy 191.589918 -110.985702)
			(xy 191.605979 -110.936272) (xy 191.629575 -110.889962) (xy 191.660125 -110.847914) (xy 191.696876 -110.811163)
			(xy 191.738924 -110.780613) (xy 191.785234 -110.757017) (xy 191.834664 -110.740956) (xy 191.885999 -110.732826)
			(xy 191.937973 -110.732826) (xy 191.989308 -110.740956) (xy 192.038738 -110.757017) (xy 192.085048 -110.780613)
			(xy 192.127096 -110.811163) (xy 192.163847 -110.847914) (xy 192.194397 -110.889962) (xy 192.217993 -110.936272)
			(xy 192.234054 -110.985702) (xy 192.242184 -111.037037) (xy 192.242694 -111.063024) (xy 192.242184 -111.089011)
			(xy 192.234054 -111.140346) (xy 192.217993 -111.189776) (xy 192.194397 -111.236086) (xy 192.163847 -111.278134)
			(xy 192.127096 -111.314885) (xy 192.085048 -111.345435) (xy 192.038738 -111.369031) (xy 191.989308 -111.385092)
			(xy 191.937973 -111.393222) (xy 191.885999 -111.393222) (xy 191.834664 -111.385092) (xy 191.785234 -111.369031)
			(xy 191.738924 -111.345435) (xy 191.696876 -111.314885) (xy 191.660125 -111.278134) (xy 191.629575 -111.236086)
			(xy 191.605979 -111.189776) (xy 191.589918 -111.140346) (xy 191.581788 -111.089011) (xy 191.442084 -111.089011)
			(xy 191.433954 -111.140346) (xy 191.417893 -111.189776) (xy 191.394297 -111.236086) (xy 191.363747 -111.278134)
			(xy 191.326996 -111.314885) (xy 191.284948 -111.345435) (xy 191.238638 -111.369031) (xy 191.189208 -111.385092)
			(xy 191.137873 -111.393222) (xy 191.085899 -111.393222) (xy 191.034564 -111.385092) (xy 190.985134 -111.369031)
			(xy 190.938824 -111.345435) (xy 190.896776 -111.314885) (xy 190.860025 -111.278134) (xy 190.829475 -111.236086)
			(xy 190.805879 -111.189776) (xy 190.789818 -111.140346) (xy 190.781688 -111.089011) (xy 190.642238 -111.089011)
			(xy 190.634108 -111.140346) (xy 190.618047 -111.189776) (xy 190.594451 -111.236086) (xy 190.563901 -111.278134)
			(xy 190.52715 -111.314885) (xy 190.485102 -111.345435) (xy 190.438792 -111.369031) (xy 190.389362 -111.385092)
			(xy 190.338027 -111.393222) (xy 190.286053 -111.393222) (xy 190.234718 -111.385092) (xy 190.185288 -111.369031)
			(xy 190.138978 -111.345435) (xy 190.09693 -111.314885) (xy 190.060179 -111.278134) (xy 190.029629 -111.236086)
			(xy 190.006033 -111.189776) (xy 189.989972 -111.140346) (xy 189.981842 -111.089011) (xy 189.842138 -111.089011)
			(xy 189.834008 -111.140346) (xy 189.817947 -111.189776) (xy 189.794351 -111.236086) (xy 189.763801 -111.278134)
			(xy 189.72705 -111.314885) (xy 189.685002 -111.345435) (xy 189.638692 -111.369031) (xy 189.589262 -111.385092)
			(xy 189.537927 -111.393222) (xy 189.485953 -111.393222) (xy 189.434618 -111.385092) (xy 189.385188 -111.369031)
			(xy 189.338878 -111.345435) (xy 189.29683 -111.314885) (xy 189.260079 -111.278134) (xy 189.229529 -111.236086)
			(xy 189.205933 -111.189776) (xy 189.189872 -111.140346) (xy 189.181742 -111.089011) (xy 189.042292 -111.089011)
			(xy 189.034162 -111.140346) (xy 189.018101 -111.189776) (xy 188.994505 -111.236086) (xy 188.963955 -111.278134)
			(xy 188.927204 -111.314885) (xy 188.885156 -111.345435) (xy 188.838846 -111.369031) (xy 188.789416 -111.385092)
			(xy 188.738081 -111.393222) (xy 188.686107 -111.393222) (xy 188.634772 -111.385092) (xy 188.585342 -111.369031)
			(xy 188.539032 -111.345435) (xy 188.496984 -111.314885) (xy 188.460233 -111.278134) (xy 188.429683 -111.236086)
			(xy 188.406087 -111.189776) (xy 188.390026 -111.140346) (xy 188.381896 -111.089011) (xy 188.242192 -111.089011)
			(xy 188.234062 -111.140346) (xy 188.218001 -111.189776) (xy 188.194405 -111.236086) (xy 188.163855 -111.278134)
			(xy 188.127104 -111.314885) (xy 188.085056 -111.345435) (xy 188.038746 -111.369031) (xy 187.989316 -111.385092)
			(xy 187.937981 -111.393222) (xy 187.886007 -111.393222) (xy 187.834672 -111.385092) (xy 187.785242 -111.369031)
			(xy 187.738932 -111.345435) (xy 187.696884 -111.314885) (xy 187.660133 -111.278134) (xy 187.629583 -111.236086)
			(xy 187.605987 -111.189776) (xy 187.589926 -111.140346) (xy 187.581796 -111.089011) (xy 187.442092 -111.089011)
			(xy 187.433962 -111.140346) (xy 187.417901 -111.189776) (xy 187.394305 -111.236086) (xy 187.363755 -111.278134)
			(xy 187.327004 -111.314885) (xy 187.284956 -111.345435) (xy 187.238646 -111.369031) (xy 187.189216 -111.385092)
			(xy 187.137881 -111.393222) (xy 187.085907 -111.393222) (xy 187.034572 -111.385092) (xy 186.985142 -111.369031)
			(xy 186.938832 -111.345435) (xy 186.896784 -111.314885) (xy 186.860033 -111.278134) (xy 186.829483 -111.236086)
			(xy 186.805887 -111.189776) (xy 186.789826 -111.140346) (xy 186.781696 -111.089011) (xy 186.642246 -111.089011)
			(xy 186.634116 -111.140346) (xy 186.618055 -111.189776) (xy 186.594459 -111.236086) (xy 186.563909 -111.278134)
			(xy 186.527158 -111.314885) (xy 186.48511 -111.345435) (xy 186.4388 -111.369031) (xy 186.38937 -111.385092)
			(xy 186.338035 -111.393222) (xy 186.286061 -111.393222) (xy 186.234726 -111.385092) (xy 186.185296 -111.369031)
			(xy 186.138986 -111.345435) (xy 186.096938 -111.314885) (xy 186.060187 -111.278134) (xy 186.029637 -111.236086)
			(xy 186.006041 -111.189776) (xy 185.98998 -111.140346) (xy 185.98185 -111.089011) (xy 185.062366 -111.089011)
			(xy 185.054236 -111.140346) (xy 185.038175 -111.189776) (xy 185.014579 -111.236086) (xy 184.984029 -111.278134)
			(xy 184.947278 -111.314885) (xy 184.90523 -111.345435) (xy 184.85892 -111.369031) (xy 184.80949 -111.385092)
			(xy 184.758155 -111.393222) (xy 184.706181 -111.393222) (xy 184.654846 -111.385092) (xy 184.605416 -111.369031)
			(xy 184.559106 -111.345435) (xy 184.517058 -111.314885) (xy 184.480307 -111.278134) (xy 184.449757 -111.236086)
			(xy 184.426161 -111.189776) (xy 184.4101 -111.140346) (xy 184.40197 -111.089011) (xy 184.26252 -111.089011)
			(xy 184.25439 -111.140346) (xy 184.238329 -111.189776) (xy 184.214733 -111.236086) (xy 184.184183 -111.278134)
			(xy 184.147432 -111.314885) (xy 184.105384 -111.345435) (xy 184.059074 -111.369031) (xy 184.009644 -111.385092)
			(xy 183.958309 -111.393222) (xy 183.906335 -111.393222) (xy 183.855 -111.385092) (xy 183.80557 -111.369031)
			(xy 183.75926 -111.345435) (xy 183.717212 -111.314885) (xy 183.680461 -111.278134) (xy 183.649911 -111.236086)
			(xy 183.626315 -111.189776) (xy 183.610254 -111.140346) (xy 183.602124 -111.089011) (xy 183.46242 -111.089011)
			(xy 183.45429 -111.140346) (xy 183.438229 -111.189776) (xy 183.414633 -111.236086) (xy 183.384083 -111.278134)
			(xy 183.347332 -111.314885) (xy 183.305284 -111.345435) (xy 183.258974 -111.369031) (xy 183.209544 -111.385092)
			(xy 183.158209 -111.393222) (xy 183.106235 -111.393222) (xy 183.0549 -111.385092) (xy 183.00547 -111.369031)
			(xy 182.95916 -111.345435) (xy 182.917112 -111.314885) (xy 182.880361 -111.278134) (xy 182.849811 -111.236086)
			(xy 182.826215 -111.189776) (xy 182.810154 -111.140346) (xy 182.802024 -111.089011) (xy 182.66232 -111.089011)
			(xy 182.65419 -111.140346) (xy 182.638129 -111.189776) (xy 182.614533 -111.236086) (xy 182.583983 -111.278134)
			(xy 182.547232 -111.314885) (xy 182.505184 -111.345435) (xy 182.458874 -111.369031) (xy 182.409444 -111.385092)
			(xy 182.358109 -111.393222) (xy 182.306135 -111.393222) (xy 182.2548 -111.385092) (xy 182.20537 -111.369031)
			(xy 182.15906 -111.345435) (xy 182.117012 -111.314885) (xy 182.080261 -111.278134) (xy 182.049711 -111.236086)
			(xy 182.026115 -111.189776) (xy 182.010054 -111.140346) (xy 182.001924 -111.089011) (xy 181.862474 -111.089011)
			(xy 181.854344 -111.140346) (xy 181.838283 -111.189776) (xy 181.814687 -111.236086) (xy 181.784137 -111.278134)
			(xy 181.747386 -111.314885) (xy 181.705338 -111.345435) (xy 181.659028 -111.369031) (xy 181.609598 -111.385092)
			(xy 181.558263 -111.393222) (xy 181.506289 -111.393222) (xy 181.454954 -111.385092) (xy 181.405524 -111.369031)
			(xy 181.359214 -111.345435) (xy 181.317166 -111.314885) (xy 181.280415 -111.278134) (xy 181.249865 -111.236086)
			(xy 181.226269 -111.189776) (xy 181.210208 -111.140346) (xy 181.202078 -111.089011) (xy 181.062374 -111.089011)
			(xy 181.054244 -111.140346) (xy 181.038183 -111.189776) (xy 181.014587 -111.236086) (xy 180.984037 -111.278134)
			(xy 180.947286 -111.314885) (xy 180.905238 -111.345435) (xy 180.858928 -111.369031) (xy 180.809498 -111.385092)
			(xy 180.758163 -111.393222) (xy 180.706189 -111.393222) (xy 180.654854 -111.385092) (xy 180.605424 -111.369031)
			(xy 180.559114 -111.345435) (xy 180.517066 -111.314885) (xy 180.480315 -111.278134) (xy 180.449765 -111.236086)
			(xy 180.426169 -111.189776) (xy 180.410108 -111.140346) (xy 180.401978 -111.089011) (xy 180.262528 -111.089011)
			(xy 180.254398 -111.140346) (xy 180.238337 -111.189776) (xy 180.214741 -111.236086) (xy 180.184191 -111.278134)
			(xy 180.14744 -111.314885) (xy 180.105392 -111.345435) (xy 180.059082 -111.369031) (xy 180.009652 -111.385092)
			(xy 179.958317 -111.393222) (xy 179.906343 -111.393222) (xy 179.855008 -111.385092) (xy 179.805578 -111.369031)
			(xy 179.759268 -111.345435) (xy 179.71722 -111.314885) (xy 179.680469 -111.278134) (xy 179.649919 -111.236086)
			(xy 179.626323 -111.189776) (xy 179.610262 -111.140346) (xy 179.602132 -111.089011) (xy 179.462428 -111.089011)
			(xy 179.454298 -111.140346) (xy 179.438237 -111.189776) (xy 179.414641 -111.236086) (xy 179.384091 -111.278134)
			(xy 179.34734 -111.314885) (xy 179.305292 -111.345435) (xy 179.258982 -111.369031) (xy 179.209552 -111.385092)
			(xy 179.158217 -111.393222) (xy 179.106243 -111.393222) (xy 179.054908 -111.385092) (xy 179.005478 -111.369031)
			(xy 178.959168 -111.345435) (xy 178.91712 -111.314885) (xy 178.880369 -111.278134) (xy 178.849819 -111.236086)
			(xy 178.826223 -111.189776) (xy 178.810162 -111.140346) (xy 178.802032 -111.089011) (xy 178.662328 -111.089011)
			(xy 178.654198 -111.140346) (xy 178.638137 -111.189776) (xy 178.614541 -111.236086) (xy 178.583991 -111.278134)
			(xy 178.54724 -111.314885) (xy 178.505192 -111.345435) (xy 178.458882 -111.369031) (xy 178.409452 -111.385092)
			(xy 178.358117 -111.393222) (xy 178.306143 -111.393222) (xy 178.254808 -111.385092) (xy 178.205378 -111.369031)
			(xy 178.159068 -111.345435) (xy 178.11702 -111.314885) (xy 178.080269 -111.278134) (xy 178.049719 -111.236086)
			(xy 178.026123 -111.189776) (xy 178.010062 -111.140346) (xy 178.001932 -111.089011) (xy 177.862482 -111.089011)
			(xy 177.854352 -111.140346) (xy 177.838291 -111.189776) (xy 177.814695 -111.236086) (xy 177.784145 -111.278134)
			(xy 177.747394 -111.314885) (xy 177.705346 -111.345435) (xy 177.659036 -111.369031) (xy 177.609606 -111.385092)
			(xy 177.558271 -111.393222) (xy 177.506297 -111.393222) (xy 177.454962 -111.385092) (xy 177.405532 -111.369031)
			(xy 177.359222 -111.345435) (xy 177.317174 -111.314885) (xy 177.280423 -111.278134) (xy 177.249873 -111.236086)
			(xy 177.226277 -111.189776) (xy 177.210216 -111.140346) (xy 177.202086 -111.089011) (xy 177.062382 -111.089011)
			(xy 177.054252 -111.140346) (xy 177.038191 -111.189776) (xy 177.014595 -111.236086) (xy 176.984045 -111.278134)
			(xy 176.947294 -111.314885) (xy 176.905246 -111.345435) (xy 176.858936 -111.369031) (xy 176.809506 -111.385092)
			(xy 176.758171 -111.393222) (xy 176.706197 -111.393222) (xy 176.654862 -111.385092) (xy 176.605432 -111.369031)
			(xy 176.559122 -111.345435) (xy 176.517074 -111.314885) (xy 176.480323 -111.278134) (xy 176.449773 -111.236086)
			(xy 176.426177 -111.189776) (xy 176.410116 -111.140346) (xy 176.401986 -111.089011) (xy 170.672798 -111.089011)
			(xy 170.680215 -111.118374) (xy 170.68799 -111.180881) (xy 170.688508 -111.212376) (xy 170.688049 -111.243357)
			(xy 170.680523 -111.30486) (xy 170.665579 -111.364994) (xy 170.64344 -111.422865) (xy 170.614432 -111.477618)
			(xy 170.578986 -111.528441) (xy 170.537628 -111.574579) (xy 170.49097 -111.615351) (xy 170.439703 -111.650151)
			(xy 170.384588 -111.678464) (xy 170.326441 -111.69987) (xy 170.266124 -111.714052) (xy 170.235372 -111.717836)
			(xy 170.225974 -111.719106) (xy 170.193208 -111.75492) (xy 170.18712 -111.762147) (xy 170.180332 -111.779767)
			(xy 170.18 -111.78921) (xy 170.18 -111.802926) (xy 170.225974 -111.853218) (xy 170.235372 -111.854488)
			(xy 170.266118 -111.858319) (xy 170.326433 -111.872499) (xy 170.370873 -111.888857) (xy 178.001932 -111.888857)
			(xy 178.001932 -111.836883) (xy 178.010062 -111.785548) (xy 178.026123 -111.736118) (xy 178.049719 -111.689808)
			(xy 178.080269 -111.64776) (xy 178.11702 -111.611009) (xy 178.159068 -111.580459) (xy 178.205378 -111.556863)
			(xy 178.254808 -111.540802) (xy 178.306143 -111.532672) (xy 178.358117 -111.532672) (xy 178.409452 -111.540802)
			(xy 178.458882 -111.556863) (xy 178.505192 -111.580459) (xy 178.54724 -111.611009) (xy 178.583991 -111.64776)
			(xy 178.614541 -111.689808) (xy 178.638137 -111.736118) (xy 178.654198 -111.785548) (xy 178.662328 -111.836883)
			(xy 178.662838 -111.86287) (xy 178.662328 -111.888857) (xy 178.802032 -111.888857) (xy 178.802032 -111.836883)
			(xy 178.810162 -111.785548) (xy 178.826223 -111.736118) (xy 178.849819 -111.689808) (xy 178.880369 -111.64776)
			(xy 178.91712 -111.611009) (xy 178.959168 -111.580459) (xy 179.005478 -111.556863) (xy 179.054908 -111.540802)
			(xy 179.106243 -111.532672) (xy 179.158217 -111.532672) (xy 179.209552 -111.540802) (xy 179.258982 -111.556863)
			(xy 179.305292 -111.580459) (xy 179.34734 -111.611009) (xy 179.384091 -111.64776) (xy 179.414641 -111.689808)
			(xy 179.438237 -111.736118) (xy 179.454298 -111.785548) (xy 179.462428 -111.836883) (xy 179.462938 -111.86287)
			(xy 179.462428 -111.888857) (xy 179.602132 -111.888857) (xy 179.602132 -111.836883) (xy 179.610262 -111.785548)
			(xy 179.626323 -111.736118) (xy 179.649919 -111.689808) (xy 179.680469 -111.64776) (xy 179.71722 -111.611009)
			(xy 179.759268 -111.580459) (xy 179.805578 -111.556863) (xy 179.855008 -111.540802) (xy 179.906343 -111.532672)
			(xy 179.958317 -111.532672) (xy 180.009652 -111.540802) (xy 180.059082 -111.556863) (xy 180.105392 -111.580459)
			(xy 180.14744 -111.611009) (xy 180.184191 -111.64776) (xy 180.214741 -111.689808) (xy 180.238337 -111.736118)
			(xy 180.254398 -111.785548) (xy 180.262528 -111.836883) (xy 180.263038 -111.86287) (xy 180.262528 -111.888857)
			(xy 180.401978 -111.888857) (xy 180.401978 -111.836883) (xy 180.410108 -111.785548) (xy 180.426169 -111.736118)
			(xy 180.449765 -111.689808) (xy 180.480315 -111.64776) (xy 180.517066 -111.611009) (xy 180.559114 -111.580459)
			(xy 180.605424 -111.556863) (xy 180.654854 -111.540802) (xy 180.706189 -111.532672) (xy 180.758163 -111.532672)
			(xy 180.809498 -111.540802) (xy 180.858928 -111.556863) (xy 180.905238 -111.580459) (xy 180.947286 -111.611009)
			(xy 180.984037 -111.64776) (xy 181.014587 -111.689808) (xy 181.038183 -111.736118) (xy 181.054244 -111.785548)
			(xy 181.062374 -111.836883) (xy 181.062884 -111.86287) (xy 181.062374 -111.888857) (xy 181.202078 -111.888857)
			(xy 181.202078 -111.836883) (xy 181.210208 -111.785548) (xy 181.226269 -111.736118) (xy 181.249865 -111.689808)
			(xy 181.280415 -111.64776) (xy 181.317166 -111.611009) (xy 181.359214 -111.580459) (xy 181.405524 -111.556863)
			(xy 181.454954 -111.540802) (xy 181.506289 -111.532672) (xy 181.558263 -111.532672) (xy 181.609598 -111.540802)
			(xy 181.659028 -111.556863) (xy 181.705338 -111.580459) (xy 181.747386 -111.611009) (xy 181.784137 -111.64776)
			(xy 181.814687 -111.689808) (xy 181.838283 -111.736118) (xy 181.854344 -111.785548) (xy 181.862474 -111.836883)
			(xy 181.862984 -111.86287) (xy 181.862474 -111.888857) (xy 182.001924 -111.888857) (xy 182.001924 -111.836883)
			(xy 182.010054 -111.785548) (xy 182.026115 -111.736118) (xy 182.049711 -111.689808) (xy 182.080261 -111.64776)
			(xy 182.117012 -111.611009) (xy 182.15906 -111.580459) (xy 182.20537 -111.556863) (xy 182.2548 -111.540802)
			(xy 182.306135 -111.532672) (xy 182.358109 -111.532672) (xy 182.409444 -111.540802) (xy 182.458874 -111.556863)
			(xy 182.505184 -111.580459) (xy 182.547232 -111.611009) (xy 182.583983 -111.64776) (xy 182.614533 -111.689808)
			(xy 182.638129 -111.736118) (xy 182.65419 -111.785548) (xy 182.66232 -111.836883) (xy 182.66283 -111.86287)
			(xy 182.66232 -111.888857) (xy 184.40197 -111.888857) (xy 184.40197 -111.836883) (xy 184.4101 -111.785548)
			(xy 184.426161 -111.736118) (xy 184.449757 -111.689808) (xy 184.480307 -111.64776) (xy 184.517058 -111.611009)
			(xy 184.559106 -111.580459) (xy 184.605416 -111.556863) (xy 184.654846 -111.540802) (xy 184.706181 -111.532672)
			(xy 184.758155 -111.532672) (xy 184.80949 -111.540802) (xy 184.85892 -111.556863) (xy 184.90523 -111.580459)
			(xy 184.947278 -111.611009) (xy 184.984029 -111.64776) (xy 185.014579 -111.689808) (xy 185.038175 -111.736118)
			(xy 185.054236 -111.785548) (xy 185.062366 -111.836883) (xy 185.062876 -111.86287) (xy 185.062366 -111.888857)
			(xy 185.98185 -111.888857) (xy 185.98185 -111.836883) (xy 185.98998 -111.785548) (xy 186.006041 -111.736118)
			(xy 186.029637 -111.689808) (xy 186.060187 -111.64776) (xy 186.096938 -111.611009) (xy 186.138986 -111.580459)
			(xy 186.185296 -111.556863) (xy 186.234726 -111.540802) (xy 186.286061 -111.532672) (xy 186.338035 -111.532672)
			(xy 186.38937 -111.540802) (xy 186.4388 -111.556863) (xy 186.48511 -111.580459) (xy 186.527158 -111.611009)
			(xy 186.563909 -111.64776) (xy 186.594459 -111.689808) (xy 186.618055 -111.736118) (xy 186.634116 -111.785548)
			(xy 186.642246 -111.836883) (xy 186.642756 -111.86287) (xy 186.642246 -111.888857) (xy 186.781696 -111.888857)
			(xy 186.781696 -111.836883) (xy 186.789826 -111.785548) (xy 186.805887 -111.736118) (xy 186.829483 -111.689808)
			(xy 186.860033 -111.64776) (xy 186.896784 -111.611009) (xy 186.938832 -111.580459) (xy 186.985142 -111.556863)
			(xy 187.034572 -111.540802) (xy 187.085907 -111.532672) (xy 187.137881 -111.532672) (xy 187.189216 -111.540802)
			(xy 187.238646 -111.556863) (xy 187.284956 -111.580459) (xy 187.327004 -111.611009) (xy 187.363755 -111.64776)
			(xy 187.394305 -111.689808) (xy 187.417901 -111.736118) (xy 187.433962 -111.785548) (xy 187.442092 -111.836883)
			(xy 187.442602 -111.86287) (xy 187.442092 -111.888857) (xy 187.581796 -111.888857) (xy 187.581796 -111.836883)
			(xy 187.589926 -111.785548) (xy 187.605987 -111.736118) (xy 187.629583 -111.689808) (xy 187.660133 -111.64776)
			(xy 187.696884 -111.611009) (xy 187.738932 -111.580459) (xy 187.785242 -111.556863) (xy 187.834672 -111.540802)
			(xy 187.886007 -111.532672) (xy 187.937981 -111.532672) (xy 187.989316 -111.540802) (xy 188.038746 -111.556863)
			(xy 188.085056 -111.580459) (xy 188.127104 -111.611009) (xy 188.163855 -111.64776) (xy 188.194405 -111.689808)
			(xy 188.218001 -111.736118) (xy 188.234062 -111.785548) (xy 188.242192 -111.836883) (xy 188.242702 -111.86287)
			(xy 188.242192 -111.888857) (xy 188.381896 -111.888857) (xy 188.381896 -111.836883) (xy 188.390026 -111.785548)
			(xy 188.406087 -111.736118) (xy 188.429683 -111.689808) (xy 188.460233 -111.64776) (xy 188.496984 -111.611009)
			(xy 188.539032 -111.580459) (xy 188.585342 -111.556863) (xy 188.634772 -111.540802) (xy 188.686107 -111.532672)
			(xy 188.738081 -111.532672) (xy 188.789416 -111.540802) (xy 188.838846 -111.556863) (xy 188.885156 -111.580459)
			(xy 188.927204 -111.611009) (xy 188.963955 -111.64776) (xy 188.994505 -111.689808) (xy 189.018101 -111.736118)
			(xy 189.034162 -111.785548) (xy 189.042292 -111.836883) (xy 189.042802 -111.86287) (xy 189.042292 -111.888857)
			(xy 189.181742 -111.888857) (xy 189.181742 -111.836883) (xy 189.189872 -111.785548) (xy 189.205933 -111.736118)
			(xy 189.229529 -111.689808) (xy 189.260079 -111.64776) (xy 189.29683 -111.611009) (xy 189.338878 -111.580459)
			(xy 189.385188 -111.556863) (xy 189.434618 -111.540802) (xy 189.485953 -111.532672) (xy 189.537927 -111.532672)
			(xy 189.589262 -111.540802) (xy 189.638692 -111.556863) (xy 189.685002 -111.580459) (xy 189.72705 -111.611009)
			(xy 189.763801 -111.64776) (xy 189.794351 -111.689808) (xy 189.817947 -111.736118) (xy 189.834008 -111.785548)
			(xy 189.842138 -111.836883) (xy 189.842648 -111.86287) (xy 189.842138 -111.888857) (xy 189.981842 -111.888857)
			(xy 189.981842 -111.836883) (xy 189.989972 -111.785548) (xy 190.006033 -111.736118) (xy 190.029629 -111.689808)
			(xy 190.060179 -111.64776) (xy 190.09693 -111.611009) (xy 190.138978 -111.580459) (xy 190.185288 -111.556863)
			(xy 190.234718 -111.540802) (xy 190.286053 -111.532672) (xy 190.338027 -111.532672) (xy 190.389362 -111.540802)
			(xy 190.438792 -111.556863) (xy 190.485102 -111.580459) (xy 190.52715 -111.611009) (xy 190.563901 -111.64776)
			(xy 190.594451 -111.689808) (xy 190.618047 -111.736118) (xy 190.634108 -111.785548) (xy 190.642238 -111.836883)
			(xy 190.642748 -111.86287) (xy 190.642238 -111.888857) (xy 190.781688 -111.888857) (xy 190.781688 -111.836883)
			(xy 190.789818 -111.785548) (xy 190.805879 -111.736118) (xy 190.829475 -111.689808) (xy 190.860025 -111.64776)
			(xy 190.896776 -111.611009) (xy 190.938824 -111.580459) (xy 190.985134 -111.556863) (xy 191.034564 -111.540802)
			(xy 191.085899 -111.532672) (xy 191.137873 -111.532672) (xy 191.189208 -111.540802) (xy 191.238638 -111.556863)
			(xy 191.284948 -111.580459) (xy 191.326996 -111.611009) (xy 191.363747 -111.64776) (xy 191.394297 -111.689808)
			(xy 191.417893 -111.736118) (xy 191.433954 -111.785548) (xy 191.442084 -111.836883) (xy 191.442594 -111.86287)
			(xy 191.442084 -111.888857) (xy 191.581788 -111.888857) (xy 191.581788 -111.836883) (xy 191.589918 -111.785548)
			(xy 191.605979 -111.736118) (xy 191.629575 -111.689808) (xy 191.660125 -111.64776) (xy 191.696876 -111.611009)
			(xy 191.738924 -111.580459) (xy 191.785234 -111.556863) (xy 191.834664 -111.540802) (xy 191.885999 -111.532672)
			(xy 191.937973 -111.532672) (xy 191.989308 -111.540802) (xy 192.038738 -111.556863) (xy 192.085048 -111.580459)
			(xy 192.127096 -111.611009) (xy 192.163847 -111.64776) (xy 192.194397 -111.689808) (xy 192.217993 -111.736118)
			(xy 192.234054 -111.785548) (xy 192.242184 -111.836883) (xy 192.242694 -111.86287) (xy 192.242184 -111.888857)
			(xy 192.234054 -111.940192) (xy 192.217993 -111.989622) (xy 192.194397 -112.035932) (xy 192.163847 -112.07798)
			(xy 192.127096 -112.114731) (xy 192.085048 -112.145281) (xy 192.038738 -112.168877) (xy 191.989308 -112.184938)
			(xy 191.937973 -112.193068) (xy 191.885999 -112.193068) (xy 191.834664 -112.184938) (xy 191.785234 -112.168877)
			(xy 191.738924 -112.145281) (xy 191.696876 -112.114731) (xy 191.660125 -112.07798) (xy 191.629575 -112.035932)
			(xy 191.605979 -111.989622) (xy 191.589918 -111.940192) (xy 191.581788 -111.888857) (xy 191.442084 -111.888857)
			(xy 191.433954 -111.940192) (xy 191.417893 -111.989622) (xy 191.394297 -112.035932) (xy 191.363747 -112.07798)
			(xy 191.326996 -112.114731) (xy 191.284948 -112.145281) (xy 191.238638 -112.168877) (xy 191.189208 -112.184938)
			(xy 191.137873 -112.193068) (xy 191.085899 -112.193068) (xy 191.034564 -112.184938) (xy 190.985134 -112.168877)
			(xy 190.938824 -112.145281) (xy 190.896776 -112.114731) (xy 190.860025 -112.07798) (xy 190.829475 -112.035932)
			(xy 190.805879 -111.989622) (xy 190.789818 -111.940192) (xy 190.781688 -111.888857) (xy 190.642238 -111.888857)
			(xy 190.634108 -111.940192) (xy 190.618047 -111.989622) (xy 190.594451 -112.035932) (xy 190.563901 -112.07798)
			(xy 190.52715 -112.114731) (xy 190.485102 -112.145281) (xy 190.438792 -112.168877) (xy 190.389362 -112.184938)
			(xy 190.338027 -112.193068) (xy 190.286053 -112.193068) (xy 190.234718 -112.184938) (xy 190.185288 -112.168877)
			(xy 190.138978 -112.145281) (xy 190.09693 -112.114731) (xy 190.060179 -112.07798) (xy 190.029629 -112.035932)
			(xy 190.006033 -111.989622) (xy 189.989972 -111.940192) (xy 189.981842 -111.888857) (xy 189.842138 -111.888857)
			(xy 189.834008 -111.940192) (xy 189.817947 -111.989622) (xy 189.794351 -112.035932) (xy 189.763801 -112.07798)
			(xy 189.72705 -112.114731) (xy 189.685002 -112.145281) (xy 189.638692 -112.168877) (xy 189.589262 -112.184938)
			(xy 189.537927 -112.193068) (xy 189.485953 -112.193068) (xy 189.434618 -112.184938) (xy 189.385188 -112.168877)
			(xy 189.338878 -112.145281) (xy 189.29683 -112.114731) (xy 189.260079 -112.07798) (xy 189.229529 -112.035932)
			(xy 189.205933 -111.989622) (xy 189.189872 -111.940192) (xy 189.181742 -111.888857) (xy 189.042292 -111.888857)
			(xy 189.034162 -111.940192) (xy 189.018101 -111.989622) (xy 188.994505 -112.035932) (xy 188.963955 -112.07798)
			(xy 188.927204 -112.114731) (xy 188.885156 -112.145281) (xy 188.838846 -112.168877) (xy 188.789416 -112.184938)
			(xy 188.738081 -112.193068) (xy 188.686107 -112.193068) (xy 188.634772 -112.184938) (xy 188.585342 -112.168877)
			(xy 188.539032 -112.145281) (xy 188.496984 -112.114731) (xy 188.460233 -112.07798) (xy 188.429683 -112.035932)
			(xy 188.406087 -111.989622) (xy 188.390026 -111.940192) (xy 188.381896 -111.888857) (xy 188.242192 -111.888857)
			(xy 188.234062 -111.940192) (xy 188.218001 -111.989622) (xy 188.194405 -112.035932) (xy 188.163855 -112.07798)
			(xy 188.127104 -112.114731) (xy 188.085056 -112.145281) (xy 188.038746 -112.168877) (xy 187.989316 -112.184938)
			(xy 187.937981 -112.193068) (xy 187.886007 -112.193068) (xy 187.834672 -112.184938) (xy 187.785242 -112.168877)
			(xy 187.738932 -112.145281) (xy 187.696884 -112.114731) (xy 187.660133 -112.07798) (xy 187.629583 -112.035932)
			(xy 187.605987 -111.989622) (xy 187.589926 -111.940192) (xy 187.581796 -111.888857) (xy 187.442092 -111.888857)
			(xy 187.433962 -111.940192) (xy 187.417901 -111.989622) (xy 187.394305 -112.035932) (xy 187.363755 -112.07798)
			(xy 187.327004 -112.114731) (xy 187.284956 -112.145281) (xy 187.238646 -112.168877) (xy 187.189216 -112.184938)
			(xy 187.137881 -112.193068) (xy 187.085907 -112.193068) (xy 187.034572 -112.184938) (xy 186.985142 -112.168877)
			(xy 186.938832 -112.145281) (xy 186.896784 -112.114731) (xy 186.860033 -112.07798) (xy 186.829483 -112.035932)
			(xy 186.805887 -111.989622) (xy 186.789826 -111.940192) (xy 186.781696 -111.888857) (xy 186.642246 -111.888857)
			(xy 186.634116 -111.940192) (xy 186.618055 -111.989622) (xy 186.594459 -112.035932) (xy 186.563909 -112.07798)
			(xy 186.527158 -112.114731) (xy 186.48511 -112.145281) (xy 186.4388 -112.168877) (xy 186.38937 -112.184938)
			(xy 186.338035 -112.193068) (xy 186.286061 -112.193068) (xy 186.234726 -112.184938) (xy 186.185296 -112.168877)
			(xy 186.138986 -112.145281) (xy 186.096938 -112.114731) (xy 186.060187 -112.07798) (xy 186.029637 -112.035932)
			(xy 186.006041 -111.989622) (xy 185.98998 -111.940192) (xy 185.98185 -111.888857) (xy 185.062366 -111.888857)
			(xy 185.054236 -111.940192) (xy 185.038175 -111.989622) (xy 185.014579 -112.035932) (xy 184.984029 -112.07798)
			(xy 184.947278 -112.114731) (xy 184.90523 -112.145281) (xy 184.85892 -112.168877) (xy 184.80949 -112.184938)
			(xy 184.758155 -112.193068) (xy 184.706181 -112.193068) (xy 184.654846 -112.184938) (xy 184.605416 -112.168877)
			(xy 184.559106 -112.145281) (xy 184.517058 -112.114731) (xy 184.480307 -112.07798) (xy 184.449757 -112.035932)
			(xy 184.426161 -111.989622) (xy 184.4101 -111.940192) (xy 184.40197 -111.888857) (xy 182.66232 -111.888857)
			(xy 182.65419 -111.940192) (xy 182.638129 -111.989622) (xy 182.614533 -112.035932) (xy 182.583983 -112.07798)
			(xy 182.547232 -112.114731) (xy 182.505184 -112.145281) (xy 182.458874 -112.168877) (xy 182.409444 -112.184938)
			(xy 182.358109 -112.193068) (xy 182.306135 -112.193068) (xy 182.2548 -112.184938) (xy 182.20537 -112.168877)
			(xy 182.15906 -112.145281) (xy 182.117012 -112.114731) (xy 182.080261 -112.07798) (xy 182.049711 -112.035932)
			(xy 182.026115 -111.989622) (xy 182.010054 -111.940192) (xy 182.001924 -111.888857) (xy 181.862474 -111.888857)
			(xy 181.854344 -111.940192) (xy 181.838283 -111.989622) (xy 181.814687 -112.035932) (xy 181.784137 -112.07798)
			(xy 181.747386 -112.114731) (xy 181.705338 -112.145281) (xy 181.659028 -112.168877) (xy 181.609598 -112.184938)
			(xy 181.558263 -112.193068) (xy 181.506289 -112.193068) (xy 181.454954 -112.184938) (xy 181.405524 -112.168877)
			(xy 181.359214 -112.145281) (xy 181.317166 -112.114731) (xy 181.280415 -112.07798) (xy 181.249865 -112.035932)
			(xy 181.226269 -111.989622) (xy 181.210208 -111.940192) (xy 181.202078 -111.888857) (xy 181.062374 -111.888857)
			(xy 181.054244 -111.940192) (xy 181.038183 -111.989622) (xy 181.014587 -112.035932) (xy 180.984037 -112.07798)
			(xy 180.947286 -112.114731) (xy 180.905238 -112.145281) (xy 180.858928 -112.168877) (xy 180.809498 -112.184938)
			(xy 180.758163 -112.193068) (xy 180.706189 -112.193068) (xy 180.654854 -112.184938) (xy 180.605424 -112.168877)
			(xy 180.559114 -112.145281) (xy 180.517066 -112.114731) (xy 180.480315 -112.07798) (xy 180.449765 -112.035932)
			(xy 180.426169 -111.989622) (xy 180.410108 -111.940192) (xy 180.401978 -111.888857) (xy 180.262528 -111.888857)
			(xy 180.254398 -111.940192) (xy 180.238337 -111.989622) (xy 180.214741 -112.035932) (xy 180.184191 -112.07798)
			(xy 180.14744 -112.114731) (xy 180.105392 -112.145281) (xy 180.059082 -112.168877) (xy 180.009652 -112.184938)
			(xy 179.958317 -112.193068) (xy 179.906343 -112.193068) (xy 179.855008 -112.184938) (xy 179.805578 -112.168877)
			(xy 179.759268 -112.145281) (xy 179.71722 -112.114731) (xy 179.680469 -112.07798) (xy 179.649919 -112.035932)
			(xy 179.626323 -111.989622) (xy 179.610262 -111.940192) (xy 179.602132 -111.888857) (xy 179.462428 -111.888857)
			(xy 179.454298 -111.940192) (xy 179.438237 -111.989622) (xy 179.414641 -112.035932) (xy 179.384091 -112.07798)
			(xy 179.34734 -112.114731) (xy 179.305292 -112.145281) (xy 179.258982 -112.168877) (xy 179.209552 -112.184938)
			(xy 179.158217 -112.193068) (xy 179.106243 -112.193068) (xy 179.054908 -112.184938) (xy 179.005478 -112.168877)
			(xy 178.959168 -112.145281) (xy 178.91712 -112.114731) (xy 178.880369 -112.07798) (xy 178.849819 -112.035932)
			(xy 178.826223 -111.989622) (xy 178.810162 -111.940192) (xy 178.802032 -111.888857) (xy 178.662328 -111.888857)
			(xy 178.654198 -111.940192) (xy 178.638137 -111.989622) (xy 178.614541 -112.035932) (xy 178.583991 -112.07798)
			(xy 178.54724 -112.114731) (xy 178.505192 -112.145281) (xy 178.458882 -112.168877) (xy 178.409452 -112.184938)
			(xy 178.358117 -112.193068) (xy 178.306143 -112.193068) (xy 178.254808 -112.184938) (xy 178.205378 -112.168877)
			(xy 178.159068 -112.145281) (xy 178.11702 -112.114731) (xy 178.080269 -112.07798) (xy 178.049719 -112.035932)
			(xy 178.026123 -111.989622) (xy 178.010062 -111.940192) (xy 178.001932 -111.888857) (xy 170.370873 -111.888857)
			(xy 170.384579 -111.893902) (xy 170.439693 -111.922211) (xy 170.49096 -111.957007) (xy 170.53762 -111.997773)
			(xy 170.57898 -112.043907) (xy 170.614429 -112.094724) (xy 170.643441 -112.149472) (xy 170.665587 -112.207339)
			(xy 170.680537 -112.267468) (xy 170.688072 -112.328968) (xy 170.688508 -112.359948) (xy 170.688034 -112.391216)
			(xy 170.680378 -112.453281) (xy 170.665174 -112.51394) (xy 170.642652 -112.572279) (xy 170.613151 -112.627419)
			(xy 170.577116 -112.678528) (xy 170.567652 -112.688957) (xy 178.001932 -112.688957) (xy 178.001932 -112.636983)
			(xy 178.010062 -112.585648) (xy 178.026123 -112.536218) (xy 178.049719 -112.489908) (xy 178.080269 -112.44786)
			(xy 178.11702 -112.411109) (xy 178.159068 -112.380559) (xy 178.205378 -112.356963) (xy 178.254808 -112.340902)
			(xy 178.306143 -112.332772) (xy 178.358117 -112.332772) (xy 178.409452 -112.340902) (xy 178.458882 -112.356963)
			(xy 178.505192 -112.380559) (xy 178.54724 -112.411109) (xy 178.583991 -112.44786) (xy 178.614541 -112.489908)
			(xy 178.638137 -112.536218) (xy 178.654198 -112.585648) (xy 178.662328 -112.636983) (xy 178.662838 -112.66297)
			(xy 178.662328 -112.688957) (xy 178.802032 -112.688957) (xy 178.802032 -112.636983) (xy 178.810162 -112.585648)
			(xy 178.826223 -112.536218) (xy 178.849819 -112.489908) (xy 178.880369 -112.44786) (xy 178.91712 -112.411109)
			(xy 178.959168 -112.380559) (xy 179.005478 -112.356963) (xy 179.054908 -112.340902) (xy 179.106243 -112.332772)
			(xy 179.158217 -112.332772) (xy 179.209552 -112.340902) (xy 179.258982 -112.356963) (xy 179.305292 -112.380559)
			(xy 179.34734 -112.411109) (xy 179.384091 -112.44786) (xy 179.414641 -112.489908) (xy 179.438237 -112.536218)
			(xy 179.454298 -112.585648) (xy 179.462428 -112.636983) (xy 179.462938 -112.66297) (xy 179.462428 -112.688957)
			(xy 179.602132 -112.688957) (xy 179.602132 -112.636983) (xy 179.610262 -112.585648) (xy 179.626323 -112.536218)
			(xy 179.649919 -112.489908) (xy 179.680469 -112.44786) (xy 179.71722 -112.411109) (xy 179.759268 -112.380559)
			(xy 179.805578 -112.356963) (xy 179.855008 -112.340902) (xy 179.906343 -112.332772) (xy 179.958317 -112.332772)
			(xy 180.009652 -112.340902) (xy 180.059082 -112.356963) (xy 180.105392 -112.380559) (xy 180.14744 -112.411109)
			(xy 180.184191 -112.44786) (xy 180.214741 -112.489908) (xy 180.238337 -112.536218) (xy 180.254398 -112.585648)
			(xy 180.262528 -112.636983) (xy 180.263038 -112.66297) (xy 180.262528 -112.688957) (xy 180.401978 -112.688957)
			(xy 180.401978 -112.636983) (xy 180.410108 -112.585648) (xy 180.426169 -112.536218) (xy 180.449765 -112.489908)
			(xy 180.480315 -112.44786) (xy 180.517066 -112.411109) (xy 180.559114 -112.380559) (xy 180.605424 -112.356963)
			(xy 180.654854 -112.340902) (xy 180.706189 -112.332772) (xy 180.758163 -112.332772) (xy 180.809498 -112.340902)
			(xy 180.858928 -112.356963) (xy 180.905238 -112.380559) (xy 180.947286 -112.411109) (xy 180.984037 -112.44786)
			(xy 181.014587 -112.489908) (xy 181.038183 -112.536218) (xy 181.054244 -112.585648) (xy 181.062374 -112.636983)
			(xy 181.062884 -112.66297) (xy 181.062374 -112.688957) (xy 181.202078 -112.688957) (xy 181.202078 -112.636983)
			(xy 181.210208 -112.585648) (xy 181.226269 -112.536218) (xy 181.249865 -112.489908) (xy 181.280415 -112.44786)
			(xy 181.317166 -112.411109) (xy 181.359214 -112.380559) (xy 181.405524 -112.356963) (xy 181.454954 -112.340902)
			(xy 181.506289 -112.332772) (xy 181.558263 -112.332772) (xy 181.609598 -112.340902) (xy 181.659028 -112.356963)
			(xy 181.705338 -112.380559) (xy 181.747386 -112.411109) (xy 181.784137 -112.44786) (xy 181.814687 -112.489908)
			(xy 181.838283 -112.536218) (xy 181.854344 -112.585648) (xy 181.862474 -112.636983) (xy 181.862984 -112.66297)
			(xy 181.862474 -112.688957) (xy 182.001924 -112.688957) (xy 182.001924 -112.636983) (xy 182.010054 -112.585648)
			(xy 182.026115 -112.536218) (xy 182.049711 -112.489908) (xy 182.080261 -112.44786) (xy 182.117012 -112.411109)
			(xy 182.15906 -112.380559) (xy 182.20537 -112.356963) (xy 182.2548 -112.340902) (xy 182.306135 -112.332772)
			(xy 182.358109 -112.332772) (xy 182.409444 -112.340902) (xy 182.458874 -112.356963) (xy 182.505184 -112.380559)
			(xy 182.547232 -112.411109) (xy 182.583983 -112.44786) (xy 182.614533 -112.489908) (xy 182.638129 -112.536218)
			(xy 182.65419 -112.585648) (xy 182.66232 -112.636983) (xy 182.66283 -112.66297) (xy 182.66232 -112.688957)
			(xy 182.802024 -112.688957) (xy 182.802024 -112.636983) (xy 182.810154 -112.585648) (xy 182.826215 -112.536218)
			(xy 182.849811 -112.489908) (xy 182.880361 -112.44786) (xy 182.917112 -112.411109) (xy 182.95916 -112.380559)
			(xy 183.00547 -112.356963) (xy 183.0549 -112.340902) (xy 183.106235 -112.332772) (xy 183.158209 -112.332772)
			(xy 183.209544 -112.340902) (xy 183.258974 -112.356963) (xy 183.305284 -112.380559) (xy 183.347332 -112.411109)
			(xy 183.384083 -112.44786) (xy 183.414633 -112.489908) (xy 183.438229 -112.536218) (xy 183.45429 -112.585648)
			(xy 183.46242 -112.636983) (xy 183.46293 -112.66297) (xy 183.46242 -112.688957) (xy 183.602124 -112.688957)
			(xy 183.602124 -112.636983) (xy 183.610254 -112.585648) (xy 183.626315 -112.536218) (xy 183.649911 -112.489908)
			(xy 183.680461 -112.44786) (xy 183.717212 -112.411109) (xy 183.75926 -112.380559) (xy 183.80557 -112.356963)
			(xy 183.855 -112.340902) (xy 183.906335 -112.332772) (xy 183.958309 -112.332772) (xy 184.009644 -112.340902)
			(xy 184.059074 -112.356963) (xy 184.105384 -112.380559) (xy 184.147432 -112.411109) (xy 184.184183 -112.44786)
			(xy 184.214733 -112.489908) (xy 184.238329 -112.536218) (xy 184.25439 -112.585648) (xy 184.26252 -112.636983)
			(xy 184.26303 -112.66297) (xy 184.26252 -112.688957) (xy 184.40197 -112.688957) (xy 184.40197 -112.636983)
			(xy 184.4101 -112.585648) (xy 184.426161 -112.536218) (xy 184.449757 -112.489908) (xy 184.480307 -112.44786)
			(xy 184.517058 -112.411109) (xy 184.559106 -112.380559) (xy 184.605416 -112.356963) (xy 184.654846 -112.340902)
			(xy 184.706181 -112.332772) (xy 184.758155 -112.332772) (xy 184.80949 -112.340902) (xy 184.85892 -112.356963)
			(xy 184.90523 -112.380559) (xy 184.947278 -112.411109) (xy 184.984029 -112.44786) (xy 185.014579 -112.489908)
			(xy 185.038175 -112.536218) (xy 185.054236 -112.585648) (xy 185.062366 -112.636983) (xy 185.062876 -112.66297)
			(xy 185.062366 -112.688957) (xy 185.98185 -112.688957) (xy 185.98185 -112.636983) (xy 185.98998 -112.585648)
			(xy 186.006041 -112.536218) (xy 186.029637 -112.489908) (xy 186.060187 -112.44786) (xy 186.096938 -112.411109)
			(xy 186.138986 -112.380559) (xy 186.185296 -112.356963) (xy 186.234726 -112.340902) (xy 186.286061 -112.332772)
			(xy 186.338035 -112.332772) (xy 186.38937 -112.340902) (xy 186.4388 -112.356963) (xy 186.48511 -112.380559)
			(xy 186.527158 -112.411109) (xy 186.563909 -112.44786) (xy 186.594459 -112.489908) (xy 186.618055 -112.536218)
			(xy 186.634116 -112.585648) (xy 186.642246 -112.636983) (xy 186.642756 -112.66297) (xy 186.642246 -112.688957)
			(xy 186.781696 -112.688957) (xy 186.781696 -112.636983) (xy 186.789826 -112.585648) (xy 186.805887 -112.536218)
			(xy 186.829483 -112.489908) (xy 186.860033 -112.44786) (xy 186.896784 -112.411109) (xy 186.938832 -112.380559)
			(xy 186.985142 -112.356963) (xy 187.034572 -112.340902) (xy 187.085907 -112.332772) (xy 187.137881 -112.332772)
			(xy 187.189216 -112.340902) (xy 187.238646 -112.356963) (xy 187.284956 -112.380559) (xy 187.327004 -112.411109)
			(xy 187.363755 -112.44786) (xy 187.394305 -112.489908) (xy 187.417901 -112.536218) (xy 187.433962 -112.585648)
			(xy 187.442092 -112.636983) (xy 187.442602 -112.66297) (xy 187.442092 -112.688957) (xy 187.581796 -112.688957)
			(xy 187.581796 -112.636983) (xy 187.589926 -112.585648) (xy 187.605987 -112.536218) (xy 187.629583 -112.489908)
			(xy 187.660133 -112.44786) (xy 187.696884 -112.411109) (xy 187.738932 -112.380559) (xy 187.785242 -112.356963)
			(xy 187.834672 -112.340902) (xy 187.886007 -112.332772) (xy 187.937981 -112.332772) (xy 187.989316 -112.340902)
			(xy 188.038746 -112.356963) (xy 188.085056 -112.380559) (xy 188.127104 -112.411109) (xy 188.163855 -112.44786)
			(xy 188.194405 -112.489908) (xy 188.218001 -112.536218) (xy 188.234062 -112.585648) (xy 188.242192 -112.636983)
			(xy 188.242702 -112.66297) (xy 188.242192 -112.688957) (xy 188.381896 -112.688957) (xy 188.381896 -112.636983)
			(xy 188.390026 -112.585648) (xy 188.406087 -112.536218) (xy 188.429683 -112.489908) (xy 188.460233 -112.44786)
			(xy 188.496984 -112.411109) (xy 188.539032 -112.380559) (xy 188.585342 -112.356963) (xy 188.634772 -112.340902)
			(xy 188.686107 -112.332772) (xy 188.738081 -112.332772) (xy 188.789416 -112.340902) (xy 188.838846 -112.356963)
			(xy 188.885156 -112.380559) (xy 188.927204 -112.411109) (xy 188.963955 -112.44786) (xy 188.994505 -112.489908)
			(xy 189.018101 -112.536218) (xy 189.034162 -112.585648) (xy 189.042292 -112.636983) (xy 189.042802 -112.66297)
			(xy 189.042292 -112.688957) (xy 189.181742 -112.688957) (xy 189.181742 -112.636983) (xy 189.189872 -112.585648)
			(xy 189.205933 -112.536218) (xy 189.229529 -112.489908) (xy 189.260079 -112.44786) (xy 189.29683 -112.411109)
			(xy 189.338878 -112.380559) (xy 189.385188 -112.356963) (xy 189.434618 -112.340902) (xy 189.485953 -112.332772)
			(xy 189.537927 -112.332772) (xy 189.589262 -112.340902) (xy 189.638692 -112.356963) (xy 189.685002 -112.380559)
			(xy 189.72705 -112.411109) (xy 189.763801 -112.44786) (xy 189.794351 -112.489908) (xy 189.817947 -112.536218)
			(xy 189.834008 -112.585648) (xy 189.842138 -112.636983) (xy 189.842648 -112.66297) (xy 189.842138 -112.688957)
			(xy 189.981842 -112.688957) (xy 189.981842 -112.636983) (xy 189.989972 -112.585648) (xy 190.006033 -112.536218)
			(xy 190.029629 -112.489908) (xy 190.060179 -112.44786) (xy 190.09693 -112.411109) (xy 190.138978 -112.380559)
			(xy 190.185288 -112.356963) (xy 190.234718 -112.340902) (xy 190.286053 -112.332772) (xy 190.338027 -112.332772)
			(xy 190.389362 -112.340902) (xy 190.438792 -112.356963) (xy 190.485102 -112.380559) (xy 190.52715 -112.411109)
			(xy 190.563901 -112.44786) (xy 190.594451 -112.489908) (xy 190.618047 -112.536218) (xy 190.634108 -112.585648)
			(xy 190.642238 -112.636983) (xy 190.642748 -112.66297) (xy 190.642238 -112.688957) (xy 190.781688 -112.688957)
			(xy 190.781688 -112.636983) (xy 190.789818 -112.585648) (xy 190.805879 -112.536218) (xy 190.829475 -112.489908)
			(xy 190.860025 -112.44786) (xy 190.896776 -112.411109) (xy 190.938824 -112.380559) (xy 190.985134 -112.356963)
			(xy 191.034564 -112.340902) (xy 191.085899 -112.332772) (xy 191.137873 -112.332772) (xy 191.189208 -112.340902)
			(xy 191.238638 -112.356963) (xy 191.284948 -112.380559) (xy 191.326996 -112.411109) (xy 191.363747 -112.44786)
			(xy 191.394297 -112.489908) (xy 191.417893 -112.536218) (xy 191.433954 -112.585648) (xy 191.442084 -112.636983)
			(xy 191.442594 -112.66297) (xy 191.442084 -112.688957) (xy 191.581788 -112.688957) (xy 191.581788 -112.636983)
			(xy 191.589918 -112.585648) (xy 191.605979 -112.536218) (xy 191.629575 -112.489908) (xy 191.660125 -112.44786)
			(xy 191.696876 -112.411109) (xy 191.738924 -112.380559) (xy 191.785234 -112.356963) (xy 191.834664 -112.340902)
			(xy 191.885999 -112.332772) (xy 191.937973 -112.332772) (xy 191.989308 -112.340902) (xy 192.038738 -112.356963)
			(xy 192.085048 -112.380559) (xy 192.127096 -112.411109) (xy 192.163847 -112.44786) (xy 192.194397 -112.489908)
			(xy 192.217993 -112.536218) (xy 192.234054 -112.585648) (xy 192.242184 -112.636983) (xy 192.242694 -112.66297)
			(xy 192.242184 -112.688957) (xy 192.234054 -112.740292) (xy 192.217993 -112.789722) (xy 192.194397 -112.836032)
			(xy 192.163847 -112.87808) (xy 192.127096 -112.914831) (xy 192.085048 -112.945381) (xy 192.038738 -112.968977)
			(xy 191.989308 -112.985038) (xy 191.937973 -112.993168) (xy 191.885999 -112.993168) (xy 191.834664 -112.985038)
			(xy 191.785234 -112.968977) (xy 191.738924 -112.945381) (xy 191.696876 -112.914831) (xy 191.660125 -112.87808)
			(xy 191.629575 -112.836032) (xy 191.605979 -112.789722) (xy 191.589918 -112.740292) (xy 191.581788 -112.688957)
			(xy 191.442084 -112.688957) (xy 191.433954 -112.740292) (xy 191.417893 -112.789722) (xy 191.394297 -112.836032)
			(xy 191.363747 -112.87808) (xy 191.326996 -112.914831) (xy 191.284948 -112.945381) (xy 191.238638 -112.968977)
			(xy 191.189208 -112.985038) (xy 191.137873 -112.993168) (xy 191.085899 -112.993168) (xy 191.034564 -112.985038)
			(xy 190.985134 -112.968977) (xy 190.938824 -112.945381) (xy 190.896776 -112.914831) (xy 190.860025 -112.87808)
			(xy 190.829475 -112.836032) (xy 190.805879 -112.789722) (xy 190.789818 -112.740292) (xy 190.781688 -112.688957)
			(xy 190.642238 -112.688957) (xy 190.634108 -112.740292) (xy 190.618047 -112.789722) (xy 190.594451 -112.836032)
			(xy 190.563901 -112.87808) (xy 190.52715 -112.914831) (xy 190.485102 -112.945381) (xy 190.438792 -112.968977)
			(xy 190.389362 -112.985038) (xy 190.338027 -112.993168) (xy 190.286053 -112.993168) (xy 190.234718 -112.985038)
			(xy 190.185288 -112.968977) (xy 190.138978 -112.945381) (xy 190.09693 -112.914831) (xy 190.060179 -112.87808)
			(xy 190.029629 -112.836032) (xy 190.006033 -112.789722) (xy 189.989972 -112.740292) (xy 189.981842 -112.688957)
			(xy 189.842138 -112.688957) (xy 189.834008 -112.740292) (xy 189.817947 -112.789722) (xy 189.794351 -112.836032)
			(xy 189.763801 -112.87808) (xy 189.72705 -112.914831) (xy 189.685002 -112.945381) (xy 189.638692 -112.968977)
			(xy 189.589262 -112.985038) (xy 189.537927 -112.993168) (xy 189.485953 -112.993168) (xy 189.434618 -112.985038)
			(xy 189.385188 -112.968977) (xy 189.338878 -112.945381) (xy 189.29683 -112.914831) (xy 189.260079 -112.87808)
			(xy 189.229529 -112.836032) (xy 189.205933 -112.789722) (xy 189.189872 -112.740292) (xy 189.181742 -112.688957)
			(xy 189.042292 -112.688957) (xy 189.034162 -112.740292) (xy 189.018101 -112.789722) (xy 188.994505 -112.836032)
			(xy 188.963955 -112.87808) (xy 188.927204 -112.914831) (xy 188.885156 -112.945381) (xy 188.838846 -112.968977)
			(xy 188.789416 -112.985038) (xy 188.738081 -112.993168) (xy 188.686107 -112.993168) (xy 188.634772 -112.985038)
			(xy 188.585342 -112.968977) (xy 188.539032 -112.945381) (xy 188.496984 -112.914831) (xy 188.460233 -112.87808)
			(xy 188.429683 -112.836032) (xy 188.406087 -112.789722) (xy 188.390026 -112.740292) (xy 188.381896 -112.688957)
			(xy 188.242192 -112.688957) (xy 188.234062 -112.740292) (xy 188.218001 -112.789722) (xy 188.194405 -112.836032)
			(xy 188.163855 -112.87808) (xy 188.127104 -112.914831) (xy 188.085056 -112.945381) (xy 188.038746 -112.968977)
			(xy 187.989316 -112.985038) (xy 187.937981 -112.993168) (xy 187.886007 -112.993168) (xy 187.834672 -112.985038)
			(xy 187.785242 -112.968977) (xy 187.738932 -112.945381) (xy 187.696884 -112.914831) (xy 187.660133 -112.87808)
			(xy 187.629583 -112.836032) (xy 187.605987 -112.789722) (xy 187.589926 -112.740292) (xy 187.581796 -112.688957)
			(xy 187.442092 -112.688957) (xy 187.433962 -112.740292) (xy 187.417901 -112.789722) (xy 187.394305 -112.836032)
			(xy 187.363755 -112.87808) (xy 187.327004 -112.914831) (xy 187.284956 -112.945381) (xy 187.238646 -112.968977)
			(xy 187.189216 -112.985038) (xy 187.137881 -112.993168) (xy 187.085907 -112.993168) (xy 187.034572 -112.985038)
			(xy 186.985142 -112.968977) (xy 186.938832 -112.945381) (xy 186.896784 -112.914831) (xy 186.860033 -112.87808)
			(xy 186.829483 -112.836032) (xy 186.805887 -112.789722) (xy 186.789826 -112.740292) (xy 186.781696 -112.688957)
			(xy 186.642246 -112.688957) (xy 186.634116 -112.740292) (xy 186.618055 -112.789722) (xy 186.594459 -112.836032)
			(xy 186.563909 -112.87808) (xy 186.527158 -112.914831) (xy 186.48511 -112.945381) (xy 186.4388 -112.968977)
			(xy 186.38937 -112.985038) (xy 186.338035 -112.993168) (xy 186.286061 -112.993168) (xy 186.234726 -112.985038)
			(xy 186.185296 -112.968977) (xy 186.138986 -112.945381) (xy 186.096938 -112.914831) (xy 186.060187 -112.87808)
			(xy 186.029637 -112.836032) (xy 186.006041 -112.789722) (xy 185.98998 -112.740292) (xy 185.98185 -112.688957)
			(xy 185.062366 -112.688957) (xy 185.054236 -112.740292) (xy 185.038175 -112.789722) (xy 185.014579 -112.836032)
			(xy 184.984029 -112.87808) (xy 184.947278 -112.914831) (xy 184.90523 -112.945381) (xy 184.85892 -112.968977)
			(xy 184.80949 -112.985038) (xy 184.758155 -112.993168) (xy 184.706181 -112.993168) (xy 184.654846 -112.985038)
			(xy 184.605416 -112.968977) (xy 184.559106 -112.945381) (xy 184.517058 -112.914831) (xy 184.480307 -112.87808)
			(xy 184.449757 -112.836032) (xy 184.426161 -112.789722) (xy 184.4101 -112.740292) (xy 184.40197 -112.688957)
			(xy 184.26252 -112.688957) (xy 184.25439 -112.740292) (xy 184.238329 -112.789722) (xy 184.214733 -112.836032)
			(xy 184.184183 -112.87808) (xy 184.147432 -112.914831) (xy 184.105384 -112.945381) (xy 184.059074 -112.968977)
			(xy 184.009644 -112.985038) (xy 183.958309 -112.993168) (xy 183.906335 -112.993168) (xy 183.855 -112.985038)
			(xy 183.80557 -112.968977) (xy 183.75926 -112.945381) (xy 183.717212 -112.914831) (xy 183.680461 -112.87808)
			(xy 183.649911 -112.836032) (xy 183.626315 -112.789722) (xy 183.610254 -112.740292) (xy 183.602124 -112.688957)
			(xy 183.46242 -112.688957) (xy 183.45429 -112.740292) (xy 183.438229 -112.789722) (xy 183.414633 -112.836032)
			(xy 183.384083 -112.87808) (xy 183.347332 -112.914831) (xy 183.305284 -112.945381) (xy 183.258974 -112.968977)
			(xy 183.209544 -112.985038) (xy 183.158209 -112.993168) (xy 183.106235 -112.993168) (xy 183.0549 -112.985038)
			(xy 183.00547 -112.968977) (xy 182.95916 -112.945381) (xy 182.917112 -112.914831) (xy 182.880361 -112.87808)
			(xy 182.849811 -112.836032) (xy 182.826215 -112.789722) (xy 182.810154 -112.740292) (xy 182.802024 -112.688957)
			(xy 182.66232 -112.688957) (xy 182.65419 -112.740292) (xy 182.638129 -112.789722) (xy 182.614533 -112.836032)
			(xy 182.583983 -112.87808) (xy 182.547232 -112.914831) (xy 182.505184 -112.945381) (xy 182.458874 -112.968977)
			(xy 182.409444 -112.985038) (xy 182.358109 -112.993168) (xy 182.306135 -112.993168) (xy 182.2548 -112.985038)
			(xy 182.20537 -112.968977) (xy 182.15906 -112.945381) (xy 182.117012 -112.914831) (xy 182.080261 -112.87808)
			(xy 182.049711 -112.836032) (xy 182.026115 -112.789722) (xy 182.010054 -112.740292) (xy 182.001924 -112.688957)
			(xy 181.862474 -112.688957) (xy 181.854344 -112.740292) (xy 181.838283 -112.789722) (xy 181.814687 -112.836032)
			(xy 181.784137 -112.87808) (xy 181.747386 -112.914831) (xy 181.705338 -112.945381) (xy 181.659028 -112.968977)
			(xy 181.609598 -112.985038) (xy 181.558263 -112.993168) (xy 181.506289 -112.993168) (xy 181.454954 -112.985038)
			(xy 181.405524 -112.968977) (xy 181.359214 -112.945381) (xy 181.317166 -112.914831) (xy 181.280415 -112.87808)
			(xy 181.249865 -112.836032) (xy 181.226269 -112.789722) (xy 181.210208 -112.740292) (xy 181.202078 -112.688957)
			(xy 181.062374 -112.688957) (xy 181.054244 -112.740292) (xy 181.038183 -112.789722) (xy 181.014587 -112.836032)
			(xy 180.984037 -112.87808) (xy 180.947286 -112.914831) (xy 180.905238 -112.945381) (xy 180.858928 -112.968977)
			(xy 180.809498 -112.985038) (xy 180.758163 -112.993168) (xy 180.706189 -112.993168) (xy 180.654854 -112.985038)
			(xy 180.605424 -112.968977) (xy 180.559114 -112.945381) (xy 180.517066 -112.914831) (xy 180.480315 -112.87808)
			(xy 180.449765 -112.836032) (xy 180.426169 -112.789722) (xy 180.410108 -112.740292) (xy 180.401978 -112.688957)
			(xy 180.262528 -112.688957) (xy 180.254398 -112.740292) (xy 180.238337 -112.789722) (xy 180.214741 -112.836032)
			(xy 180.184191 -112.87808) (xy 180.14744 -112.914831) (xy 180.105392 -112.945381) (xy 180.059082 -112.968977)
			(xy 180.009652 -112.985038) (xy 179.958317 -112.993168) (xy 179.906343 -112.993168) (xy 179.855008 -112.985038)
			(xy 179.805578 -112.968977) (xy 179.759268 -112.945381) (xy 179.71722 -112.914831) (xy 179.680469 -112.87808)
			(xy 179.649919 -112.836032) (xy 179.626323 -112.789722) (xy 179.610262 -112.740292) (xy 179.602132 -112.688957)
			(xy 179.462428 -112.688957) (xy 179.454298 -112.740292) (xy 179.438237 -112.789722) (xy 179.414641 -112.836032)
			(xy 179.384091 -112.87808) (xy 179.34734 -112.914831) (xy 179.305292 -112.945381) (xy 179.258982 -112.968977)
			(xy 179.209552 -112.985038) (xy 179.158217 -112.993168) (xy 179.106243 -112.993168) (xy 179.054908 -112.985038)
			(xy 179.005478 -112.968977) (xy 178.959168 -112.945381) (xy 178.91712 -112.914831) (xy 178.880369 -112.87808)
			(xy 178.849819 -112.836032) (xy 178.826223 -112.789722) (xy 178.810162 -112.740292) (xy 178.802032 -112.688957)
			(xy 178.662328 -112.688957) (xy 178.654198 -112.740292) (xy 178.638137 -112.789722) (xy 178.614541 -112.836032)
			(xy 178.583991 -112.87808) (xy 178.54724 -112.914831) (xy 178.505192 -112.945381) (xy 178.458882 -112.968977)
			(xy 178.409452 -112.985038) (xy 178.358117 -112.993168) (xy 178.306143 -112.993168) (xy 178.254808 -112.985038)
			(xy 178.205378 -112.968977) (xy 178.159068 -112.945381) (xy 178.11702 -112.914831) (xy 178.080269 -112.87808)
			(xy 178.049719 -112.836032) (xy 178.026123 -112.789722) (xy 178.010062 -112.740292) (xy 178.001932 -112.688957)
			(xy 170.567652 -112.688957) (xy 170.53509 -112.724837) (xy 170.487707 -112.765648) (xy 170.46194 -112.783366)
			(xy 170.461686 -112.783366) (xy 170.454089 -112.788883) (xy 170.443144 -112.804121) (xy 170.44035 -112.813084)
			(xy 170.438826 -112.825022) (xy 170.438826 -112.910874) (xy 170.44035 -112.922812) (xy 170.44283 -112.930957)
			(xy 170.452317 -112.945085) (xy 170.458892 -112.950498) (xy 170.484958 -112.968183) (xy 170.532938 -113.008996)
			(xy 170.575516 -113.055418) (xy 170.612041 -113.106737) (xy 170.641956 -113.162171) (xy 170.664803 -113.220873)
			(xy 170.680233 -113.281944) (xy 170.688011 -113.344453) (xy 170.688508 -113.375948) (xy 170.688088 -113.405613)
			(xy 170.681179 -113.46454) (xy 170.675352 -113.489057) (xy 177.202086 -113.489057) (xy 177.202086 -113.437083)
			(xy 177.210216 -113.385748) (xy 177.226277 -113.336318) (xy 177.249873 -113.290008) (xy 177.280423 -113.24796)
			(xy 177.317174 -113.211209) (xy 177.359222 -113.180659) (xy 177.405532 -113.157063) (xy 177.454962 -113.141002)
			(xy 177.506297 -113.132872) (xy 177.558271 -113.132872) (xy 177.609606 -113.141002) (xy 177.659036 -113.157063)
			(xy 177.705346 -113.180659) (xy 177.747394 -113.211209) (xy 177.784145 -113.24796) (xy 177.814695 -113.290008)
			(xy 177.838291 -113.336318) (xy 177.854352 -113.385748) (xy 177.862482 -113.437083) (xy 177.862992 -113.46307)
			(xy 177.862482 -113.489057) (xy 178.001932 -113.489057) (xy 178.001932 -113.437083) (xy 178.010062 -113.385748)
			(xy 178.026123 -113.336318) (xy 178.049719 -113.290008) (xy 178.080269 -113.24796) (xy 178.11702 -113.211209)
			(xy 178.159068 -113.180659) (xy 178.205378 -113.157063) (xy 178.254808 -113.141002) (xy 178.306143 -113.132872)
			(xy 178.358117 -113.132872) (xy 178.409452 -113.141002) (xy 178.458882 -113.157063) (xy 178.505192 -113.180659)
			(xy 178.54724 -113.211209) (xy 178.583991 -113.24796) (xy 178.614541 -113.290008) (xy 178.638137 -113.336318)
			(xy 178.654198 -113.385748) (xy 178.662328 -113.437083) (xy 178.662838 -113.46307) (xy 178.662328 -113.489057)
			(xy 178.802032 -113.489057) (xy 178.802032 -113.437083) (xy 178.810162 -113.385748) (xy 178.826223 -113.336318)
			(xy 178.849819 -113.290008) (xy 178.880369 -113.24796) (xy 178.91712 -113.211209) (xy 178.959168 -113.180659)
			(xy 179.005478 -113.157063) (xy 179.054908 -113.141002) (xy 179.106243 -113.132872) (xy 179.158217 -113.132872)
			(xy 179.209552 -113.141002) (xy 179.258982 -113.157063) (xy 179.305292 -113.180659) (xy 179.34734 -113.211209)
			(xy 179.384091 -113.24796) (xy 179.414641 -113.290008) (xy 179.438237 -113.336318) (xy 179.454298 -113.385748)
			(xy 179.462428 -113.437083) (xy 179.462938 -113.46307) (xy 179.462428 -113.489057) (xy 179.602132 -113.489057)
			(xy 179.602132 -113.437083) (xy 179.610262 -113.385748) (xy 179.626323 -113.336318) (xy 179.649919 -113.290008)
			(xy 179.680469 -113.24796) (xy 179.71722 -113.211209) (xy 179.759268 -113.180659) (xy 179.805578 -113.157063)
			(xy 179.855008 -113.141002) (xy 179.906343 -113.132872) (xy 179.958317 -113.132872) (xy 180.009652 -113.141002)
			(xy 180.059082 -113.157063) (xy 180.105392 -113.180659) (xy 180.14744 -113.211209) (xy 180.184191 -113.24796)
			(xy 180.214741 -113.290008) (xy 180.238337 -113.336318) (xy 180.254398 -113.385748) (xy 180.262528 -113.437083)
			(xy 180.263038 -113.46307) (xy 180.262528 -113.489057) (xy 180.401978 -113.489057) (xy 180.401978 -113.437083)
			(xy 180.410108 -113.385748) (xy 180.426169 -113.336318) (xy 180.449765 -113.290008) (xy 180.480315 -113.24796)
			(xy 180.517066 -113.211209) (xy 180.559114 -113.180659) (xy 180.605424 -113.157063) (xy 180.654854 -113.141002)
			(xy 180.706189 -113.132872) (xy 180.758163 -113.132872) (xy 180.809498 -113.141002) (xy 180.858928 -113.157063)
			(xy 180.905238 -113.180659) (xy 180.947286 -113.211209) (xy 180.984037 -113.24796) (xy 181.014587 -113.290008)
			(xy 181.038183 -113.336318) (xy 181.054244 -113.385748) (xy 181.062374 -113.437083) (xy 181.062884 -113.46307)
			(xy 181.062374 -113.489057) (xy 181.202078 -113.489057) (xy 181.202078 -113.437083) (xy 181.210208 -113.385748)
			(xy 181.226269 -113.336318) (xy 181.249865 -113.290008) (xy 181.280415 -113.24796) (xy 181.317166 -113.211209)
			(xy 181.359214 -113.180659) (xy 181.405524 -113.157063) (xy 181.454954 -113.141002) (xy 181.506289 -113.132872)
			(xy 181.558263 -113.132872) (xy 181.609598 -113.141002) (xy 181.659028 -113.157063) (xy 181.705338 -113.180659)
			(xy 181.747386 -113.211209) (xy 181.784137 -113.24796) (xy 181.814687 -113.290008) (xy 181.838283 -113.336318)
			(xy 181.854344 -113.385748) (xy 181.862474 -113.437083) (xy 181.862984 -113.46307) (xy 181.862474 -113.489057)
			(xy 182.001924 -113.489057) (xy 182.001924 -113.437083) (xy 182.010054 -113.385748) (xy 182.026115 -113.336318)
			(xy 182.049711 -113.290008) (xy 182.080261 -113.24796) (xy 182.117012 -113.211209) (xy 182.15906 -113.180659)
			(xy 182.20537 -113.157063) (xy 182.2548 -113.141002) (xy 182.306135 -113.132872) (xy 182.358109 -113.132872)
			(xy 182.409444 -113.141002) (xy 182.458874 -113.157063) (xy 182.505184 -113.180659) (xy 182.547232 -113.211209)
			(xy 182.583983 -113.24796) (xy 182.614533 -113.290008) (xy 182.638129 -113.336318) (xy 182.65419 -113.385748)
			(xy 182.66232 -113.437083) (xy 182.66283 -113.46307) (xy 182.66232 -113.489057) (xy 182.802024 -113.489057)
			(xy 182.802024 -113.437083) (xy 182.810154 -113.385748) (xy 182.826215 -113.336318) (xy 182.849811 -113.290008)
			(xy 182.880361 -113.24796) (xy 182.917112 -113.211209) (xy 182.95916 -113.180659) (xy 183.00547 -113.157063)
			(xy 183.0549 -113.141002) (xy 183.106235 -113.132872) (xy 183.158209 -113.132872) (xy 183.209544 -113.141002)
			(xy 183.258974 -113.157063) (xy 183.305284 -113.180659) (xy 183.347332 -113.211209) (xy 183.384083 -113.24796)
			(xy 183.414633 -113.290008) (xy 183.438229 -113.336318) (xy 183.45429 -113.385748) (xy 183.46242 -113.437083)
			(xy 183.46293 -113.46307) (xy 183.46242 -113.489057) (xy 183.602124 -113.489057) (xy 183.602124 -113.437083)
			(xy 183.610254 -113.385748) (xy 183.626315 -113.336318) (xy 183.649911 -113.290008) (xy 183.680461 -113.24796)
			(xy 183.717212 -113.211209) (xy 183.75926 -113.180659) (xy 183.80557 -113.157063) (xy 183.855 -113.141002)
			(xy 183.906335 -113.132872) (xy 183.958309 -113.132872) (xy 184.009644 -113.141002) (xy 184.059074 -113.157063)
			(xy 184.105384 -113.180659) (xy 184.147432 -113.211209) (xy 184.184183 -113.24796) (xy 184.214733 -113.290008)
			(xy 184.238329 -113.336318) (xy 184.25439 -113.385748) (xy 184.26252 -113.437083) (xy 184.26303 -113.46307)
			(xy 184.26252 -113.489057) (xy 184.40197 -113.489057) (xy 184.40197 -113.437083) (xy 184.4101 -113.385748)
			(xy 184.426161 -113.336318) (xy 184.449757 -113.290008) (xy 184.480307 -113.24796) (xy 184.517058 -113.211209)
			(xy 184.559106 -113.180659) (xy 184.605416 -113.157063) (xy 184.654846 -113.141002) (xy 184.706181 -113.132872)
			(xy 184.758155 -113.132872) (xy 184.80949 -113.141002) (xy 184.85892 -113.157063) (xy 184.90523 -113.180659)
			(xy 184.947278 -113.211209) (xy 184.984029 -113.24796) (xy 185.014579 -113.290008) (xy 185.038175 -113.336318)
			(xy 185.054236 -113.385748) (xy 185.062366 -113.437083) (xy 185.062876 -113.46307) (xy 185.062366 -113.489057)
			(xy 185.98185 -113.489057) (xy 185.98185 -113.437083) (xy 185.98998 -113.385748) (xy 186.006041 -113.336318)
			(xy 186.029637 -113.290008) (xy 186.060187 -113.24796) (xy 186.096938 -113.211209) (xy 186.138986 -113.180659)
			(xy 186.185296 -113.157063) (xy 186.234726 -113.141002) (xy 186.286061 -113.132872) (xy 186.338035 -113.132872)
			(xy 186.38937 -113.141002) (xy 186.4388 -113.157063) (xy 186.48511 -113.180659) (xy 186.527158 -113.211209)
			(xy 186.563909 -113.24796) (xy 186.594459 -113.290008) (xy 186.618055 -113.336318) (xy 186.634116 -113.385748)
			(xy 186.642246 -113.437083) (xy 186.642756 -113.46307) (xy 186.642246 -113.489057) (xy 186.781696 -113.489057)
			(xy 186.781696 -113.437083) (xy 186.789826 -113.385748) (xy 186.805887 -113.336318) (xy 186.829483 -113.290008)
			(xy 186.860033 -113.24796) (xy 186.896784 -113.211209) (xy 186.938832 -113.180659) (xy 186.985142 -113.157063)
			(xy 187.034572 -113.141002) (xy 187.085907 -113.132872) (xy 187.137881 -113.132872) (xy 187.189216 -113.141002)
			(xy 187.238646 -113.157063) (xy 187.284956 -113.180659) (xy 187.327004 -113.211209) (xy 187.363755 -113.24796)
			(xy 187.394305 -113.290008) (xy 187.417901 -113.336318) (xy 187.433962 -113.385748) (xy 187.442092 -113.437083)
			(xy 187.442602 -113.46307) (xy 187.442092 -113.489057) (xy 187.581796 -113.489057) (xy 187.581796 -113.437083)
			(xy 187.589926 -113.385748) (xy 187.605987 -113.336318) (xy 187.629583 -113.290008) (xy 187.660133 -113.24796)
			(xy 187.696884 -113.211209) (xy 187.738932 -113.180659) (xy 187.785242 -113.157063) (xy 187.834672 -113.141002)
			(xy 187.886007 -113.132872) (xy 187.937981 -113.132872) (xy 187.989316 -113.141002) (xy 188.038746 -113.157063)
			(xy 188.085056 -113.180659) (xy 188.127104 -113.211209) (xy 188.163855 -113.24796) (xy 188.194405 -113.290008)
			(xy 188.218001 -113.336318) (xy 188.234062 -113.385748) (xy 188.242192 -113.437083) (xy 188.242702 -113.46307)
			(xy 188.242192 -113.489057) (xy 188.381896 -113.489057) (xy 188.381896 -113.437083) (xy 188.390026 -113.385748)
			(xy 188.406087 -113.336318) (xy 188.429683 -113.290008) (xy 188.460233 -113.24796) (xy 188.496984 -113.211209)
			(xy 188.539032 -113.180659) (xy 188.585342 -113.157063) (xy 188.634772 -113.141002) (xy 188.686107 -113.132872)
			(xy 188.738081 -113.132872) (xy 188.789416 -113.141002) (xy 188.838846 -113.157063) (xy 188.885156 -113.180659)
			(xy 188.927204 -113.211209) (xy 188.963955 -113.24796) (xy 188.994505 -113.290008) (xy 189.018101 -113.336318)
			(xy 189.034162 -113.385748) (xy 189.042292 -113.437083) (xy 189.042802 -113.46307) (xy 189.042292 -113.489057)
			(xy 189.181742 -113.489057) (xy 189.181742 -113.437083) (xy 189.189872 -113.385748) (xy 189.205933 -113.336318)
			(xy 189.229529 -113.290008) (xy 189.260079 -113.24796) (xy 189.29683 -113.211209) (xy 189.338878 -113.180659)
			(xy 189.385188 -113.157063) (xy 189.434618 -113.141002) (xy 189.485953 -113.132872) (xy 189.537927 -113.132872)
			(xy 189.589262 -113.141002) (xy 189.638692 -113.157063) (xy 189.685002 -113.180659) (xy 189.72705 -113.211209)
			(xy 189.763801 -113.24796) (xy 189.794351 -113.290008) (xy 189.817947 -113.336318) (xy 189.834008 -113.385748)
			(xy 189.842138 -113.437083) (xy 189.842648 -113.46307) (xy 189.842138 -113.489057) (xy 189.981842 -113.489057)
			(xy 189.981842 -113.437083) (xy 189.989972 -113.385748) (xy 190.006033 -113.336318) (xy 190.029629 -113.290008)
			(xy 190.060179 -113.24796) (xy 190.09693 -113.211209) (xy 190.138978 -113.180659) (xy 190.185288 -113.157063)
			(xy 190.234718 -113.141002) (xy 190.286053 -113.132872) (xy 190.338027 -113.132872) (xy 190.389362 -113.141002)
			(xy 190.438792 -113.157063) (xy 190.485102 -113.180659) (xy 190.52715 -113.211209) (xy 190.563901 -113.24796)
			(xy 190.594451 -113.290008) (xy 190.618047 -113.336318) (xy 190.634108 -113.385748) (xy 190.642238 -113.437083)
			(xy 190.642748 -113.46307) (xy 190.642238 -113.489057) (xy 190.781688 -113.489057) (xy 190.781688 -113.437083)
			(xy 190.789818 -113.385748) (xy 190.805879 -113.336318) (xy 190.829475 -113.290008) (xy 190.860025 -113.24796)
			(xy 190.896776 -113.211209) (xy 190.938824 -113.180659) (xy 190.985134 -113.157063) (xy 191.034564 -113.141002)
			(xy 191.085899 -113.132872) (xy 191.137873 -113.132872) (xy 191.189208 -113.141002) (xy 191.238638 -113.157063)
			(xy 191.284948 -113.180659) (xy 191.326996 -113.211209) (xy 191.363747 -113.24796) (xy 191.394297 -113.290008)
			(xy 191.417893 -113.336318) (xy 191.433954 -113.385748) (xy 191.442084 -113.437083) (xy 191.442594 -113.46307)
			(xy 191.442084 -113.489057) (xy 191.581788 -113.489057) (xy 191.581788 -113.437083) (xy 191.589918 -113.385748)
			(xy 191.605979 -113.336318) (xy 191.629575 -113.290008) (xy 191.660125 -113.24796) (xy 191.696876 -113.211209)
			(xy 191.738924 -113.180659) (xy 191.785234 -113.157063) (xy 191.834664 -113.141002) (xy 191.885999 -113.132872)
			(xy 191.937973 -113.132872) (xy 191.989308 -113.141002) (xy 192.038738 -113.157063) (xy 192.085048 -113.180659)
			(xy 192.127096 -113.211209) (xy 192.163847 -113.24796) (xy 192.194397 -113.290008) (xy 192.217993 -113.336318)
			(xy 192.234054 -113.385748) (xy 192.242184 -113.437083) (xy 192.242694 -113.46307) (xy 192.242184 -113.489057)
			(xy 192.234054 -113.540392) (xy 192.217993 -113.589822) (xy 192.194397 -113.636132) (xy 192.163847 -113.67818)
			(xy 192.127096 -113.714931) (xy 192.085048 -113.745481) (xy 192.038738 -113.769077) (xy 191.989308 -113.785138)
			(xy 191.937973 -113.793268) (xy 191.885999 -113.793268) (xy 191.834664 -113.785138) (xy 191.785234 -113.769077)
			(xy 191.738924 -113.745481) (xy 191.696876 -113.714931) (xy 191.660125 -113.67818) (xy 191.629575 -113.636132)
			(xy 191.605979 -113.589822) (xy 191.589918 -113.540392) (xy 191.581788 -113.489057) (xy 191.442084 -113.489057)
			(xy 191.433954 -113.540392) (xy 191.417893 -113.589822) (xy 191.394297 -113.636132) (xy 191.363747 -113.67818)
			(xy 191.326996 -113.714931) (xy 191.284948 -113.745481) (xy 191.238638 -113.769077) (xy 191.189208 -113.785138)
			(xy 191.137873 -113.793268) (xy 191.085899 -113.793268) (xy 191.034564 -113.785138) (xy 190.985134 -113.769077)
			(xy 190.938824 -113.745481) (xy 190.896776 -113.714931) (xy 190.860025 -113.67818) (xy 190.829475 -113.636132)
			(xy 190.805879 -113.589822) (xy 190.789818 -113.540392) (xy 190.781688 -113.489057) (xy 190.642238 -113.489057)
			(xy 190.634108 -113.540392) (xy 190.618047 -113.589822) (xy 190.594451 -113.636132) (xy 190.563901 -113.67818)
			(xy 190.52715 -113.714931) (xy 190.485102 -113.745481) (xy 190.438792 -113.769077) (xy 190.389362 -113.785138)
			(xy 190.338027 -113.793268) (xy 190.286053 -113.793268) (xy 190.234718 -113.785138) (xy 190.185288 -113.769077)
			(xy 190.138978 -113.745481) (xy 190.09693 -113.714931) (xy 190.060179 -113.67818) (xy 190.029629 -113.636132)
			(xy 190.006033 -113.589822) (xy 189.989972 -113.540392) (xy 189.981842 -113.489057) (xy 189.842138 -113.489057)
			(xy 189.834008 -113.540392) (xy 189.817947 -113.589822) (xy 189.794351 -113.636132) (xy 189.763801 -113.67818)
			(xy 189.72705 -113.714931) (xy 189.685002 -113.745481) (xy 189.638692 -113.769077) (xy 189.589262 -113.785138)
			(xy 189.537927 -113.793268) (xy 189.485953 -113.793268) (xy 189.434618 -113.785138) (xy 189.385188 -113.769077)
			(xy 189.338878 -113.745481) (xy 189.29683 -113.714931) (xy 189.260079 -113.67818) (xy 189.229529 -113.636132)
			(xy 189.205933 -113.589822) (xy 189.189872 -113.540392) (xy 189.181742 -113.489057) (xy 189.042292 -113.489057)
			(xy 189.034162 -113.540392) (xy 189.018101 -113.589822) (xy 188.994505 -113.636132) (xy 188.963955 -113.67818)
			(xy 188.927204 -113.714931) (xy 188.885156 -113.745481) (xy 188.838846 -113.769077) (xy 188.789416 -113.785138)
			(xy 188.738081 -113.793268) (xy 188.686107 -113.793268) (xy 188.634772 -113.785138) (xy 188.585342 -113.769077)
			(xy 188.539032 -113.745481) (xy 188.496984 -113.714931) (xy 188.460233 -113.67818) (xy 188.429683 -113.636132)
			(xy 188.406087 -113.589822) (xy 188.390026 -113.540392) (xy 188.381896 -113.489057) (xy 188.242192 -113.489057)
			(xy 188.234062 -113.540392) (xy 188.218001 -113.589822) (xy 188.194405 -113.636132) (xy 188.163855 -113.67818)
			(xy 188.127104 -113.714931) (xy 188.085056 -113.745481) (xy 188.038746 -113.769077) (xy 187.989316 -113.785138)
			(xy 187.937981 -113.793268) (xy 187.886007 -113.793268) (xy 187.834672 -113.785138) (xy 187.785242 -113.769077)
			(xy 187.738932 -113.745481) (xy 187.696884 -113.714931) (xy 187.660133 -113.67818) (xy 187.629583 -113.636132)
			(xy 187.605987 -113.589822) (xy 187.589926 -113.540392) (xy 187.581796 -113.489057) (xy 187.442092 -113.489057)
			(xy 187.433962 -113.540392) (xy 187.417901 -113.589822) (xy 187.394305 -113.636132) (xy 187.363755 -113.67818)
			(xy 187.327004 -113.714931) (xy 187.284956 -113.745481) (xy 187.238646 -113.769077) (xy 187.189216 -113.785138)
			(xy 187.137881 -113.793268) (xy 187.085907 -113.793268) (xy 187.034572 -113.785138) (xy 186.985142 -113.769077)
			(xy 186.938832 -113.745481) (xy 186.896784 -113.714931) (xy 186.860033 -113.67818) (xy 186.829483 -113.636132)
			(xy 186.805887 -113.589822) (xy 186.789826 -113.540392) (xy 186.781696 -113.489057) (xy 186.642246 -113.489057)
			(xy 186.634116 -113.540392) (xy 186.618055 -113.589822) (xy 186.594459 -113.636132) (xy 186.563909 -113.67818)
			(xy 186.527158 -113.714931) (xy 186.48511 -113.745481) (xy 186.4388 -113.769077) (xy 186.38937 -113.785138)
			(xy 186.338035 -113.793268) (xy 186.286061 -113.793268) (xy 186.234726 -113.785138) (xy 186.185296 -113.769077)
			(xy 186.138986 -113.745481) (xy 186.096938 -113.714931) (xy 186.060187 -113.67818) (xy 186.029637 -113.636132)
			(xy 186.006041 -113.589822) (xy 185.98998 -113.540392) (xy 185.98185 -113.489057) (xy 185.062366 -113.489057)
			(xy 185.054236 -113.540392) (xy 185.038175 -113.589822) (xy 185.014579 -113.636132) (xy 184.984029 -113.67818)
			(xy 184.947278 -113.714931) (xy 184.90523 -113.745481) (xy 184.85892 -113.769077) (xy 184.80949 -113.785138)
			(xy 184.758155 -113.793268) (xy 184.706181 -113.793268) (xy 184.654846 -113.785138) (xy 184.605416 -113.769077)
			(xy 184.559106 -113.745481) (xy 184.517058 -113.714931) (xy 184.480307 -113.67818) (xy 184.449757 -113.636132)
			(xy 184.426161 -113.589822) (xy 184.4101 -113.540392) (xy 184.40197 -113.489057) (xy 184.26252 -113.489057)
			(xy 184.25439 -113.540392) (xy 184.238329 -113.589822) (xy 184.214733 -113.636132) (xy 184.184183 -113.67818)
			(xy 184.147432 -113.714931) (xy 184.105384 -113.745481) (xy 184.059074 -113.769077) (xy 184.009644 -113.785138)
			(xy 183.958309 -113.793268) (xy 183.906335 -113.793268) (xy 183.855 -113.785138) (xy 183.80557 -113.769077)
			(xy 183.75926 -113.745481) (xy 183.717212 -113.714931) (xy 183.680461 -113.67818) (xy 183.649911 -113.636132)
			(xy 183.626315 -113.589822) (xy 183.610254 -113.540392) (xy 183.602124 -113.489057) (xy 183.46242 -113.489057)
			(xy 183.45429 -113.540392) (xy 183.438229 -113.589822) (xy 183.414633 -113.636132) (xy 183.384083 -113.67818)
			(xy 183.347332 -113.714931) (xy 183.305284 -113.745481) (xy 183.258974 -113.769077) (xy 183.209544 -113.785138)
			(xy 183.158209 -113.793268) (xy 183.106235 -113.793268) (xy 183.0549 -113.785138) (xy 183.00547 -113.769077)
			(xy 182.95916 -113.745481) (xy 182.917112 -113.714931) (xy 182.880361 -113.67818) (xy 182.849811 -113.636132)
			(xy 182.826215 -113.589822) (xy 182.810154 -113.540392) (xy 182.802024 -113.489057) (xy 182.66232 -113.489057)
			(xy 182.65419 -113.540392) (xy 182.638129 -113.589822) (xy 182.614533 -113.636132) (xy 182.583983 -113.67818)
			(xy 182.547232 -113.714931) (xy 182.505184 -113.745481) (xy 182.458874 -113.769077) (xy 182.409444 -113.785138)
			(xy 182.358109 -113.793268) (xy 182.306135 -113.793268) (xy 182.2548 -113.785138) (xy 182.20537 -113.769077)
			(xy 182.15906 -113.745481) (xy 182.117012 -113.714931) (xy 182.080261 -113.67818) (xy 182.049711 -113.636132)
			(xy 182.026115 -113.589822) (xy 182.010054 -113.540392) (xy 182.001924 -113.489057) (xy 181.862474 -113.489057)
			(xy 181.854344 -113.540392) (xy 181.838283 -113.589822) (xy 181.814687 -113.636132) (xy 181.784137 -113.67818)
			(xy 181.747386 -113.714931) (xy 181.705338 -113.745481) (xy 181.659028 -113.769077) (xy 181.609598 -113.785138)
			(xy 181.558263 -113.793268) (xy 181.506289 -113.793268) (xy 181.454954 -113.785138) (xy 181.405524 -113.769077)
			(xy 181.359214 -113.745481) (xy 181.317166 -113.714931) (xy 181.280415 -113.67818) (xy 181.249865 -113.636132)
			(xy 181.226269 -113.589822) (xy 181.210208 -113.540392) (xy 181.202078 -113.489057) (xy 181.062374 -113.489057)
			(xy 181.054244 -113.540392) (xy 181.038183 -113.589822) (xy 181.014587 -113.636132) (xy 180.984037 -113.67818)
			(xy 180.947286 -113.714931) (xy 180.905238 -113.745481) (xy 180.858928 -113.769077) (xy 180.809498 -113.785138)
			(xy 180.758163 -113.793268) (xy 180.706189 -113.793268) (xy 180.654854 -113.785138) (xy 180.605424 -113.769077)
			(xy 180.559114 -113.745481) (xy 180.517066 -113.714931) (xy 180.480315 -113.67818) (xy 180.449765 -113.636132)
			(xy 180.426169 -113.589822) (xy 180.410108 -113.540392) (xy 180.401978 -113.489057) (xy 180.262528 -113.489057)
			(xy 180.254398 -113.540392) (xy 180.238337 -113.589822) (xy 180.214741 -113.636132) (xy 180.184191 -113.67818)
			(xy 180.14744 -113.714931) (xy 180.105392 -113.745481) (xy 180.059082 -113.769077) (xy 180.009652 -113.785138)
			(xy 179.958317 -113.793268) (xy 179.906343 -113.793268) (xy 179.855008 -113.785138) (xy 179.805578 -113.769077)
			(xy 179.759268 -113.745481) (xy 179.71722 -113.714931) (xy 179.680469 -113.67818) (xy 179.649919 -113.636132)
			(xy 179.626323 -113.589822) (xy 179.610262 -113.540392) (xy 179.602132 -113.489057) (xy 179.462428 -113.489057)
			(xy 179.454298 -113.540392) (xy 179.438237 -113.589822) (xy 179.414641 -113.636132) (xy 179.384091 -113.67818)
			(xy 179.34734 -113.714931) (xy 179.305292 -113.745481) (xy 179.258982 -113.769077) (xy 179.209552 -113.785138)
			(xy 179.158217 -113.793268) (xy 179.106243 -113.793268) (xy 179.054908 -113.785138) (xy 179.005478 -113.769077)
			(xy 178.959168 -113.745481) (xy 178.91712 -113.714931) (xy 178.880369 -113.67818) (xy 178.849819 -113.636132)
			(xy 178.826223 -113.589822) (xy 178.810162 -113.540392) (xy 178.802032 -113.489057) (xy 178.662328 -113.489057)
			(xy 178.654198 -113.540392) (xy 178.638137 -113.589822) (xy 178.614541 -113.636132) (xy 178.583991 -113.67818)
			(xy 178.54724 -113.714931) (xy 178.505192 -113.745481) (xy 178.458882 -113.769077) (xy 178.409452 -113.785138)
			(xy 178.358117 -113.793268) (xy 178.306143 -113.793268) (xy 178.254808 -113.785138) (xy 178.205378 -113.769077)
			(xy 178.159068 -113.745481) (xy 178.11702 -113.714931) (xy 178.080269 -113.67818) (xy 178.049719 -113.636132)
			(xy 178.026123 -113.589822) (xy 178.010062 -113.540392) (xy 178.001932 -113.489057) (xy 177.862482 -113.489057)
			(xy 177.854352 -113.540392) (xy 177.838291 -113.589822) (xy 177.814695 -113.636132) (xy 177.784145 -113.67818)
			(xy 177.747394 -113.714931) (xy 177.705346 -113.745481) (xy 177.659036 -113.769077) (xy 177.609606 -113.785138)
			(xy 177.558271 -113.793268) (xy 177.506297 -113.793268) (xy 177.454962 -113.785138) (xy 177.405532 -113.769077)
			(xy 177.359222 -113.745481) (xy 177.317174 -113.714931) (xy 177.280423 -113.67818) (xy 177.249873 -113.636132)
			(xy 177.226277 -113.589822) (xy 177.210216 -113.540392) (xy 177.202086 -113.489057) (xy 170.675352 -113.489057)
			(xy 170.667461 -113.522262) (xy 170.64712 -113.577997) (xy 170.620432 -113.630986) (xy 170.587761 -113.68051)
			(xy 170.549548 -113.725896) (xy 170.528234 -113.746534) (xy 170.520614 -113.753646) (xy 170.51655 -113.763298)
			(xy 170.514551 -113.768139) (xy 170.512382 -113.778382) (xy 170.512232 -113.783618) (xy 170.512232 -113.857278)
			(xy 170.512394 -113.862511) (xy 170.514577 -113.872748) (xy 170.51655 -113.877598) (xy 170.520614 -113.88725)
			(xy 170.528234 -113.894362) (xy 170.549569 -113.914981) (xy 170.587788 -113.960366) (xy 170.620465 -114.009891)
			(xy 170.647154 -114.062884) (xy 170.667494 -114.118622) (xy 170.681208 -114.17635) (xy 170.688109 -114.235281)
			(xy 170.688508 -114.264948) (xy 170.688146 -114.288903) (xy 176.401986 -114.288903) (xy 176.401986 -114.236929)
			(xy 176.410116 -114.185594) (xy 176.426177 -114.136164) (xy 176.449773 -114.089854) (xy 176.480323 -114.047806)
			(xy 176.517074 -114.011055) (xy 176.559122 -113.980505) (xy 176.605432 -113.956909) (xy 176.654862 -113.940848)
			(xy 176.706197 -113.932718) (xy 176.758171 -113.932718) (xy 176.809506 -113.940848) (xy 176.858936 -113.956909)
			(xy 176.905246 -113.980505) (xy 176.947294 -114.011055) (xy 176.984045 -114.047806) (xy 177.014595 -114.089854)
			(xy 177.038191 -114.136164) (xy 177.054252 -114.185594) (xy 177.062382 -114.236929) (xy 177.062892 -114.262916)
			(xy 177.062382 -114.288903) (xy 177.202086 -114.288903) (xy 177.202086 -114.236929) (xy 177.210216 -114.185594)
			(xy 177.226277 -114.136164) (xy 177.249873 -114.089854) (xy 177.280423 -114.047806) (xy 177.317174 -114.011055)
			(xy 177.359222 -113.980505) (xy 177.405532 -113.956909) (xy 177.454962 -113.940848) (xy 177.506297 -113.932718)
			(xy 177.558271 -113.932718) (xy 177.609606 -113.940848) (xy 177.659036 -113.956909) (xy 177.705346 -113.980505)
			(xy 177.747394 -114.011055) (xy 177.784145 -114.047806) (xy 177.814695 -114.089854) (xy 177.838291 -114.136164)
			(xy 177.854352 -114.185594) (xy 177.862482 -114.236929) (xy 177.862992 -114.262916) (xy 177.862482 -114.288903)
			(xy 178.001932 -114.288903) (xy 178.001932 -114.236929) (xy 178.010062 -114.185594) (xy 178.026123 -114.136164)
			(xy 178.049719 -114.089854) (xy 178.080269 -114.047806) (xy 178.11702 -114.011055) (xy 178.159068 -113.980505)
			(xy 178.205378 -113.956909) (xy 178.254808 -113.940848) (xy 178.306143 -113.932718) (xy 178.358117 -113.932718)
			(xy 178.409452 -113.940848) (xy 178.458882 -113.956909) (xy 178.505192 -113.980505) (xy 178.54724 -114.011055)
			(xy 178.583991 -114.047806) (xy 178.614541 -114.089854) (xy 178.638137 -114.136164) (xy 178.654198 -114.185594)
			(xy 178.662328 -114.236929) (xy 178.662838 -114.262916) (xy 178.662328 -114.288903) (xy 179.602132 -114.288903)
			(xy 179.602132 -114.236929) (xy 179.610262 -114.185594) (xy 179.626323 -114.136164) (xy 179.649919 -114.089854)
			(xy 179.680469 -114.047806) (xy 179.71722 -114.011055) (xy 179.759268 -113.980505) (xy 179.805578 -113.956909)
			(xy 179.855008 -113.940848) (xy 179.906343 -113.932718) (xy 179.958317 -113.932718) (xy 180.009652 -113.940848)
			(xy 180.059082 -113.956909) (xy 180.105392 -113.980505) (xy 180.14744 -114.011055) (xy 180.184191 -114.047806)
			(xy 180.214741 -114.089854) (xy 180.238337 -114.136164) (xy 180.254398 -114.185594) (xy 180.262528 -114.236929)
			(xy 180.263038 -114.262916) (xy 180.262528 -114.288903) (xy 180.401978 -114.288903) (xy 180.401978 -114.236929)
			(xy 180.410108 -114.185594) (xy 180.426169 -114.136164) (xy 180.449765 -114.089854) (xy 180.480315 -114.047806)
			(xy 180.517066 -114.011055) (xy 180.559114 -113.980505) (xy 180.605424 -113.956909) (xy 180.654854 -113.940848)
			(xy 180.706189 -113.932718) (xy 180.758163 -113.932718) (xy 180.809498 -113.940848) (xy 180.858928 -113.956909)
			(xy 180.905238 -113.980505) (xy 180.947286 -114.011055) (xy 180.984037 -114.047806) (xy 181.014587 -114.089854)
			(xy 181.038183 -114.136164) (xy 181.054244 -114.185594) (xy 181.062374 -114.236929) (xy 181.062884 -114.262916)
			(xy 181.062374 -114.288903) (xy 181.202078 -114.288903) (xy 181.202078 -114.236929) (xy 181.210208 -114.185594)
			(xy 181.226269 -114.136164) (xy 181.249865 -114.089854) (xy 181.280415 -114.047806) (xy 181.317166 -114.011055)
			(xy 181.359214 -113.980505) (xy 181.405524 -113.956909) (xy 181.454954 -113.940848) (xy 181.506289 -113.932718)
			(xy 181.558263 -113.932718) (xy 181.609598 -113.940848) (xy 181.659028 -113.956909) (xy 181.705338 -113.980505)
			(xy 181.747386 -114.011055) (xy 181.784137 -114.047806) (xy 181.814687 -114.089854) (xy 181.838283 -114.136164)
			(xy 181.854344 -114.185594) (xy 181.862474 -114.236929) (xy 181.862984 -114.262916) (xy 181.862474 -114.288903)
			(xy 182.001924 -114.288903) (xy 182.001924 -114.236929) (xy 182.010054 -114.185594) (xy 182.026115 -114.136164)
			(xy 182.049711 -114.089854) (xy 182.080261 -114.047806) (xy 182.117012 -114.011055) (xy 182.15906 -113.980505)
			(xy 182.20537 -113.956909) (xy 182.2548 -113.940848) (xy 182.306135 -113.932718) (xy 182.358109 -113.932718)
			(xy 182.409444 -113.940848) (xy 182.458874 -113.956909) (xy 182.505184 -113.980505) (xy 182.547232 -114.011055)
			(xy 182.583983 -114.047806) (xy 182.614533 -114.089854) (xy 182.638129 -114.136164) (xy 182.65419 -114.185594)
			(xy 182.66232 -114.236929) (xy 182.66283 -114.262916) (xy 182.66232 -114.288903) (xy 182.802024 -114.288903)
			(xy 182.802024 -114.236929) (xy 182.810154 -114.185594) (xy 182.826215 -114.136164) (xy 182.849811 -114.089854)
			(xy 182.880361 -114.047806) (xy 182.917112 -114.011055) (xy 182.95916 -113.980505) (xy 183.00547 -113.956909)
			(xy 183.0549 -113.940848) (xy 183.106235 -113.932718) (xy 183.158209 -113.932718) (xy 183.209544 -113.940848)
			(xy 183.258974 -113.956909) (xy 183.305284 -113.980505) (xy 183.347332 -114.011055) (xy 183.384083 -114.047806)
			(xy 183.414633 -114.089854) (xy 183.438229 -114.136164) (xy 183.45429 -114.185594) (xy 183.46242 -114.236929)
			(xy 183.46293 -114.262916) (xy 183.46242 -114.288903) (xy 183.602124 -114.288903) (xy 183.602124 -114.236929)
			(xy 183.610254 -114.185594) (xy 183.626315 -114.136164) (xy 183.649911 -114.089854) (xy 183.680461 -114.047806)
			(xy 183.717212 -114.011055) (xy 183.75926 -113.980505) (xy 183.80557 -113.956909) (xy 183.855 -113.940848)
			(xy 183.906335 -113.932718) (xy 183.958309 -113.932718) (xy 184.009644 -113.940848) (xy 184.059074 -113.956909)
			(xy 184.105384 -113.980505) (xy 184.147432 -114.011055) (xy 184.184183 -114.047806) (xy 184.214733 -114.089854)
			(xy 184.238329 -114.136164) (xy 184.25439 -114.185594) (xy 184.26252 -114.236929) (xy 184.26303 -114.262916)
			(xy 184.26252 -114.288903) (xy 184.40197 -114.288903) (xy 184.40197 -114.236929) (xy 184.4101 -114.185594)
			(xy 184.426161 -114.136164) (xy 184.449757 -114.089854) (xy 184.480307 -114.047806) (xy 184.517058 -114.011055)
			(xy 184.559106 -113.980505) (xy 184.605416 -113.956909) (xy 184.654846 -113.940848) (xy 184.706181 -113.932718)
			(xy 184.758155 -113.932718) (xy 184.80949 -113.940848) (xy 184.85892 -113.956909) (xy 184.90523 -113.980505)
			(xy 184.947278 -114.011055) (xy 184.984029 -114.047806) (xy 185.014579 -114.089854) (xy 185.038175 -114.136164)
			(xy 185.054236 -114.185594) (xy 185.062366 -114.236929) (xy 185.062876 -114.262916) (xy 185.062366 -114.288903)
			(xy 185.98185 -114.288903) (xy 185.98185 -114.236929) (xy 185.98998 -114.185594) (xy 186.006041 -114.136164)
			(xy 186.029637 -114.089854) (xy 186.060187 -114.047806) (xy 186.096938 -114.011055) (xy 186.138986 -113.980505)
			(xy 186.185296 -113.956909) (xy 186.234726 -113.940848) (xy 186.286061 -113.932718) (xy 186.338035 -113.932718)
			(xy 186.38937 -113.940848) (xy 186.4388 -113.956909) (xy 186.48511 -113.980505) (xy 186.527158 -114.011055)
			(xy 186.563909 -114.047806) (xy 186.594459 -114.089854) (xy 186.618055 -114.136164) (xy 186.634116 -114.185594)
			(xy 186.642246 -114.236929) (xy 186.642756 -114.262916) (xy 186.642246 -114.288903) (xy 186.781696 -114.288903)
			(xy 186.781696 -114.236929) (xy 186.789826 -114.185594) (xy 186.805887 -114.136164) (xy 186.829483 -114.089854)
			(xy 186.860033 -114.047806) (xy 186.896784 -114.011055) (xy 186.938832 -113.980505) (xy 186.985142 -113.956909)
			(xy 187.034572 -113.940848) (xy 187.085907 -113.932718) (xy 187.137881 -113.932718) (xy 187.189216 -113.940848)
			(xy 187.238646 -113.956909) (xy 187.284956 -113.980505) (xy 187.327004 -114.011055) (xy 187.363755 -114.047806)
			(xy 187.394305 -114.089854) (xy 187.417901 -114.136164) (xy 187.433962 -114.185594) (xy 187.442092 -114.236929)
			(xy 187.442602 -114.262916) (xy 187.442092 -114.288903) (xy 187.581796 -114.288903) (xy 187.581796 -114.236929)
			(xy 187.589926 -114.185594) (xy 187.605987 -114.136164) (xy 187.629583 -114.089854) (xy 187.660133 -114.047806)
			(xy 187.696884 -114.011055) (xy 187.738932 -113.980505) (xy 187.785242 -113.956909) (xy 187.834672 -113.940848)
			(xy 187.886007 -113.932718) (xy 187.937981 -113.932718) (xy 187.989316 -113.940848) (xy 188.038746 -113.956909)
			(xy 188.085056 -113.980505) (xy 188.127104 -114.011055) (xy 188.163855 -114.047806) (xy 188.194405 -114.089854)
			(xy 188.218001 -114.136164) (xy 188.234062 -114.185594) (xy 188.242192 -114.236929) (xy 188.242702 -114.262916)
			(xy 188.242192 -114.288903) (xy 188.381896 -114.288903) (xy 188.381896 -114.236929) (xy 188.390026 -114.185594)
			(xy 188.406087 -114.136164) (xy 188.429683 -114.089854) (xy 188.460233 -114.047806) (xy 188.496984 -114.011055)
			(xy 188.539032 -113.980505) (xy 188.585342 -113.956909) (xy 188.634772 -113.940848) (xy 188.686107 -113.932718)
			(xy 188.738081 -113.932718) (xy 188.789416 -113.940848) (xy 188.838846 -113.956909) (xy 188.885156 -113.980505)
			(xy 188.927204 -114.011055) (xy 188.963955 -114.047806) (xy 188.994505 -114.089854) (xy 189.018101 -114.136164)
			(xy 189.034162 -114.185594) (xy 189.042292 -114.236929) (xy 189.042802 -114.262916) (xy 189.042292 -114.288903)
			(xy 189.181742 -114.288903) (xy 189.181742 -114.236929) (xy 189.189872 -114.185594) (xy 189.205933 -114.136164)
			(xy 189.229529 -114.089854) (xy 189.260079 -114.047806) (xy 189.29683 -114.011055) (xy 189.338878 -113.980505)
			(xy 189.385188 -113.956909) (xy 189.434618 -113.940848) (xy 189.485953 -113.932718) (xy 189.537927 -113.932718)
			(xy 189.589262 -113.940848) (xy 189.638692 -113.956909) (xy 189.685002 -113.980505) (xy 189.72705 -114.011055)
			(xy 189.763801 -114.047806) (xy 189.794351 -114.089854) (xy 189.817947 -114.136164) (xy 189.834008 -114.185594)
			(xy 189.842138 -114.236929) (xy 189.842648 -114.262916) (xy 189.842138 -114.288903) (xy 189.981842 -114.288903)
			(xy 189.981842 -114.236929) (xy 189.989972 -114.185594) (xy 190.006033 -114.136164) (xy 190.029629 -114.089854)
			(xy 190.060179 -114.047806) (xy 190.09693 -114.011055) (xy 190.138978 -113.980505) (xy 190.185288 -113.956909)
			(xy 190.234718 -113.940848) (xy 190.286053 -113.932718) (xy 190.338027 -113.932718) (xy 190.389362 -113.940848)
			(xy 190.438792 -113.956909) (xy 190.485102 -113.980505) (xy 190.52715 -114.011055) (xy 190.563901 -114.047806)
			(xy 190.594451 -114.089854) (xy 190.618047 -114.136164) (xy 190.634108 -114.185594) (xy 190.642238 -114.236929)
			(xy 190.642748 -114.262916) (xy 190.642238 -114.288903) (xy 190.781688 -114.288903) (xy 190.781688 -114.236929)
			(xy 190.789818 -114.185594) (xy 190.805879 -114.136164) (xy 190.829475 -114.089854) (xy 190.860025 -114.047806)
			(xy 190.896776 -114.011055) (xy 190.938824 -113.980505) (xy 190.985134 -113.956909) (xy 191.034564 -113.940848)
			(xy 191.085899 -113.932718) (xy 191.137873 -113.932718) (xy 191.189208 -113.940848) (xy 191.238638 -113.956909)
			(xy 191.284948 -113.980505) (xy 191.326996 -114.011055) (xy 191.363747 -114.047806) (xy 191.394297 -114.089854)
			(xy 191.417893 -114.136164) (xy 191.433954 -114.185594) (xy 191.442084 -114.236929) (xy 191.442594 -114.262916)
			(xy 191.442084 -114.288903) (xy 191.581788 -114.288903) (xy 191.581788 -114.236929) (xy 191.589918 -114.185594)
			(xy 191.605979 -114.136164) (xy 191.629575 -114.089854) (xy 191.660125 -114.047806) (xy 191.696876 -114.011055)
			(xy 191.738924 -113.980505) (xy 191.785234 -113.956909) (xy 191.834664 -113.940848) (xy 191.885999 -113.932718)
			(xy 191.937973 -113.932718) (xy 191.989308 -113.940848) (xy 192.038738 -113.956909) (xy 192.085048 -113.980505)
			(xy 192.127096 -114.011055) (xy 192.163847 -114.047806) (xy 192.194397 -114.089854) (xy 192.217993 -114.136164)
			(xy 192.234054 -114.185594) (xy 192.242184 -114.236929) (xy 192.242694 -114.262916) (xy 192.242184 -114.288903)
			(xy 192.234054 -114.340238) (xy 192.217993 -114.389668) (xy 192.194397 -114.435978) (xy 192.163847 -114.478026)
			(xy 192.127096 -114.514777) (xy 192.085048 -114.545327) (xy 192.038738 -114.568923) (xy 191.989308 -114.584984)
			(xy 191.937973 -114.593114) (xy 191.885999 -114.593114) (xy 191.834664 -114.584984) (xy 191.785234 -114.568923)
			(xy 191.738924 -114.545327) (xy 191.696876 -114.514777) (xy 191.660125 -114.478026) (xy 191.629575 -114.435978)
			(xy 191.605979 -114.389668) (xy 191.589918 -114.340238) (xy 191.581788 -114.288903) (xy 191.442084 -114.288903)
			(xy 191.433954 -114.340238) (xy 191.417893 -114.389668) (xy 191.394297 -114.435978) (xy 191.363747 -114.478026)
			(xy 191.326996 -114.514777) (xy 191.284948 -114.545327) (xy 191.238638 -114.568923) (xy 191.189208 -114.584984)
			(xy 191.137873 -114.593114) (xy 191.085899 -114.593114) (xy 191.034564 -114.584984) (xy 190.985134 -114.568923)
			(xy 190.938824 -114.545327) (xy 190.896776 -114.514777) (xy 190.860025 -114.478026) (xy 190.829475 -114.435978)
			(xy 190.805879 -114.389668) (xy 190.789818 -114.340238) (xy 190.781688 -114.288903) (xy 190.642238 -114.288903)
			(xy 190.634108 -114.340238) (xy 190.618047 -114.389668) (xy 190.594451 -114.435978) (xy 190.563901 -114.478026)
			(xy 190.52715 -114.514777) (xy 190.485102 -114.545327) (xy 190.438792 -114.568923) (xy 190.389362 -114.584984)
			(xy 190.338027 -114.593114) (xy 190.286053 -114.593114) (xy 190.234718 -114.584984) (xy 190.185288 -114.568923)
			(xy 190.138978 -114.545327) (xy 190.09693 -114.514777) (xy 190.060179 -114.478026) (xy 190.029629 -114.435978)
			(xy 190.006033 -114.389668) (xy 189.989972 -114.340238) (xy 189.981842 -114.288903) (xy 189.842138 -114.288903)
			(xy 189.834008 -114.340238) (xy 189.817947 -114.389668) (xy 189.794351 -114.435978) (xy 189.763801 -114.478026)
			(xy 189.72705 -114.514777) (xy 189.685002 -114.545327) (xy 189.638692 -114.568923) (xy 189.589262 -114.584984)
			(xy 189.537927 -114.593114) (xy 189.485953 -114.593114) (xy 189.434618 -114.584984) (xy 189.385188 -114.568923)
			(xy 189.338878 -114.545327) (xy 189.29683 -114.514777) (xy 189.260079 -114.478026) (xy 189.229529 -114.435978)
			(xy 189.205933 -114.389668) (xy 189.189872 -114.340238) (xy 189.181742 -114.288903) (xy 189.042292 -114.288903)
			(xy 189.034162 -114.340238) (xy 189.018101 -114.389668) (xy 188.994505 -114.435978) (xy 188.963955 -114.478026)
			(xy 188.927204 -114.514777) (xy 188.885156 -114.545327) (xy 188.838846 -114.568923) (xy 188.789416 -114.584984)
			(xy 188.738081 -114.593114) (xy 188.686107 -114.593114) (xy 188.634772 -114.584984) (xy 188.585342 -114.568923)
			(xy 188.539032 -114.545327) (xy 188.496984 -114.514777) (xy 188.460233 -114.478026) (xy 188.429683 -114.435978)
			(xy 188.406087 -114.389668) (xy 188.390026 -114.340238) (xy 188.381896 -114.288903) (xy 188.242192 -114.288903)
			(xy 188.234062 -114.340238) (xy 188.218001 -114.389668) (xy 188.194405 -114.435978) (xy 188.163855 -114.478026)
			(xy 188.127104 -114.514777) (xy 188.085056 -114.545327) (xy 188.038746 -114.568923) (xy 187.989316 -114.584984)
			(xy 187.937981 -114.593114) (xy 187.886007 -114.593114) (xy 187.834672 -114.584984) (xy 187.785242 -114.568923)
			(xy 187.738932 -114.545327) (xy 187.696884 -114.514777) (xy 187.660133 -114.478026) (xy 187.629583 -114.435978)
			(xy 187.605987 -114.389668) (xy 187.589926 -114.340238) (xy 187.581796 -114.288903) (xy 187.442092 -114.288903)
			(xy 187.433962 -114.340238) (xy 187.417901 -114.389668) (xy 187.394305 -114.435978) (xy 187.363755 -114.478026)
			(xy 187.327004 -114.514777) (xy 187.284956 -114.545327) (xy 187.238646 -114.568923) (xy 187.189216 -114.584984)
			(xy 187.137881 -114.593114) (xy 187.085907 -114.593114) (xy 187.034572 -114.584984) (xy 186.985142 -114.568923)
			(xy 186.938832 -114.545327) (xy 186.896784 -114.514777) (xy 186.860033 -114.478026) (xy 186.829483 -114.435978)
			(xy 186.805887 -114.389668) (xy 186.789826 -114.340238) (xy 186.781696 -114.288903) (xy 186.642246 -114.288903)
			(xy 186.634116 -114.340238) (xy 186.618055 -114.389668) (xy 186.594459 -114.435978) (xy 186.563909 -114.478026)
			(xy 186.527158 -114.514777) (xy 186.48511 -114.545327) (xy 186.4388 -114.568923) (xy 186.38937 -114.584984)
			(xy 186.338035 -114.593114) (xy 186.286061 -114.593114) (xy 186.234726 -114.584984) (xy 186.185296 -114.568923)
			(xy 186.138986 -114.545327) (xy 186.096938 -114.514777) (xy 186.060187 -114.478026) (xy 186.029637 -114.435978)
			(xy 186.006041 -114.389668) (xy 185.98998 -114.340238) (xy 185.98185 -114.288903) (xy 185.062366 -114.288903)
			(xy 185.054236 -114.340238) (xy 185.038175 -114.389668) (xy 185.014579 -114.435978) (xy 184.984029 -114.478026)
			(xy 184.947278 -114.514777) (xy 184.90523 -114.545327) (xy 184.85892 -114.568923) (xy 184.80949 -114.584984)
			(xy 184.758155 -114.593114) (xy 184.706181 -114.593114) (xy 184.654846 -114.584984) (xy 184.605416 -114.568923)
			(xy 184.559106 -114.545327) (xy 184.517058 -114.514777) (xy 184.480307 -114.478026) (xy 184.449757 -114.435978)
			(xy 184.426161 -114.389668) (xy 184.4101 -114.340238) (xy 184.40197 -114.288903) (xy 184.26252 -114.288903)
			(xy 184.25439 -114.340238) (xy 184.238329 -114.389668) (xy 184.214733 -114.435978) (xy 184.184183 -114.478026)
			(xy 184.147432 -114.514777) (xy 184.105384 -114.545327) (xy 184.059074 -114.568923) (xy 184.009644 -114.584984)
			(xy 183.958309 -114.593114) (xy 183.906335 -114.593114) (xy 183.855 -114.584984) (xy 183.80557 -114.568923)
			(xy 183.75926 -114.545327) (xy 183.717212 -114.514777) (xy 183.680461 -114.478026) (xy 183.649911 -114.435978)
			(xy 183.626315 -114.389668) (xy 183.610254 -114.340238) (xy 183.602124 -114.288903) (xy 183.46242 -114.288903)
			(xy 183.45429 -114.340238) (xy 183.438229 -114.389668) (xy 183.414633 -114.435978) (xy 183.384083 -114.478026)
			(xy 183.347332 -114.514777) (xy 183.305284 -114.545327) (xy 183.258974 -114.568923) (xy 183.209544 -114.584984)
			(xy 183.158209 -114.593114) (xy 183.106235 -114.593114) (xy 183.0549 -114.584984) (xy 183.00547 -114.568923)
			(xy 182.95916 -114.545327) (xy 182.917112 -114.514777) (xy 182.880361 -114.478026) (xy 182.849811 -114.435978)
			(xy 182.826215 -114.389668) (xy 182.810154 -114.340238) (xy 182.802024 -114.288903) (xy 182.66232 -114.288903)
			(xy 182.65419 -114.340238) (xy 182.638129 -114.389668) (xy 182.614533 -114.435978) (xy 182.583983 -114.478026)
			(xy 182.547232 -114.514777) (xy 182.505184 -114.545327) (xy 182.458874 -114.568923) (xy 182.409444 -114.584984)
			(xy 182.358109 -114.593114) (xy 182.306135 -114.593114) (xy 182.2548 -114.584984) (xy 182.20537 -114.568923)
			(xy 182.15906 -114.545327) (xy 182.117012 -114.514777) (xy 182.080261 -114.478026) (xy 182.049711 -114.435978)
			(xy 182.026115 -114.389668) (xy 182.010054 -114.340238) (xy 182.001924 -114.288903) (xy 181.862474 -114.288903)
			(xy 181.854344 -114.340238) (xy 181.838283 -114.389668) (xy 181.814687 -114.435978) (xy 181.784137 -114.478026)
			(xy 181.747386 -114.514777) (xy 181.705338 -114.545327) (xy 181.659028 -114.568923) (xy 181.609598 -114.584984)
			(xy 181.558263 -114.593114) (xy 181.506289 -114.593114) (xy 181.454954 -114.584984) (xy 181.405524 -114.568923)
			(xy 181.359214 -114.545327) (xy 181.317166 -114.514777) (xy 181.280415 -114.478026) (xy 181.249865 -114.435978)
			(xy 181.226269 -114.389668) (xy 181.210208 -114.340238) (xy 181.202078 -114.288903) (xy 181.062374 -114.288903)
			(xy 181.054244 -114.340238) (xy 181.038183 -114.389668) (xy 181.014587 -114.435978) (xy 180.984037 -114.478026)
			(xy 180.947286 -114.514777) (xy 180.905238 -114.545327) (xy 180.858928 -114.568923) (xy 180.809498 -114.584984)
			(xy 180.758163 -114.593114) (xy 180.706189 -114.593114) (xy 180.654854 -114.584984) (xy 180.605424 -114.568923)
			(xy 180.559114 -114.545327) (xy 180.517066 -114.514777) (xy 180.480315 -114.478026) (xy 180.449765 -114.435978)
			(xy 180.426169 -114.389668) (xy 180.410108 -114.340238) (xy 180.401978 -114.288903) (xy 180.262528 -114.288903)
			(xy 180.254398 -114.340238) (xy 180.238337 -114.389668) (xy 180.214741 -114.435978) (xy 180.184191 -114.478026)
			(xy 180.14744 -114.514777) (xy 180.105392 -114.545327) (xy 180.059082 -114.568923) (xy 180.009652 -114.584984)
			(xy 179.958317 -114.593114) (xy 179.906343 -114.593114) (xy 179.855008 -114.584984) (xy 179.805578 -114.568923)
			(xy 179.759268 -114.545327) (xy 179.71722 -114.514777) (xy 179.680469 -114.478026) (xy 179.649919 -114.435978)
			(xy 179.626323 -114.389668) (xy 179.610262 -114.340238) (xy 179.602132 -114.288903) (xy 178.662328 -114.288903)
			(xy 178.654198 -114.340238) (xy 178.638137 -114.389668) (xy 178.614541 -114.435978) (xy 178.583991 -114.478026)
			(xy 178.54724 -114.514777) (xy 178.505192 -114.545327) (xy 178.458882 -114.568923) (xy 178.409452 -114.584984)
			(xy 178.358117 -114.593114) (xy 178.306143 -114.593114) (xy 178.254808 -114.584984) (xy 178.205378 -114.568923)
			(xy 178.159068 -114.545327) (xy 178.11702 -114.514777) (xy 178.080269 -114.478026) (xy 178.049719 -114.435978)
			(xy 178.026123 -114.389668) (xy 178.010062 -114.340238) (xy 178.001932 -114.288903) (xy 177.862482 -114.288903)
			(xy 177.854352 -114.340238) (xy 177.838291 -114.389668) (xy 177.814695 -114.435978) (xy 177.784145 -114.478026)
			(xy 177.747394 -114.514777) (xy 177.705346 -114.545327) (xy 177.659036 -114.568923) (xy 177.609606 -114.584984)
			(xy 177.558271 -114.593114) (xy 177.506297 -114.593114) (xy 177.454962 -114.584984) (xy 177.405532 -114.568923)
			(xy 177.359222 -114.545327) (xy 177.317174 -114.514777) (xy 177.280423 -114.478026) (xy 177.249873 -114.435978)
			(xy 177.226277 -114.389668) (xy 177.210216 -114.340238) (xy 177.202086 -114.288903) (xy 177.062382 -114.288903)
			(xy 177.054252 -114.340238) (xy 177.038191 -114.389668) (xy 177.014595 -114.435978) (xy 176.984045 -114.478026)
			(xy 176.947294 -114.514777) (xy 176.905246 -114.545327) (xy 176.858936 -114.568923) (xy 176.809506 -114.584984)
			(xy 176.758171 -114.593114) (xy 176.706197 -114.593114) (xy 176.654862 -114.584984) (xy 176.605432 -114.568923)
			(xy 176.559122 -114.545327) (xy 176.517074 -114.514777) (xy 176.480323 -114.478026) (xy 176.449773 -114.435978)
			(xy 176.426177 -114.389668) (xy 176.410116 -114.340238) (xy 176.401986 -114.288903) (xy 170.688146 -114.288903)
			(xy 170.688039 -114.296006) (xy 170.680466 -114.357658) (xy 170.665437 -114.417929) (xy 170.643178 -114.475919)
			(xy 170.614019 -114.530765) (xy 170.578395 -114.581651) (xy 170.536837 -114.627817) (xy 170.489964 -114.668576)
			(xy 170.46448 -114.686334) (xy 170.454501 -114.693813) (xy 170.44278 -114.715791) (xy 170.442128 -114.728244)
			(xy 170.442128 -114.81308) (xy 170.44279 -114.824438) (xy 170.452671 -114.844897) (xy 170.461178 -114.85245)
			(xy 170.487001 -114.870186) (xy 170.534531 -114.910998) (xy 170.576693 -114.957333) (xy 170.612852 -115.008491)
			(xy 170.642461 -115.0637) (xy 170.665072 -115.122124) (xy 170.680344 -115.182881) (xy 170.688046 -115.245053)
			(xy 170.688508 -115.276376) (xy 170.688064 -115.307109) (xy 170.680658 -115.368127) (xy 170.66595 -115.427808)
			(xy 170.644156 -115.48528) (xy 170.615593 -115.539707) (xy 170.580678 -115.590293) (xy 170.539919 -115.636302)
			(xy 170.538543 -115.637521) (xy 171.973742 -115.637521) (xy 171.973742 -115.573599) (xy 171.981753 -115.510181)
			(xy 171.99765 -115.448267) (xy 172.021182 -115.388834) (xy 172.051976 -115.332819) (xy 172.089549 -115.281104)
			(xy 172.133306 -115.234507) (xy 172.182559 -115.193762) (xy 172.23653 -115.159511) (xy 172.294369 -115.132294)
			(xy 172.355162 -115.112541) (xy 172.417952 -115.100563) (xy 172.481748 -115.09655) (xy 172.545544 -115.100563)
			(xy 172.608334 -115.112541) (xy 172.669127 -115.132294) (xy 172.726966 -115.159511) (xy 172.780937 -115.193762)
			(xy 172.83019 -115.234507) (xy 172.873947 -115.281104) (xy 172.91152 -115.332819) (xy 172.942314 -115.388834)
			(xy 172.965846 -115.448267) (xy 172.981743 -115.510181) (xy 172.989754 -115.573599) (xy 172.990256 -115.60556)
			(xy 172.989754 -115.637521) (xy 172.981743 -115.700939) (xy 172.965846 -115.762853) (xy 172.942314 -115.822286)
			(xy 172.916752 -115.868783) (xy 178.001932 -115.868783) (xy 178.001932 -115.816809) (xy 178.010062 -115.765474)
			(xy 178.026123 -115.716044) (xy 178.049719 -115.669734) (xy 178.080269 -115.627686) (xy 178.11702 -115.590935)
			(xy 178.159068 -115.560385) (xy 178.205378 -115.536789) (xy 178.254808 -115.520728) (xy 178.306143 -115.512598)
			(xy 178.358117 -115.512598) (xy 178.409452 -115.520728) (xy 178.458882 -115.536789) (xy 178.505192 -115.560385)
			(xy 178.54724 -115.590935) (xy 178.583991 -115.627686) (xy 178.614541 -115.669734) (xy 178.638137 -115.716044)
			(xy 178.654198 -115.765474) (xy 178.662328 -115.816809) (xy 178.662838 -115.842796) (xy 178.662328 -115.868783)
			(xy 178.802032 -115.868783) (xy 178.802032 -115.816809) (xy 178.810162 -115.765474) (xy 178.826223 -115.716044)
			(xy 178.849819 -115.669734) (xy 178.880369 -115.627686) (xy 178.91712 -115.590935) (xy 178.959168 -115.560385)
			(xy 179.005478 -115.536789) (xy 179.054908 -115.520728) (xy 179.106243 -115.512598) (xy 179.158217 -115.512598)
			(xy 179.209552 -115.520728) (xy 179.258982 -115.536789) (xy 179.305292 -115.560385) (xy 179.34734 -115.590935)
			(xy 179.384091 -115.627686) (xy 179.414641 -115.669734) (xy 179.438237 -115.716044) (xy 179.454298 -115.765474)
			(xy 179.462428 -115.816809) (xy 179.462938 -115.842796) (xy 179.462428 -115.868783) (xy 179.602132 -115.868783)
			(xy 179.602132 -115.816809) (xy 179.610262 -115.765474) (xy 179.626323 -115.716044) (xy 179.649919 -115.669734)
			(xy 179.680469 -115.627686) (xy 179.71722 -115.590935) (xy 179.759268 -115.560385) (xy 179.805578 -115.536789)
			(xy 179.855008 -115.520728) (xy 179.906343 -115.512598) (xy 179.958317 -115.512598) (xy 180.009652 -115.520728)
			(xy 180.059082 -115.536789) (xy 180.105392 -115.560385) (xy 180.14744 -115.590935) (xy 180.184191 -115.627686)
			(xy 180.214741 -115.669734) (xy 180.238337 -115.716044) (xy 180.254398 -115.765474) (xy 180.262528 -115.816809)
			(xy 180.263038 -115.842796) (xy 180.262528 -115.868783) (xy 180.401978 -115.868783) (xy 180.401978 -115.816809)
			(xy 180.410108 -115.765474) (xy 180.426169 -115.716044) (xy 180.449765 -115.669734) (xy 180.480315 -115.627686)
			(xy 180.517066 -115.590935) (xy 180.559114 -115.560385) (xy 180.605424 -115.536789) (xy 180.654854 -115.520728)
			(xy 180.706189 -115.512598) (xy 180.758163 -115.512598) (xy 180.809498 -115.520728) (xy 180.858928 -115.536789)
			(xy 180.905238 -115.560385) (xy 180.947286 -115.590935) (xy 180.984037 -115.627686) (xy 181.014587 -115.669734)
			(xy 181.038183 -115.716044) (xy 181.054244 -115.765474) (xy 181.062374 -115.816809) (xy 181.062884 -115.842796)
			(xy 181.062374 -115.868783) (xy 181.202078 -115.868783) (xy 181.202078 -115.816809) (xy 181.210208 -115.765474)
			(xy 181.226269 -115.716044) (xy 181.249865 -115.669734) (xy 181.280415 -115.627686) (xy 181.317166 -115.590935)
			(xy 181.359214 -115.560385) (xy 181.405524 -115.536789) (xy 181.454954 -115.520728) (xy 181.506289 -115.512598)
			(xy 181.558263 -115.512598) (xy 181.609598 -115.520728) (xy 181.659028 -115.536789) (xy 181.705338 -115.560385)
			(xy 181.747386 -115.590935) (xy 181.784137 -115.627686) (xy 181.814687 -115.669734) (xy 181.838283 -115.716044)
			(xy 181.854344 -115.765474) (xy 181.862474 -115.816809) (xy 181.862984 -115.842796) (xy 181.862474 -115.868783)
			(xy 182.001924 -115.868783) (xy 182.001924 -115.816809) (xy 182.010054 -115.765474) (xy 182.026115 -115.716044)
			(xy 182.049711 -115.669734) (xy 182.080261 -115.627686) (xy 182.117012 -115.590935) (xy 182.15906 -115.560385)
			(xy 182.20537 -115.536789) (xy 182.2548 -115.520728) (xy 182.306135 -115.512598) (xy 182.358109 -115.512598)
			(xy 182.409444 -115.520728) (xy 182.458874 -115.536789) (xy 182.505184 -115.560385) (xy 182.547232 -115.590935)
			(xy 182.583983 -115.627686) (xy 182.614533 -115.669734) (xy 182.638129 -115.716044) (xy 182.65419 -115.765474)
			(xy 182.66232 -115.816809) (xy 182.66283 -115.842796) (xy 182.66232 -115.868783) (xy 182.802024 -115.868783)
			(xy 182.802024 -115.816809) (xy 182.810154 -115.765474) (xy 182.826215 -115.716044) (xy 182.849811 -115.669734)
			(xy 182.880361 -115.627686) (xy 182.917112 -115.590935) (xy 182.95916 -115.560385) (xy 183.00547 -115.536789)
			(xy 183.0549 -115.520728) (xy 183.106235 -115.512598) (xy 183.158209 -115.512598) (xy 183.209544 -115.520728)
			(xy 183.258974 -115.536789) (xy 183.305284 -115.560385) (xy 183.347332 -115.590935) (xy 183.384083 -115.627686)
			(xy 183.414633 -115.669734) (xy 183.438229 -115.716044) (xy 183.45429 -115.765474) (xy 183.46242 -115.816809)
			(xy 183.46293 -115.842796) (xy 183.46242 -115.868783) (xy 183.602124 -115.868783) (xy 183.602124 -115.816809)
			(xy 183.610254 -115.765474) (xy 183.626315 -115.716044) (xy 183.649911 -115.669734) (xy 183.680461 -115.627686)
			(xy 183.717212 -115.590935) (xy 183.75926 -115.560385) (xy 183.80557 -115.536789) (xy 183.855 -115.520728)
			(xy 183.906335 -115.512598) (xy 183.958309 -115.512598) (xy 184.009644 -115.520728) (xy 184.059074 -115.536789)
			(xy 184.105384 -115.560385) (xy 184.147432 -115.590935) (xy 184.184183 -115.627686) (xy 184.214733 -115.669734)
			(xy 184.238329 -115.716044) (xy 184.25439 -115.765474) (xy 184.26252 -115.816809) (xy 184.26303 -115.842796)
			(xy 184.26252 -115.868783) (xy 184.40197 -115.868783) (xy 184.40197 -115.816809) (xy 184.4101 -115.765474)
			(xy 184.426161 -115.716044) (xy 184.449757 -115.669734) (xy 184.480307 -115.627686) (xy 184.517058 -115.590935)
			(xy 184.559106 -115.560385) (xy 184.605416 -115.536789) (xy 184.654846 -115.520728) (xy 184.706181 -115.512598)
			(xy 184.758155 -115.512598) (xy 184.80949 -115.520728) (xy 184.85892 -115.536789) (xy 184.90523 -115.560385)
			(xy 184.947278 -115.590935) (xy 184.984029 -115.627686) (xy 185.014579 -115.669734) (xy 185.038175 -115.716044)
			(xy 185.054236 -115.765474) (xy 185.062366 -115.816809) (xy 185.062876 -115.842796) (xy 185.062366 -115.868783)
			(xy 185.98185 -115.868783) (xy 185.98185 -115.816809) (xy 185.98998 -115.765474) (xy 186.006041 -115.716044)
			(xy 186.029637 -115.669734) (xy 186.060187 -115.627686) (xy 186.096938 -115.590935) (xy 186.138986 -115.560385)
			(xy 186.185296 -115.536789) (xy 186.234726 -115.520728) (xy 186.286061 -115.512598) (xy 186.338035 -115.512598)
			(xy 186.38937 -115.520728) (xy 186.4388 -115.536789) (xy 186.48511 -115.560385) (xy 186.527158 -115.590935)
			(xy 186.563909 -115.627686) (xy 186.594459 -115.669734) (xy 186.618055 -115.716044) (xy 186.634116 -115.765474)
			(xy 186.642246 -115.816809) (xy 186.642756 -115.842796) (xy 186.642246 -115.868783) (xy 186.781696 -115.868783)
			(xy 186.781696 -115.816809) (xy 186.789826 -115.765474) (xy 186.805887 -115.716044) (xy 186.829483 -115.669734)
			(xy 186.860033 -115.627686) (xy 186.896784 -115.590935) (xy 186.938832 -115.560385) (xy 186.985142 -115.536789)
			(xy 187.034572 -115.520728) (xy 187.085907 -115.512598) (xy 187.137881 -115.512598) (xy 187.189216 -115.520728)
			(xy 187.238646 -115.536789) (xy 187.284956 -115.560385) (xy 187.327004 -115.590935) (xy 187.363755 -115.627686)
			(xy 187.394305 -115.669734) (xy 187.417901 -115.716044) (xy 187.433962 -115.765474) (xy 187.442092 -115.816809)
			(xy 187.442602 -115.842796) (xy 187.442092 -115.868783) (xy 187.581796 -115.868783) (xy 187.581796 -115.816809)
			(xy 187.589926 -115.765474) (xy 187.605987 -115.716044) (xy 187.629583 -115.669734) (xy 187.660133 -115.627686)
			(xy 187.696884 -115.590935) (xy 187.738932 -115.560385) (xy 187.785242 -115.536789) (xy 187.834672 -115.520728)
			(xy 187.886007 -115.512598) (xy 187.937981 -115.512598) (xy 187.989316 -115.520728) (xy 188.038746 -115.536789)
			(xy 188.085056 -115.560385) (xy 188.127104 -115.590935) (xy 188.163855 -115.627686) (xy 188.194405 -115.669734)
			(xy 188.218001 -115.716044) (xy 188.234062 -115.765474) (xy 188.242192 -115.816809) (xy 188.242702 -115.842796)
			(xy 188.242192 -115.868783) (xy 188.381896 -115.868783) (xy 188.381896 -115.816809) (xy 188.390026 -115.765474)
			(xy 188.406087 -115.716044) (xy 188.429683 -115.669734) (xy 188.460233 -115.627686) (xy 188.496984 -115.590935)
			(xy 188.539032 -115.560385) (xy 188.585342 -115.536789) (xy 188.634772 -115.520728) (xy 188.686107 -115.512598)
			(xy 188.738081 -115.512598) (xy 188.789416 -115.520728) (xy 188.838846 -115.536789) (xy 188.885156 -115.560385)
			(xy 188.927204 -115.590935) (xy 188.963955 -115.627686) (xy 188.994505 -115.669734) (xy 189.018101 -115.716044)
			(xy 189.034162 -115.765474) (xy 189.042292 -115.816809) (xy 189.042802 -115.842796) (xy 189.042292 -115.868783)
			(xy 189.181742 -115.868783) (xy 189.181742 -115.816809) (xy 189.189872 -115.765474) (xy 189.205933 -115.716044)
			(xy 189.229529 -115.669734) (xy 189.260079 -115.627686) (xy 189.29683 -115.590935) (xy 189.338878 -115.560385)
			(xy 189.385188 -115.536789) (xy 189.434618 -115.520728) (xy 189.485953 -115.512598) (xy 189.537927 -115.512598)
			(xy 189.589262 -115.520728) (xy 189.638692 -115.536789) (xy 189.685002 -115.560385) (xy 189.72705 -115.590935)
			(xy 189.763801 -115.627686) (xy 189.794351 -115.669734) (xy 189.817947 -115.716044) (xy 189.834008 -115.765474)
			(xy 189.842138 -115.816809) (xy 189.842648 -115.842796) (xy 189.842138 -115.868783) (xy 189.981842 -115.868783)
			(xy 189.981842 -115.816809) (xy 189.989972 -115.765474) (xy 190.006033 -115.716044) (xy 190.029629 -115.669734)
			(xy 190.060179 -115.627686) (xy 190.09693 -115.590935) (xy 190.138978 -115.560385) (xy 190.185288 -115.536789)
			(xy 190.234718 -115.520728) (xy 190.286053 -115.512598) (xy 190.338027 -115.512598) (xy 190.389362 -115.520728)
			(xy 190.438792 -115.536789) (xy 190.485102 -115.560385) (xy 190.52715 -115.590935) (xy 190.563901 -115.627686)
			(xy 190.594451 -115.669734) (xy 190.618047 -115.716044) (xy 190.634108 -115.765474) (xy 190.642238 -115.816809)
			(xy 190.642748 -115.842796) (xy 190.642238 -115.868783) (xy 190.781688 -115.868783) (xy 190.781688 -115.816809)
			(xy 190.789818 -115.765474) (xy 190.805879 -115.716044) (xy 190.829475 -115.669734) (xy 190.860025 -115.627686)
			(xy 190.896776 -115.590935) (xy 190.938824 -115.560385) (xy 190.985134 -115.536789) (xy 191.034564 -115.520728)
			(xy 191.085899 -115.512598) (xy 191.137873 -115.512598) (xy 191.189208 -115.520728) (xy 191.238638 -115.536789)
			(xy 191.284948 -115.560385) (xy 191.326996 -115.590935) (xy 191.363747 -115.627686) (xy 191.394297 -115.669734)
			(xy 191.417893 -115.716044) (xy 191.433954 -115.765474) (xy 191.442084 -115.816809) (xy 191.442594 -115.842796)
			(xy 191.442084 -115.868783) (xy 191.581788 -115.868783) (xy 191.581788 -115.816809) (xy 191.589918 -115.765474)
			(xy 191.605979 -115.716044) (xy 191.629575 -115.669734) (xy 191.660125 -115.627686) (xy 191.696876 -115.590935)
			(xy 191.738924 -115.560385) (xy 191.785234 -115.536789) (xy 191.834664 -115.520728) (xy 191.885999 -115.512598)
			(xy 191.937973 -115.512598) (xy 191.989308 -115.520728) (xy 192.038738 -115.536789) (xy 192.085048 -115.560385)
			(xy 192.127096 -115.590935) (xy 192.163847 -115.627686) (xy 192.194397 -115.669734) (xy 192.217993 -115.716044)
			(xy 192.234054 -115.765474) (xy 192.242184 -115.816809) (xy 192.242694 -115.842796) (xy 192.242184 -115.868783)
			(xy 192.234054 -115.920118) (xy 192.217993 -115.969548) (xy 192.194397 -116.015858) (xy 192.163847 -116.057906)
			(xy 192.127096 -116.094657) (xy 192.085048 -116.125207) (xy 192.038738 -116.148803) (xy 191.989308 -116.164864)
			(xy 191.937973 -116.172994) (xy 191.885999 -116.172994) (xy 191.834664 -116.164864) (xy 191.785234 -116.148803)
			(xy 191.738924 -116.125207) (xy 191.696876 -116.094657) (xy 191.660125 -116.057906) (xy 191.629575 -116.015858)
			(xy 191.605979 -115.969548) (xy 191.589918 -115.920118) (xy 191.581788 -115.868783) (xy 191.442084 -115.868783)
			(xy 191.433954 -115.920118) (xy 191.417893 -115.969548) (xy 191.394297 -116.015858) (xy 191.363747 -116.057906)
			(xy 191.326996 -116.094657) (xy 191.284948 -116.125207) (xy 191.238638 -116.148803) (xy 191.189208 -116.164864)
			(xy 191.137873 -116.172994) (xy 191.085899 -116.172994) (xy 191.034564 -116.164864) (xy 190.985134 -116.148803)
			(xy 190.938824 -116.125207) (xy 190.896776 -116.094657) (xy 190.860025 -116.057906) (xy 190.829475 -116.015858)
			(xy 190.805879 -115.969548) (xy 190.789818 -115.920118) (xy 190.781688 -115.868783) (xy 190.642238 -115.868783)
			(xy 190.634108 -115.920118) (xy 190.618047 -115.969548) (xy 190.594451 -116.015858) (xy 190.563901 -116.057906)
			(xy 190.52715 -116.094657) (xy 190.485102 -116.125207) (xy 190.438792 -116.148803) (xy 190.389362 -116.164864)
			(xy 190.338027 -116.172994) (xy 190.286053 -116.172994) (xy 190.234718 -116.164864) (xy 190.185288 -116.148803)
			(xy 190.138978 -116.125207) (xy 190.09693 -116.094657) (xy 190.060179 -116.057906) (xy 190.029629 -116.015858)
			(xy 190.006033 -115.969548) (xy 189.989972 -115.920118) (xy 189.981842 -115.868783) (xy 189.842138 -115.868783)
			(xy 189.834008 -115.920118) (xy 189.817947 -115.969548) (xy 189.794351 -116.015858) (xy 189.763801 -116.057906)
			(xy 189.72705 -116.094657) (xy 189.685002 -116.125207) (xy 189.638692 -116.148803) (xy 189.589262 -116.164864)
			(xy 189.537927 -116.172994) (xy 189.485953 -116.172994) (xy 189.434618 -116.164864) (xy 189.385188 -116.148803)
			(xy 189.338878 -116.125207) (xy 189.29683 -116.094657) (xy 189.260079 -116.057906) (xy 189.229529 -116.015858)
			(xy 189.205933 -115.969548) (xy 189.189872 -115.920118) (xy 189.181742 -115.868783) (xy 189.042292 -115.868783)
			(xy 189.034162 -115.920118) (xy 189.018101 -115.969548) (xy 188.994505 -116.015858) (xy 188.963955 -116.057906)
			(xy 188.927204 -116.094657) (xy 188.885156 -116.125207) (xy 188.838846 -116.148803) (xy 188.789416 -116.164864)
			(xy 188.738081 -116.172994) (xy 188.686107 -116.172994) (xy 188.634772 -116.164864) (xy 188.585342 -116.148803)
			(xy 188.539032 -116.125207) (xy 188.496984 -116.094657) (xy 188.460233 -116.057906) (xy 188.429683 -116.015858)
			(xy 188.406087 -115.969548) (xy 188.390026 -115.920118) (xy 188.381896 -115.868783) (xy 188.242192 -115.868783)
			(xy 188.234062 -115.920118) (xy 188.218001 -115.969548) (xy 188.194405 -116.015858) (xy 188.163855 -116.057906)
			(xy 188.127104 -116.094657) (xy 188.085056 -116.125207) (xy 188.038746 -116.148803) (xy 187.989316 -116.164864)
			(xy 187.937981 -116.172994) (xy 187.886007 -116.172994) (xy 187.834672 -116.164864) (xy 187.785242 -116.148803)
			(xy 187.738932 -116.125207) (xy 187.696884 -116.094657) (xy 187.660133 -116.057906) (xy 187.629583 -116.015858)
			(xy 187.605987 -115.969548) (xy 187.589926 -115.920118) (xy 187.581796 -115.868783) (xy 187.442092 -115.868783)
			(xy 187.433962 -115.920118) (xy 187.417901 -115.969548) (xy 187.394305 -116.015858) (xy 187.363755 -116.057906)
			(xy 187.327004 -116.094657) (xy 187.284956 -116.125207) (xy 187.238646 -116.148803) (xy 187.189216 -116.164864)
			(xy 187.137881 -116.172994) (xy 187.085907 -116.172994) (xy 187.034572 -116.164864) (xy 186.985142 -116.148803)
			(xy 186.938832 -116.125207) (xy 186.896784 -116.094657) (xy 186.860033 -116.057906) (xy 186.829483 -116.015858)
			(xy 186.805887 -115.969548) (xy 186.789826 -115.920118) (xy 186.781696 -115.868783) (xy 186.642246 -115.868783)
			(xy 186.634116 -115.920118) (xy 186.618055 -115.969548) (xy 186.594459 -116.015858) (xy 186.563909 -116.057906)
			(xy 186.527158 -116.094657) (xy 186.48511 -116.125207) (xy 186.4388 -116.148803) (xy 186.38937 -116.164864)
			(xy 186.338035 -116.172994) (xy 186.286061 -116.172994) (xy 186.234726 -116.164864) (xy 186.185296 -116.148803)
			(xy 186.138986 -116.125207) (xy 186.096938 -116.094657) (xy 186.060187 -116.057906) (xy 186.029637 -116.015858)
			(xy 186.006041 -115.969548) (xy 185.98998 -115.920118) (xy 185.98185 -115.868783) (xy 185.062366 -115.868783)
			(xy 185.054236 -115.920118) (xy 185.038175 -115.969548) (xy 185.014579 -116.015858) (xy 184.984029 -116.057906)
			(xy 184.947278 -116.094657) (xy 184.90523 -116.125207) (xy 184.85892 -116.148803) (xy 184.80949 -116.164864)
			(xy 184.758155 -116.172994) (xy 184.706181 -116.172994) (xy 184.654846 -116.164864) (xy 184.605416 -116.148803)
			(xy 184.559106 -116.125207) (xy 184.517058 -116.094657) (xy 184.480307 -116.057906) (xy 184.449757 -116.015858)
			(xy 184.426161 -115.969548) (xy 184.4101 -115.920118) (xy 184.40197 -115.868783) (xy 184.26252 -115.868783)
			(xy 184.25439 -115.920118) (xy 184.238329 -115.969548) (xy 184.214733 -116.015858) (xy 184.184183 -116.057906)
			(xy 184.147432 -116.094657) (xy 184.105384 -116.125207) (xy 184.059074 -116.148803) (xy 184.009644 -116.164864)
			(xy 183.958309 -116.172994) (xy 183.906335 -116.172994) (xy 183.855 -116.164864) (xy 183.80557 -116.148803)
			(xy 183.75926 -116.125207) (xy 183.717212 -116.094657) (xy 183.680461 -116.057906) (xy 183.649911 -116.015858)
			(xy 183.626315 -115.969548) (xy 183.610254 -115.920118) (xy 183.602124 -115.868783) (xy 183.46242 -115.868783)
			(xy 183.45429 -115.920118) (xy 183.438229 -115.969548) (xy 183.414633 -116.015858) (xy 183.384083 -116.057906)
			(xy 183.347332 -116.094657) (xy 183.305284 -116.125207) (xy 183.258974 -116.148803) (xy 183.209544 -116.164864)
			(xy 183.158209 -116.172994) (xy 183.106235 -116.172994) (xy 183.0549 -116.164864) (xy 183.00547 -116.148803)
			(xy 182.95916 -116.125207) (xy 182.917112 -116.094657) (xy 182.880361 -116.057906) (xy 182.849811 -116.015858)
			(xy 182.826215 -115.969548) (xy 182.810154 -115.920118) (xy 182.802024 -115.868783) (xy 182.66232 -115.868783)
			(xy 182.65419 -115.920118) (xy 182.638129 -115.969548) (xy 182.614533 -116.015858) (xy 182.583983 -116.057906)
			(xy 182.547232 -116.094657) (xy 182.505184 -116.125207) (xy 182.458874 -116.148803) (xy 182.409444 -116.164864)
			(xy 182.358109 -116.172994) (xy 182.306135 -116.172994) (xy 182.2548 -116.164864) (xy 182.20537 -116.148803)
			(xy 182.15906 -116.125207) (xy 182.117012 -116.094657) (xy 182.080261 -116.057906) (xy 182.049711 -116.015858)
			(xy 182.026115 -115.969548) (xy 182.010054 -115.920118) (xy 182.001924 -115.868783) (xy 181.862474 -115.868783)
			(xy 181.854344 -115.920118) (xy 181.838283 -115.969548) (xy 181.814687 -116.015858) (xy 181.784137 -116.057906)
			(xy 181.747386 -116.094657) (xy 181.705338 -116.125207) (xy 181.659028 -116.148803) (xy 181.609598 -116.164864)
			(xy 181.558263 -116.172994) (xy 181.506289 -116.172994) (xy 181.454954 -116.164864) (xy 181.405524 -116.148803)
			(xy 181.359214 -116.125207) (xy 181.317166 -116.094657) (xy 181.280415 -116.057906) (xy 181.249865 -116.015858)
			(xy 181.226269 -115.969548) (xy 181.210208 -115.920118) (xy 181.202078 -115.868783) (xy 181.062374 -115.868783)
			(xy 181.054244 -115.920118) (xy 181.038183 -115.969548) (xy 181.014587 -116.015858) (xy 180.984037 -116.057906)
			(xy 180.947286 -116.094657) (xy 180.905238 -116.125207) (xy 180.858928 -116.148803) (xy 180.809498 -116.164864)
			(xy 180.758163 -116.172994) (xy 180.706189 -116.172994) (xy 180.654854 -116.164864) (xy 180.605424 -116.148803)
			(xy 180.559114 -116.125207) (xy 180.517066 -116.094657) (xy 180.480315 -116.057906) (xy 180.449765 -116.015858)
			(xy 180.426169 -115.969548) (xy 180.410108 -115.920118) (xy 180.401978 -115.868783) (xy 180.262528 -115.868783)
			(xy 180.254398 -115.920118) (xy 180.238337 -115.969548) (xy 180.214741 -116.015858) (xy 180.184191 -116.057906)
			(xy 180.14744 -116.094657) (xy 180.105392 -116.125207) (xy 180.059082 -116.148803) (xy 180.009652 -116.164864)
			(xy 179.958317 -116.172994) (xy 179.906343 -116.172994) (xy 179.855008 -116.164864) (xy 179.805578 -116.148803)
			(xy 179.759268 -116.125207) (xy 179.71722 -116.094657) (xy 179.680469 -116.057906) (xy 179.649919 -116.015858)
			(xy 179.626323 -115.969548) (xy 179.610262 -115.920118) (xy 179.602132 -115.868783) (xy 179.462428 -115.868783)
			(xy 179.454298 -115.920118) (xy 179.438237 -115.969548) (xy 179.414641 -116.015858) (xy 179.384091 -116.057906)
			(xy 179.34734 -116.094657) (xy 179.305292 -116.125207) (xy 179.258982 -116.148803) (xy 179.209552 -116.164864)
			(xy 179.158217 -116.172994) (xy 179.106243 -116.172994) (xy 179.054908 -116.164864) (xy 179.005478 -116.148803)
			(xy 178.959168 -116.125207) (xy 178.91712 -116.094657) (xy 178.880369 -116.057906) (xy 178.849819 -116.015858)
			(xy 178.826223 -115.969548) (xy 178.810162 -115.920118) (xy 178.802032 -115.868783) (xy 178.662328 -115.868783)
			(xy 178.654198 -115.920118) (xy 178.638137 -115.969548) (xy 178.614541 -116.015858) (xy 178.583991 -116.057906)
			(xy 178.54724 -116.094657) (xy 178.505192 -116.125207) (xy 178.458882 -116.148803) (xy 178.409452 -116.164864)
			(xy 178.358117 -116.172994) (xy 178.306143 -116.172994) (xy 178.254808 -116.164864) (xy 178.205378 -116.148803)
			(xy 178.159068 -116.125207) (xy 178.11702 -116.094657) (xy 178.080269 -116.057906) (xy 178.049719 -116.015858)
			(xy 178.026123 -115.969548) (xy 178.010062 -115.920118) (xy 178.001932 -115.868783) (xy 172.916752 -115.868783)
			(xy 172.91152 -115.878301) (xy 172.873947 -115.930016) (xy 172.83019 -115.976613) (xy 172.780937 -116.017358)
			(xy 172.726966 -116.051609) (xy 172.669127 -116.078826) (xy 172.608334 -116.098579) (xy 172.545544 -116.110557)
			(xy 172.481748 -116.114571) (xy 172.417952 -116.110557) (xy 172.355162 -116.098579) (xy 172.294369 -116.078826)
			(xy 172.23653 -116.051609) (xy 172.182559 -116.017358) (xy 172.133306 -115.976613) (xy 172.089549 -115.930016)
			(xy 172.051976 -115.878301) (xy 172.021182 -115.822286) (xy 171.99765 -115.762853) (xy 171.981753 -115.700939)
			(xy 171.973742 -115.637521) (xy 170.538543 -115.637521) (xy 170.493912 -115.677063) (xy 170.443327 -115.711981)
			(xy 170.388902 -115.740546) (xy 170.331431 -115.762343) (xy 170.271751 -115.777053) (xy 170.210733 -115.784462)
			(xy 170.18 -115.784884) (xy 170.167278 -115.784806) (xy 170.141866 -115.783536) (xy 170.1292 -115.782344)
			(xy 170.097049 -115.778621) (xy 170.033984 -115.764062) (xy 169.973276 -115.741619) (xy 169.915907 -115.711655)
			(xy 169.862802 -115.674654) (xy 169.814822 -115.631215) (xy 169.77274 -115.582039) (xy 169.75455 -115.555268)
			(xy 169.749163 -115.548669) (xy 169.735018 -115.539191) (xy 169.726864 -115.536726) (xy 169.714926 -115.535202)
			(xy 169.629074 -115.535202) (xy 169.617136 -115.536726) (xy 169.608119 -115.539416) (xy 169.592833 -115.550368)
			(xy 169.587418 -115.558062) (xy 169.587418 -115.558316) (xy 169.567993 -115.58642) (xy 169.522801 -115.637656)
			(xy 169.471159 -115.682384) (xy 169.442892 -115.701572) (xy 169.441622 -115.702334) (xy 169.436034 -115.70589)
			(xy 169.43197 -115.710462) (xy 169.424858 -115.722146) (xy 169.42435 -115.722654) (xy 169.422188 -115.727719)
			(xy 169.419877 -115.738484) (xy 169.419778 -115.74399) (xy 169.419778 -115.823492) (xy 169.42054 -115.832382)
			(xy 169.423588 -115.846606) (xy 169.427144 -115.856258) (xy 169.4307 -115.863878) (xy 169.443908 -115.872514)
			(xy 169.469874 -115.890182) (xy 169.517663 -115.930936) (xy 169.560066 -115.977269) (xy 169.596437 -116.028473)
			(xy 169.62622 -116.08377) (xy 169.648963 -116.142314) (xy 169.664318 -116.203215) (xy 169.672052 -116.265544)
			(xy 169.672442 -116.292376) (xy 169.797982 -116.292376) (xy 169.802053 -116.236754) (xy 169.814179 -116.182317)
			(xy 169.834102 -116.130226) (xy 169.861398 -116.081591) (xy 169.895484 -116.037448) (xy 169.935633 -115.998739)
			(xy 169.980991 -115.966288) (xy 170.030591 -115.940787) (xy 170.083375 -115.92278) (xy 170.138218 -115.91265)
			(xy 170.193952 -115.910613) (xy 170.249389 -115.916713) (xy 170.303346 -115.930819) (xy 170.354675 -115.952631)
			(xy 170.402281 -115.981685) (xy 170.445149 -116.01736) (xy 170.482366 -116.058897) (xy 170.513139 -116.10541)
			(xy 170.536811 -116.155907) (xy 170.552879 -116.209314) (xy 170.560999 -116.26449) (xy 170.561508 -116.292376)
			(xy 170.560999 -116.320262) (xy 170.552879 -116.375438) (xy 170.536811 -116.428845) (xy 170.513139 -116.479342)
			(xy 170.482366 -116.525855) (xy 170.445149 -116.567392) (xy 170.402281 -116.603067) (xy 170.354675 -116.632121)
			(xy 170.303346 -116.653933) (xy 170.249389 -116.668039) (xy 170.244027 -116.668629) (xy 178.001932 -116.668629)
			(xy 178.001932 -116.616655) (xy 178.010062 -116.56532) (xy 178.026123 -116.51589) (xy 178.049719 -116.46958)
			(xy 178.080269 -116.427532) (xy 178.11702 -116.390781) (xy 178.159068 -116.360231) (xy 178.205378 -116.336635)
			(xy 178.254808 -116.320574) (xy 178.306143 -116.312444) (xy 178.358117 -116.312444) (xy 178.409452 -116.320574)
			(xy 178.458882 -116.336635) (xy 178.505192 -116.360231) (xy 178.54724 -116.390781) (xy 178.583991 -116.427532)
			(xy 178.614541 -116.46958) (xy 178.638137 -116.51589) (xy 178.654198 -116.56532) (xy 178.662328 -116.616655)
			(xy 178.662838 -116.642642) (xy 178.662328 -116.668629) (xy 178.802032 -116.668629) (xy 178.802032 -116.616655)
			(xy 178.810162 -116.56532) (xy 178.826223 -116.51589) (xy 178.849819 -116.46958) (xy 178.880369 -116.427532)
			(xy 178.91712 -116.390781) (xy 178.959168 -116.360231) (xy 179.005478 -116.336635) (xy 179.054908 -116.320574)
			(xy 179.106243 -116.312444) (xy 179.158217 -116.312444) (xy 179.209552 -116.320574) (xy 179.258982 -116.336635)
			(xy 179.305292 -116.360231) (xy 179.34734 -116.390781) (xy 179.384091 -116.427532) (xy 179.414641 -116.46958)
			(xy 179.438237 -116.51589) (xy 179.454298 -116.56532) (xy 179.462428 -116.616655) (xy 179.462938 -116.642642)
			(xy 179.462428 -116.668629) (xy 179.602132 -116.668629) (xy 179.602132 -116.616655) (xy 179.610262 -116.56532)
			(xy 179.626323 -116.51589) (xy 179.649919 -116.46958) (xy 179.680469 -116.427532) (xy 179.71722 -116.390781)
			(xy 179.759268 -116.360231) (xy 179.805578 -116.336635) (xy 179.855008 -116.320574) (xy 179.906343 -116.312444)
			(xy 179.958317 -116.312444) (xy 180.009652 -116.320574) (xy 180.059082 -116.336635) (xy 180.105392 -116.360231)
			(xy 180.14744 -116.390781) (xy 180.184191 -116.427532) (xy 180.214741 -116.46958) (xy 180.238337 -116.51589)
			(xy 180.254398 -116.56532) (xy 180.262528 -116.616655) (xy 180.263038 -116.642642) (xy 180.262528 -116.668629)
			(xy 180.401978 -116.668629) (xy 180.401978 -116.616655) (xy 180.410108 -116.56532) (xy 180.426169 -116.51589)
			(xy 180.449765 -116.46958) (xy 180.480315 -116.427532) (xy 180.517066 -116.390781) (xy 180.559114 -116.360231)
			(xy 180.605424 -116.336635) (xy 180.654854 -116.320574) (xy 180.706189 -116.312444) (xy 180.758163 -116.312444)
			(xy 180.809498 -116.320574) (xy 180.858928 -116.336635) (xy 180.905238 -116.360231) (xy 180.947286 -116.390781)
			(xy 180.984037 -116.427532) (xy 181.014587 -116.46958) (xy 181.038183 -116.51589) (xy 181.054244 -116.56532)
			(xy 181.062374 -116.616655) (xy 181.062884 -116.642642) (xy 181.062374 -116.668629) (xy 181.202078 -116.668629)
			(xy 181.202078 -116.616655) (xy 181.210208 -116.56532) (xy 181.226269 -116.51589) (xy 181.249865 -116.46958)
			(xy 181.280415 -116.427532) (xy 181.317166 -116.390781) (xy 181.359214 -116.360231) (xy 181.405524 -116.336635)
			(xy 181.454954 -116.320574) (xy 181.506289 -116.312444) (xy 181.558263 -116.312444) (xy 181.609598 -116.320574)
			(xy 181.659028 -116.336635) (xy 181.705338 -116.360231) (xy 181.747386 -116.390781) (xy 181.784137 -116.427532)
			(xy 181.814687 -116.46958) (xy 181.838283 -116.51589) (xy 181.854344 -116.56532) (xy 181.862474 -116.616655)
			(xy 181.862984 -116.642642) (xy 181.862474 -116.668629) (xy 182.001924 -116.668629) (xy 182.001924 -116.616655)
			(xy 182.010054 -116.56532) (xy 182.026115 -116.51589) (xy 182.049711 -116.46958) (xy 182.080261 -116.427532)
			(xy 182.117012 -116.390781) (xy 182.15906 -116.360231) (xy 182.20537 -116.336635) (xy 182.2548 -116.320574)
			(xy 182.306135 -116.312444) (xy 182.358109 -116.312444) (xy 182.409444 -116.320574) (xy 182.458874 -116.336635)
			(xy 182.505184 -116.360231) (xy 182.547232 -116.390781) (xy 182.583983 -116.427532) (xy 182.614533 -116.46958)
			(xy 182.638129 -116.51589) (xy 182.65419 -116.56532) (xy 182.66232 -116.616655) (xy 182.66283 -116.642642)
			(xy 182.66232 -116.668629) (xy 182.802024 -116.668629) (xy 182.802024 -116.616655) (xy 182.810154 -116.56532)
			(xy 182.826215 -116.51589) (xy 182.849811 -116.46958) (xy 182.880361 -116.427532) (xy 182.917112 -116.390781)
			(xy 182.95916 -116.360231) (xy 183.00547 -116.336635) (xy 183.0549 -116.320574) (xy 183.106235 -116.312444)
			(xy 183.158209 -116.312444) (xy 183.209544 -116.320574) (xy 183.258974 -116.336635) (xy 183.305284 -116.360231)
			(xy 183.347332 -116.390781) (xy 183.384083 -116.427532) (xy 183.414633 -116.46958) (xy 183.438229 -116.51589)
			(xy 183.45429 -116.56532) (xy 183.46242 -116.616655) (xy 183.46293 -116.642642) (xy 183.46242 -116.668629)
			(xy 183.602124 -116.668629) (xy 183.602124 -116.616655) (xy 183.610254 -116.56532) (xy 183.626315 -116.51589)
			(xy 183.649911 -116.46958) (xy 183.680461 -116.427532) (xy 183.717212 -116.390781) (xy 183.75926 -116.360231)
			(xy 183.80557 -116.336635) (xy 183.855 -116.320574) (xy 183.906335 -116.312444) (xy 183.958309 -116.312444)
			(xy 184.009644 -116.320574) (xy 184.059074 -116.336635) (xy 184.105384 -116.360231) (xy 184.147432 -116.390781)
			(xy 184.184183 -116.427532) (xy 184.214733 -116.46958) (xy 184.238329 -116.51589) (xy 184.25439 -116.56532)
			(xy 184.26252 -116.616655) (xy 184.26303 -116.642642) (xy 184.26252 -116.668629) (xy 184.40197 -116.668629)
			(xy 184.40197 -116.616655) (xy 184.4101 -116.56532) (xy 184.426161 -116.51589) (xy 184.449757 -116.46958)
			(xy 184.480307 -116.427532) (xy 184.517058 -116.390781) (xy 184.559106 -116.360231) (xy 184.605416 -116.336635)
			(xy 184.654846 -116.320574) (xy 184.706181 -116.312444) (xy 184.758155 -116.312444) (xy 184.80949 -116.320574)
			(xy 184.85892 -116.336635) (xy 184.90523 -116.360231) (xy 184.947278 -116.390781) (xy 184.984029 -116.427532)
			(xy 185.014579 -116.46958) (xy 185.038175 -116.51589) (xy 185.054236 -116.56532) (xy 185.062366 -116.616655)
			(xy 185.062876 -116.642642) (xy 185.062366 -116.668629) (xy 185.98185 -116.668629) (xy 185.98185 -116.616655)
			(xy 185.98998 -116.56532) (xy 186.006041 -116.51589) (xy 186.029637 -116.46958) (xy 186.060187 -116.427532)
			(xy 186.096938 -116.390781) (xy 186.138986 -116.360231) (xy 186.185296 -116.336635) (xy 186.234726 -116.320574)
			(xy 186.286061 -116.312444) (xy 186.338035 -116.312444) (xy 186.38937 -116.320574) (xy 186.4388 -116.336635)
			(xy 186.48511 -116.360231) (xy 186.527158 -116.390781) (xy 186.563909 -116.427532) (xy 186.594459 -116.46958)
			(xy 186.618055 -116.51589) (xy 186.634116 -116.56532) (xy 186.642246 -116.616655) (xy 186.642756 -116.642642)
			(xy 186.642246 -116.668629) (xy 186.781696 -116.668629) (xy 186.781696 -116.616655) (xy 186.789826 -116.56532)
			(xy 186.805887 -116.51589) (xy 186.829483 -116.46958) (xy 186.860033 -116.427532) (xy 186.896784 -116.390781)
			(xy 186.938832 -116.360231) (xy 186.985142 -116.336635) (xy 187.034572 -116.320574) (xy 187.085907 -116.312444)
			(xy 187.137881 -116.312444) (xy 187.189216 -116.320574) (xy 187.238646 -116.336635) (xy 187.284956 -116.360231)
			(xy 187.327004 -116.390781) (xy 187.363755 -116.427532) (xy 187.394305 -116.46958) (xy 187.417901 -116.51589)
			(xy 187.433962 -116.56532) (xy 187.442092 -116.616655) (xy 187.442602 -116.642642) (xy 187.442092 -116.668629)
			(xy 187.581796 -116.668629) (xy 187.581796 -116.616655) (xy 187.589926 -116.56532) (xy 187.605987 -116.51589)
			(xy 187.629583 -116.46958) (xy 187.660133 -116.427532) (xy 187.696884 -116.390781) (xy 187.738932 -116.360231)
			(xy 187.785242 -116.336635) (xy 187.834672 -116.320574) (xy 187.886007 -116.312444) (xy 187.937981 -116.312444)
			(xy 187.989316 -116.320574) (xy 188.038746 -116.336635) (xy 188.085056 -116.360231) (xy 188.127104 -116.390781)
			(xy 188.163855 -116.427532) (xy 188.194405 -116.46958) (xy 188.218001 -116.51589) (xy 188.234062 -116.56532)
			(xy 188.242192 -116.616655) (xy 188.242702 -116.642642) (xy 188.242192 -116.668629) (xy 188.381896 -116.668629)
			(xy 188.381896 -116.616655) (xy 188.390026 -116.56532) (xy 188.406087 -116.51589) (xy 188.429683 -116.46958)
			(xy 188.460233 -116.427532) (xy 188.496984 -116.390781) (xy 188.539032 -116.360231) (xy 188.585342 -116.336635)
			(xy 188.634772 -116.320574) (xy 188.686107 -116.312444) (xy 188.738081 -116.312444) (xy 188.789416 -116.320574)
			(xy 188.838846 -116.336635) (xy 188.885156 -116.360231) (xy 188.927204 -116.390781) (xy 188.963955 -116.427532)
			(xy 188.994505 -116.46958) (xy 189.018101 -116.51589) (xy 189.034162 -116.56532) (xy 189.042292 -116.616655)
			(xy 189.042802 -116.642642) (xy 189.042292 -116.668629) (xy 189.181742 -116.668629) (xy 189.181742 -116.616655)
			(xy 189.189872 -116.56532) (xy 189.205933 -116.51589) (xy 189.229529 -116.46958) (xy 189.260079 -116.427532)
			(xy 189.29683 -116.390781) (xy 189.338878 -116.360231) (xy 189.385188 -116.336635) (xy 189.434618 -116.320574)
			(xy 189.485953 -116.312444) (xy 189.537927 -116.312444) (xy 189.589262 -116.320574) (xy 189.638692 -116.336635)
			(xy 189.685002 -116.360231) (xy 189.72705 -116.390781) (xy 189.763801 -116.427532) (xy 189.794351 -116.46958)
			(xy 189.817947 -116.51589) (xy 189.834008 -116.56532) (xy 189.842138 -116.616655) (xy 189.842648 -116.642642)
			(xy 189.842138 -116.668629) (xy 189.981842 -116.668629) (xy 189.981842 -116.616655) (xy 189.989972 -116.56532)
			(xy 190.006033 -116.51589) (xy 190.029629 -116.46958) (xy 190.060179 -116.427532) (xy 190.09693 -116.390781)
			(xy 190.138978 -116.360231) (xy 190.185288 -116.336635) (xy 190.234718 -116.320574) (xy 190.286053 -116.312444)
			(xy 190.338027 -116.312444) (xy 190.389362 -116.320574) (xy 190.438792 -116.336635) (xy 190.485102 -116.360231)
			(xy 190.52715 -116.390781) (xy 190.563901 -116.427532) (xy 190.594451 -116.46958) (xy 190.618047 -116.51589)
			(xy 190.634108 -116.56532) (xy 190.642238 -116.616655) (xy 190.642748 -116.642642) (xy 190.642238 -116.668629)
			(xy 190.781688 -116.668629) (xy 190.781688 -116.616655) (xy 190.789818 -116.56532) (xy 190.805879 -116.51589)
			(xy 190.829475 -116.46958) (xy 190.860025 -116.427532) (xy 190.896776 -116.390781) (xy 190.938824 -116.360231)
			(xy 190.985134 -116.336635) (xy 191.034564 -116.320574) (xy 191.085899 -116.312444) (xy 191.137873 -116.312444)
			(xy 191.189208 -116.320574) (xy 191.238638 -116.336635) (xy 191.284948 -116.360231) (xy 191.326996 -116.390781)
			(xy 191.363747 -116.427532) (xy 191.394297 -116.46958) (xy 191.417893 -116.51589) (xy 191.433954 -116.56532)
			(xy 191.442084 -116.616655) (xy 191.442594 -116.642642) (xy 191.442084 -116.668629) (xy 191.581788 -116.668629)
			(xy 191.581788 -116.616655) (xy 191.589918 -116.56532) (xy 191.605979 -116.51589) (xy 191.629575 -116.46958)
			(xy 191.660125 -116.427532) (xy 191.696876 -116.390781) (xy 191.738924 -116.360231) (xy 191.785234 -116.336635)
			(xy 191.834664 -116.320574) (xy 191.885999 -116.312444) (xy 191.937973 -116.312444) (xy 191.989308 -116.320574)
			(xy 192.038738 -116.336635) (xy 192.085048 -116.360231) (xy 192.127096 -116.390781) (xy 192.163847 -116.427532)
			(xy 192.194397 -116.46958) (xy 192.217993 -116.51589) (xy 192.234054 -116.56532) (xy 192.242184 -116.616655)
			(xy 192.242694 -116.642642) (xy 192.242184 -116.668629) (xy 192.234054 -116.719964) (xy 192.217993 -116.769394)
			(xy 192.194397 -116.815704) (xy 192.163847 -116.857752) (xy 192.127096 -116.894503) (xy 192.085048 -116.925053)
			(xy 192.038738 -116.948649) (xy 191.989308 -116.96471) (xy 191.937973 -116.97284) (xy 191.885999 -116.97284)
			(xy 191.834664 -116.96471) (xy 191.785234 -116.948649) (xy 191.738924 -116.925053) (xy 191.696876 -116.894503)
			(xy 191.660125 -116.857752) (xy 191.629575 -116.815704) (xy 191.605979 -116.769394) (xy 191.589918 -116.719964)
			(xy 191.581788 -116.668629) (xy 191.442084 -116.668629) (xy 191.433954 -116.719964) (xy 191.417893 -116.769394)
			(xy 191.394297 -116.815704) (xy 191.363747 -116.857752) (xy 191.326996 -116.894503) (xy 191.284948 -116.925053)
			(xy 191.238638 -116.948649) (xy 191.189208 -116.96471) (xy 191.137873 -116.97284) (xy 191.085899 -116.97284)
			(xy 191.034564 -116.96471) (xy 190.985134 -116.948649) (xy 190.938824 -116.925053) (xy 190.896776 -116.894503)
			(xy 190.860025 -116.857752) (xy 190.829475 -116.815704) (xy 190.805879 -116.769394) (xy 190.789818 -116.719964)
			(xy 190.781688 -116.668629) (xy 190.642238 -116.668629) (xy 190.634108 -116.719964) (xy 190.618047 -116.769394)
			(xy 190.594451 -116.815704) (xy 190.563901 -116.857752) (xy 190.52715 -116.894503) (xy 190.485102 -116.925053)
			(xy 190.438792 -116.948649) (xy 190.389362 -116.96471) (xy 190.338027 -116.97284) (xy 190.286053 -116.97284)
			(xy 190.234718 -116.96471) (xy 190.185288 -116.948649) (xy 190.138978 -116.925053) (xy 190.09693 -116.894503)
			(xy 190.060179 -116.857752) (xy 190.029629 -116.815704) (xy 190.006033 -116.769394) (xy 189.989972 -116.719964)
			(xy 189.981842 -116.668629) (xy 189.842138 -116.668629) (xy 189.834008 -116.719964) (xy 189.817947 -116.769394)
			(xy 189.794351 -116.815704) (xy 189.763801 -116.857752) (xy 189.72705 -116.894503) (xy 189.685002 -116.925053)
			(xy 189.638692 -116.948649) (xy 189.589262 -116.96471) (xy 189.537927 -116.97284) (xy 189.485953 -116.97284)
			(xy 189.434618 -116.96471) (xy 189.385188 -116.948649) (xy 189.338878 -116.925053) (xy 189.29683 -116.894503)
			(xy 189.260079 -116.857752) (xy 189.229529 -116.815704) (xy 189.205933 -116.769394) (xy 189.189872 -116.719964)
			(xy 189.181742 -116.668629) (xy 189.042292 -116.668629) (xy 189.034162 -116.719964) (xy 189.018101 -116.769394)
			(xy 188.994505 -116.815704) (xy 188.963955 -116.857752) (xy 188.927204 -116.894503) (xy 188.885156 -116.925053)
			(xy 188.838846 -116.948649) (xy 188.789416 -116.96471) (xy 188.738081 -116.97284) (xy 188.686107 -116.97284)
			(xy 188.634772 -116.96471) (xy 188.585342 -116.948649) (xy 188.539032 -116.925053) (xy 188.496984 -116.894503)
			(xy 188.460233 -116.857752) (xy 188.429683 -116.815704) (xy 188.406087 -116.769394) (xy 188.390026 -116.719964)
			(xy 188.381896 -116.668629) (xy 188.242192 -116.668629) (xy 188.234062 -116.719964) (xy 188.218001 -116.769394)
			(xy 188.194405 -116.815704) (xy 188.163855 -116.857752) (xy 188.127104 -116.894503) (xy 188.085056 -116.925053)
			(xy 188.038746 -116.948649) (xy 187.989316 -116.96471) (xy 187.937981 -116.97284) (xy 187.886007 -116.97284)
			(xy 187.834672 -116.96471) (xy 187.785242 -116.948649) (xy 187.738932 -116.925053) (xy 187.696884 -116.894503)
			(xy 187.660133 -116.857752) (xy 187.629583 -116.815704) (xy 187.605987 -116.769394) (xy 187.589926 -116.719964)
			(xy 187.581796 -116.668629) (xy 187.442092 -116.668629) (xy 187.433962 -116.719964) (xy 187.417901 -116.769394)
			(xy 187.394305 -116.815704) (xy 187.363755 -116.857752) (xy 187.327004 -116.894503) (xy 187.284956 -116.925053)
			(xy 187.238646 -116.948649) (xy 187.189216 -116.96471) (xy 187.137881 -116.97284) (xy 187.085907 -116.97284)
			(xy 187.034572 -116.96471) (xy 186.985142 -116.948649) (xy 186.938832 -116.925053) (xy 186.896784 -116.894503)
			(xy 186.860033 -116.857752) (xy 186.829483 -116.815704) (xy 186.805887 -116.769394) (xy 186.789826 -116.719964)
			(xy 186.781696 -116.668629) (xy 186.642246 -116.668629) (xy 186.634116 -116.719964) (xy 186.618055 -116.769394)
			(xy 186.594459 -116.815704) (xy 186.563909 -116.857752) (xy 186.527158 -116.894503) (xy 186.48511 -116.925053)
			(xy 186.4388 -116.948649) (xy 186.38937 -116.96471) (xy 186.338035 -116.97284) (xy 186.286061 -116.97284)
			(xy 186.234726 -116.96471) (xy 186.185296 -116.948649) (xy 186.138986 -116.925053) (xy 186.096938 -116.894503)
			(xy 186.060187 -116.857752) (xy 186.029637 -116.815704) (xy 186.006041 -116.769394) (xy 185.98998 -116.719964)
			(xy 185.98185 -116.668629) (xy 185.062366 -116.668629) (xy 185.054236 -116.719964) (xy 185.038175 -116.769394)
			(xy 185.014579 -116.815704) (xy 184.984029 -116.857752) (xy 184.947278 -116.894503) (xy 184.90523 -116.925053)
			(xy 184.85892 -116.948649) (xy 184.80949 -116.96471) (xy 184.758155 -116.97284) (xy 184.706181 -116.97284)
			(xy 184.654846 -116.96471) (xy 184.605416 -116.948649) (xy 184.559106 -116.925053) (xy 184.517058 -116.894503)
			(xy 184.480307 -116.857752) (xy 184.449757 -116.815704) (xy 184.426161 -116.769394) (xy 184.4101 -116.719964)
			(xy 184.40197 -116.668629) (xy 184.26252 -116.668629) (xy 184.25439 -116.719964) (xy 184.238329 -116.769394)
			(xy 184.214733 -116.815704) (xy 184.184183 -116.857752) (xy 184.147432 -116.894503) (xy 184.105384 -116.925053)
			(xy 184.059074 -116.948649) (xy 184.009644 -116.96471) (xy 183.958309 -116.97284) (xy 183.906335 -116.97284)
			(xy 183.855 -116.96471) (xy 183.80557 -116.948649) (xy 183.75926 -116.925053) (xy 183.717212 -116.894503)
			(xy 183.680461 -116.857752) (xy 183.649911 -116.815704) (xy 183.626315 -116.769394) (xy 183.610254 -116.719964)
			(xy 183.602124 -116.668629) (xy 183.46242 -116.668629) (xy 183.45429 -116.719964) (xy 183.438229 -116.769394)
			(xy 183.414633 -116.815704) (xy 183.384083 -116.857752) (xy 183.347332 -116.894503) (xy 183.305284 -116.925053)
			(xy 183.258974 -116.948649) (xy 183.209544 -116.96471) (xy 183.158209 -116.97284) (xy 183.106235 -116.97284)
			(xy 183.0549 -116.96471) (xy 183.00547 -116.948649) (xy 182.95916 -116.925053) (xy 182.917112 -116.894503)
			(xy 182.880361 -116.857752) (xy 182.849811 -116.815704) (xy 182.826215 -116.769394) (xy 182.810154 -116.719964)
			(xy 182.802024 -116.668629) (xy 182.66232 -116.668629) (xy 182.65419 -116.719964) (xy 182.638129 -116.769394)
			(xy 182.614533 -116.815704) (xy 182.583983 -116.857752) (xy 182.547232 -116.894503) (xy 182.505184 -116.925053)
			(xy 182.458874 -116.948649) (xy 182.409444 -116.96471) (xy 182.358109 -116.97284) (xy 182.306135 -116.97284)
			(xy 182.2548 -116.96471) (xy 182.20537 -116.948649) (xy 182.15906 -116.925053) (xy 182.117012 -116.894503)
			(xy 182.080261 -116.857752) (xy 182.049711 -116.815704) (xy 182.026115 -116.769394) (xy 182.010054 -116.719964)
			(xy 182.001924 -116.668629) (xy 181.862474 -116.668629) (xy 181.854344 -116.719964) (xy 181.838283 -116.769394)
			(xy 181.814687 -116.815704) (xy 181.784137 -116.857752) (xy 181.747386 -116.894503) (xy 181.705338 -116.925053)
			(xy 181.659028 -116.948649) (xy 181.609598 -116.96471) (xy 181.558263 -116.97284) (xy 181.506289 -116.97284)
			(xy 181.454954 -116.96471) (xy 181.405524 -116.948649) (xy 181.359214 -116.925053) (xy 181.317166 -116.894503)
			(xy 181.280415 -116.857752) (xy 181.249865 -116.815704) (xy 181.226269 -116.769394) (xy 181.210208 -116.719964)
			(xy 181.202078 -116.668629) (xy 181.062374 -116.668629) (xy 181.054244 -116.719964) (xy 181.038183 -116.769394)
			(xy 181.014587 -116.815704) (xy 180.984037 -116.857752) (xy 180.947286 -116.894503) (xy 180.905238 -116.925053)
			(xy 180.858928 -116.948649) (xy 180.809498 -116.96471) (xy 180.758163 -116.97284) (xy 180.706189 -116.97284)
			(xy 180.654854 -116.96471) (xy 180.605424 -116.948649) (xy 180.559114 -116.925053) (xy 180.517066 -116.894503)
			(xy 180.480315 -116.857752) (xy 180.449765 -116.815704) (xy 180.426169 -116.769394) (xy 180.410108 -116.719964)
			(xy 180.401978 -116.668629) (xy 180.262528 -116.668629) (xy 180.254398 -116.719964) (xy 180.238337 -116.769394)
			(xy 180.214741 -116.815704) (xy 180.184191 -116.857752) (xy 180.14744 -116.894503) (xy 180.105392 -116.925053)
			(xy 180.059082 -116.948649) (xy 180.009652 -116.96471) (xy 179.958317 -116.97284) (xy 179.906343 -116.97284)
			(xy 179.855008 -116.96471) (xy 179.805578 -116.948649) (xy 179.759268 -116.925053) (xy 179.71722 -116.894503)
			(xy 179.680469 -116.857752) (xy 179.649919 -116.815704) (xy 179.626323 -116.769394) (xy 179.610262 -116.719964)
			(xy 179.602132 -116.668629) (xy 179.462428 -116.668629) (xy 179.454298 -116.719964) (xy 179.438237 -116.769394)
			(xy 179.414641 -116.815704) (xy 179.384091 -116.857752) (xy 179.34734 -116.894503) (xy 179.305292 -116.925053)
			(xy 179.258982 -116.948649) (xy 179.209552 -116.96471) (xy 179.158217 -116.97284) (xy 179.106243 -116.97284)
			(xy 179.054908 -116.96471) (xy 179.005478 -116.948649) (xy 178.959168 -116.925053) (xy 178.91712 -116.894503)
			(xy 178.880369 -116.857752) (xy 178.849819 -116.815704) (xy 178.826223 -116.769394) (xy 178.810162 -116.719964)
			(xy 178.802032 -116.668629) (xy 178.662328 -116.668629) (xy 178.654198 -116.719964) (xy 178.638137 -116.769394)
			(xy 178.614541 -116.815704) (xy 178.583991 -116.857752) (xy 178.54724 -116.894503) (xy 178.505192 -116.925053)
			(xy 178.458882 -116.948649) (xy 178.409452 -116.96471) (xy 178.358117 -116.97284) (xy 178.306143 -116.97284)
			(xy 178.254808 -116.96471) (xy 178.205378 -116.948649) (xy 178.159068 -116.925053) (xy 178.11702 -116.894503)
			(xy 178.080269 -116.857752) (xy 178.049719 -116.815704) (xy 178.026123 -116.769394) (xy 178.010062 -116.719964)
			(xy 178.001932 -116.668629) (xy 170.244027 -116.668629) (xy 170.193952 -116.674139) (xy 170.138218 -116.672102)
			(xy 170.083375 -116.661972) (xy 170.030591 -116.643965) (xy 169.980991 -116.618464) (xy 169.935633 -116.586013)
			(xy 169.895484 -116.547304) (xy 169.861398 -116.503161) (xy 169.834102 -116.454526) (xy 169.814179 -116.402435)
			(xy 169.802053 -116.347998) (xy 169.797982 -116.292376) (xy 169.672442 -116.292376) (xy 169.672508 -116.296948)
			(xy 169.672429 -116.30967) (xy 169.671157 -116.335082) (xy 169.669968 -116.347748) (xy 169.666248 -116.379901)
			(xy 169.651695 -116.44297) (xy 169.629257 -116.503683) (xy 169.599298 -116.561059) (xy 169.5623 -116.61417)
			(xy 169.518864 -116.662157) (xy 169.469689 -116.704245) (xy 169.442892 -116.722398) (xy 169.436295 -116.727787)
			(xy 169.426826 -116.741934) (xy 169.42435 -116.750084) (xy 169.422826 -116.762022) (xy 169.422826 -116.847874)
			(xy 169.42435 -116.859812) (xy 169.42683 -116.867957) (xy 169.436317 -116.882085) (xy 169.442892 -116.887498)
			(xy 169.468958 -116.905183) (xy 169.516938 -116.945996) (xy 169.559516 -116.992418) (xy 169.596041 -117.043737)
			(xy 169.625956 -117.099171) (xy 169.648803 -117.157873) (xy 169.664233 -117.218944) (xy 169.672011 -117.281453)
			(xy 169.672508 -117.312948) (xy 169.672041 -117.343677) (xy 169.664628 -117.404687) (xy 169.649915 -117.464358)
			(xy 169.648257 -117.468729) (xy 178.001932 -117.468729) (xy 178.001932 -117.416755) (xy 178.010062 -117.36542)
			(xy 178.026123 -117.31599) (xy 178.049719 -117.26968) (xy 178.080269 -117.227632) (xy 178.11702 -117.190881)
			(xy 178.159068 -117.160331) (xy 178.205378 -117.136735) (xy 178.254808 -117.120674) (xy 178.306143 -117.112544)
			(xy 178.358117 -117.112544) (xy 178.409452 -117.120674) (xy 178.458882 -117.136735) (xy 178.505192 -117.160331)
			(xy 178.54724 -117.190881) (xy 178.583991 -117.227632) (xy 178.614541 -117.26968) (xy 178.638137 -117.31599)
			(xy 178.654198 -117.36542) (xy 178.662328 -117.416755) (xy 178.662838 -117.442742) (xy 178.662328 -117.468729)
			(xy 178.802032 -117.468729) (xy 178.802032 -117.416755) (xy 178.810162 -117.36542) (xy 178.826223 -117.31599)
			(xy 178.849819 -117.26968) (xy 178.880369 -117.227632) (xy 178.91712 -117.190881) (xy 178.959168 -117.160331)
			(xy 179.005478 -117.136735) (xy 179.054908 -117.120674) (xy 179.106243 -117.112544) (xy 179.158217 -117.112544)
			(xy 179.209552 -117.120674) (xy 179.258982 -117.136735) (xy 179.305292 -117.160331) (xy 179.34734 -117.190881)
			(xy 179.384091 -117.227632) (xy 179.414641 -117.26968) (xy 179.438237 -117.31599) (xy 179.454298 -117.36542)
			(xy 179.462428 -117.416755) (xy 179.462938 -117.442742) (xy 179.462428 -117.468729) (xy 179.602132 -117.468729)
			(xy 179.602132 -117.416755) (xy 179.610262 -117.36542) (xy 179.626323 -117.31599) (xy 179.649919 -117.26968)
			(xy 179.680469 -117.227632) (xy 179.71722 -117.190881) (xy 179.759268 -117.160331) (xy 179.805578 -117.136735)
			(xy 179.855008 -117.120674) (xy 179.906343 -117.112544) (xy 179.958317 -117.112544) (xy 180.009652 -117.120674)
			(xy 180.059082 -117.136735) (xy 180.105392 -117.160331) (xy 180.14744 -117.190881) (xy 180.184191 -117.227632)
			(xy 180.214741 -117.26968) (xy 180.238337 -117.31599) (xy 180.254398 -117.36542) (xy 180.262528 -117.416755)
			(xy 180.263038 -117.442742) (xy 180.262528 -117.468729) (xy 180.401978 -117.468729) (xy 180.401978 -117.416755)
			(xy 180.410108 -117.36542) (xy 180.426169 -117.31599) (xy 180.449765 -117.26968) (xy 180.480315 -117.227632)
			(xy 180.517066 -117.190881) (xy 180.559114 -117.160331) (xy 180.605424 -117.136735) (xy 180.654854 -117.120674)
			(xy 180.706189 -117.112544) (xy 180.758163 -117.112544) (xy 180.809498 -117.120674) (xy 180.858928 -117.136735)
			(xy 180.905238 -117.160331) (xy 180.947286 -117.190881) (xy 180.984037 -117.227632) (xy 181.014587 -117.26968)
			(xy 181.038183 -117.31599) (xy 181.054244 -117.36542) (xy 181.062374 -117.416755) (xy 181.062884 -117.442742)
			(xy 181.062374 -117.468729) (xy 181.202078 -117.468729) (xy 181.202078 -117.416755) (xy 181.210208 -117.36542)
			(xy 181.226269 -117.31599) (xy 181.249865 -117.26968) (xy 181.280415 -117.227632) (xy 181.317166 -117.190881)
			(xy 181.359214 -117.160331) (xy 181.405524 -117.136735) (xy 181.454954 -117.120674) (xy 181.506289 -117.112544)
			(xy 181.558263 -117.112544) (xy 181.609598 -117.120674) (xy 181.659028 -117.136735) (xy 181.705338 -117.160331)
			(xy 181.747386 -117.190881) (xy 181.784137 -117.227632) (xy 181.814687 -117.26968) (xy 181.838283 -117.31599)
			(xy 181.854344 -117.36542) (xy 181.862474 -117.416755) (xy 181.862984 -117.442742) (xy 181.862474 -117.468729)
			(xy 182.001924 -117.468729) (xy 182.001924 -117.416755) (xy 182.010054 -117.36542) (xy 182.026115 -117.31599)
			(xy 182.049711 -117.26968) (xy 182.080261 -117.227632) (xy 182.117012 -117.190881) (xy 182.15906 -117.160331)
			(xy 182.20537 -117.136735) (xy 182.2548 -117.120674) (xy 182.306135 -117.112544) (xy 182.358109 -117.112544)
			(xy 182.409444 -117.120674) (xy 182.458874 -117.136735) (xy 182.505184 -117.160331) (xy 182.547232 -117.190881)
			(xy 182.583983 -117.227632) (xy 182.614533 -117.26968) (xy 182.638129 -117.31599) (xy 182.65419 -117.36542)
			(xy 182.66232 -117.416755) (xy 182.66283 -117.442742) (xy 182.66232 -117.468729) (xy 182.802024 -117.468729)
			(xy 182.802024 -117.416755) (xy 182.810154 -117.36542) (xy 182.826215 -117.31599) (xy 182.849811 -117.26968)
			(xy 182.880361 -117.227632) (xy 182.917112 -117.190881) (xy 182.95916 -117.160331) (xy 183.00547 -117.136735)
			(xy 183.0549 -117.120674) (xy 183.106235 -117.112544) (xy 183.158209 -117.112544) (xy 183.209544 -117.120674)
			(xy 183.258974 -117.136735) (xy 183.305284 -117.160331) (xy 183.347332 -117.190881) (xy 183.384083 -117.227632)
			(xy 183.414633 -117.26968) (xy 183.438229 -117.31599) (xy 183.45429 -117.36542) (xy 183.46242 -117.416755)
			(xy 183.46293 -117.442742) (xy 183.46242 -117.468729) (xy 183.602124 -117.468729) (xy 183.602124 -117.416755)
			(xy 183.610254 -117.36542) (xy 183.626315 -117.31599) (xy 183.649911 -117.26968) (xy 183.680461 -117.227632)
			(xy 183.717212 -117.190881) (xy 183.75926 -117.160331) (xy 183.80557 -117.136735) (xy 183.855 -117.120674)
			(xy 183.906335 -117.112544) (xy 183.958309 -117.112544) (xy 184.009644 -117.120674) (xy 184.059074 -117.136735)
			(xy 184.105384 -117.160331) (xy 184.147432 -117.190881) (xy 184.184183 -117.227632) (xy 184.214733 -117.26968)
			(xy 184.238329 -117.31599) (xy 184.25439 -117.36542) (xy 184.26252 -117.416755) (xy 184.26303 -117.442742)
			(xy 184.26252 -117.468729) (xy 184.40197 -117.468729) (xy 184.40197 -117.416755) (xy 184.4101 -117.36542)
			(xy 184.426161 -117.31599) (xy 184.449757 -117.26968) (xy 184.480307 -117.227632) (xy 184.517058 -117.190881)
			(xy 184.559106 -117.160331) (xy 184.605416 -117.136735) (xy 184.654846 -117.120674) (xy 184.706181 -117.112544)
			(xy 184.758155 -117.112544) (xy 184.80949 -117.120674) (xy 184.85892 -117.136735) (xy 184.90523 -117.160331)
			(xy 184.947278 -117.190881) (xy 184.984029 -117.227632) (xy 185.014579 -117.26968) (xy 185.038175 -117.31599)
			(xy 185.054236 -117.36542) (xy 185.062366 -117.416755) (xy 185.062876 -117.442742) (xy 185.062366 -117.468729)
			(xy 185.98185 -117.468729) (xy 185.98185 -117.416755) (xy 185.98998 -117.36542) (xy 186.006041 -117.31599)
			(xy 186.029637 -117.26968) (xy 186.060187 -117.227632) (xy 186.096938 -117.190881) (xy 186.138986 -117.160331)
			(xy 186.185296 -117.136735) (xy 186.234726 -117.120674) (xy 186.286061 -117.112544) (xy 186.338035 -117.112544)
			(xy 186.38937 -117.120674) (xy 186.4388 -117.136735) (xy 186.48511 -117.160331) (xy 186.527158 -117.190881)
			(xy 186.563909 -117.227632) (xy 186.594459 -117.26968) (xy 186.618055 -117.31599) (xy 186.634116 -117.36542)
			(xy 186.642246 -117.416755) (xy 186.642756 -117.442742) (xy 186.642246 -117.468729) (xy 186.781696 -117.468729)
			(xy 186.781696 -117.416755) (xy 186.789826 -117.36542) (xy 186.805887 -117.31599) (xy 186.829483 -117.26968)
			(xy 186.860033 -117.227632) (xy 186.896784 -117.190881) (xy 186.938832 -117.160331) (xy 186.985142 -117.136735)
			(xy 187.034572 -117.120674) (xy 187.085907 -117.112544) (xy 187.137881 -117.112544) (xy 187.189216 -117.120674)
			(xy 187.238646 -117.136735) (xy 187.284956 -117.160331) (xy 187.327004 -117.190881) (xy 187.363755 -117.227632)
			(xy 187.394305 -117.26968) (xy 187.417901 -117.31599) (xy 187.433962 -117.36542) (xy 187.442092 -117.416755)
			(xy 187.442602 -117.442742) (xy 187.442092 -117.468729) (xy 187.581796 -117.468729) (xy 187.581796 -117.416755)
			(xy 187.589926 -117.36542) (xy 187.605987 -117.31599) (xy 187.629583 -117.26968) (xy 187.660133 -117.227632)
			(xy 187.696884 -117.190881) (xy 187.738932 -117.160331) (xy 187.785242 -117.136735) (xy 187.834672 -117.120674)
			(xy 187.886007 -117.112544) (xy 187.937981 -117.112544) (xy 187.989316 -117.120674) (xy 188.038746 -117.136735)
			(xy 188.085056 -117.160331) (xy 188.127104 -117.190881) (xy 188.163855 -117.227632) (xy 188.194405 -117.26968)
			(xy 188.218001 -117.31599) (xy 188.234062 -117.36542) (xy 188.242192 -117.416755) (xy 188.242702 -117.442742)
			(xy 188.242192 -117.468729) (xy 188.381896 -117.468729) (xy 188.381896 -117.416755) (xy 188.390026 -117.36542)
			(xy 188.406087 -117.31599) (xy 188.429683 -117.26968) (xy 188.460233 -117.227632) (xy 188.496984 -117.190881)
			(xy 188.539032 -117.160331) (xy 188.585342 -117.136735) (xy 188.634772 -117.120674) (xy 188.686107 -117.112544)
			(xy 188.738081 -117.112544) (xy 188.789416 -117.120674) (xy 188.838846 -117.136735) (xy 188.885156 -117.160331)
			(xy 188.927204 -117.190881) (xy 188.963955 -117.227632) (xy 188.994505 -117.26968) (xy 189.018101 -117.31599)
			(xy 189.034162 -117.36542) (xy 189.042292 -117.416755) (xy 189.042802 -117.442742) (xy 189.042292 -117.468729)
			(xy 189.181742 -117.468729) (xy 189.181742 -117.416755) (xy 189.189872 -117.36542) (xy 189.205933 -117.31599)
			(xy 189.229529 -117.26968) (xy 189.260079 -117.227632) (xy 189.29683 -117.190881) (xy 189.338878 -117.160331)
			(xy 189.385188 -117.136735) (xy 189.434618 -117.120674) (xy 189.485953 -117.112544) (xy 189.537927 -117.112544)
			(xy 189.589262 -117.120674) (xy 189.638692 -117.136735) (xy 189.685002 -117.160331) (xy 189.72705 -117.190881)
			(xy 189.763801 -117.227632) (xy 189.794351 -117.26968) (xy 189.817947 -117.31599) (xy 189.834008 -117.36542)
			(xy 189.842138 -117.416755) (xy 189.842648 -117.442742) (xy 189.842138 -117.468729) (xy 189.981842 -117.468729)
			(xy 189.981842 -117.416755) (xy 189.989972 -117.36542) (xy 190.006033 -117.31599) (xy 190.029629 -117.26968)
			(xy 190.060179 -117.227632) (xy 190.09693 -117.190881) (xy 190.138978 -117.160331) (xy 190.185288 -117.136735)
			(xy 190.234718 -117.120674) (xy 190.286053 -117.112544) (xy 190.338027 -117.112544) (xy 190.389362 -117.120674)
			(xy 190.438792 -117.136735) (xy 190.485102 -117.160331) (xy 190.52715 -117.190881) (xy 190.563901 -117.227632)
			(xy 190.594451 -117.26968) (xy 190.618047 -117.31599) (xy 190.634108 -117.36542) (xy 190.642238 -117.416755)
			(xy 190.642748 -117.442742) (xy 190.642238 -117.468729) (xy 190.781688 -117.468729) (xy 190.781688 -117.416755)
			(xy 190.789818 -117.36542) (xy 190.805879 -117.31599) (xy 190.829475 -117.26968) (xy 190.860025 -117.227632)
			(xy 190.896776 -117.190881) (xy 190.938824 -117.160331) (xy 190.985134 -117.136735) (xy 191.034564 -117.120674)
			(xy 191.085899 -117.112544) (xy 191.137873 -117.112544) (xy 191.189208 -117.120674) (xy 191.238638 -117.136735)
			(xy 191.284948 -117.160331) (xy 191.326996 -117.190881) (xy 191.363747 -117.227632) (xy 191.394297 -117.26968)
			(xy 191.417893 -117.31599) (xy 191.433954 -117.36542) (xy 191.442084 -117.416755) (xy 191.442594 -117.442742)
			(xy 191.442084 -117.468729) (xy 191.581788 -117.468729) (xy 191.581788 -117.416755) (xy 191.589918 -117.36542)
			(xy 191.605979 -117.31599) (xy 191.629575 -117.26968) (xy 191.660125 -117.227632) (xy 191.696876 -117.190881)
			(xy 191.738924 -117.160331) (xy 191.785234 -117.136735) (xy 191.834664 -117.120674) (xy 191.885999 -117.112544)
			(xy 191.937973 -117.112544) (xy 191.989308 -117.120674) (xy 192.038738 -117.136735) (xy 192.085048 -117.160331)
			(xy 192.127096 -117.190881) (xy 192.163847 -117.227632) (xy 192.194397 -117.26968) (xy 192.217993 -117.31599)
			(xy 192.234054 -117.36542) (xy 192.242184 -117.416755) (xy 192.242694 -117.442742) (xy 192.242184 -117.468729)
			(xy 192.234054 -117.520064) (xy 192.217993 -117.569494) (xy 192.194397 -117.615804) (xy 192.163847 -117.657852)
			(xy 192.127096 -117.694603) (xy 192.085048 -117.725153) (xy 192.038738 -117.748749) (xy 191.989308 -117.76481)
			(xy 191.937973 -117.77294) (xy 191.885999 -117.77294) (xy 191.834664 -117.76481) (xy 191.785234 -117.748749)
			(xy 191.738924 -117.725153) (xy 191.696876 -117.694603) (xy 191.660125 -117.657852) (xy 191.629575 -117.615804)
			(xy 191.605979 -117.569494) (xy 191.589918 -117.520064) (xy 191.581788 -117.468729) (xy 191.442084 -117.468729)
			(xy 191.433954 -117.520064) (xy 191.417893 -117.569494) (xy 191.394297 -117.615804) (xy 191.363747 -117.657852)
			(xy 191.326996 -117.694603) (xy 191.284948 -117.725153) (xy 191.238638 -117.748749) (xy 191.189208 -117.76481)
			(xy 191.137873 -117.77294) (xy 191.085899 -117.77294) (xy 191.034564 -117.76481) (xy 190.985134 -117.748749)
			(xy 190.938824 -117.725153) (xy 190.896776 -117.694603) (xy 190.860025 -117.657852) (xy 190.829475 -117.615804)
			(xy 190.805879 -117.569494) (xy 190.789818 -117.520064) (xy 190.781688 -117.468729) (xy 190.642238 -117.468729)
			(xy 190.634108 -117.520064) (xy 190.618047 -117.569494) (xy 190.594451 -117.615804) (xy 190.563901 -117.657852)
			(xy 190.52715 -117.694603) (xy 190.485102 -117.725153) (xy 190.438792 -117.748749) (xy 190.389362 -117.76481)
			(xy 190.338027 -117.77294) (xy 190.286053 -117.77294) (xy 190.234718 -117.76481) (xy 190.185288 -117.748749)
			(xy 190.138978 -117.725153) (xy 190.09693 -117.694603) (xy 190.060179 -117.657852) (xy 190.029629 -117.615804)
			(xy 190.006033 -117.569494) (xy 189.989972 -117.520064) (xy 189.981842 -117.468729) (xy 189.842138 -117.468729)
			(xy 189.834008 -117.520064) (xy 189.817947 -117.569494) (xy 189.794351 -117.615804) (xy 189.763801 -117.657852)
			(xy 189.72705 -117.694603) (xy 189.685002 -117.725153) (xy 189.638692 -117.748749) (xy 189.589262 -117.76481)
			(xy 189.537927 -117.77294) (xy 189.485953 -117.77294) (xy 189.434618 -117.76481) (xy 189.385188 -117.748749)
			(xy 189.338878 -117.725153) (xy 189.29683 -117.694603) (xy 189.260079 -117.657852) (xy 189.229529 -117.615804)
			(xy 189.205933 -117.569494) (xy 189.189872 -117.520064) (xy 189.181742 -117.468729) (xy 189.042292 -117.468729)
			(xy 189.034162 -117.520064) (xy 189.018101 -117.569494) (xy 188.994505 -117.615804) (xy 188.963955 -117.657852)
			(xy 188.927204 -117.694603) (xy 188.885156 -117.725153) (xy 188.838846 -117.748749) (xy 188.789416 -117.76481)
			(xy 188.738081 -117.77294) (xy 188.686107 -117.77294) (xy 188.634772 -117.76481) (xy 188.585342 -117.748749)
			(xy 188.539032 -117.725153) (xy 188.496984 -117.694603) (xy 188.460233 -117.657852) (xy 188.429683 -117.615804)
			(xy 188.406087 -117.569494) (xy 188.390026 -117.520064) (xy 188.381896 -117.468729) (xy 188.242192 -117.468729)
			(xy 188.234062 -117.520064) (xy 188.218001 -117.569494) (xy 188.194405 -117.615804) (xy 188.163855 -117.657852)
			(xy 188.127104 -117.694603) (xy 188.085056 -117.725153) (xy 188.038746 -117.748749) (xy 187.989316 -117.76481)
			(xy 187.937981 -117.77294) (xy 187.886007 -117.77294) (xy 187.834672 -117.76481) (xy 187.785242 -117.748749)
			(xy 187.738932 -117.725153) (xy 187.696884 -117.694603) (xy 187.660133 -117.657852) (xy 187.629583 -117.615804)
			(xy 187.605987 -117.569494) (xy 187.589926 -117.520064) (xy 187.581796 -117.468729) (xy 187.442092 -117.468729)
			(xy 187.433962 -117.520064) (xy 187.417901 -117.569494) (xy 187.394305 -117.615804) (xy 187.363755 -117.657852)
			(xy 187.327004 -117.694603) (xy 187.284956 -117.725153) (xy 187.238646 -117.748749) (xy 187.189216 -117.76481)
			(xy 187.137881 -117.77294) (xy 187.085907 -117.77294) (xy 187.034572 -117.76481) (xy 186.985142 -117.748749)
			(xy 186.938832 -117.725153) (xy 186.896784 -117.694603) (xy 186.860033 -117.657852) (xy 186.829483 -117.615804)
			(xy 186.805887 -117.569494) (xy 186.789826 -117.520064) (xy 186.781696 -117.468729) (xy 186.642246 -117.468729)
			(xy 186.634116 -117.520064) (xy 186.618055 -117.569494) (xy 186.594459 -117.615804) (xy 186.563909 -117.657852)
			(xy 186.527158 -117.694603) (xy 186.48511 -117.725153) (xy 186.4388 -117.748749) (xy 186.38937 -117.76481)
			(xy 186.338035 -117.77294) (xy 186.286061 -117.77294) (xy 186.234726 -117.76481) (xy 186.185296 -117.748749)
			(xy 186.138986 -117.725153) (xy 186.096938 -117.694603) (xy 186.060187 -117.657852) (xy 186.029637 -117.615804)
			(xy 186.006041 -117.569494) (xy 185.98998 -117.520064) (xy 185.98185 -117.468729) (xy 185.062366 -117.468729)
			(xy 185.054236 -117.520064) (xy 185.038175 -117.569494) (xy 185.014579 -117.615804) (xy 184.984029 -117.657852)
			(xy 184.947278 -117.694603) (xy 184.90523 -117.725153) (xy 184.85892 -117.748749) (xy 184.80949 -117.76481)
			(xy 184.758155 -117.77294) (xy 184.706181 -117.77294) (xy 184.654846 -117.76481) (xy 184.605416 -117.748749)
			(xy 184.559106 -117.725153) (xy 184.517058 -117.694603) (xy 184.480307 -117.657852) (xy 184.449757 -117.615804)
			(xy 184.426161 -117.569494) (xy 184.4101 -117.520064) (xy 184.40197 -117.468729) (xy 184.26252 -117.468729)
			(xy 184.25439 -117.520064) (xy 184.238329 -117.569494) (xy 184.214733 -117.615804) (xy 184.184183 -117.657852)
			(xy 184.147432 -117.694603) (xy 184.105384 -117.725153) (xy 184.059074 -117.748749) (xy 184.009644 -117.76481)
			(xy 183.958309 -117.77294) (xy 183.906335 -117.77294) (xy 183.855 -117.76481) (xy 183.80557 -117.748749)
			(xy 183.75926 -117.725153) (xy 183.717212 -117.694603) (xy 183.680461 -117.657852) (xy 183.649911 -117.615804)
			(xy 183.626315 -117.569494) (xy 183.610254 -117.520064) (xy 183.602124 -117.468729) (xy 183.46242 -117.468729)
			(xy 183.45429 -117.520064) (xy 183.438229 -117.569494) (xy 183.414633 -117.615804) (xy 183.384083 -117.657852)
			(xy 183.347332 -117.694603) (xy 183.305284 -117.725153) (xy 183.258974 -117.748749) (xy 183.209544 -117.76481)
			(xy 183.158209 -117.77294) (xy 183.106235 -117.77294) (xy 183.0549 -117.76481) (xy 183.00547 -117.748749)
			(xy 182.95916 -117.725153) (xy 182.917112 -117.694603) (xy 182.880361 -117.657852) (xy 182.849811 -117.615804)
			(xy 182.826215 -117.569494) (xy 182.810154 -117.520064) (xy 182.802024 -117.468729) (xy 182.66232 -117.468729)
			(xy 182.65419 -117.520064) (xy 182.638129 -117.569494) (xy 182.614533 -117.615804) (xy 182.583983 -117.657852)
			(xy 182.547232 -117.694603) (xy 182.505184 -117.725153) (xy 182.458874 -117.748749) (xy 182.409444 -117.76481)
			(xy 182.358109 -117.77294) (xy 182.306135 -117.77294) (xy 182.2548 -117.76481) (xy 182.20537 -117.748749)
			(xy 182.15906 -117.725153) (xy 182.117012 -117.694603) (xy 182.080261 -117.657852) (xy 182.049711 -117.615804)
			(xy 182.026115 -117.569494) (xy 182.010054 -117.520064) (xy 182.001924 -117.468729) (xy 181.862474 -117.468729)
			(xy 181.854344 -117.520064) (xy 181.838283 -117.569494) (xy 181.814687 -117.615804) (xy 181.784137 -117.657852)
			(xy 181.747386 -117.694603) (xy 181.705338 -117.725153) (xy 181.659028 -117.748749) (xy 181.609598 -117.76481)
			(xy 181.558263 -117.77294) (xy 181.506289 -117.77294) (xy 181.454954 -117.76481) (xy 181.405524 -117.748749)
			(xy 181.359214 -117.725153) (xy 181.317166 -117.694603) (xy 181.280415 -117.657852) (xy 181.249865 -117.615804)
			(xy 181.226269 -117.569494) (xy 181.210208 -117.520064) (xy 181.202078 -117.468729) (xy 181.062374 -117.468729)
			(xy 181.054244 -117.520064) (xy 181.038183 -117.569494) (xy 181.014587 -117.615804) (xy 180.984037 -117.657852)
			(xy 180.947286 -117.694603) (xy 180.905238 -117.725153) (xy 180.858928 -117.748749) (xy 180.809498 -117.76481)
			(xy 180.758163 -117.77294) (xy 180.706189 -117.77294) (xy 180.654854 -117.76481) (xy 180.605424 -117.748749)
			(xy 180.559114 -117.725153) (xy 180.517066 -117.694603) (xy 180.480315 -117.657852) (xy 180.449765 -117.615804)
			(xy 180.426169 -117.569494) (xy 180.410108 -117.520064) (xy 180.401978 -117.468729) (xy 180.262528 -117.468729)
			(xy 180.254398 -117.520064) (xy 180.238337 -117.569494) (xy 180.214741 -117.615804) (xy 180.184191 -117.657852)
			(xy 180.14744 -117.694603) (xy 180.105392 -117.725153) (xy 180.059082 -117.748749) (xy 180.009652 -117.76481)
			(xy 179.958317 -117.77294) (xy 179.906343 -117.77294) (xy 179.855008 -117.76481) (xy 179.805578 -117.748749)
			(xy 179.759268 -117.725153) (xy 179.71722 -117.694603) (xy 179.680469 -117.657852) (xy 179.649919 -117.615804)
			(xy 179.626323 -117.569494) (xy 179.610262 -117.520064) (xy 179.602132 -117.468729) (xy 179.462428 -117.468729)
			(xy 179.454298 -117.520064) (xy 179.438237 -117.569494) (xy 179.414641 -117.615804) (xy 179.384091 -117.657852)
			(xy 179.34734 -117.694603) (xy 179.305292 -117.725153) (xy 179.258982 -117.748749) (xy 179.209552 -117.76481)
			(xy 179.158217 -117.77294) (xy 179.106243 -117.77294) (xy 179.054908 -117.76481) (xy 179.005478 -117.748749)
			(xy 178.959168 -117.725153) (xy 178.91712 -117.694603) (xy 178.880369 -117.657852) (xy 178.849819 -117.615804)
			(xy 178.826223 -117.569494) (xy 178.810162 -117.520064) (xy 178.802032 -117.468729) (xy 178.662328 -117.468729)
			(xy 178.654198 -117.520064) (xy 178.638137 -117.569494) (xy 178.614541 -117.615804) (xy 178.583991 -117.657852)
			(xy 178.54724 -117.694603) (xy 178.505192 -117.725153) (xy 178.458882 -117.748749) (xy 178.409452 -117.76481)
			(xy 178.358117 -117.77294) (xy 178.306143 -117.77294) (xy 178.254808 -117.76481) (xy 178.205378 -117.748749)
			(xy 178.159068 -117.725153) (xy 178.11702 -117.694603) (xy 178.080269 -117.657852) (xy 178.049719 -117.615804)
			(xy 178.026123 -117.569494) (xy 178.010062 -117.520064) (xy 178.001932 -117.468729) (xy 169.648257 -117.468729)
			(xy 169.628118 -117.521821) (xy 169.599553 -117.576238) (xy 169.564638 -117.626815) (xy 169.523881 -117.672815)
			(xy 169.477877 -117.713567) (xy 169.427296 -117.748478) (xy 169.372877 -117.777037) (xy 169.315412 -117.798829)
			(xy 169.255739 -117.813536) (xy 169.194729 -117.820944) (xy 169.164 -117.821456) (xy 169.131658 -117.820945)
			(xy 169.067497 -117.812734) (xy 169.004895 -117.796455) (xy 168.944861 -117.772374) (xy 168.888363 -117.740876)
			(xy 168.836314 -117.702472) (xy 168.789553 -117.65778) (xy 168.768776 -117.632988) (xy 168.768268 -117.63248)
			(xy 168.76776 -117.631718) (xy 168.764499 -117.627987) (xy 168.756833 -117.621711) (xy 168.75252 -117.619272)
			(xy 168.744392 -117.614954) (xy 168.697402 -117.610636) (xy 168.66108 -117.607334) (xy 168.655949 -117.606951)
			(xy 168.645713 -117.607974) (xy 168.64076 -117.609366) (xy 168.631616 -117.612414) (xy 168.623488 -117.619272)
			(xy 168.623234 -117.619526) (xy 168.613899 -117.627419) (xy 168.594587 -117.642411) (xy 168.584626 -117.649498)
			(xy 168.552397 -117.671151) (xy 168.48275 -117.705465) (xy 168.445942 -117.717824) (xy 168.43883 -117.719856)
			(xy 168.427654 -117.727476) (xy 168.42105 -117.735096) (xy 168.417471 -117.739987) (xy 168.412473 -117.751026)
			(xy 168.411144 -117.75694) (xy 168.398444 -117.852444) (xy 168.397905 -117.860987) (xy 168.401917 -117.877615)
			(xy 168.406318 -117.884956) (xy 168.418002 -117.89664) (xy 168.42613 -117.903244) (xy 168.442132 -117.914166)
			(xy 168.467424 -117.932702) (xy 168.513722 -117.974994) (xy 168.554474 -118.022654) (xy 168.589062 -118.074959)
			(xy 168.616963 -118.131117) (xy 168.637753 -118.190277) (xy 168.651119 -118.251543) (xy 168.654476 -118.28272)
			(xy 168.654984 -118.288816) (xy 168.656334 -118.324376) (xy 169.797982 -118.324376) (xy 169.802053 -118.268754)
			(xy 169.814179 -118.214317) (xy 169.834102 -118.162226) (xy 169.861398 -118.113591) (xy 169.895484 -118.069448)
			(xy 169.935633 -118.030739) (xy 169.980991 -117.998288) (xy 170.030591 -117.972787) (xy 170.083375 -117.95478)
			(xy 170.138218 -117.94465) (xy 170.193952 -117.942613) (xy 170.249389 -117.948713) (xy 170.303346 -117.962819)
			(xy 170.354675 -117.984631) (xy 170.402281 -118.013685) (xy 170.445149 -118.04936) (xy 170.482366 -118.090897)
			(xy 170.513139 -118.13741) (xy 170.536811 -118.187907) (xy 170.539341 -118.196317) (xy 175.151282 -118.196317)
			(xy 175.151282 -118.132395) (xy 175.159293 -118.068977) (xy 175.17519 -118.007063) (xy 175.198722 -117.94763)
			(xy 175.229516 -117.891615) (xy 175.267089 -117.8399) (xy 175.310846 -117.793303) (xy 175.360099 -117.752558)
			(xy 175.41407 -117.718307) (xy 175.471909 -117.69109) (xy 175.532702 -117.671337) (xy 175.595492 -117.659359)
			(xy 175.659288 -117.655346) (xy 175.723084 -117.659359) (xy 175.785874 -117.671337) (xy 175.846667 -117.69109)
			(xy 175.904506 -117.718307) (xy 175.958477 -117.752558) (xy 176.00773 -117.793303) (xy 176.051487 -117.8399)
			(xy 176.08906 -117.891615) (xy 176.119854 -117.94763) (xy 176.143386 -118.007063) (xy 176.159283 -118.068977)
			(xy 176.167294 -118.132395) (xy 176.167796 -118.164356) (xy 176.167294 -118.196317) (xy 176.159283 -118.259735)
			(xy 176.156948 -118.268829) (xy 176.401986 -118.268829) (xy 176.401986 -118.216855) (xy 176.410116 -118.16552)
			(xy 176.426177 -118.11609) (xy 176.449773 -118.06978) (xy 176.480323 -118.027732) (xy 176.517074 -117.990981)
			(xy 176.559122 -117.960431) (xy 176.605432 -117.936835) (xy 176.654862 -117.920774) (xy 176.706197 -117.912644)
			(xy 176.758171 -117.912644) (xy 176.809506 -117.920774) (xy 176.858936 -117.936835) (xy 176.905246 -117.960431)
			(xy 176.947294 -117.990981) (xy 176.984045 -118.027732) (xy 177.014595 -118.06978) (xy 177.038191 -118.11609)
			(xy 177.054252 -118.16552) (xy 177.062382 -118.216855) (xy 177.062892 -118.242842) (xy 177.062382 -118.268829)
			(xy 177.202086 -118.268829) (xy 177.202086 -118.216855) (xy 177.210216 -118.16552) (xy 177.226277 -118.11609)
			(xy 177.249873 -118.06978) (xy 177.280423 -118.027732) (xy 177.317174 -117.990981) (xy 177.359222 -117.960431)
			(xy 177.405532 -117.936835) (xy 177.454962 -117.920774) (xy 177.506297 -117.912644) (xy 177.558271 -117.912644)
			(xy 177.609606 -117.920774) (xy 177.659036 -117.936835) (xy 177.705346 -117.960431) (xy 177.747394 -117.990981)
			(xy 177.784145 -118.027732) (xy 177.814695 -118.06978) (xy 177.838291 -118.11609) (xy 177.854352 -118.16552)
			(xy 177.862482 -118.216855) (xy 177.862992 -118.242842) (xy 177.862482 -118.268829) (xy 178.001932 -118.268829)
			(xy 178.001932 -118.216855) (xy 178.010062 -118.16552) (xy 178.026123 -118.11609) (xy 178.049719 -118.06978)
			(xy 178.080269 -118.027732) (xy 178.11702 -117.990981) (xy 178.159068 -117.960431) (xy 178.205378 -117.936835)
			(xy 178.254808 -117.920774) (xy 178.306143 -117.912644) (xy 178.358117 -117.912644) (xy 178.409452 -117.920774)
			(xy 178.458882 -117.936835) (xy 178.505192 -117.960431) (xy 178.54724 -117.990981) (xy 178.583991 -118.027732)
			(xy 178.614541 -118.06978) (xy 178.638137 -118.11609) (xy 178.654198 -118.16552) (xy 178.662328 -118.216855)
			(xy 178.662838 -118.242842) (xy 178.662328 -118.268829) (xy 178.802032 -118.268829) (xy 178.802032 -118.216855)
			(xy 178.810162 -118.16552) (xy 178.826223 -118.11609) (xy 178.849819 -118.06978) (xy 178.880369 -118.027732)
			(xy 178.91712 -117.990981) (xy 178.959168 -117.960431) (xy 179.005478 -117.936835) (xy 179.054908 -117.920774)
			(xy 179.106243 -117.912644) (xy 179.158217 -117.912644) (xy 179.209552 -117.920774) (xy 179.258982 -117.936835)
			(xy 179.305292 -117.960431) (xy 179.34734 -117.990981) (xy 179.384091 -118.027732) (xy 179.414641 -118.06978)
			(xy 179.438237 -118.11609) (xy 179.454298 -118.16552) (xy 179.462428 -118.216855) (xy 179.462938 -118.242842)
			(xy 179.462428 -118.268829) (xy 179.602132 -118.268829) (xy 179.602132 -118.216855) (xy 179.610262 -118.16552)
			(xy 179.626323 -118.11609) (xy 179.649919 -118.06978) (xy 179.680469 -118.027732) (xy 179.71722 -117.990981)
			(xy 179.759268 -117.960431) (xy 179.805578 -117.936835) (xy 179.855008 -117.920774) (xy 179.906343 -117.912644)
			(xy 179.958317 -117.912644) (xy 180.009652 -117.920774) (xy 180.059082 -117.936835) (xy 180.105392 -117.960431)
			(xy 180.14744 -117.990981) (xy 180.184191 -118.027732) (xy 180.214741 -118.06978) (xy 180.238337 -118.11609)
			(xy 180.254398 -118.16552) (xy 180.262528 -118.216855) (xy 180.263038 -118.242842) (xy 180.262528 -118.268829)
			(xy 180.401978 -118.268829) (xy 180.401978 -118.216855) (xy 180.410108 -118.16552) (xy 180.426169 -118.11609)
			(xy 180.449765 -118.06978) (xy 180.480315 -118.027732) (xy 180.517066 -117.990981) (xy 180.559114 -117.960431)
			(xy 180.605424 -117.936835) (xy 180.654854 -117.920774) (xy 180.706189 -117.912644) (xy 180.758163 -117.912644)
			(xy 180.809498 -117.920774) (xy 180.858928 -117.936835) (xy 180.905238 -117.960431) (xy 180.947286 -117.990981)
			(xy 180.984037 -118.027732) (xy 181.014587 -118.06978) (xy 181.038183 -118.11609) (xy 181.054244 -118.16552)
			(xy 181.062374 -118.216855) (xy 181.062884 -118.242842) (xy 181.062374 -118.268829) (xy 181.202078 -118.268829)
			(xy 181.202078 -118.216855) (xy 181.210208 -118.16552) (xy 181.226269 -118.11609) (xy 181.249865 -118.06978)
			(xy 181.280415 -118.027732) (xy 181.317166 -117.990981) (xy 181.359214 -117.960431) (xy 181.405524 -117.936835)
			(xy 181.454954 -117.920774) (xy 181.506289 -117.912644) (xy 181.558263 -117.912644) (xy 181.609598 -117.920774)
			(xy 181.659028 -117.936835) (xy 181.705338 -117.960431) (xy 181.747386 -117.990981) (xy 181.784137 -118.027732)
			(xy 181.814687 -118.06978) (xy 181.838283 -118.11609) (xy 181.854344 -118.16552) (xy 181.862474 -118.216855)
			(xy 181.862984 -118.242842) (xy 181.862474 -118.268829) (xy 182.001924 -118.268829) (xy 182.001924 -118.216855)
			(xy 182.010054 -118.16552) (xy 182.026115 -118.11609) (xy 182.049711 -118.06978) (xy 182.080261 -118.027732)
			(xy 182.117012 -117.990981) (xy 182.15906 -117.960431) (xy 182.20537 -117.936835) (xy 182.2548 -117.920774)
			(xy 182.306135 -117.912644) (xy 182.358109 -117.912644) (xy 182.409444 -117.920774) (xy 182.458874 -117.936835)
			(xy 182.505184 -117.960431) (xy 182.547232 -117.990981) (xy 182.583983 -118.027732) (xy 182.614533 -118.06978)
			(xy 182.638129 -118.11609) (xy 182.65419 -118.16552) (xy 182.66232 -118.216855) (xy 182.66283 -118.242842)
			(xy 182.66232 -118.268829) (xy 188.381896 -118.268829) (xy 188.381896 -118.216855) (xy 188.390026 -118.16552)
			(xy 188.406087 -118.11609) (xy 188.429683 -118.06978) (xy 188.460233 -118.027732) (xy 188.496984 -117.990981)
			(xy 188.539032 -117.960431) (xy 188.585342 -117.936835) (xy 188.634772 -117.920774) (xy 188.686107 -117.912644)
			(xy 188.738081 -117.912644) (xy 188.789416 -117.920774) (xy 188.838846 -117.936835) (xy 188.885156 -117.960431)
			(xy 188.927204 -117.990981) (xy 188.963955 -118.027732) (xy 188.994505 -118.06978) (xy 189.018101 -118.11609)
			(xy 189.034162 -118.16552) (xy 189.042292 -118.216855) (xy 189.042802 -118.242842) (xy 189.042292 -118.268829)
			(xy 189.181742 -118.268829) (xy 189.181742 -118.216855) (xy 189.189872 -118.16552) (xy 189.205933 -118.11609)
			(xy 189.229529 -118.06978) (xy 189.260079 -118.027732) (xy 189.29683 -117.990981) (xy 189.338878 -117.960431)
			(xy 189.385188 -117.936835) (xy 189.434618 -117.920774) (xy 189.485953 -117.912644) (xy 189.537927 -117.912644)
			(xy 189.589262 -117.920774) (xy 189.638692 -117.936835) (xy 189.685002 -117.960431) (xy 189.72705 -117.990981)
			(xy 189.763801 -118.027732) (xy 189.794351 -118.06978) (xy 189.817947 -118.11609) (xy 189.834008 -118.16552)
			(xy 189.842138 -118.216855) (xy 189.842648 -118.242842) (xy 189.842138 -118.268829) (xy 189.981842 -118.268829)
			(xy 189.981842 -118.216855) (xy 189.989972 -118.16552) (xy 190.006033 -118.11609) (xy 190.029629 -118.06978)
			(xy 190.060179 -118.027732) (xy 190.09693 -117.990981) (xy 190.138978 -117.960431) (xy 190.185288 -117.936835)
			(xy 190.234718 -117.920774) (xy 190.286053 -117.912644) (xy 190.338027 -117.912644) (xy 190.389362 -117.920774)
			(xy 190.438792 -117.936835) (xy 190.485102 -117.960431) (xy 190.52715 -117.990981) (xy 190.563901 -118.027732)
			(xy 190.594451 -118.06978) (xy 190.618047 -118.11609) (xy 190.634108 -118.16552) (xy 190.642238 -118.216855)
			(xy 190.642748 -118.242842) (xy 190.642238 -118.268829) (xy 190.781688 -118.268829) (xy 190.781688 -118.216855)
			(xy 190.789818 -118.16552) (xy 190.805879 -118.11609) (xy 190.829475 -118.06978) (xy 190.860025 -118.027732)
			(xy 190.896776 -117.990981) (xy 190.938824 -117.960431) (xy 190.985134 -117.936835) (xy 191.034564 -117.920774)
			(xy 191.085899 -117.912644) (xy 191.137873 -117.912644) (xy 191.189208 -117.920774) (xy 191.238638 -117.936835)
			(xy 191.284948 -117.960431) (xy 191.326996 -117.990981) (xy 191.363747 -118.027732) (xy 191.394297 -118.06978)
			(xy 191.417893 -118.11609) (xy 191.433954 -118.16552) (xy 191.442084 -118.216855) (xy 191.442594 -118.242842)
			(xy 191.442084 -118.268829) (xy 191.581788 -118.268829) (xy 191.581788 -118.216855) (xy 191.589918 -118.16552)
			(xy 191.605979 -118.11609) (xy 191.629575 -118.06978) (xy 191.660125 -118.027732) (xy 191.696876 -117.990981)
			(xy 191.738924 -117.960431) (xy 191.785234 -117.936835) (xy 191.834664 -117.920774) (xy 191.885999 -117.912644)
			(xy 191.937973 -117.912644) (xy 191.989308 -117.920774) (xy 192.038738 -117.936835) (xy 192.085048 -117.960431)
			(xy 192.127096 -117.990981) (xy 192.163847 -118.027732) (xy 192.194397 -118.06978) (xy 192.217993 -118.11609)
			(xy 192.234054 -118.16552) (xy 192.242184 -118.216855) (xy 192.242694 -118.242842) (xy 192.242184 -118.268829)
			(xy 192.234054 -118.320164) (xy 192.217993 -118.369594) (xy 192.194397 -118.415904) (xy 192.163847 -118.457952)
			(xy 192.127096 -118.494703) (xy 192.085048 -118.525253) (xy 192.038738 -118.548849) (xy 191.989308 -118.56491)
			(xy 191.937973 -118.57304) (xy 191.885999 -118.57304) (xy 191.834664 -118.56491) (xy 191.785234 -118.548849)
			(xy 191.738924 -118.525253) (xy 191.696876 -118.494703) (xy 191.660125 -118.457952) (xy 191.629575 -118.415904)
			(xy 191.605979 -118.369594) (xy 191.589918 -118.320164) (xy 191.581788 -118.268829) (xy 191.442084 -118.268829)
			(xy 191.433954 -118.320164) (xy 191.417893 -118.369594) (xy 191.394297 -118.415904) (xy 191.363747 -118.457952)
			(xy 191.326996 -118.494703) (xy 191.284948 -118.525253) (xy 191.238638 -118.548849) (xy 191.189208 -118.56491)
			(xy 191.137873 -118.57304) (xy 191.085899 -118.57304) (xy 191.034564 -118.56491) (xy 190.985134 -118.548849)
			(xy 190.938824 -118.525253) (xy 190.896776 -118.494703) (xy 190.860025 -118.457952) (xy 190.829475 -118.415904)
			(xy 190.805879 -118.369594) (xy 190.789818 -118.320164) (xy 190.781688 -118.268829) (xy 190.642238 -118.268829)
			(xy 190.634108 -118.320164) (xy 190.618047 -118.369594) (xy 190.594451 -118.415904) (xy 190.563901 -118.457952)
			(xy 190.52715 -118.494703) (xy 190.485102 -118.525253) (xy 190.438792 -118.548849) (xy 190.389362 -118.56491)
			(xy 190.338027 -118.57304) (xy 190.286053 -118.57304) (xy 190.234718 -118.56491) (xy 190.185288 -118.548849)
			(xy 190.138978 -118.525253) (xy 190.09693 -118.494703) (xy 190.060179 -118.457952) (xy 190.029629 -118.415904)
			(xy 190.006033 -118.369594) (xy 189.989972 -118.320164) (xy 189.981842 -118.268829) (xy 189.842138 -118.268829)
			(xy 189.834008 -118.320164) (xy 189.817947 -118.369594) (xy 189.794351 -118.415904) (xy 189.763801 -118.457952)
			(xy 189.72705 -118.494703) (xy 189.685002 -118.525253) (xy 189.638692 -118.548849) (xy 189.589262 -118.56491)
			(xy 189.537927 -118.57304) (xy 189.485953 -118.57304) (xy 189.434618 -118.56491) (xy 189.385188 -118.548849)
			(xy 189.338878 -118.525253) (xy 189.29683 -118.494703) (xy 189.260079 -118.457952) (xy 189.229529 -118.415904)
			(xy 189.205933 -118.369594) (xy 189.189872 -118.320164) (xy 189.181742 -118.268829) (xy 189.042292 -118.268829)
			(xy 189.034162 -118.320164) (xy 189.018101 -118.369594) (xy 188.994505 -118.415904) (xy 188.963955 -118.457952)
			(xy 188.927204 -118.494703) (xy 188.885156 -118.525253) (xy 188.838846 -118.548849) (xy 188.789416 -118.56491)
			(xy 188.738081 -118.57304) (xy 188.686107 -118.57304) (xy 188.634772 -118.56491) (xy 188.585342 -118.548849)
			(xy 188.539032 -118.525253) (xy 188.496984 -118.494703) (xy 188.460233 -118.457952) (xy 188.429683 -118.415904)
			(xy 188.406087 -118.369594) (xy 188.390026 -118.320164) (xy 188.381896 -118.268829) (xy 182.66232 -118.268829)
			(xy 182.65419 -118.320164) (xy 182.638129 -118.369594) (xy 182.614533 -118.415904) (xy 182.583983 -118.457952)
			(xy 182.547232 -118.494703) (xy 182.505184 -118.525253) (xy 182.458874 -118.548849) (xy 182.409444 -118.56491)
			(xy 182.358109 -118.57304) (xy 182.306135 -118.57304) (xy 182.2548 -118.56491) (xy 182.20537 -118.548849)
			(xy 182.15906 -118.525253) (xy 182.117012 -118.494703) (xy 182.080261 -118.457952) (xy 182.049711 -118.415904)
			(xy 182.026115 -118.369594) (xy 182.010054 -118.320164) (xy 182.001924 -118.268829) (xy 181.862474 -118.268829)
			(xy 181.854344 -118.320164) (xy 181.838283 -118.369594) (xy 181.814687 -118.415904) (xy 181.784137 -118.457952)
			(xy 181.747386 -118.494703) (xy 181.705338 -118.525253) (xy 181.659028 -118.548849) (xy 181.609598 -118.56491)
			(xy 181.558263 -118.57304) (xy 181.506289 -118.57304) (xy 181.454954 -118.56491) (xy 181.405524 -118.548849)
			(xy 181.359214 -118.525253) (xy 181.317166 -118.494703) (xy 181.280415 -118.457952) (xy 181.249865 -118.415904)
			(xy 181.226269 -118.369594) (xy 181.210208 -118.320164) (xy 181.202078 -118.268829) (xy 181.062374 -118.268829)
			(xy 181.054244 -118.320164) (xy 181.038183 -118.369594) (xy 181.014587 -118.415904) (xy 180.984037 -118.457952)
			(xy 180.947286 -118.494703) (xy 180.905238 -118.525253) (xy 180.858928 -118.548849) (xy 180.809498 -118.56491)
			(xy 180.758163 -118.57304) (xy 180.706189 -118.57304) (xy 180.654854 -118.56491) (xy 180.605424 -118.548849)
			(xy 180.559114 -118.525253) (xy 180.517066 -118.494703) (xy 180.480315 -118.457952) (xy 180.449765 -118.415904)
			(xy 180.426169 -118.369594) (xy 180.410108 -118.320164) (xy 180.401978 -118.268829) (xy 180.262528 -118.268829)
			(xy 180.254398 -118.320164) (xy 180.238337 -118.369594) (xy 180.214741 -118.415904) (xy 180.184191 -118.457952)
			(xy 180.14744 -118.494703) (xy 180.105392 -118.525253) (xy 180.059082 -118.548849) (xy 180.009652 -118.56491)
			(xy 179.958317 -118.57304) (xy 179.906343 -118.57304) (xy 179.855008 -118.56491) (xy 179.805578 -118.548849)
			(xy 179.759268 -118.525253) (xy 179.71722 -118.494703) (xy 179.680469 -118.457952) (xy 179.649919 -118.415904)
			(xy 179.626323 -118.369594) (xy 179.610262 -118.320164) (xy 179.602132 -118.268829) (xy 179.462428 -118.268829)
			(xy 179.454298 -118.320164) (xy 179.438237 -118.369594) (xy 179.414641 -118.415904) (xy 179.384091 -118.457952)
			(xy 179.34734 -118.494703) (xy 179.305292 -118.525253) (xy 179.258982 -118.548849) (xy 179.209552 -118.56491)
			(xy 179.158217 -118.57304) (xy 179.106243 -118.57304) (xy 179.054908 -118.56491) (xy 179.005478 -118.548849)
			(xy 178.959168 -118.525253) (xy 178.91712 -118.494703) (xy 178.880369 -118.457952) (xy 178.849819 -118.415904)
			(xy 178.826223 -118.369594) (xy 178.810162 -118.320164) (xy 178.802032 -118.268829) (xy 178.662328 -118.268829)
			(xy 178.654198 -118.320164) (xy 178.638137 -118.369594) (xy 178.614541 -118.415904) (xy 178.583991 -118.457952)
			(xy 178.54724 -118.494703) (xy 178.505192 -118.525253) (xy 178.458882 -118.548849) (xy 178.409452 -118.56491)
			(xy 178.358117 -118.57304) (xy 178.306143 -118.57304) (xy 178.254808 -118.56491) (xy 178.205378 -118.548849)
			(xy 178.159068 -118.525253) (xy 178.11702 -118.494703) (xy 178.080269 -118.457952) (xy 178.049719 -118.415904)
			(xy 178.026123 -118.369594) (xy 178.010062 -118.320164) (xy 178.001932 -118.268829) (xy 177.862482 -118.268829)
			(xy 177.854352 -118.320164) (xy 177.838291 -118.369594) (xy 177.814695 -118.415904) (xy 177.784145 -118.457952)
			(xy 177.747394 -118.494703) (xy 177.705346 -118.525253) (xy 177.659036 -118.548849) (xy 177.609606 -118.56491)
			(xy 177.558271 -118.57304) (xy 177.506297 -118.57304) (xy 177.454962 -118.56491) (xy 177.405532 -118.548849)
			(xy 177.359222 -118.525253) (xy 177.317174 -118.494703) (xy 177.280423 -118.457952) (xy 177.249873 -118.415904)
			(xy 177.226277 -118.369594) (xy 177.210216 -118.320164) (xy 177.202086 -118.268829) (xy 177.062382 -118.268829)
			(xy 177.054252 -118.320164) (xy 177.038191 -118.369594) (xy 177.014595 -118.415904) (xy 176.984045 -118.457952)
			(xy 176.947294 -118.494703) (xy 176.905246 -118.525253) (xy 176.858936 -118.548849) (xy 176.809506 -118.56491)
			(xy 176.758171 -118.57304) (xy 176.706197 -118.57304) (xy 176.654862 -118.56491) (xy 176.605432 -118.548849)
			(xy 176.559122 -118.525253) (xy 176.517074 -118.494703) (xy 176.480323 -118.457952) (xy 176.449773 -118.415904)
			(xy 176.426177 -118.369594) (xy 176.410116 -118.320164) (xy 176.401986 -118.268829) (xy 176.156948 -118.268829)
			(xy 176.143386 -118.321649) (xy 176.119854 -118.381082) (xy 176.08906 -118.437097) (xy 176.051487 -118.488812)
			(xy 176.00773 -118.535409) (xy 175.958477 -118.576154) (xy 175.904506 -118.610405) (xy 175.846667 -118.637622)
			(xy 175.785874 -118.657375) (xy 175.723084 -118.669353) (xy 175.659288 -118.673367) (xy 175.595492 -118.669353)
			(xy 175.532702 -118.657375) (xy 175.471909 -118.637622) (xy 175.41407 -118.610405) (xy 175.360099 -118.576154)
			(xy 175.310846 -118.535409) (xy 175.267089 -118.488812) (xy 175.229516 -118.437097) (xy 175.198722 -118.381082)
			(xy 175.17519 -118.321649) (xy 175.159293 -118.259735) (xy 175.151282 -118.196317) (xy 170.539341 -118.196317)
			(xy 170.552879 -118.241314) (xy 170.560999 -118.29649) (xy 170.561508 -118.324376) (xy 170.560999 -118.352262)
			(xy 170.552879 -118.407438) (xy 170.536811 -118.460845) (xy 170.513139 -118.511342) (xy 170.482366 -118.557855)
			(xy 170.445149 -118.599392) (xy 170.402281 -118.635067) (xy 170.354675 -118.664121) (xy 170.303346 -118.685933)
			(xy 170.249389 -118.700039) (xy 170.193952 -118.706139) (xy 170.138218 -118.704102) (xy 170.083375 -118.693972)
			(xy 170.030591 -118.675965) (xy 169.980991 -118.650464) (xy 169.935633 -118.618013) (xy 169.895484 -118.579304)
			(xy 169.861398 -118.535161) (xy 169.834102 -118.486526) (xy 169.814179 -118.434435) (xy 169.802053 -118.379998)
			(xy 169.797982 -118.324376) (xy 168.656334 -118.324376) (xy 168.656508 -118.328948) (xy 168.65604 -118.360446)
			(xy 168.648271 -118.42296) (xy 168.632845 -118.484038) (xy 168.609999 -118.542745) (xy 168.580082 -118.598183)
			(xy 168.54355 -118.649504) (xy 168.500964 -118.695924) (xy 168.452974 -118.736733) (xy 168.426892 -118.754398)
			(xy 168.420295 -118.759787) (xy 168.410826 -118.773934) (xy 168.40835 -118.782084) (xy 168.406826 -118.794022)
			(xy 168.406826 -118.879874) (xy 168.40835 -118.891812) (xy 168.41083 -118.899957) (xy 168.420317 -118.914085)
			(xy 168.426892 -118.919498) (xy 168.452966 -118.937174) (xy 168.500961 -118.977975) (xy 168.543553 -119.024388)
			(xy 168.58009 -119.075704) (xy 168.610013 -119.131138) (xy 168.632864 -119.189841) (xy 168.648294 -119.250916)
			(xy 168.656067 -119.313429) (xy 168.656064 -119.367257) (xy 169.671994 -119.367257) (xy 169.671994 -119.303335)
			(xy 169.680005 -119.239917) (xy 169.695902 -119.178003) (xy 169.719434 -119.11857) (xy 169.750228 -119.062555)
			(xy 169.787801 -119.01084) (xy 169.831558 -118.964243) (xy 169.880811 -118.923498) (xy 169.934782 -118.889247)
			(xy 169.992621 -118.86203) (xy 170.053414 -118.842277) (xy 170.116204 -118.830299) (xy 170.18 -118.826286)
			(xy 170.243796 -118.830299) (xy 170.306586 -118.842277) (xy 170.367379 -118.86203) (xy 170.425218 -118.889247)
			(xy 170.479189 -118.923498) (xy 170.528442 -118.964243) (xy 170.572199 -119.01084) (xy 170.609772 -119.062555)
			(xy 170.613136 -119.068675) (xy 176.401986 -119.068675) (xy 176.401986 -119.016701) (xy 176.410116 -118.965366)
			(xy 176.426177 -118.915936) (xy 176.449773 -118.869626) (xy 176.480323 -118.827578) (xy 176.517074 -118.790827)
			(xy 176.559122 -118.760277) (xy 176.605432 -118.736681) (xy 176.654862 -118.72062) (xy 176.706197 -118.71249)
			(xy 176.758171 -118.71249) (xy 176.809506 -118.72062) (xy 176.858936 -118.736681) (xy 176.905246 -118.760277)
			(xy 176.947294 -118.790827) (xy 176.984045 -118.827578) (xy 177.014595 -118.869626) (xy 177.038191 -118.915936)
			(xy 177.054252 -118.965366) (xy 177.062382 -119.016701) (xy 177.062892 -119.042688) (xy 177.062382 -119.068675)
			(xy 177.202086 -119.068675) (xy 177.202086 -119.016701) (xy 177.210216 -118.965366) (xy 177.226277 -118.915936)
			(xy 177.249873 -118.869626) (xy 177.280423 -118.827578) (xy 177.317174 -118.790827) (xy 177.359222 -118.760277)
			(xy 177.405532 -118.736681) (xy 177.454962 -118.72062) (xy 177.506297 -118.71249) (xy 177.558271 -118.71249)
			(xy 177.609606 -118.72062) (xy 177.659036 -118.736681) (xy 177.705346 -118.760277) (xy 177.747394 -118.790827)
			(xy 177.784145 -118.827578) (xy 177.814695 -118.869626) (xy 177.838291 -118.915936) (xy 177.854352 -118.965366)
			(xy 177.862482 -119.016701) (xy 177.862992 -119.042688) (xy 177.862482 -119.068675) (xy 178.001932 -119.068675)
			(xy 178.001932 -119.016701) (xy 178.010062 -118.965366) (xy 178.026123 -118.915936) (xy 178.049719 -118.869626)
			(xy 178.080269 -118.827578) (xy 178.11702 -118.790827) (xy 178.159068 -118.760277) (xy 178.205378 -118.736681)
			(xy 178.254808 -118.72062) (xy 178.306143 -118.71249) (xy 178.358117 -118.71249) (xy 178.409452 -118.72062)
			(xy 178.458882 -118.736681) (xy 178.505192 -118.760277) (xy 178.54724 -118.790827) (xy 178.583991 -118.827578)
			(xy 178.614541 -118.869626) (xy 178.638137 -118.915936) (xy 178.654198 -118.965366) (xy 178.662328 -119.016701)
			(xy 178.662838 -119.042688) (xy 178.662328 -119.068675) (xy 178.802032 -119.068675) (xy 178.802032 -119.016701)
			(xy 178.810162 -118.965366) (xy 178.826223 -118.915936) (xy 178.849819 -118.869626) (xy 178.880369 -118.827578)
			(xy 178.91712 -118.790827) (xy 178.959168 -118.760277) (xy 179.005478 -118.736681) (xy 179.054908 -118.72062)
			(xy 179.106243 -118.71249) (xy 179.158217 -118.71249) (xy 179.209552 -118.72062) (xy 179.258982 -118.736681)
			(xy 179.305292 -118.760277) (xy 179.34734 -118.790827) (xy 179.384091 -118.827578) (xy 179.414641 -118.869626)
			(xy 179.438237 -118.915936) (xy 179.454298 -118.965366) (xy 179.462428 -119.016701) (xy 179.462938 -119.042688)
			(xy 179.462428 -119.068675) (xy 179.602132 -119.068675) (xy 179.602132 -119.016701) (xy 179.610262 -118.965366)
			(xy 179.626323 -118.915936) (xy 179.649919 -118.869626) (xy 179.680469 -118.827578) (xy 179.71722 -118.790827)
			(xy 179.759268 -118.760277) (xy 179.805578 -118.736681) (xy 179.855008 -118.72062) (xy 179.906343 -118.71249)
			(xy 179.958317 -118.71249) (xy 180.009652 -118.72062) (xy 180.059082 -118.736681) (xy 180.105392 -118.760277)
			(xy 180.14744 -118.790827) (xy 180.184191 -118.827578) (xy 180.214741 -118.869626) (xy 180.238337 -118.915936)
			(xy 180.254398 -118.965366) (xy 180.262528 -119.016701) (xy 180.263038 -119.042688) (xy 180.262528 -119.068675)
			(xy 180.401978 -119.068675) (xy 180.401978 -119.016701) (xy 180.410108 -118.965366) (xy 180.426169 -118.915936)
			(xy 180.449765 -118.869626) (xy 180.480315 -118.827578) (xy 180.517066 -118.790827) (xy 180.559114 -118.760277)
			(xy 180.605424 -118.736681) (xy 180.654854 -118.72062) (xy 180.706189 -118.71249) (xy 180.758163 -118.71249)
			(xy 180.809498 -118.72062) (xy 180.858928 -118.736681) (xy 180.905238 -118.760277) (xy 180.947286 -118.790827)
			(xy 180.984037 -118.827578) (xy 181.014587 -118.869626) (xy 181.038183 -118.915936) (xy 181.054244 -118.965366)
			(xy 181.062374 -119.016701) (xy 181.062884 -119.042688) (xy 181.062374 -119.068675) (xy 181.202078 -119.068675)
			(xy 181.202078 -119.016701) (xy 181.210208 -118.965366) (xy 181.226269 -118.915936) (xy 181.249865 -118.869626)
			(xy 181.280415 -118.827578) (xy 181.317166 -118.790827) (xy 181.359214 -118.760277) (xy 181.405524 -118.736681)
			(xy 181.454954 -118.72062) (xy 181.506289 -118.71249) (xy 181.558263 -118.71249) (xy 181.609598 -118.72062)
			(xy 181.659028 -118.736681) (xy 181.705338 -118.760277) (xy 181.747386 -118.790827) (xy 181.784137 -118.827578)
			(xy 181.814687 -118.869626) (xy 181.838283 -118.915936) (xy 181.854344 -118.965366) (xy 181.862474 -119.016701)
			(xy 181.862984 -119.042688) (xy 181.862474 -119.068675) (xy 182.001924 -119.068675) (xy 182.001924 -119.016701)
			(xy 182.010054 -118.965366) (xy 182.026115 -118.915936) (xy 182.049711 -118.869626) (xy 182.080261 -118.827578)
			(xy 182.117012 -118.790827) (xy 182.15906 -118.760277) (xy 182.20537 -118.736681) (xy 182.2548 -118.72062)
			(xy 182.306135 -118.71249) (xy 182.358109 -118.71249) (xy 182.409444 -118.72062) (xy 182.458874 -118.736681)
			(xy 182.505184 -118.760277) (xy 182.547232 -118.790827) (xy 182.583983 -118.827578) (xy 182.614533 -118.869626)
			(xy 182.638129 -118.915936) (xy 182.65419 -118.965366) (xy 182.66232 -119.016701) (xy 182.66283 -119.042688)
			(xy 182.66232 -119.068675) (xy 182.802024 -119.068675) (xy 182.802024 -119.016701) (xy 182.810154 -118.965366)
			(xy 182.826215 -118.915936) (xy 182.849811 -118.869626) (xy 182.880361 -118.827578) (xy 182.917112 -118.790827)
			(xy 182.95916 -118.760277) (xy 183.00547 -118.736681) (xy 183.0549 -118.72062) (xy 183.106235 -118.71249)
			(xy 183.158209 -118.71249) (xy 183.209544 -118.72062) (xy 183.258974 -118.736681) (xy 183.305284 -118.760277)
			(xy 183.347332 -118.790827) (xy 183.384083 -118.827578) (xy 183.414633 -118.869626) (xy 183.438229 -118.915936)
			(xy 183.45429 -118.965366) (xy 183.46242 -119.016701) (xy 183.46293 -119.042688) (xy 183.46242 -119.068675)
			(xy 183.602124 -119.068675) (xy 183.602124 -119.016701) (xy 183.610254 -118.965366) (xy 183.626315 -118.915936)
			(xy 183.649911 -118.869626) (xy 183.680461 -118.827578) (xy 183.717212 -118.790827) (xy 183.75926 -118.760277)
			(xy 183.80557 -118.736681) (xy 183.855 -118.72062) (xy 183.906335 -118.71249) (xy 183.958309 -118.71249)
			(xy 184.009644 -118.72062) (xy 184.059074 -118.736681) (xy 184.105384 -118.760277) (xy 184.147432 -118.790827)
			(xy 184.184183 -118.827578) (xy 184.214733 -118.869626) (xy 184.238329 -118.915936) (xy 184.25439 -118.965366)
			(xy 184.26252 -119.016701) (xy 184.26303 -119.042688) (xy 184.26252 -119.068675) (xy 184.40197 -119.068675)
			(xy 184.40197 -119.016701) (xy 184.4101 -118.965366) (xy 184.426161 -118.915936) (xy 184.449757 -118.869626)
			(xy 184.480307 -118.827578) (xy 184.517058 -118.790827) (xy 184.559106 -118.760277) (xy 184.605416 -118.736681)
			(xy 184.654846 -118.72062) (xy 184.706181 -118.71249) (xy 184.758155 -118.71249) (xy 184.80949 -118.72062)
			(xy 184.85892 -118.736681) (xy 184.90523 -118.760277) (xy 184.947278 -118.790827) (xy 184.984029 -118.827578)
			(xy 185.014579 -118.869626) (xy 185.038175 -118.915936) (xy 185.054236 -118.965366) (xy 185.062366 -119.016701)
			(xy 185.062876 -119.042688) (xy 185.062366 -119.068675) (xy 185.98185 -119.068675) (xy 185.98185 -119.016701)
			(xy 185.98998 -118.965366) (xy 186.006041 -118.915936) (xy 186.029637 -118.869626) (xy 186.060187 -118.827578)
			(xy 186.096938 -118.790827) (xy 186.138986 -118.760277) (xy 186.185296 -118.736681) (xy 186.234726 -118.72062)
			(xy 186.286061 -118.71249) (xy 186.338035 -118.71249) (xy 186.38937 -118.72062) (xy 186.4388 -118.736681)
			(xy 186.48511 -118.760277) (xy 186.527158 -118.790827) (xy 186.563909 -118.827578) (xy 186.594459 -118.869626)
			(xy 186.618055 -118.915936) (xy 186.634116 -118.965366) (xy 186.642246 -119.016701) (xy 186.642756 -119.042688)
			(xy 186.642246 -119.068675) (xy 186.781696 -119.068675) (xy 186.781696 -119.016701) (xy 186.789826 -118.965366)
			(xy 186.805887 -118.915936) (xy 186.829483 -118.869626) (xy 186.860033 -118.827578) (xy 186.896784 -118.790827)
			(xy 186.938832 -118.760277) (xy 186.985142 -118.736681) (xy 187.034572 -118.72062) (xy 187.085907 -118.71249)
			(xy 187.137881 -118.71249) (xy 187.189216 -118.72062) (xy 187.238646 -118.736681) (xy 187.284956 -118.760277)
			(xy 187.327004 -118.790827) (xy 187.363755 -118.827578) (xy 187.394305 -118.869626) (xy 187.417901 -118.915936)
			(xy 187.433962 -118.965366) (xy 187.442092 -119.016701) (xy 187.442602 -119.042688) (xy 187.442092 -119.068675)
			(xy 187.581796 -119.068675) (xy 187.581796 -119.016701) (xy 187.589926 -118.965366) (xy 187.605987 -118.915936)
			(xy 187.629583 -118.869626) (xy 187.660133 -118.827578) (xy 187.696884 -118.790827) (xy 187.738932 -118.760277)
			(xy 187.785242 -118.736681) (xy 187.834672 -118.72062) (xy 187.886007 -118.71249) (xy 187.937981 -118.71249)
			(xy 187.989316 -118.72062) (xy 188.038746 -118.736681) (xy 188.085056 -118.760277) (xy 188.127104 -118.790827)
			(xy 188.163855 -118.827578) (xy 188.194405 -118.869626) (xy 188.218001 -118.915936) (xy 188.234062 -118.965366)
			(xy 188.242192 -119.016701) (xy 188.242702 -119.042688) (xy 188.242192 -119.068675) (xy 188.381896 -119.068675)
			(xy 188.381896 -119.016701) (xy 188.390026 -118.965366) (xy 188.406087 -118.915936) (xy 188.429683 -118.869626)
			(xy 188.460233 -118.827578) (xy 188.496984 -118.790827) (xy 188.539032 -118.760277) (xy 188.585342 -118.736681)
			(xy 188.634772 -118.72062) (xy 188.686107 -118.71249) (xy 188.738081 -118.71249) (xy 188.789416 -118.72062)
			(xy 188.838846 -118.736681) (xy 188.885156 -118.760277) (xy 188.927204 -118.790827) (xy 188.963955 -118.827578)
			(xy 188.994505 -118.869626) (xy 189.018101 -118.915936) (xy 189.034162 -118.965366) (xy 189.042292 -119.016701)
			(xy 189.042802 -119.042688) (xy 189.042292 -119.068675) (xy 189.181742 -119.068675) (xy 189.181742 -119.016701)
			(xy 189.189872 -118.965366) (xy 189.205933 -118.915936) (xy 189.229529 -118.869626) (xy 189.260079 -118.827578)
			(xy 189.29683 -118.790827) (xy 189.338878 -118.760277) (xy 189.385188 -118.736681) (xy 189.434618 -118.72062)
			(xy 189.485953 -118.71249) (xy 189.537927 -118.71249) (xy 189.589262 -118.72062) (xy 189.638692 -118.736681)
			(xy 189.685002 -118.760277) (xy 189.72705 -118.790827) (xy 189.763801 -118.827578) (xy 189.794351 -118.869626)
			(xy 189.817947 -118.915936) (xy 189.834008 -118.965366) (xy 189.842138 -119.016701) (xy 189.842648 -119.042688)
			(xy 189.842138 -119.068675) (xy 189.981842 -119.068675) (xy 189.981842 -119.016701) (xy 189.989972 -118.965366)
			(xy 190.006033 -118.915936) (xy 190.029629 -118.869626) (xy 190.060179 -118.827578) (xy 190.09693 -118.790827)
			(xy 190.138978 -118.760277) (xy 190.185288 -118.736681) (xy 190.234718 -118.72062) (xy 190.286053 -118.71249)
			(xy 190.338027 -118.71249) (xy 190.389362 -118.72062) (xy 190.438792 -118.736681) (xy 190.485102 -118.760277)
			(xy 190.52715 -118.790827) (xy 190.563901 -118.827578) (xy 190.594451 -118.869626) (xy 190.618047 -118.915936)
			(xy 190.634108 -118.965366) (xy 190.642238 -119.016701) (xy 190.642748 -119.042688) (xy 190.642238 -119.068675)
			(xy 190.781688 -119.068675) (xy 190.781688 -119.016701) (xy 190.789818 -118.965366) (xy 190.805879 -118.915936)
			(xy 190.829475 -118.869626) (xy 190.860025 -118.827578) (xy 190.896776 -118.790827) (xy 190.938824 -118.760277)
			(xy 190.985134 -118.736681) (xy 191.034564 -118.72062) (xy 191.085899 -118.71249) (xy 191.137873 -118.71249)
			(xy 191.189208 -118.72062) (xy 191.238638 -118.736681) (xy 191.284948 -118.760277) (xy 191.326996 -118.790827)
			(xy 191.363747 -118.827578) (xy 191.394297 -118.869626) (xy 191.417893 -118.915936) (xy 191.433954 -118.965366)
			(xy 191.442084 -119.016701) (xy 191.442594 -119.042688) (xy 191.442084 -119.068675) (xy 191.581788 -119.068675)
			(xy 191.581788 -119.016701) (xy 191.589918 -118.965366) (xy 191.605979 -118.915936) (xy 191.629575 -118.869626)
			(xy 191.660125 -118.827578) (xy 191.696876 -118.790827) (xy 191.738924 -118.760277) (xy 191.785234 -118.736681)
			(xy 191.834664 -118.72062) (xy 191.885999 -118.71249) (xy 191.937973 -118.71249) (xy 191.989308 -118.72062)
			(xy 192.038738 -118.736681) (xy 192.085048 -118.760277) (xy 192.127096 -118.790827) (xy 192.163847 -118.827578)
			(xy 192.194397 -118.869626) (xy 192.217993 -118.915936) (xy 192.234054 -118.965366) (xy 192.242184 -119.016701)
			(xy 192.242694 -119.042688) (xy 192.242184 -119.068675) (xy 192.234054 -119.12001) (xy 192.217993 -119.16944)
			(xy 192.194397 -119.21575) (xy 192.163847 -119.257798) (xy 192.127096 -119.294549) (xy 192.085048 -119.325099)
			(xy 192.038738 -119.348695) (xy 191.989308 -119.364756) (xy 191.937973 -119.372886) (xy 191.885999 -119.372886)
			(xy 191.834664 -119.364756) (xy 191.785234 -119.348695) (xy 191.738924 -119.325099) (xy 191.696876 -119.294549)
			(xy 191.660125 -119.257798) (xy 191.629575 -119.21575) (xy 191.605979 -119.16944) (xy 191.589918 -119.12001)
			(xy 191.581788 -119.068675) (xy 191.442084 -119.068675) (xy 191.433954 -119.12001) (xy 191.417893 -119.16944)
			(xy 191.394297 -119.21575) (xy 191.363747 -119.257798) (xy 191.326996 -119.294549) (xy 191.284948 -119.325099)
			(xy 191.238638 -119.348695) (xy 191.189208 -119.364756) (xy 191.137873 -119.372886) (xy 191.085899 -119.372886)
			(xy 191.034564 -119.364756) (xy 190.985134 -119.348695) (xy 190.938824 -119.325099) (xy 190.896776 -119.294549)
			(xy 190.860025 -119.257798) (xy 190.829475 -119.21575) (xy 190.805879 -119.16944) (xy 190.789818 -119.12001)
			(xy 190.781688 -119.068675) (xy 190.642238 -119.068675) (xy 190.634108 -119.12001) (xy 190.618047 -119.16944)
			(xy 190.594451 -119.21575) (xy 190.563901 -119.257798) (xy 190.52715 -119.294549) (xy 190.485102 -119.325099)
			(xy 190.438792 -119.348695) (xy 190.389362 -119.364756) (xy 190.338027 -119.372886) (xy 190.286053 -119.372886)
			(xy 190.234718 -119.364756) (xy 190.185288 -119.348695) (xy 190.138978 -119.325099) (xy 190.09693 -119.294549)
			(xy 190.060179 -119.257798) (xy 190.029629 -119.21575) (xy 190.006033 -119.16944) (xy 189.989972 -119.12001)
			(xy 189.981842 -119.068675) (xy 189.842138 -119.068675) (xy 189.834008 -119.12001) (xy 189.817947 -119.16944)
			(xy 189.794351 -119.21575) (xy 189.763801 -119.257798) (xy 189.72705 -119.294549) (xy 189.685002 -119.325099)
			(xy 189.638692 -119.348695) (xy 189.589262 -119.364756) (xy 189.537927 -119.372886) (xy 189.485953 -119.372886)
			(xy 189.434618 -119.364756) (xy 189.385188 -119.348695) (xy 189.338878 -119.325099) (xy 189.29683 -119.294549)
			(xy 189.260079 -119.257798) (xy 189.229529 -119.21575) (xy 189.205933 -119.16944) (xy 189.189872 -119.12001)
			(xy 189.181742 -119.068675) (xy 189.042292 -119.068675) (xy 189.034162 -119.12001) (xy 189.018101 -119.16944)
			(xy 188.994505 -119.21575) (xy 188.963955 -119.257798) (xy 188.927204 -119.294549) (xy 188.885156 -119.325099)
			(xy 188.838846 -119.348695) (xy 188.789416 -119.364756) (xy 188.738081 -119.372886) (xy 188.686107 -119.372886)
			(xy 188.634772 -119.364756) (xy 188.585342 -119.348695) (xy 188.539032 -119.325099) (xy 188.496984 -119.294549)
			(xy 188.460233 -119.257798) (xy 188.429683 -119.21575) (xy 188.406087 -119.16944) (xy 188.390026 -119.12001)
			(xy 188.381896 -119.068675) (xy 188.242192 -119.068675) (xy 188.234062 -119.12001) (xy 188.218001 -119.16944)
			(xy 188.194405 -119.21575) (xy 188.163855 -119.257798) (xy 188.127104 -119.294549) (xy 188.085056 -119.325099)
			(xy 188.038746 -119.348695) (xy 187.989316 -119.364756) (xy 187.937981 -119.372886) (xy 187.886007 -119.372886)
			(xy 187.834672 -119.364756) (xy 187.785242 -119.348695) (xy 187.738932 -119.325099) (xy 187.696884 -119.294549)
			(xy 187.660133 -119.257798) (xy 187.629583 -119.21575) (xy 187.605987 -119.16944) (xy 187.589926 -119.12001)
			(xy 187.581796 -119.068675) (xy 187.442092 -119.068675) (xy 187.433962 -119.12001) (xy 187.417901 -119.16944)
			(xy 187.394305 -119.21575) (xy 187.363755 -119.257798) (xy 187.327004 -119.294549) (xy 187.284956 -119.325099)
			(xy 187.238646 -119.348695) (xy 187.189216 -119.364756) (xy 187.137881 -119.372886) (xy 187.085907 -119.372886)
			(xy 187.034572 -119.364756) (xy 186.985142 -119.348695) (xy 186.938832 -119.325099) (xy 186.896784 -119.294549)
			(xy 186.860033 -119.257798) (xy 186.829483 -119.21575) (xy 186.805887 -119.16944) (xy 186.789826 -119.12001)
			(xy 186.781696 -119.068675) (xy 186.642246 -119.068675) (xy 186.634116 -119.12001) (xy 186.618055 -119.16944)
			(xy 186.594459 -119.21575) (xy 186.563909 -119.257798) (xy 186.527158 -119.294549) (xy 186.48511 -119.325099)
			(xy 186.4388 -119.348695) (xy 186.38937 -119.364756) (xy 186.338035 -119.372886) (xy 186.286061 -119.372886)
			(xy 186.234726 -119.364756) (xy 186.185296 -119.348695) (xy 186.138986 -119.325099) (xy 186.096938 -119.294549)
			(xy 186.060187 -119.257798) (xy 186.029637 -119.21575) (xy 186.006041 -119.16944) (xy 185.98998 -119.12001)
			(xy 185.98185 -119.068675) (xy 185.062366 -119.068675) (xy 185.054236 -119.12001) (xy 185.038175 -119.16944)
			(xy 185.014579 -119.21575) (xy 184.984029 -119.257798) (xy 184.947278 -119.294549) (xy 184.90523 -119.325099)
			(xy 184.85892 -119.348695) (xy 184.80949 -119.364756) (xy 184.758155 -119.372886) (xy 184.706181 -119.372886)
			(xy 184.654846 -119.364756) (xy 184.605416 -119.348695) (xy 184.559106 -119.325099) (xy 184.517058 -119.294549)
			(xy 184.480307 -119.257798) (xy 184.449757 -119.21575) (xy 184.426161 -119.16944) (xy 184.4101 -119.12001)
			(xy 184.40197 -119.068675) (xy 184.26252 -119.068675) (xy 184.25439 -119.12001) (xy 184.238329 -119.16944)
			(xy 184.214733 -119.21575) (xy 184.184183 -119.257798) (xy 184.147432 -119.294549) (xy 184.105384 -119.325099)
			(xy 184.059074 -119.348695) (xy 184.009644 -119.364756) (xy 183.958309 -119.372886) (xy 183.906335 -119.372886)
			(xy 183.855 -119.364756) (xy 183.80557 -119.348695) (xy 183.75926 -119.325099) (xy 183.717212 -119.294549)
			(xy 183.680461 -119.257798) (xy 183.649911 -119.21575) (xy 183.626315 -119.16944) (xy 183.610254 -119.12001)
			(xy 183.602124 -119.068675) (xy 183.46242 -119.068675) (xy 183.45429 -119.12001) (xy 183.438229 -119.16944)
			(xy 183.414633 -119.21575) (xy 183.384083 -119.257798) (xy 183.347332 -119.294549) (xy 183.305284 -119.325099)
			(xy 183.258974 -119.348695) (xy 183.209544 -119.364756) (xy 183.158209 -119.372886) (xy 183.106235 -119.372886)
			(xy 183.0549 -119.364756) (xy 183.00547 -119.348695) (xy 182.95916 -119.325099) (xy 182.917112 -119.294549)
			(xy 182.880361 -119.257798) (xy 182.849811 -119.21575) (xy 182.826215 -119.16944) (xy 182.810154 -119.12001)
			(xy 182.802024 -119.068675) (xy 182.66232 -119.068675) (xy 182.65419 -119.12001) (xy 182.638129 -119.16944)
			(xy 182.614533 -119.21575) (xy 182.583983 -119.257798) (xy 182.547232 -119.294549) (xy 182.505184 -119.325099)
			(xy 182.458874 -119.348695) (xy 182.409444 -119.364756) (xy 182.358109 -119.372886) (xy 182.306135 -119.372886)
			(xy 182.2548 -119.364756) (xy 182.20537 -119.348695) (xy 182.15906 -119.325099) (xy 182.117012 -119.294549)
			(xy 182.080261 -119.257798) (xy 182.049711 -119.21575) (xy 182.026115 -119.16944) (xy 182.010054 -119.12001)
			(xy 182.001924 -119.068675) (xy 181.862474 -119.068675) (xy 181.854344 -119.12001) (xy 181.838283 -119.16944)
			(xy 181.814687 -119.21575) (xy 181.784137 -119.257798) (xy 181.747386 -119.294549) (xy 181.705338 -119.325099)
			(xy 181.659028 -119.348695) (xy 181.609598 -119.364756) (xy 181.558263 -119.372886) (xy 181.506289 -119.372886)
			(xy 181.454954 -119.364756) (xy 181.405524 -119.348695) (xy 181.359214 -119.325099) (xy 181.317166 -119.294549)
			(xy 181.280415 -119.257798) (xy 181.249865 -119.21575) (xy 181.226269 -119.16944) (xy 181.210208 -119.12001)
			(xy 181.202078 -119.068675) (xy 181.062374 -119.068675) (xy 181.054244 -119.12001) (xy 181.038183 -119.16944)
			(xy 181.014587 -119.21575) (xy 180.984037 -119.257798) (xy 180.947286 -119.294549) (xy 180.905238 -119.325099)
			(xy 180.858928 -119.348695) (xy 180.809498 -119.364756) (xy 180.758163 -119.372886) (xy 180.706189 -119.372886)
			(xy 180.654854 -119.364756) (xy 180.605424 -119.348695) (xy 180.559114 -119.325099) (xy 180.517066 -119.294549)
			(xy 180.480315 -119.257798) (xy 180.449765 -119.21575) (xy 180.426169 -119.16944) (xy 180.410108 -119.12001)
			(xy 180.401978 -119.068675) (xy 180.262528 -119.068675) (xy 180.254398 -119.12001) (xy 180.238337 -119.16944)
			(xy 180.214741 -119.21575) (xy 180.184191 -119.257798) (xy 180.14744 -119.294549) (xy 180.105392 -119.325099)
			(xy 180.059082 -119.348695) (xy 180.009652 -119.364756) (xy 179.958317 -119.372886) (xy 179.906343 -119.372886)
			(xy 179.855008 -119.364756) (xy 179.805578 -119.348695) (xy 179.759268 -119.325099) (xy 179.71722 -119.294549)
			(xy 179.680469 -119.257798) (xy 179.649919 -119.21575) (xy 179.626323 -119.16944) (xy 179.610262 -119.12001)
			(xy 179.602132 -119.068675) (xy 179.462428 -119.068675) (xy 179.454298 -119.12001) (xy 179.438237 -119.16944)
			(xy 179.414641 -119.21575) (xy 179.384091 -119.257798) (xy 179.34734 -119.294549) (xy 179.305292 -119.325099)
			(xy 179.258982 -119.348695) (xy 179.209552 -119.364756) (xy 179.158217 -119.372886) (xy 179.106243 -119.372886)
			(xy 179.054908 -119.364756) (xy 179.005478 -119.348695) (xy 178.959168 -119.325099) (xy 178.91712 -119.294549)
			(xy 178.880369 -119.257798) (xy 178.849819 -119.21575) (xy 178.826223 -119.16944) (xy 178.810162 -119.12001)
			(xy 178.802032 -119.068675) (xy 178.662328 -119.068675) (xy 178.654198 -119.12001) (xy 178.638137 -119.16944)
			(xy 178.614541 -119.21575) (xy 178.583991 -119.257798) (xy 178.54724 -119.294549) (xy 178.505192 -119.325099)
			(xy 178.458882 -119.348695) (xy 178.409452 -119.364756) (xy 178.358117 -119.372886) (xy 178.306143 -119.372886)
			(xy 178.254808 -119.364756) (xy 178.205378 -119.348695) (xy 178.159068 -119.325099) (xy 178.11702 -119.294549)
			(xy 178.080269 -119.257798) (xy 178.049719 -119.21575) (xy 178.026123 -119.16944) (xy 178.010062 -119.12001)
			(xy 178.001932 -119.068675) (xy 177.862482 -119.068675) (xy 177.854352 -119.12001) (xy 177.838291 -119.16944)
			(xy 177.814695 -119.21575) (xy 177.784145 -119.257798) (xy 177.747394 -119.294549) (xy 177.705346 -119.325099)
			(xy 177.659036 -119.348695) (xy 177.609606 -119.364756) (xy 177.558271 -119.372886) (xy 177.506297 -119.372886)
			(xy 177.454962 -119.364756) (xy 177.405532 -119.348695) (xy 177.359222 -119.325099) (xy 177.317174 -119.294549)
			(xy 177.280423 -119.257798) (xy 177.249873 -119.21575) (xy 177.226277 -119.16944) (xy 177.210216 -119.12001)
			(xy 177.202086 -119.068675) (xy 177.062382 -119.068675) (xy 177.054252 -119.12001) (xy 177.038191 -119.16944)
			(xy 177.014595 -119.21575) (xy 176.984045 -119.257798) (xy 176.947294 -119.294549) (xy 176.905246 -119.325099)
			(xy 176.858936 -119.348695) (xy 176.809506 -119.364756) (xy 176.758171 -119.372886) (xy 176.706197 -119.372886)
			(xy 176.654862 -119.364756) (xy 176.605432 -119.348695) (xy 176.559122 -119.325099) (xy 176.517074 -119.294549)
			(xy 176.480323 -119.257798) (xy 176.449773 -119.21575) (xy 176.426177 -119.16944) (xy 176.410116 -119.12001)
			(xy 176.401986 -119.068675) (xy 170.613136 -119.068675) (xy 170.640566 -119.11857) (xy 170.664098 -119.178003)
			(xy 170.679995 -119.239917) (xy 170.688006 -119.303335) (xy 170.688508 -119.335296) (xy 170.688006 -119.367257)
			(xy 170.679995 -119.430675) (xy 170.664098 -119.492589) (xy 170.640566 -119.552022) (xy 170.609772 -119.608037)
			(xy 170.572199 -119.659752) (xy 170.528442 -119.706349) (xy 170.479189 -119.747094) (xy 170.425218 -119.781345)
			(xy 170.367379 -119.808562) (xy 170.306586 -119.828315) (xy 170.243796 -119.840293) (xy 170.18 -119.844307)
			(xy 170.116204 -119.840293) (xy 170.053414 -119.828315) (xy 169.992621 -119.808562) (xy 169.934782 -119.781345)
			(xy 169.880811 -119.747094) (xy 169.831558 -119.706349) (xy 169.787801 -119.659752) (xy 169.750228 -119.608037)
			(xy 169.719434 -119.552022) (xy 169.695902 -119.492589) (xy 169.680005 -119.430675) (xy 169.671994 -119.367257)
			(xy 168.656064 -119.367257) (xy 168.656064 -119.376423) (xy 168.648284 -119.438935) (xy 168.632848 -119.500009)
			(xy 168.609991 -119.55871) (xy 168.580062 -119.61414) (xy 168.54352 -119.665453) (xy 168.500923 -119.711861)
			(xy 168.452923 -119.752657) (xy 168.426892 -119.770398) (xy 168.420295 -119.775787) (xy 168.410826 -119.789934)
			(xy 168.40835 -119.798084) (xy 168.406826 -119.810022) (xy 168.406826 -119.895874) (xy 168.40835 -119.907812)
			(xy 168.411048 -119.916823) (xy 168.422011 -119.932092) (xy 168.429686 -119.93753) (xy 168.42994 -119.93753)
			(xy 168.45229 -119.952874) (xy 168.49391 -119.98762) (xy 168.512998 -120.006872) (xy 168.527873 -120.022536)
			(xy 168.555214 -120.055982) (xy 168.567608 -120.073674) (xy 168.570402 -120.077738) (xy 168.583864 -120.0912)
			(xy 168.589781 -120.094957) (xy 168.603044 -120.099473) (xy 168.610026 -120.10009) (xy 168.669462 -120.099836)
			(xy 168.697402 -120.099582) (xy 168.703634 -120.099377) (xy 168.715716 -120.096303) (xy 168.721278 -120.093486)
			(xy 168.726612 -120.090692) (xy 168.735756 -120.08231) (xy 168.739312 -120.076722) (xy 168.756987 -120.050734)
			(xy 168.79776 -120.002904) (xy 168.844117 -119.960463) (xy 168.895351 -119.924059) (xy 168.95068 -119.894247)
			(xy 169.009262 -119.87148) (xy 169.070204 -119.856107) (xy 169.132575 -119.848361) (xy 169.164 -119.847868)
			(xy 169.195963 -119.84837) (xy 169.259384 -119.856382) (xy 169.3213 -119.872279) (xy 169.345501 -119.881861)
			(xy 174.145442 -119.881861) (xy 174.145442 -119.817939) (xy 174.153453 -119.754521) (xy 174.16935 -119.692607)
			(xy 174.192882 -119.633174) (xy 174.223676 -119.577159) (xy 174.261249 -119.525444) (xy 174.305006 -119.478847)
			(xy 174.354259 -119.438102) (xy 174.40823 -119.403851) (xy 174.466069 -119.376634) (xy 174.526862 -119.356881)
			(xy 174.589652 -119.344903) (xy 174.653448 -119.34089) (xy 174.717244 -119.344903) (xy 174.780034 -119.356881)
			(xy 174.840827 -119.376634) (xy 174.898666 -119.403851) (xy 174.952637 -119.438102) (xy 175.00189 -119.478847)
			(xy 175.045647 -119.525444) (xy 175.08322 -119.577159) (xy 175.114014 -119.633174) (xy 175.137546 -119.692607)
			(xy 175.153443 -119.754521) (xy 175.161454 -119.817939) (xy 175.161956 -119.8499) (xy 175.16166 -119.868775)
			(xy 176.401986 -119.868775) (xy 176.401986 -119.816801) (xy 176.410116 -119.765466) (xy 176.426177 -119.716036)
			(xy 176.449773 -119.669726) (xy 176.480323 -119.627678) (xy 176.517074 -119.590927) (xy 176.559122 -119.560377)
			(xy 176.605432 -119.536781) (xy 176.654862 -119.52072) (xy 176.706197 -119.51259) (xy 176.758171 -119.51259)
			(xy 176.809506 -119.52072) (xy 176.858936 -119.536781) (xy 176.905246 -119.560377) (xy 176.947294 -119.590927)
			(xy 176.984045 -119.627678) (xy 177.014595 -119.669726) (xy 177.038191 -119.716036) (xy 177.054252 -119.765466)
			(xy 177.062382 -119.816801) (xy 177.062892 -119.842788) (xy 177.062382 -119.868775) (xy 177.202086 -119.868775)
			(xy 177.202086 -119.816801) (xy 177.210216 -119.765466) (xy 177.226277 -119.716036) (xy 177.249873 -119.669726)
			(xy 177.280423 -119.627678) (xy 177.317174 -119.590927) (xy 177.359222 -119.560377) (xy 177.405532 -119.536781)
			(xy 177.454962 -119.52072) (xy 177.506297 -119.51259) (xy 177.558271 -119.51259) (xy 177.609606 -119.52072)
			(xy 177.659036 -119.536781) (xy 177.705346 -119.560377) (xy 177.747394 -119.590927) (xy 177.784145 -119.627678)
			(xy 177.814695 -119.669726) (xy 177.838291 -119.716036) (xy 177.854352 -119.765466) (xy 177.862482 -119.816801)
			(xy 177.862992 -119.842788) (xy 177.862482 -119.868775) (xy 178.001932 -119.868775) (xy 178.001932 -119.816801)
			(xy 178.010062 -119.765466) (xy 178.026123 -119.716036) (xy 178.049719 -119.669726) (xy 178.080269 -119.627678)
			(xy 178.11702 -119.590927) (xy 178.159068 -119.560377) (xy 178.205378 -119.536781) (xy 178.254808 -119.52072)
			(xy 178.306143 -119.51259) (xy 178.358117 -119.51259) (xy 178.409452 -119.52072) (xy 178.458882 -119.536781)
			(xy 178.505192 -119.560377) (xy 178.54724 -119.590927) (xy 178.583991 -119.627678) (xy 178.614541 -119.669726)
			(xy 178.638137 -119.716036) (xy 178.654198 -119.765466) (xy 178.662328 -119.816801) (xy 178.662838 -119.842788)
			(xy 178.662328 -119.868775) (xy 178.802032 -119.868775) (xy 178.802032 -119.816801) (xy 178.810162 -119.765466)
			(xy 178.826223 -119.716036) (xy 178.849819 -119.669726) (xy 178.880369 -119.627678) (xy 178.91712 -119.590927)
			(xy 178.959168 -119.560377) (xy 179.005478 -119.536781) (xy 179.054908 -119.52072) (xy 179.106243 -119.51259)
			(xy 179.158217 -119.51259) (xy 179.209552 -119.52072) (xy 179.258982 -119.536781) (xy 179.305292 -119.560377)
			(xy 179.34734 -119.590927) (xy 179.384091 -119.627678) (xy 179.414641 -119.669726) (xy 179.438237 -119.716036)
			(xy 179.454298 -119.765466) (xy 179.462428 -119.816801) (xy 179.462938 -119.842788) (xy 179.462428 -119.868775)
			(xy 179.602132 -119.868775) (xy 179.602132 -119.816801) (xy 179.610262 -119.765466) (xy 179.626323 -119.716036)
			(xy 179.649919 -119.669726) (xy 179.680469 -119.627678) (xy 179.71722 -119.590927) (xy 179.759268 -119.560377)
			(xy 179.805578 -119.536781) (xy 179.855008 -119.52072) (xy 179.906343 -119.51259) (xy 179.958317 -119.51259)
			(xy 180.009652 -119.52072) (xy 180.059082 -119.536781) (xy 180.105392 -119.560377) (xy 180.14744 -119.590927)
			(xy 180.184191 -119.627678) (xy 180.214741 -119.669726) (xy 180.238337 -119.716036) (xy 180.254398 -119.765466)
			(xy 180.262528 -119.816801) (xy 180.263038 -119.842788) (xy 180.262528 -119.868775) (xy 180.401978 -119.868775)
			(xy 180.401978 -119.816801) (xy 180.410108 -119.765466) (xy 180.426169 -119.716036) (xy 180.449765 -119.669726)
			(xy 180.480315 -119.627678) (xy 180.517066 -119.590927) (xy 180.559114 -119.560377) (xy 180.605424 -119.536781)
			(xy 180.654854 -119.52072) (xy 180.706189 -119.51259) (xy 180.758163 -119.51259) (xy 180.809498 -119.52072)
			(xy 180.858928 -119.536781) (xy 180.905238 -119.560377) (xy 180.947286 -119.590927) (xy 180.984037 -119.627678)
			(xy 181.014587 -119.669726) (xy 181.038183 -119.716036) (xy 181.054244 -119.765466) (xy 181.062374 -119.816801)
			(xy 181.062884 -119.842788) (xy 181.062374 -119.868775) (xy 181.202078 -119.868775) (xy 181.202078 -119.816801)
			(xy 181.210208 -119.765466) (xy 181.226269 -119.716036) (xy 181.249865 -119.669726) (xy 181.280415 -119.627678)
			(xy 181.317166 -119.590927) (xy 181.359214 -119.560377) (xy 181.405524 -119.536781) (xy 181.454954 -119.52072)
			(xy 181.506289 -119.51259) (xy 181.558263 -119.51259) (xy 181.609598 -119.52072) (xy 181.659028 -119.536781)
			(xy 181.705338 -119.560377) (xy 181.747386 -119.590927) (xy 181.784137 -119.627678) (xy 181.814687 -119.669726)
			(xy 181.838283 -119.716036) (xy 181.854344 -119.765466) (xy 181.862474 -119.816801) (xy 181.862984 -119.842788)
			(xy 181.862474 -119.868775) (xy 182.001924 -119.868775) (xy 182.001924 -119.816801) (xy 182.010054 -119.765466)
			(xy 182.026115 -119.716036) (xy 182.049711 -119.669726) (xy 182.080261 -119.627678) (xy 182.117012 -119.590927)
			(xy 182.15906 -119.560377) (xy 182.20537 -119.536781) (xy 182.2548 -119.52072) (xy 182.306135 -119.51259)
			(xy 182.358109 -119.51259) (xy 182.409444 -119.52072) (xy 182.458874 -119.536781) (xy 182.505184 -119.560377)
			(xy 182.547232 -119.590927) (xy 182.583983 -119.627678) (xy 182.614533 -119.669726) (xy 182.638129 -119.716036)
			(xy 182.65419 -119.765466) (xy 182.66232 -119.816801) (xy 182.66283 -119.842788) (xy 182.66232 -119.868775)
			(xy 182.802024 -119.868775) (xy 182.802024 -119.816801) (xy 182.810154 -119.765466) (xy 182.826215 -119.716036)
			(xy 182.849811 -119.669726) (xy 182.880361 -119.627678) (xy 182.917112 -119.590927) (xy 182.95916 -119.560377)
			(xy 183.00547 -119.536781) (xy 183.0549 -119.52072) (xy 183.106235 -119.51259) (xy 183.158209 -119.51259)
			(xy 183.209544 -119.52072) (xy 183.258974 -119.536781) (xy 183.305284 -119.560377) (xy 183.347332 -119.590927)
			(xy 183.384083 -119.627678) (xy 183.414633 -119.669726) (xy 183.438229 -119.716036) (xy 183.45429 -119.765466)
			(xy 183.46242 -119.816801) (xy 183.46293 -119.842788) (xy 183.46242 -119.868775) (xy 183.602124 -119.868775)
			(xy 183.602124 -119.816801) (xy 183.610254 -119.765466) (xy 183.626315 -119.716036) (xy 183.649911 -119.669726)
			(xy 183.680461 -119.627678) (xy 183.717212 -119.590927) (xy 183.75926 -119.560377) (xy 183.80557 -119.536781)
			(xy 183.855 -119.52072) (xy 183.906335 -119.51259) (xy 183.958309 -119.51259) (xy 184.009644 -119.52072)
			(xy 184.059074 -119.536781) (xy 184.105384 -119.560377) (xy 184.147432 -119.590927) (xy 184.184183 -119.627678)
			(xy 184.214733 -119.669726) (xy 184.238329 -119.716036) (xy 184.25439 -119.765466) (xy 184.26252 -119.816801)
			(xy 184.26303 -119.842788) (xy 184.26252 -119.868775) (xy 184.40197 -119.868775) (xy 184.40197 -119.816801)
			(xy 184.4101 -119.765466) (xy 184.426161 -119.716036) (xy 184.449757 -119.669726) (xy 184.480307 -119.627678)
			(xy 184.517058 -119.590927) (xy 184.559106 -119.560377) (xy 184.605416 -119.536781) (xy 184.654846 -119.52072)
			(xy 184.706181 -119.51259) (xy 184.758155 -119.51259) (xy 184.80949 -119.52072) (xy 184.85892 -119.536781)
			(xy 184.90523 -119.560377) (xy 184.947278 -119.590927) (xy 184.984029 -119.627678) (xy 185.014579 -119.669726)
			(xy 185.038175 -119.716036) (xy 185.054236 -119.765466) (xy 185.062366 -119.816801) (xy 185.062876 -119.842788)
			(xy 185.062366 -119.868775) (xy 185.98185 -119.868775) (xy 185.98185 -119.816801) (xy 185.98998 -119.765466)
			(xy 186.006041 -119.716036) (xy 186.029637 -119.669726) (xy 186.060187 -119.627678) (xy 186.096938 -119.590927)
			(xy 186.138986 -119.560377) (xy 186.185296 -119.536781) (xy 186.234726 -119.52072) (xy 186.286061 -119.51259)
			(xy 186.338035 -119.51259) (xy 186.38937 -119.52072) (xy 186.4388 -119.536781) (xy 186.48511 -119.560377)
			(xy 186.527158 -119.590927) (xy 186.563909 -119.627678) (xy 186.594459 -119.669726) (xy 186.618055 -119.716036)
			(xy 186.634116 -119.765466) (xy 186.642246 -119.816801) (xy 186.642756 -119.842788) (xy 186.642246 -119.868775)
			(xy 186.781696 -119.868775) (xy 186.781696 -119.816801) (xy 186.789826 -119.765466) (xy 186.805887 -119.716036)
			(xy 186.829483 -119.669726) (xy 186.860033 -119.627678) (xy 186.896784 -119.590927) (xy 186.938832 -119.560377)
			(xy 186.985142 -119.536781) (xy 187.034572 -119.52072) (xy 187.085907 -119.51259) (xy 187.137881 -119.51259)
			(xy 187.189216 -119.52072) (xy 187.238646 -119.536781) (xy 187.284956 -119.560377) (xy 187.327004 -119.590927)
			(xy 187.363755 -119.627678) (xy 187.394305 -119.669726) (xy 187.417901 -119.716036) (xy 187.433962 -119.765466)
			(xy 187.442092 -119.816801) (xy 187.442602 -119.842788) (xy 187.442092 -119.868775) (xy 187.581796 -119.868775)
			(xy 187.581796 -119.816801) (xy 187.589926 -119.765466) (xy 187.605987 -119.716036) (xy 187.629583 -119.669726)
			(xy 187.660133 -119.627678) (xy 187.696884 -119.590927) (xy 187.738932 -119.560377) (xy 187.785242 -119.536781)
			(xy 187.834672 -119.52072) (xy 187.886007 -119.51259) (xy 187.937981 -119.51259) (xy 187.989316 -119.52072)
			(xy 188.038746 -119.536781) (xy 188.085056 -119.560377) (xy 188.127104 -119.590927) (xy 188.163855 -119.627678)
			(xy 188.194405 -119.669726) (xy 188.218001 -119.716036) (xy 188.234062 -119.765466) (xy 188.242192 -119.816801)
			(xy 188.242702 -119.842788) (xy 188.242192 -119.868775) (xy 188.381896 -119.868775) (xy 188.381896 -119.816801)
			(xy 188.390026 -119.765466) (xy 188.406087 -119.716036) (xy 188.429683 -119.669726) (xy 188.460233 -119.627678)
			(xy 188.496984 -119.590927) (xy 188.539032 -119.560377) (xy 188.585342 -119.536781) (xy 188.634772 -119.52072)
			(xy 188.686107 -119.51259) (xy 188.738081 -119.51259) (xy 188.789416 -119.52072) (xy 188.838846 -119.536781)
			(xy 188.885156 -119.560377) (xy 188.927204 -119.590927) (xy 188.963955 -119.627678) (xy 188.994505 -119.669726)
			(xy 189.018101 -119.716036) (xy 189.034162 -119.765466) (xy 189.042292 -119.816801) (xy 189.042802 -119.842788)
			(xy 189.042292 -119.868775) (xy 189.181742 -119.868775) (xy 189.181742 -119.816801) (xy 189.189872 -119.765466)
			(xy 189.205933 -119.716036) (xy 189.229529 -119.669726) (xy 189.260079 -119.627678) (xy 189.29683 -119.590927)
			(xy 189.338878 -119.560377) (xy 189.385188 -119.536781) (xy 189.434618 -119.52072) (xy 189.485953 -119.51259)
			(xy 189.537927 -119.51259) (xy 189.589262 -119.52072) (xy 189.638692 -119.536781) (xy 189.685002 -119.560377)
			(xy 189.72705 -119.590927) (xy 189.763801 -119.627678) (xy 189.794351 -119.669726) (xy 189.817947 -119.716036)
			(xy 189.834008 -119.765466) (xy 189.842138 -119.816801) (xy 189.842648 -119.842788) (xy 189.842138 -119.868775)
			(xy 189.981842 -119.868775) (xy 189.981842 -119.816801) (xy 189.989972 -119.765466) (xy 190.006033 -119.716036)
			(xy 190.029629 -119.669726) (xy 190.060179 -119.627678) (xy 190.09693 -119.590927) (xy 190.138978 -119.560377)
			(xy 190.185288 -119.536781) (xy 190.234718 -119.52072) (xy 190.286053 -119.51259) (xy 190.338027 -119.51259)
			(xy 190.389362 -119.52072) (xy 190.438792 -119.536781) (xy 190.485102 -119.560377) (xy 190.52715 -119.590927)
			(xy 190.563901 -119.627678) (xy 190.594451 -119.669726) (xy 190.618047 -119.716036) (xy 190.634108 -119.765466)
			(xy 190.642238 -119.816801) (xy 190.642748 -119.842788) (xy 190.642238 -119.868775) (xy 190.781688 -119.868775)
			(xy 190.781688 -119.816801) (xy 190.789818 -119.765466) (xy 190.805879 -119.716036) (xy 190.829475 -119.669726)
			(xy 190.860025 -119.627678) (xy 190.896776 -119.590927) (xy 190.938824 -119.560377) (xy 190.985134 -119.536781)
			(xy 191.034564 -119.52072) (xy 191.085899 -119.51259) (xy 191.137873 -119.51259) (xy 191.189208 -119.52072)
			(xy 191.238638 -119.536781) (xy 191.284948 -119.560377) (xy 191.326996 -119.590927) (xy 191.363747 -119.627678)
			(xy 191.394297 -119.669726) (xy 191.417893 -119.716036) (xy 191.433954 -119.765466) (xy 191.442084 -119.816801)
			(xy 191.442594 -119.842788) (xy 191.442084 -119.868775) (xy 191.581788 -119.868775) (xy 191.581788 -119.816801)
			(xy 191.589918 -119.765466) (xy 191.605979 -119.716036) (xy 191.629575 -119.669726) (xy 191.660125 -119.627678)
			(xy 191.696876 -119.590927) (xy 191.738924 -119.560377) (xy 191.785234 -119.536781) (xy 191.834664 -119.52072)
			(xy 191.885999 -119.51259) (xy 191.937973 -119.51259) (xy 191.989308 -119.52072) (xy 192.038738 -119.536781)
			(xy 192.085048 -119.560377) (xy 192.127096 -119.590927) (xy 192.163847 -119.627678) (xy 192.194397 -119.669726)
			(xy 192.217993 -119.716036) (xy 192.234054 -119.765466) (xy 192.242184 -119.816801) (xy 192.242694 -119.842788)
			(xy 192.242184 -119.868775) (xy 192.234054 -119.92011) (xy 192.217993 -119.96954) (xy 192.194397 -120.01585)
			(xy 192.163847 -120.057898) (xy 192.127096 -120.094649) (xy 192.085048 -120.125199) (xy 192.038738 -120.148795)
			(xy 191.989308 -120.164856) (xy 191.937973 -120.172986) (xy 191.885999 -120.172986) (xy 191.834664 -120.164856)
			(xy 191.785234 -120.148795) (xy 191.738924 -120.125199) (xy 191.696876 -120.094649) (xy 191.660125 -120.057898)
			(xy 191.629575 -120.01585) (xy 191.605979 -119.96954) (xy 191.589918 -119.92011) (xy 191.581788 -119.868775)
			(xy 191.442084 -119.868775) (xy 191.433954 -119.92011) (xy 191.417893 -119.96954) (xy 191.394297 -120.01585)
			(xy 191.363747 -120.057898) (xy 191.326996 -120.094649) (xy 191.284948 -120.125199) (xy 191.238638 -120.148795)
			(xy 191.189208 -120.164856) (xy 191.137873 -120.172986) (xy 191.085899 -120.172986) (xy 191.034564 -120.164856)
			(xy 190.985134 -120.148795) (xy 190.938824 -120.125199) (xy 190.896776 -120.094649) (xy 190.860025 -120.057898)
			(xy 190.829475 -120.01585) (xy 190.805879 -119.96954) (xy 190.789818 -119.92011) (xy 190.781688 -119.868775)
			(xy 190.642238 -119.868775) (xy 190.634108 -119.92011) (xy 190.618047 -119.96954) (xy 190.594451 -120.01585)
			(xy 190.563901 -120.057898) (xy 190.52715 -120.094649) (xy 190.485102 -120.125199) (xy 190.438792 -120.148795)
			(xy 190.389362 -120.164856) (xy 190.338027 -120.172986) (xy 190.286053 -120.172986) (xy 190.234718 -120.164856)
			(xy 190.185288 -120.148795) (xy 190.138978 -120.125199) (xy 190.09693 -120.094649) (xy 190.060179 -120.057898)
			(xy 190.029629 -120.01585) (xy 190.006033 -119.96954) (xy 189.989972 -119.92011) (xy 189.981842 -119.868775)
			(xy 189.842138 -119.868775) (xy 189.834008 -119.92011) (xy 189.817947 -119.96954) (xy 189.794351 -120.01585)
			(xy 189.763801 -120.057898) (xy 189.72705 -120.094649) (xy 189.685002 -120.125199) (xy 189.638692 -120.148795)
			(xy 189.589262 -120.164856) (xy 189.537927 -120.172986) (xy 189.485953 -120.172986) (xy 189.434618 -120.164856)
			(xy 189.385188 -120.148795) (xy 189.338878 -120.125199) (xy 189.29683 -120.094649) (xy 189.260079 -120.057898)
			(xy 189.229529 -120.01585) (xy 189.205933 -119.96954) (xy 189.189872 -119.92011) (xy 189.181742 -119.868775)
			(xy 189.042292 -119.868775) (xy 189.034162 -119.92011) (xy 189.018101 -119.96954) (xy 188.994505 -120.01585)
			(xy 188.963955 -120.057898) (xy 188.927204 -120.094649) (xy 188.885156 -120.125199) (xy 188.838846 -120.148795)
			(xy 188.789416 -120.164856) (xy 188.738081 -120.172986) (xy 188.686107 -120.172986) (xy 188.634772 -120.164856)
			(xy 188.585342 -120.148795) (xy 188.539032 -120.125199) (xy 188.496984 -120.094649) (xy 188.460233 -120.057898)
			(xy 188.429683 -120.01585) (xy 188.406087 -119.96954) (xy 188.390026 -119.92011) (xy 188.381896 -119.868775)
			(xy 188.242192 -119.868775) (xy 188.234062 -119.92011) (xy 188.218001 -119.96954) (xy 188.194405 -120.01585)
			(xy 188.163855 -120.057898) (xy 188.127104 -120.094649) (xy 188.085056 -120.125199) (xy 188.038746 -120.148795)
			(xy 187.989316 -120.164856) (xy 187.937981 -120.172986) (xy 187.886007 -120.172986) (xy 187.834672 -120.164856)
			(xy 187.785242 -120.148795) (xy 187.738932 -120.125199) (xy 187.696884 -120.094649) (xy 187.660133 -120.057898)
			(xy 187.629583 -120.01585) (xy 187.605987 -119.96954) (xy 187.589926 -119.92011) (xy 187.581796 -119.868775)
			(xy 187.442092 -119.868775) (xy 187.433962 -119.92011) (xy 187.417901 -119.96954) (xy 187.394305 -120.01585)
			(xy 187.363755 -120.057898) (xy 187.327004 -120.094649) (xy 187.284956 -120.125199) (xy 187.238646 -120.148795)
			(xy 187.189216 -120.164856) (xy 187.137881 -120.172986) (xy 187.085907 -120.172986) (xy 187.034572 -120.164856)
			(xy 186.985142 -120.148795) (xy 186.938832 -120.125199) (xy 186.896784 -120.094649) (xy 186.860033 -120.057898)
			(xy 186.829483 -120.01585) (xy 186.805887 -119.96954) (xy 186.789826 -119.92011) (xy 186.781696 -119.868775)
			(xy 186.642246 -119.868775) (xy 186.634116 -119.92011) (xy 186.618055 -119.96954) (xy 186.594459 -120.01585)
			(xy 186.563909 -120.057898) (xy 186.527158 -120.094649) (xy 186.48511 -120.125199) (xy 186.4388 -120.148795)
			(xy 186.38937 -120.164856) (xy 186.338035 -120.172986) (xy 186.286061 -120.172986) (xy 186.234726 -120.164856)
			(xy 186.185296 -120.148795) (xy 186.138986 -120.125199) (xy 186.096938 -120.094649) (xy 186.060187 -120.057898)
			(xy 186.029637 -120.01585) (xy 186.006041 -119.96954) (xy 185.98998 -119.92011) (xy 185.98185 -119.868775)
			(xy 185.062366 -119.868775) (xy 185.054236 -119.92011) (xy 185.038175 -119.96954) (xy 185.014579 -120.01585)
			(xy 184.984029 -120.057898) (xy 184.947278 -120.094649) (xy 184.90523 -120.125199) (xy 184.85892 -120.148795)
			(xy 184.80949 -120.164856) (xy 184.758155 -120.172986) (xy 184.706181 -120.172986) (xy 184.654846 -120.164856)
			(xy 184.605416 -120.148795) (xy 184.559106 -120.125199) (xy 184.517058 -120.094649) (xy 184.480307 -120.057898)
			(xy 184.449757 -120.01585) (xy 184.426161 -119.96954) (xy 184.4101 -119.92011) (xy 184.40197 -119.868775)
			(xy 184.26252 -119.868775) (xy 184.25439 -119.92011) (xy 184.238329 -119.96954) (xy 184.214733 -120.01585)
			(xy 184.184183 -120.057898) (xy 184.147432 -120.094649) (xy 184.105384 -120.125199) (xy 184.059074 -120.148795)
			(xy 184.009644 -120.164856) (xy 183.958309 -120.172986) (xy 183.906335 -120.172986) (xy 183.855 -120.164856)
			(xy 183.80557 -120.148795) (xy 183.75926 -120.125199) (xy 183.717212 -120.094649) (xy 183.680461 -120.057898)
			(xy 183.649911 -120.01585) (xy 183.626315 -119.96954) (xy 183.610254 -119.92011) (xy 183.602124 -119.868775)
			(xy 183.46242 -119.868775) (xy 183.45429 -119.92011) (xy 183.438229 -119.96954) (xy 183.414633 -120.01585)
			(xy 183.384083 -120.057898) (xy 183.347332 -120.094649) (xy 183.305284 -120.125199) (xy 183.258974 -120.148795)
			(xy 183.209544 -120.164856) (xy 183.158209 -120.172986) (xy 183.106235 -120.172986) (xy 183.0549 -120.164856)
			(xy 183.00547 -120.148795) (xy 182.95916 -120.125199) (xy 182.917112 -120.094649) (xy 182.880361 -120.057898)
			(xy 182.849811 -120.01585) (xy 182.826215 -119.96954) (xy 182.810154 -119.92011) (xy 182.802024 -119.868775)
			(xy 182.66232 -119.868775) (xy 182.65419 -119.92011) (xy 182.638129 -119.96954) (xy 182.614533 -120.01585)
			(xy 182.583983 -120.057898) (xy 182.547232 -120.094649) (xy 182.505184 -120.125199) (xy 182.458874 -120.148795)
			(xy 182.409444 -120.164856) (xy 182.358109 -120.172986) (xy 182.306135 -120.172986) (xy 182.2548 -120.164856)
			(xy 182.20537 -120.148795) (xy 182.15906 -120.125199) (xy 182.117012 -120.094649) (xy 182.080261 -120.057898)
			(xy 182.049711 -120.01585) (xy 182.026115 -119.96954) (xy 182.010054 -119.92011) (xy 182.001924 -119.868775)
			(xy 181.862474 -119.868775) (xy 181.854344 -119.92011) (xy 181.838283 -119.96954) (xy 181.814687 -120.01585)
			(xy 181.784137 -120.057898) (xy 181.747386 -120.094649) (xy 181.705338 -120.125199) (xy 181.659028 -120.148795)
			(xy 181.609598 -120.164856) (xy 181.558263 -120.172986) (xy 181.506289 -120.172986) (xy 181.454954 -120.164856)
			(xy 181.405524 -120.148795) (xy 181.359214 -120.125199) (xy 181.317166 -120.094649) (xy 181.280415 -120.057898)
			(xy 181.249865 -120.01585) (xy 181.226269 -119.96954) (xy 181.210208 -119.92011) (xy 181.202078 -119.868775)
			(xy 181.062374 -119.868775) (xy 181.054244 -119.92011) (xy 181.038183 -119.96954) (xy 181.014587 -120.01585)
			(xy 180.984037 -120.057898) (xy 180.947286 -120.094649) (xy 180.905238 -120.125199) (xy 180.858928 -120.148795)
			(xy 180.809498 -120.164856) (xy 180.758163 -120.172986) (xy 180.706189 -120.172986) (xy 180.654854 -120.164856)
			(xy 180.605424 -120.148795) (xy 180.559114 -120.125199) (xy 180.517066 -120.094649) (xy 180.480315 -120.057898)
			(xy 180.449765 -120.01585) (xy 180.426169 -119.96954) (xy 180.410108 -119.92011) (xy 180.401978 -119.868775)
			(xy 180.262528 -119.868775) (xy 180.254398 -119.92011) (xy 180.238337 -119.96954) (xy 180.214741 -120.01585)
			(xy 180.184191 -120.057898) (xy 180.14744 -120.094649) (xy 180.105392 -120.125199) (xy 180.059082 -120.148795)
			(xy 180.009652 -120.164856) (xy 179.958317 -120.172986) (xy 179.906343 -120.172986) (xy 179.855008 -120.164856)
			(xy 179.805578 -120.148795) (xy 179.759268 -120.125199) (xy 179.71722 -120.094649) (xy 179.680469 -120.057898)
			(xy 179.649919 -120.01585) (xy 179.626323 -119.96954) (xy 179.610262 -119.92011) (xy 179.602132 -119.868775)
			(xy 179.462428 -119.868775) (xy 179.454298 -119.92011) (xy 179.438237 -119.96954) (xy 179.414641 -120.01585)
			(xy 179.384091 -120.057898) (xy 179.34734 -120.094649) (xy 179.305292 -120.125199) (xy 179.258982 -120.148795)
			(xy 179.209552 -120.164856) (xy 179.158217 -120.172986) (xy 179.106243 -120.172986) (xy 179.054908 -120.164856)
			(xy 179.005478 -120.148795) (xy 178.959168 -120.125199) (xy 178.91712 -120.094649) (xy 178.880369 -120.057898)
			(xy 178.849819 -120.01585) (xy 178.826223 -119.96954) (xy 178.810162 -119.92011) (xy 178.802032 -119.868775)
			(xy 178.662328 -119.868775) (xy 178.654198 -119.92011) (xy 178.638137 -119.96954) (xy 178.614541 -120.01585)
			(xy 178.583991 -120.057898) (xy 178.54724 -120.094649) (xy 178.505192 -120.125199) (xy 178.458882 -120.148795)
			(xy 178.409452 -120.164856) (xy 178.358117 -120.172986) (xy 178.306143 -120.172986) (xy 178.254808 -120.164856)
			(xy 178.205378 -120.148795) (xy 178.159068 -120.125199) (xy 178.11702 -120.094649) (xy 178.080269 -120.057898)
			(xy 178.049719 -120.01585) (xy 178.026123 -119.96954) (xy 178.010062 -119.92011) (xy 178.001932 -119.868775)
			(xy 177.862482 -119.868775) (xy 177.854352 -119.92011) (xy 177.838291 -119.96954) (xy 177.814695 -120.01585)
			(xy 177.784145 -120.057898) (xy 177.747394 -120.094649) (xy 177.705346 -120.125199) (xy 177.659036 -120.148795)
			(xy 177.609606 -120.164856) (xy 177.558271 -120.172986) (xy 177.506297 -120.172986) (xy 177.454962 -120.164856)
			(xy 177.405532 -120.148795) (xy 177.359222 -120.125199) (xy 177.317174 -120.094649) (xy 177.280423 -120.057898)
			(xy 177.249873 -120.01585) (xy 177.226277 -119.96954) (xy 177.210216 -119.92011) (xy 177.202086 -119.868775)
			(xy 177.062382 -119.868775) (xy 177.054252 -119.92011) (xy 177.038191 -119.96954) (xy 177.014595 -120.01585)
			(xy 176.984045 -120.057898) (xy 176.947294 -120.094649) (xy 176.905246 -120.125199) (xy 176.858936 -120.148795)
			(xy 176.809506 -120.164856) (xy 176.758171 -120.172986) (xy 176.706197 -120.172986) (xy 176.654862 -120.164856)
			(xy 176.605432 -120.148795) (xy 176.559122 -120.125199) (xy 176.517074 -120.094649) (xy 176.480323 -120.057898)
			(xy 176.449773 -120.01585) (xy 176.426177 -119.96954) (xy 176.410116 -119.92011) (xy 176.401986 -119.868775)
			(xy 175.16166 -119.868775) (xy 175.161454 -119.881861) (xy 175.153443 -119.945279) (xy 175.137546 -120.007193)
			(xy 175.114014 -120.066626) (xy 175.08322 -120.122641) (xy 175.045647 -120.174356) (xy 175.00189 -120.220953)
			(xy 174.952637 -120.261698) (xy 174.898666 -120.295949) (xy 174.840827 -120.323166) (xy 174.780034 -120.342919)
			(xy 174.717244 -120.354897) (xy 174.653448 -120.358911) (xy 174.589652 -120.354897) (xy 174.526862 -120.342919)
			(xy 174.466069 -120.323166) (xy 174.40823 -120.295949) (xy 174.354259 -120.261698) (xy 174.305006 -120.220953)
			(xy 174.261249 -120.174356) (xy 174.223676 -120.122641) (xy 174.192882 -120.066626) (xy 174.16935 -120.007193)
			(xy 174.153453 -119.945279) (xy 174.145442 -119.881861) (xy 169.345501 -119.881861) (xy 169.380736 -119.895812)
			(xy 169.436754 -119.926608) (xy 169.488471 -119.964182) (xy 169.53507 -120.007942) (xy 169.575818 -120.057197)
			(xy 169.61007 -120.111171) (xy 169.637288 -120.169012) (xy 169.657042 -120.229808) (xy 169.669021 -120.292601)
			(xy 169.673035 -120.3564) (xy 169.669021 -120.420199) (xy 169.657042 -120.482992) (xy 169.637288 -120.543788)
			(xy 169.61007 -120.601629) (xy 169.575818 -120.655603) (xy 169.565048 -120.668621) (xy 178.001932 -120.668621)
			(xy 178.001932 -120.616647) (xy 178.010062 -120.565312) (xy 178.026123 -120.515882) (xy 178.049719 -120.469572)
			(xy 178.080269 -120.427524) (xy 178.11702 -120.390773) (xy 178.159068 -120.360223) (xy 178.205378 -120.336627)
			(xy 178.254808 -120.320566) (xy 178.306143 -120.312436) (xy 178.358117 -120.312436) (xy 178.409452 -120.320566)
			(xy 178.458882 -120.336627) (xy 178.505192 -120.360223) (xy 178.54724 -120.390773) (xy 178.583991 -120.427524)
			(xy 178.614541 -120.469572) (xy 178.638137 -120.515882) (xy 178.654198 -120.565312) (xy 178.662328 -120.616647)
			(xy 178.662838 -120.642634) (xy 178.662328 -120.668621) (xy 178.802032 -120.668621) (xy 178.802032 -120.616647)
			(xy 178.810162 -120.565312) (xy 178.826223 -120.515882) (xy 178.849819 -120.469572) (xy 178.880369 -120.427524)
			(xy 178.91712 -120.390773) (xy 178.959168 -120.360223) (xy 179.005478 -120.336627) (xy 179.054908 -120.320566)
			(xy 179.106243 -120.312436) (xy 179.158217 -120.312436) (xy 179.209552 -120.320566) (xy 179.258982 -120.336627)
			(xy 179.305292 -120.360223) (xy 179.34734 -120.390773) (xy 179.384091 -120.427524) (xy 179.414641 -120.469572)
			(xy 179.438237 -120.515882) (xy 179.454298 -120.565312) (xy 179.462428 -120.616647) (xy 179.462938 -120.642634)
			(xy 179.462428 -120.668621) (xy 179.602132 -120.668621) (xy 179.602132 -120.616647) (xy 179.610262 -120.565312)
			(xy 179.626323 -120.515882) (xy 179.649919 -120.469572) (xy 179.680469 -120.427524) (xy 179.71722 -120.390773)
			(xy 179.759268 -120.360223) (xy 179.805578 -120.336627) (xy 179.855008 -120.320566) (xy 179.906343 -120.312436)
			(xy 179.958317 -120.312436) (xy 180.009652 -120.320566) (xy 180.059082 -120.336627) (xy 180.105392 -120.360223)
			(xy 180.14744 -120.390773) (xy 180.184191 -120.427524) (xy 180.214741 -120.469572) (xy 180.238337 -120.515882)
			(xy 180.254398 -120.565312) (xy 180.262528 -120.616647) (xy 180.263038 -120.642634) (xy 180.262528 -120.668621)
			(xy 180.401978 -120.668621) (xy 180.401978 -120.616647) (xy 180.410108 -120.565312) (xy 180.426169 -120.515882)
			(xy 180.449765 -120.469572) (xy 180.480315 -120.427524) (xy 180.517066 -120.390773) (xy 180.559114 -120.360223)
			(xy 180.605424 -120.336627) (xy 180.654854 -120.320566) (xy 180.706189 -120.312436) (xy 180.758163 -120.312436)
			(xy 180.809498 -120.320566) (xy 180.858928 -120.336627) (xy 180.905238 -120.360223) (xy 180.947286 -120.390773)
			(xy 180.984037 -120.427524) (xy 181.014587 -120.469572) (xy 181.038183 -120.515882) (xy 181.054244 -120.565312)
			(xy 181.062374 -120.616647) (xy 181.062884 -120.642634) (xy 181.062374 -120.668621) (xy 181.202078 -120.668621)
			(xy 181.202078 -120.616647) (xy 181.210208 -120.565312) (xy 181.226269 -120.515882) (xy 181.249865 -120.469572)
			(xy 181.280415 -120.427524) (xy 181.317166 -120.390773) (xy 181.359214 -120.360223) (xy 181.405524 -120.336627)
			(xy 181.454954 -120.320566) (xy 181.506289 -120.312436) (xy 181.558263 -120.312436) (xy 181.609598 -120.320566)
			(xy 181.659028 -120.336627) (xy 181.705338 -120.360223) (xy 181.747386 -120.390773) (xy 181.784137 -120.427524)
			(xy 181.814687 -120.469572) (xy 181.838283 -120.515882) (xy 181.854344 -120.565312) (xy 181.862474 -120.616647)
			(xy 181.862984 -120.642634) (xy 181.862474 -120.668621) (xy 182.001924 -120.668621) (xy 182.001924 -120.616647)
			(xy 182.010054 -120.565312) (xy 182.026115 -120.515882) (xy 182.049711 -120.469572) (xy 182.080261 -120.427524)
			(xy 182.117012 -120.390773) (xy 182.15906 -120.360223) (xy 182.20537 -120.336627) (xy 182.2548 -120.320566)
			(xy 182.306135 -120.312436) (xy 182.358109 -120.312436) (xy 182.409444 -120.320566) (xy 182.458874 -120.336627)
			(xy 182.505184 -120.360223) (xy 182.547232 -120.390773) (xy 182.583983 -120.427524) (xy 182.614533 -120.469572)
			(xy 182.638129 -120.515882) (xy 182.65419 -120.565312) (xy 182.66232 -120.616647) (xy 182.66283 -120.642634)
			(xy 182.66232 -120.668621) (xy 182.802024 -120.668621) (xy 182.802024 -120.616647) (xy 182.810154 -120.565312)
			(xy 182.826215 -120.515882) (xy 182.849811 -120.469572) (xy 182.880361 -120.427524) (xy 182.917112 -120.390773)
			(xy 182.95916 -120.360223) (xy 183.00547 -120.336627) (xy 183.0549 -120.320566) (xy 183.106235 -120.312436)
			(xy 183.158209 -120.312436) (xy 183.209544 -120.320566) (xy 183.258974 -120.336627) (xy 183.305284 -120.360223)
			(xy 183.347332 -120.390773) (xy 183.384083 -120.427524) (xy 183.414633 -120.469572) (xy 183.438229 -120.515882)
			(xy 183.45429 -120.565312) (xy 183.46242 -120.616647) (xy 183.46293 -120.642634) (xy 183.46242 -120.668621)
			(xy 183.602124 -120.668621) (xy 183.602124 -120.616647) (xy 183.610254 -120.565312) (xy 183.626315 -120.515882)
			(xy 183.649911 -120.469572) (xy 183.680461 -120.427524) (xy 183.717212 -120.390773) (xy 183.75926 -120.360223)
			(xy 183.80557 -120.336627) (xy 183.855 -120.320566) (xy 183.906335 -120.312436) (xy 183.958309 -120.312436)
			(xy 184.009644 -120.320566) (xy 184.059074 -120.336627) (xy 184.105384 -120.360223) (xy 184.147432 -120.390773)
			(xy 184.184183 -120.427524) (xy 184.214733 -120.469572) (xy 184.238329 -120.515882) (xy 184.25439 -120.565312)
			(xy 184.26252 -120.616647) (xy 184.26303 -120.642634) (xy 184.26252 -120.668621) (xy 184.40197 -120.668621)
			(xy 184.40197 -120.616647) (xy 184.4101 -120.565312) (xy 184.426161 -120.515882) (xy 184.449757 -120.469572)
			(xy 184.480307 -120.427524) (xy 184.517058 -120.390773) (xy 184.559106 -120.360223) (xy 184.605416 -120.336627)
			(xy 184.654846 -120.320566) (xy 184.706181 -120.312436) (xy 184.758155 -120.312436) (xy 184.80949 -120.320566)
			(xy 184.85892 -120.336627) (xy 184.90523 -120.360223) (xy 184.947278 -120.390773) (xy 184.984029 -120.427524)
			(xy 185.014579 -120.469572) (xy 185.038175 -120.515882) (xy 185.054236 -120.565312) (xy 185.062366 -120.616647)
			(xy 185.062876 -120.642634) (xy 185.062366 -120.668621) (xy 186.781696 -120.668621) (xy 186.781696 -120.616647)
			(xy 186.789826 -120.565312) (xy 186.805887 -120.515882) (xy 186.829483 -120.469572) (xy 186.860033 -120.427524)
			(xy 186.896784 -120.390773) (xy 186.938832 -120.360223) (xy 186.985142 -120.336627) (xy 187.034572 -120.320566)
			(xy 187.085907 -120.312436) (xy 187.137881 -120.312436) (xy 187.189216 -120.320566) (xy 187.238646 -120.336627)
			(xy 187.284956 -120.360223) (xy 187.327004 -120.390773) (xy 187.363755 -120.427524) (xy 187.394305 -120.469572)
			(xy 187.417901 -120.515882) (xy 187.433962 -120.565312) (xy 187.442092 -120.616647) (xy 187.442602 -120.642634)
			(xy 187.442092 -120.668621) (xy 187.581796 -120.668621) (xy 187.581796 -120.616647) (xy 187.589926 -120.565312)
			(xy 187.605987 -120.515882) (xy 187.629583 -120.469572) (xy 187.660133 -120.427524) (xy 187.696884 -120.390773)
			(xy 187.738932 -120.360223) (xy 187.785242 -120.336627) (xy 187.834672 -120.320566) (xy 187.886007 -120.312436)
			(xy 187.937981 -120.312436) (xy 187.989316 -120.320566) (xy 188.038746 -120.336627) (xy 188.085056 -120.360223)
			(xy 188.127104 -120.390773) (xy 188.163855 -120.427524) (xy 188.194405 -120.469572) (xy 188.218001 -120.515882)
			(xy 188.234062 -120.565312) (xy 188.242192 -120.616647) (xy 188.242702 -120.642634) (xy 188.242192 -120.668621)
			(xy 188.381896 -120.668621) (xy 188.381896 -120.616647) (xy 188.390026 -120.565312) (xy 188.406087 -120.515882)
			(xy 188.429683 -120.469572) (xy 188.460233 -120.427524) (xy 188.496984 -120.390773) (xy 188.539032 -120.360223)
			(xy 188.585342 -120.336627) (xy 188.634772 -120.320566) (xy 188.686107 -120.312436) (xy 188.738081 -120.312436)
			(xy 188.789416 -120.320566) (xy 188.838846 -120.336627) (xy 188.885156 -120.360223) (xy 188.927204 -120.390773)
			(xy 188.963955 -120.427524) (xy 188.994505 -120.469572) (xy 189.018101 -120.515882) (xy 189.034162 -120.565312)
			(xy 189.042292 -120.616647) (xy 189.042802 -120.642634) (xy 189.042292 -120.668621) (xy 189.181742 -120.668621)
			(xy 189.181742 -120.616647) (xy 189.189872 -120.565312) (xy 189.205933 -120.515882) (xy 189.229529 -120.469572)
			(xy 189.260079 -120.427524) (xy 189.29683 -120.390773) (xy 189.338878 -120.360223) (xy 189.385188 -120.336627)
			(xy 189.434618 -120.320566) (xy 189.485953 -120.312436) (xy 189.537927 -120.312436) (xy 189.589262 -120.320566)
			(xy 189.638692 -120.336627) (xy 189.685002 -120.360223) (xy 189.72705 -120.390773) (xy 189.763801 -120.427524)
			(xy 189.794351 -120.469572) (xy 189.817947 -120.515882) (xy 189.834008 -120.565312) (xy 189.842138 -120.616647)
			(xy 189.842648 -120.642634) (xy 189.842138 -120.668621) (xy 189.981842 -120.668621) (xy 189.981842 -120.616647)
			(xy 189.989972 -120.565312) (xy 190.006033 -120.515882) (xy 190.029629 -120.469572) (xy 190.060179 -120.427524)
			(xy 190.09693 -120.390773) (xy 190.138978 -120.360223) (xy 190.185288 -120.336627) (xy 190.234718 -120.320566)
			(xy 190.286053 -120.312436) (xy 190.338027 -120.312436) (xy 190.389362 -120.320566) (xy 190.438792 -120.336627)
			(xy 190.485102 -120.360223) (xy 190.52715 -120.390773) (xy 190.563901 -120.427524) (xy 190.594451 -120.469572)
			(xy 190.618047 -120.515882) (xy 190.634108 -120.565312) (xy 190.642238 -120.616647) (xy 190.642748 -120.642634)
			(xy 190.642238 -120.668621) (xy 190.781688 -120.668621) (xy 190.781688 -120.616647) (xy 190.789818 -120.565312)
			(xy 190.805879 -120.515882) (xy 190.829475 -120.469572) (xy 190.860025 -120.427524) (xy 190.896776 -120.390773)
			(xy 190.938824 -120.360223) (xy 190.985134 -120.336627) (xy 191.034564 -120.320566) (xy 191.085899 -120.312436)
			(xy 191.137873 -120.312436) (xy 191.189208 -120.320566) (xy 191.238638 -120.336627) (xy 191.284948 -120.360223)
			(xy 191.326996 -120.390773) (xy 191.363747 -120.427524) (xy 191.394297 -120.469572) (xy 191.417893 -120.515882)
			(xy 191.433954 -120.565312) (xy 191.442084 -120.616647) (xy 191.442594 -120.642634) (xy 191.442084 -120.668621)
			(xy 191.581788 -120.668621) (xy 191.581788 -120.616647) (xy 191.589918 -120.565312) (xy 191.605979 -120.515882)
			(xy 191.629575 -120.469572) (xy 191.660125 -120.427524) (xy 191.696876 -120.390773) (xy 191.738924 -120.360223)
			(xy 191.785234 -120.336627) (xy 191.834664 -120.320566) (xy 191.885999 -120.312436) (xy 191.937973 -120.312436)
			(xy 191.989308 -120.320566) (xy 192.038738 -120.336627) (xy 192.085048 -120.360223) (xy 192.127096 -120.390773)
			(xy 192.163847 -120.427524) (xy 192.194397 -120.469572) (xy 192.217993 -120.515882) (xy 192.234054 -120.565312)
			(xy 192.242184 -120.616647) (xy 192.242694 -120.642634) (xy 192.242184 -120.668621) (xy 192.381888 -120.668621)
			(xy 192.381888 -120.616647) (xy 192.390018 -120.565312) (xy 192.406079 -120.515882) (xy 192.429675 -120.469572)
			(xy 192.460225 -120.427524) (xy 192.496976 -120.390773) (xy 192.539024 -120.360223) (xy 192.585334 -120.336627)
			(xy 192.634764 -120.320566) (xy 192.686099 -120.312436) (xy 192.738073 -120.312436) (xy 192.789408 -120.320566)
			(xy 192.838838 -120.336627) (xy 192.885148 -120.360223) (xy 192.927196 -120.390773) (xy 192.963947 -120.427524)
			(xy 192.994497 -120.469572) (xy 193.018093 -120.515882) (xy 193.034154 -120.565312) (xy 193.042284 -120.616647)
			(xy 193.042794 -120.642634) (xy 193.042284 -120.668621) (xy 193.034154 -120.719956) (xy 193.018093 -120.769386)
			(xy 192.994497 -120.815696) (xy 192.963947 -120.857744) (xy 192.927196 -120.894495) (xy 192.885148 -120.925045)
			(xy 192.838838 -120.948641) (xy 192.789408 -120.964702) (xy 192.738073 -120.972832) (xy 192.686099 -120.972832)
			(xy 192.634764 -120.964702) (xy 192.585334 -120.948641) (xy 192.539024 -120.925045) (xy 192.496976 -120.894495)
			(xy 192.460225 -120.857744) (xy 192.429675 -120.815696) (xy 192.406079 -120.769386) (xy 192.390018 -120.719956)
			(xy 192.381888 -120.668621) (xy 192.242184 -120.668621) (xy 192.234054 -120.719956) (xy 192.217993 -120.769386)
			(xy 192.194397 -120.815696) (xy 192.163847 -120.857744) (xy 192.127096 -120.894495) (xy 192.085048 -120.925045)
			(xy 192.038738 -120.948641) (xy 191.989308 -120.964702) (xy 191.937973 -120.972832) (xy 191.885999 -120.972832)
			(xy 191.834664 -120.964702) (xy 191.785234 -120.948641) (xy 191.738924 -120.925045) (xy 191.696876 -120.894495)
			(xy 191.660125 -120.857744) (xy 191.629575 -120.815696) (xy 191.605979 -120.769386) (xy 191.589918 -120.719956)
			(xy 191.581788 -120.668621) (xy 191.442084 -120.668621) (xy 191.433954 -120.719956) (xy 191.417893 -120.769386)
			(xy 191.394297 -120.815696) (xy 191.363747 -120.857744) (xy 191.326996 -120.894495) (xy 191.284948 -120.925045)
			(xy 191.238638 -120.948641) (xy 191.189208 -120.964702) (xy 191.137873 -120.972832) (xy 191.085899 -120.972832)
			(xy 191.034564 -120.964702) (xy 190.985134 -120.948641) (xy 190.938824 -120.925045) (xy 190.896776 -120.894495)
			(xy 190.860025 -120.857744) (xy 190.829475 -120.815696) (xy 190.805879 -120.769386) (xy 190.789818 -120.719956)
			(xy 190.781688 -120.668621) (xy 190.642238 -120.668621) (xy 190.634108 -120.719956) (xy 190.618047 -120.769386)
			(xy 190.594451 -120.815696) (xy 190.563901 -120.857744) (xy 190.52715 -120.894495) (xy 190.485102 -120.925045)
			(xy 190.438792 -120.948641) (xy 190.389362 -120.964702) (xy 190.338027 -120.972832) (xy 190.286053 -120.972832)
			(xy 190.234718 -120.964702) (xy 190.185288 -120.948641) (xy 190.138978 -120.925045) (xy 190.09693 -120.894495)
			(xy 190.060179 -120.857744) (xy 190.029629 -120.815696) (xy 190.006033 -120.769386) (xy 189.989972 -120.719956)
			(xy 189.981842 -120.668621) (xy 189.842138 -120.668621) (xy 189.834008 -120.719956) (xy 189.817947 -120.769386)
			(xy 189.794351 -120.815696) (xy 189.763801 -120.857744) (xy 189.72705 -120.894495) (xy 189.685002 -120.925045)
			(xy 189.638692 -120.948641) (xy 189.589262 -120.964702) (xy 189.537927 -120.972832) (xy 189.485953 -120.972832)
			(xy 189.434618 -120.964702) (xy 189.385188 -120.948641) (xy 189.338878 -120.925045) (xy 189.29683 -120.894495)
			(xy 189.260079 -120.857744) (xy 189.229529 -120.815696) (xy 189.205933 -120.769386) (xy 189.189872 -120.719956)
			(xy 189.181742 -120.668621) (xy 189.042292 -120.668621) (xy 189.034162 -120.719956) (xy 189.018101 -120.769386)
			(xy 188.994505 -120.815696) (xy 188.963955 -120.857744) (xy 188.927204 -120.894495) (xy 188.885156 -120.925045)
			(xy 188.838846 -120.948641) (xy 188.789416 -120.964702) (xy 188.738081 -120.972832) (xy 188.686107 -120.972832)
			(xy 188.634772 -120.964702) (xy 188.585342 -120.948641) (xy 188.539032 -120.925045) (xy 188.496984 -120.894495)
			(xy 188.460233 -120.857744) (xy 188.429683 -120.815696) (xy 188.406087 -120.769386) (xy 188.390026 -120.719956)
			(xy 188.381896 -120.668621) (xy 188.242192 -120.668621) (xy 188.234062 -120.719956) (xy 188.218001 -120.769386)
			(xy 188.194405 -120.815696) (xy 188.163855 -120.857744) (xy 188.127104 -120.894495) (xy 188.085056 -120.925045)
			(xy 188.038746 -120.948641) (xy 187.989316 -120.964702) (xy 187.937981 -120.972832) (xy 187.886007 -120.972832)
			(xy 187.834672 -120.964702) (xy 187.785242 -120.948641) (xy 187.738932 -120.925045) (xy 187.696884 -120.894495)
			(xy 187.660133 -120.857744) (xy 187.629583 -120.815696) (xy 187.605987 -120.769386) (xy 187.589926 -120.719956)
			(xy 187.581796 -120.668621) (xy 187.442092 -120.668621) (xy 187.433962 -120.719956) (xy 187.417901 -120.769386)
			(xy 187.394305 -120.815696) (xy 187.363755 -120.857744) (xy 187.327004 -120.894495) (xy 187.284956 -120.925045)
			(xy 187.238646 -120.948641) (xy 187.189216 -120.964702) (xy 187.137881 -120.972832) (xy 187.085907 -120.972832)
			(xy 187.034572 -120.964702) (xy 186.985142 -120.948641) (xy 186.938832 -120.925045) (xy 186.896784 -120.894495)
			(xy 186.860033 -120.857744) (xy 186.829483 -120.815696) (xy 186.805887 -120.769386) (xy 186.789826 -120.719956)
			(xy 186.781696 -120.668621) (xy 185.062366 -120.668621) (xy 185.054236 -120.719956) (xy 185.038175 -120.769386)
			(xy 185.014579 -120.815696) (xy 184.984029 -120.857744) (xy 184.947278 -120.894495) (xy 184.90523 -120.925045)
			(xy 184.85892 -120.948641) (xy 184.80949 -120.964702) (xy 184.758155 -120.972832) (xy 184.706181 -120.972832)
			(xy 184.654846 -120.964702) (xy 184.605416 -120.948641) (xy 184.559106 -120.925045) (xy 184.517058 -120.894495)
			(xy 184.480307 -120.857744) (xy 184.449757 -120.815696) (xy 184.426161 -120.769386) (xy 184.4101 -120.719956)
			(xy 184.40197 -120.668621) (xy 184.26252 -120.668621) (xy 184.25439 -120.719956) (xy 184.238329 -120.769386)
			(xy 184.214733 -120.815696) (xy 184.184183 -120.857744) (xy 184.147432 -120.894495) (xy 184.105384 -120.925045)
			(xy 184.059074 -120.948641) (xy 184.009644 -120.964702) (xy 183.958309 -120.972832) (xy 183.906335 -120.972832)
			(xy 183.855 -120.964702) (xy 183.80557 -120.948641) (xy 183.75926 -120.925045) (xy 183.717212 -120.894495)
			(xy 183.680461 -120.857744) (xy 183.649911 -120.815696) (xy 183.626315 -120.769386) (xy 183.610254 -120.719956)
			(xy 183.602124 -120.668621) (xy 183.46242 -120.668621) (xy 183.45429 -120.719956) (xy 183.438229 -120.769386)
			(xy 183.414633 -120.815696) (xy 183.384083 -120.857744) (xy 183.347332 -120.894495) (xy 183.305284 -120.925045)
			(xy 183.258974 -120.948641) (xy 183.209544 -120.964702) (xy 183.158209 -120.972832) (xy 183.106235 -120.972832)
			(xy 183.0549 -120.964702) (xy 183.00547 -120.948641) (xy 182.95916 -120.925045) (xy 182.917112 -120.894495)
			(xy 182.880361 -120.857744) (xy 182.849811 -120.815696) (xy 182.826215 -120.769386) (xy 182.810154 -120.719956)
			(xy 182.802024 -120.668621) (xy 182.66232 -120.668621) (xy 182.65419 -120.719956) (xy 182.638129 -120.769386)
			(xy 182.614533 -120.815696) (xy 182.583983 -120.857744) (xy 182.547232 -120.894495) (xy 182.505184 -120.925045)
			(xy 182.458874 -120.948641) (xy 182.409444 -120.964702) (xy 182.358109 -120.972832) (xy 182.306135 -120.972832)
			(xy 182.2548 -120.964702) (xy 182.20537 -120.948641) (xy 182.15906 -120.925045) (xy 182.117012 -120.894495)
			(xy 182.080261 -120.857744) (xy 182.049711 -120.815696) (xy 182.026115 -120.769386) (xy 182.010054 -120.719956)
			(xy 182.001924 -120.668621) (xy 181.862474 -120.668621) (xy 181.854344 -120.719956) (xy 181.838283 -120.769386)
			(xy 181.814687 -120.815696) (xy 181.784137 -120.857744) (xy 181.747386 -120.894495) (xy 181.705338 -120.925045)
			(xy 181.659028 -120.948641) (xy 181.609598 -120.964702) (xy 181.558263 -120.972832) (xy 181.506289 -120.972832)
			(xy 181.454954 -120.964702) (xy 181.405524 -120.948641) (xy 181.359214 -120.925045) (xy 181.317166 -120.894495)
			(xy 181.280415 -120.857744) (xy 181.249865 -120.815696) (xy 181.226269 -120.769386) (xy 181.210208 -120.719956)
			(xy 181.202078 -120.668621) (xy 181.062374 -120.668621) (xy 181.054244 -120.719956) (xy 181.038183 -120.769386)
			(xy 181.014587 -120.815696) (xy 180.984037 -120.857744) (xy 180.947286 -120.894495) (xy 180.905238 -120.925045)
			(xy 180.858928 -120.948641) (xy 180.809498 -120.964702) (xy 180.758163 -120.972832) (xy 180.706189 -120.972832)
			(xy 180.654854 -120.964702) (xy 180.605424 -120.948641) (xy 180.559114 -120.925045) (xy 180.517066 -120.894495)
			(xy 180.480315 -120.857744) (xy 180.449765 -120.815696) (xy 180.426169 -120.769386) (xy 180.410108 -120.719956)
			(xy 180.401978 -120.668621) (xy 180.262528 -120.668621) (xy 180.254398 -120.719956) (xy 180.238337 -120.769386)
			(xy 180.214741 -120.815696) (xy 180.184191 -120.857744) (xy 180.14744 -120.894495) (xy 180.105392 -120.925045)
			(xy 180.059082 -120.948641) (xy 180.009652 -120.964702) (xy 179.958317 -120.972832) (xy 179.906343 -120.972832)
			(xy 179.855008 -120.964702) (xy 179.805578 -120.948641) (xy 179.759268 -120.925045) (xy 179.71722 -120.894495)
			(xy 179.680469 -120.857744) (xy 179.649919 -120.815696) (xy 179.626323 -120.769386) (xy 179.610262 -120.719956)
			(xy 179.602132 -120.668621) (xy 179.462428 -120.668621) (xy 179.454298 -120.719956) (xy 179.438237 -120.769386)
			(xy 179.414641 -120.815696) (xy 179.384091 -120.857744) (xy 179.34734 -120.894495) (xy 179.305292 -120.925045)
			(xy 179.258982 -120.948641) (xy 179.209552 -120.964702) (xy 179.158217 -120.972832) (xy 179.106243 -120.972832)
			(xy 179.054908 -120.964702) (xy 179.005478 -120.948641) (xy 178.959168 -120.925045) (xy 178.91712 -120.894495)
			(xy 178.880369 -120.857744) (xy 178.849819 -120.815696) (xy 178.826223 -120.769386) (xy 178.810162 -120.719956)
			(xy 178.802032 -120.668621) (xy 178.662328 -120.668621) (xy 178.654198 -120.719956) (xy 178.638137 -120.769386)
			(xy 178.614541 -120.815696) (xy 178.583991 -120.857744) (xy 178.54724 -120.894495) (xy 178.505192 -120.925045)
			(xy 178.458882 -120.948641) (xy 178.409452 -120.964702) (xy 178.358117 -120.972832) (xy 178.306143 -120.972832)
			(xy 178.254808 -120.964702) (xy 178.205378 -120.948641) (xy 178.159068 -120.925045) (xy 178.11702 -120.894495)
			(xy 178.080269 -120.857744) (xy 178.049719 -120.815696) (xy 178.026123 -120.769386) (xy 178.010062 -120.719956)
			(xy 178.001932 -120.668621) (xy 169.565048 -120.668621) (xy 169.53507 -120.704858) (xy 169.488471 -120.748618)
			(xy 169.436754 -120.786192) (xy 169.380736 -120.816988) (xy 169.3213 -120.840521) (xy 169.259384 -120.856418)
			(xy 169.195963 -120.86443) (xy 169.164 -120.864884) (xy 169.133146 -120.864431) (xy 169.071891 -120.856965)
			(xy 169.01199 -120.842142) (xy 168.954322 -120.82018) (xy 168.899735 -120.791401) (xy 168.849031 -120.75623)
			(xy 168.802956 -120.715182) (xy 168.762185 -120.66886) (xy 168.744392 -120.64365) (xy 168.741598 -120.639586)
			(xy 168.728136 -120.626124) (xy 168.722217 -120.622371) (xy 168.708954 -120.617862) (xy 168.701974 -120.617234)
			(xy 168.642538 -120.617488) (xy 168.614598 -120.617742) (xy 168.608366 -120.617948) (xy 168.596285 -120.621023)
			(xy 168.590722 -120.623838) (xy 168.585388 -120.626632) (xy 168.576244 -120.635014) (xy 168.572688 -120.640602)
			(xy 168.555064 -120.666485) (xy 168.51446 -120.714155) (xy 168.468311 -120.756481) (xy 168.417315 -120.792821)
			(xy 168.362244 -120.822626) (xy 168.30393 -120.845445) (xy 168.243257 -120.860933) (xy 168.212262 -120.865392)
			(xy 168.203118 -120.866662) (xy 168.195498 -120.870726) (xy 168.191611 -120.872834) (xy 168.184584 -120.878199)
			(xy 168.181528 -120.881394) (xy 168.159684 -120.90527) (xy 168.1571 -120.908515) (xy 168.152888 -120.915661)
			(xy 168.151302 -120.919494) (xy 168.149739 -120.923902) (xy 168.148073 -120.933105) (xy 168.148 -120.937782)
			(xy 168.148 -121.408909) (xy 169.671994 -121.408909) (xy 169.671994 -121.344987) (xy 169.680005 -121.281569)
			(xy 169.695902 -121.219655) (xy 169.719434 -121.160222) (xy 169.750228 -121.104207) (xy 169.787801 -121.052492)
			(xy 169.831558 -121.005895) (xy 169.880811 -120.96515) (xy 169.934782 -120.930899) (xy 169.992621 -120.903682)
			(xy 170.053414 -120.883929) (xy 170.116204 -120.871951) (xy 170.18 -120.867938) (xy 170.243796 -120.871951)
			(xy 170.306586 -120.883929) (xy 170.367379 -120.903682) (xy 170.425218 -120.930899) (xy 170.479189 -120.96515)
			(xy 170.528442 -121.005895) (xy 170.572199 -121.052492) (xy 170.609772 -121.104207) (xy 170.640566 -121.160222)
			(xy 170.664098 -121.219655) (xy 170.679995 -121.281569) (xy 170.688006 -121.344987) (xy 170.688508 -121.376948)
			(xy 170.688006 -121.408909) (xy 171.703994 -121.408909) (xy 171.703994 -121.344987) (xy 171.712005 -121.281569)
			(xy 171.727902 -121.219655) (xy 171.751434 -121.160222) (xy 171.782228 -121.104207) (xy 171.819801 -121.052492)
			(xy 171.863558 -121.005895) (xy 171.912811 -120.96515) (xy 171.966782 -120.930899) (xy 172.024621 -120.903682)
			(xy 172.085414 -120.883929) (xy 172.148204 -120.871951) (xy 172.212 -120.867938) (xy 172.275796 -120.871951)
			(xy 172.338586 -120.883929) (xy 172.399379 -120.903682) (xy 172.457218 -120.930899) (xy 172.511189 -120.96515)
			(xy 172.560442 -121.005895) (xy 172.604199 -121.052492) (xy 172.641772 -121.104207) (xy 172.672566 -121.160222)
			(xy 172.696098 -121.219655) (xy 172.711995 -121.281569) (xy 172.720006 -121.344987) (xy 172.720508 -121.376948)
			(xy 172.720006 -121.408909) (xy 172.711995 -121.472327) (xy 172.696098 -121.534241) (xy 172.672566 -121.593674)
			(xy 172.641772 -121.649689) (xy 172.604199 -121.701404) (xy 172.560442 -121.748001) (xy 172.511189 -121.788746)
			(xy 172.457218 -121.822997) (xy 172.399379 -121.850214) (xy 172.338586 -121.869967) (xy 172.275796 -121.881945)
			(xy 172.212 -121.885959) (xy 172.148204 -121.881945) (xy 172.085414 -121.869967) (xy 172.024621 -121.850214)
			(xy 171.966782 -121.822997) (xy 171.912811 -121.788746) (xy 171.863558 -121.748001) (xy 171.819801 -121.701404)
			(xy 171.782228 -121.649689) (xy 171.751434 -121.593674) (xy 171.727902 -121.534241) (xy 171.712005 -121.472327)
			(xy 171.703994 -121.408909) (xy 170.688006 -121.408909) (xy 170.679995 -121.472327) (xy 170.664098 -121.534241)
			(xy 170.640566 -121.593674) (xy 170.609772 -121.649689) (xy 170.572199 -121.701404) (xy 170.528442 -121.748001)
			(xy 170.479189 -121.788746) (xy 170.425218 -121.822997) (xy 170.367379 -121.850214) (xy 170.306586 -121.869967)
			(xy 170.243796 -121.881945) (xy 170.18 -121.885959) (xy 170.116204 -121.881945) (xy 170.053414 -121.869967)
			(xy 169.992621 -121.850214) (xy 169.934782 -121.822997) (xy 169.880811 -121.788746) (xy 169.831558 -121.748001)
			(xy 169.787801 -121.701404) (xy 169.750228 -121.649689) (xy 169.719434 -121.593674) (xy 169.695902 -121.534241)
			(xy 169.680005 -121.472327) (xy 169.671994 -121.408909) (xy 168.148 -121.408909) (xy 168.148 -122.406918)
			(xy 168.148762 -122.4153) (xy 168.150275 -122.422906) (xy 168.157258 -122.436743) (xy 168.162478 -122.442478)
			(xy 168.249092 -122.529092) (xy 168.256021 -122.535507) (xy 168.273219 -122.543262) (xy 168.292056 -122.544293)
			(xy 168.301162 -122.541792) (xy 168.304464 -122.540268) (xy 168.334925 -122.528335) (xy 168.398151 -122.511524)
			(xy 168.463016 -122.502997) (xy 168.495726 -122.502422) (xy 168.505124 -122.502422) (xy 168.536964 -122.50343)
			(xy 168.600034 -122.512401) (xy 168.661491 -122.529173) (xy 168.720374 -122.553483) (xy 168.775763 -122.584953)
			(xy 168.826792 -122.623089) (xy 168.872662 -122.667295) (xy 168.88203 -122.678909) (xy 169.671994 -122.678909)
			(xy 169.671994 -122.614987) (xy 169.680005 -122.551569) (xy 169.695902 -122.489655) (xy 169.719434 -122.430222)
			(xy 169.750228 -122.374207) (xy 169.787801 -122.322492) (xy 169.831558 -122.275895) (xy 169.880811 -122.23515)
			(xy 169.934782 -122.200899) (xy 169.992621 -122.173682) (xy 170.053414 -122.153929) (xy 170.116204 -122.141951)
			(xy 170.18 -122.137938) (xy 170.243796 -122.141951) (xy 170.306586 -122.153929) (xy 170.367379 -122.173682)
			(xy 170.425218 -122.200899) (xy 170.479189 -122.23515) (xy 170.528442 -122.275895) (xy 170.572199 -122.322492)
			(xy 170.609772 -122.374207) (xy 170.640566 -122.430222) (xy 170.664098 -122.489655) (xy 170.679995 -122.551569)
			(xy 170.688006 -122.614987) (xy 170.688508 -122.646948) (xy 170.688006 -122.678909) (xy 171.703994 -122.678909)
			(xy 171.703994 -122.614987) (xy 171.712005 -122.551569) (xy 171.727902 -122.489655) (xy 171.751434 -122.430222)
			(xy 171.782228 -122.374207) (xy 171.819801 -122.322492) (xy 171.863558 -122.275895) (xy 171.912811 -122.23515)
			(xy 171.966782 -122.200899) (xy 172.024621 -122.173682) (xy 172.085414 -122.153929) (xy 172.148204 -122.141951)
			(xy 172.212 -122.137938) (xy 172.275796 -122.141951) (xy 172.338586 -122.153929) (xy 172.399379 -122.173682)
			(xy 172.457218 -122.200899) (xy 172.511189 -122.23515) (xy 172.560442 -122.275895) (xy 172.604199 -122.322492)
			(xy 172.641772 -122.374207) (xy 172.672566 -122.430222) (xy 172.696098 -122.489655) (xy 172.711995 -122.551569)
			(xy 172.720006 -122.614987) (xy 172.720508 -122.646948) (xy 172.720006 -122.678909) (xy 172.711995 -122.742327)
			(xy 172.696098 -122.804241) (xy 172.672566 -122.863674) (xy 172.641772 -122.919689) (xy 172.604199 -122.971404)
			(xy 172.560442 -123.018001) (xy 172.511189 -123.058746) (xy 172.457218 -123.092997) (xy 172.399379 -123.120214)
			(xy 172.338586 -123.139967) (xy 172.275796 -123.151945) (xy 172.212 -123.155959) (xy 172.148204 -123.151945)
			(xy 172.085414 -123.139967) (xy 172.024621 -123.120214) (xy 171.966782 -123.092997) (xy 171.912811 -123.058746)
			(xy 171.863558 -123.018001) (xy 171.819801 -122.971404) (xy 171.782228 -122.919689) (xy 171.751434 -122.863674)
			(xy 171.727902 -122.804241) (xy 171.712005 -122.742327) (xy 171.703994 -122.678909) (xy 170.688006 -122.678909)
			(xy 170.679995 -122.742327) (xy 170.664098 -122.804241) (xy 170.640566 -122.863674) (xy 170.609772 -122.919689)
			(xy 170.572199 -122.971404) (xy 170.528442 -123.018001) (xy 170.479189 -123.058746) (xy 170.425218 -123.092997)
			(xy 170.367379 -123.120214) (xy 170.306586 -123.139967) (xy 170.243796 -123.151945) (xy 170.18 -123.155959)
			(xy 170.116204 -123.151945) (xy 170.053414 -123.139967) (xy 169.992621 -123.120214) (xy 169.934782 -123.092997)
			(xy 169.880811 -123.058746) (xy 169.831558 -123.018001) (xy 169.787801 -122.971404) (xy 169.750228 -122.919689)
			(xy 169.719434 -122.863674) (xy 169.695902 -122.804241) (xy 169.680005 -122.742327) (xy 169.671994 -122.678909)
			(xy 168.88203 -122.678909) (xy 168.912657 -122.71688) (xy 168.929812 -122.743722) (xy 168.932352 -122.74804)
			(xy 168.94972 -122.777911) (xy 168.977102 -122.84135) (xy 168.995627 -122.907917) (xy 169.004954 -122.976381)
			(xy 169.005504 -123.01093) (xy 169.005425 -123.023652) (xy 169.004154 -123.049064) (xy 169.002964 -123.06173)
			(xy 169.003218 -123.06173) (xy 168.998865 -123.098214) (xy 168.981009 -123.169485) (xy 168.967658 -123.203716)
			(xy 168.96588 -123.208034) (xy 168.963342 -123.218094) (xy 168.965709 -123.238684) (xy 168.970452 -123.247912)
			(xy 168.97858 -123.25858) (xy 169.149268 -123.429268) (xy 173.400212 -123.429268) (xy 173.40075 -123.396053)
			(xy 173.409397 -123.330188) (xy 173.426553 -123.266011) (xy 173.451925 -123.204617) (xy 173.48508 -123.147053)
			(xy 173.525453 -123.094299) (xy 173.572356 -123.047256) (xy 173.624989 -123.006725) (xy 173.65345 -122.989594)
			(xy 173.660696 -122.984945) (xy 173.671824 -122.971823) (xy 173.677999 -122.955764) (xy 173.678596 -122.947176)
			(xy 173.68139 -122.860816) (xy 173.681349 -122.852179) (xy 173.676171 -122.835715) (xy 173.665788 -122.821927)
			(xy 173.658784 -122.816874) (xy 173.65853 -122.816874) (xy 173.632666 -122.799161) (xy 173.585033 -122.758407)
			(xy 173.542772 -122.712105) (xy 173.506527 -122.660958) (xy 173.476846 -122.605741) (xy 173.45418 -122.547294)
			(xy 173.438874 -122.486504) (xy 173.431159 -122.424292) (xy 173.430692 -122.392948) (xy 173.431167 -122.36166)
			(xy 173.438844 -122.299558) (xy 173.454088 -122.238868) (xy 173.476668 -122.180509) (xy 173.506242 -122.125364)
			(xy 173.542363 -122.074267) (xy 173.584485 -122.027991) (xy 173.631969 -121.987238) (xy 173.657768 -121.96953)
			(xy 173.667888 -121.961973) (xy 173.679765 -121.939725) (xy 173.680374 -121.927112) (xy 173.680374 -121.842784)
			(xy 173.679745 -121.830177) (xy 173.667876 -121.80793) (xy 173.657768 -121.800366) (xy 173.631992 -121.782627)
			(xy 173.584512 -121.741874) (xy 173.542393 -121.695602) (xy 173.506272 -121.644509) (xy 173.476696 -121.589369)
			(xy 173.454112 -121.531015) (xy 173.438861 -121.470331) (xy 173.431175 -121.408234) (xy 173.430692 -121.376948)
			(xy 173.431194 -121.344987) (xy 173.439205 -121.281569) (xy 173.455102 -121.219655) (xy 173.478634 -121.160222)
			(xy 173.509428 -121.104207) (xy 173.547001 -121.052492) (xy 173.590758 -121.005895) (xy 173.640011 -120.96515)
			(xy 173.693982 -120.930899) (xy 173.751821 -120.903682) (xy 173.812614 -120.883929) (xy 173.875404 -120.871951)
			(xy 173.9392 -120.867938) (xy 174.002996 -120.871951) (xy 174.065786 -120.883929) (xy 174.126579 -120.903682)
			(xy 174.184418 -120.930899) (xy 174.238389 -120.96515) (xy 174.287642 -121.005895) (xy 174.331399 -121.052492)
			(xy 174.368972 -121.104207) (xy 174.399766 -121.160222) (xy 174.423298 -121.219655) (xy 174.439195 -121.281569)
			(xy 174.447206 -121.344987) (xy 174.447708 -121.376948) (xy 174.44723 -121.408235) (xy 174.439753 -121.468721)
			(xy 178.001932 -121.468721) (xy 178.001932 -121.416747) (xy 178.010062 -121.365412) (xy 178.026123 -121.315982)
			(xy 178.049719 -121.269672) (xy 178.080269 -121.227624) (xy 178.11702 -121.190873) (xy 178.159068 -121.160323)
			(xy 178.205378 -121.136727) (xy 178.254808 -121.120666) (xy 178.306143 -121.112536) (xy 178.358117 -121.112536)
			(xy 178.409452 -121.120666) (xy 178.458882 -121.136727) (xy 178.505192 -121.160323) (xy 178.54724 -121.190873)
			(xy 178.583991 -121.227624) (xy 178.614541 -121.269672) (xy 178.638137 -121.315982) (xy 178.654198 -121.365412)
			(xy 178.662328 -121.416747) (xy 178.662838 -121.442734) (xy 178.662328 -121.468721) (xy 178.802032 -121.468721)
			(xy 178.802032 -121.416747) (xy 178.810162 -121.365412) (xy 178.826223 -121.315982) (xy 178.849819 -121.269672)
			(xy 178.880369 -121.227624) (xy 178.91712 -121.190873) (xy 178.959168 -121.160323) (xy 179.005478 -121.136727)
			(xy 179.054908 -121.120666) (xy 179.106243 -121.112536) (xy 179.158217 -121.112536) (xy 179.209552 -121.120666)
			(xy 179.258982 -121.136727) (xy 179.305292 -121.160323) (xy 179.34734 -121.190873) (xy 179.384091 -121.227624)
			(xy 179.414641 -121.269672) (xy 179.438237 -121.315982) (xy 179.454298 -121.365412) (xy 179.462428 -121.416747)
			(xy 179.462938 -121.442734) (xy 179.462428 -121.468721) (xy 179.602132 -121.468721) (xy 179.602132 -121.416747)
			(xy 179.610262 -121.365412) (xy 179.626323 -121.315982) (xy 179.649919 -121.269672) (xy 179.680469 -121.227624)
			(xy 179.71722 -121.190873) (xy 179.759268 -121.160323) (xy 179.805578 -121.136727) (xy 179.855008 -121.120666)
			(xy 179.906343 -121.112536) (xy 179.958317 -121.112536) (xy 180.009652 -121.120666) (xy 180.059082 -121.136727)
			(xy 180.105392 -121.160323) (xy 180.14744 -121.190873) (xy 180.184191 -121.227624) (xy 180.214741 -121.269672)
			(xy 180.238337 -121.315982) (xy 180.254398 -121.365412) (xy 180.262528 -121.416747) (xy 180.263038 -121.442734)
			(xy 180.262528 -121.468721) (xy 180.401978 -121.468721) (xy 180.401978 -121.416747) (xy 180.410108 -121.365412)
			(xy 180.426169 -121.315982) (xy 180.449765 -121.269672) (xy 180.480315 -121.227624) (xy 180.517066 -121.190873)
			(xy 180.559114 -121.160323) (xy 180.605424 -121.136727) (xy 180.654854 -121.120666) (xy 180.706189 -121.112536)
			(xy 180.758163 -121.112536) (xy 180.809498 -121.120666) (xy 180.858928 -121.136727) (xy 180.905238 -121.160323)
			(xy 180.947286 -121.190873) (xy 180.984037 -121.227624) (xy 181.014587 -121.269672) (xy 181.038183 -121.315982)
			(xy 181.054244 -121.365412) (xy 181.062374 -121.416747) (xy 181.062884 -121.442734) (xy 181.062374 -121.468721)
			(xy 181.202078 -121.468721) (xy 181.202078 -121.416747) (xy 181.210208 -121.365412) (xy 181.226269 -121.315982)
			(xy 181.249865 -121.269672) (xy 181.280415 -121.227624) (xy 181.317166 -121.190873) (xy 181.359214 -121.160323)
			(xy 181.405524 -121.136727) (xy 181.454954 -121.120666) (xy 181.506289 -121.112536) (xy 181.558263 -121.112536)
			(xy 181.609598 -121.120666) (xy 181.659028 -121.136727) (xy 181.705338 -121.160323) (xy 181.747386 -121.190873)
			(xy 181.784137 -121.227624) (xy 181.814687 -121.269672) (xy 181.838283 -121.315982) (xy 181.854344 -121.365412)
			(xy 181.862474 -121.416747) (xy 181.862984 -121.442734) (xy 181.862474 -121.468721) (xy 182.001924 -121.468721)
			(xy 182.001924 -121.416747) (xy 182.010054 -121.365412) (xy 182.026115 -121.315982) (xy 182.049711 -121.269672)
			(xy 182.080261 -121.227624) (xy 182.117012 -121.190873) (xy 182.15906 -121.160323) (xy 182.20537 -121.136727)
			(xy 182.2548 -121.120666) (xy 182.306135 -121.112536) (xy 182.358109 -121.112536) (xy 182.409444 -121.120666)
			(xy 182.458874 -121.136727) (xy 182.505184 -121.160323) (xy 182.547232 -121.190873) (xy 182.583983 -121.227624)
			(xy 182.614533 -121.269672) (xy 182.638129 -121.315982) (xy 182.65419 -121.365412) (xy 182.66232 -121.416747)
			(xy 182.66283 -121.442734) (xy 182.66232 -121.468721) (xy 182.802024 -121.468721) (xy 182.802024 -121.416747)
			(xy 182.810154 -121.365412) (xy 182.826215 -121.315982) (xy 182.849811 -121.269672) (xy 182.880361 -121.227624)
			(xy 182.917112 -121.190873) (xy 182.95916 -121.160323) (xy 183.00547 -121.136727) (xy 183.0549 -121.120666)
			(xy 183.106235 -121.112536) (xy 183.158209 -121.112536) (xy 183.209544 -121.120666) (xy 183.258974 -121.136727)
			(xy 183.305284 -121.160323) (xy 183.347332 -121.190873) (xy 183.384083 -121.227624) (xy 183.414633 -121.269672)
			(xy 183.438229 -121.315982) (xy 183.45429 -121.365412) (xy 183.46242 -121.416747) (xy 183.46293 -121.442734)
			(xy 183.46242 -121.468721) (xy 183.602124 -121.468721) (xy 183.602124 -121.416747) (xy 183.610254 -121.365412)
			(xy 183.626315 -121.315982) (xy 183.649911 -121.269672) (xy 183.680461 -121.227624) (xy 183.717212 -121.190873)
			(xy 183.75926 -121.160323) (xy 183.80557 -121.136727) (xy 183.855 -121.120666) (xy 183.906335 -121.112536)
			(xy 183.958309 -121.112536) (xy 184.009644 -121.120666) (xy 184.059074 -121.136727) (xy 184.105384 -121.160323)
			(xy 184.147432 -121.190873) (xy 184.184183 -121.227624) (xy 184.214733 -121.269672) (xy 184.238329 -121.315982)
			(xy 184.25439 -121.365412) (xy 184.26252 -121.416747) (xy 184.26303 -121.442734) (xy 184.26252 -121.468721)
			(xy 184.40197 -121.468721) (xy 184.40197 -121.416747) (xy 184.4101 -121.365412) (xy 184.426161 -121.315982)
			(xy 184.449757 -121.269672) (xy 184.480307 -121.227624) (xy 184.517058 -121.190873) (xy 184.559106 -121.160323)
			(xy 184.605416 -121.136727) (xy 184.654846 -121.120666) (xy 184.706181 -121.112536) (xy 184.758155 -121.112536)
			(xy 184.80949 -121.120666) (xy 184.85892 -121.136727) (xy 184.90523 -121.160323) (xy 184.947278 -121.190873)
			(xy 184.984029 -121.227624) (xy 185.014579 -121.269672) (xy 185.038175 -121.315982) (xy 185.054236 -121.365412)
			(xy 185.062366 -121.416747) (xy 185.062876 -121.442734) (xy 185.062366 -121.468721) (xy 185.98185 -121.468721)
			(xy 185.98185 -121.416747) (xy 185.98998 -121.365412) (xy 186.006041 -121.315982) (xy 186.029637 -121.269672)
			(xy 186.060187 -121.227624) (xy 186.096938 -121.190873) (xy 186.138986 -121.160323) (xy 186.185296 -121.136727)
			(xy 186.234726 -121.120666) (xy 186.286061 -121.112536) (xy 186.338035 -121.112536) (xy 186.38937 -121.120666)
			(xy 186.4388 -121.136727) (xy 186.48511 -121.160323) (xy 186.527158 -121.190873) (xy 186.563909 -121.227624)
			(xy 186.594459 -121.269672) (xy 186.618055 -121.315982) (xy 186.634116 -121.365412) (xy 186.642246 -121.416747)
			(xy 186.642756 -121.442734) (xy 186.642246 -121.468721) (xy 186.781696 -121.468721) (xy 186.781696 -121.416747)
			(xy 186.789826 -121.365412) (xy 186.805887 -121.315982) (xy 186.829483 -121.269672) (xy 186.860033 -121.227624)
			(xy 186.896784 -121.190873) (xy 186.938832 -121.160323) (xy 186.985142 -121.136727) (xy 187.034572 -121.120666)
			(xy 187.085907 -121.112536) (xy 187.137881 -121.112536) (xy 187.189216 -121.120666) (xy 187.238646 -121.136727)
			(xy 187.284956 -121.160323) (xy 187.327004 -121.190873) (xy 187.363755 -121.227624) (xy 187.394305 -121.269672)
			(xy 187.417901 -121.315982) (xy 187.433962 -121.365412) (xy 187.442092 -121.416747) (xy 187.442602 -121.442734)
			(xy 187.442092 -121.468721) (xy 187.581796 -121.468721) (xy 187.581796 -121.416747) (xy 187.589926 -121.365412)
			(xy 187.605987 -121.315982) (xy 187.629583 -121.269672) (xy 187.660133 -121.227624) (xy 187.696884 -121.190873)
			(xy 187.738932 -121.160323) (xy 187.785242 -121.136727) (xy 187.834672 -121.120666) (xy 187.886007 -121.112536)
			(xy 187.937981 -121.112536) (xy 187.989316 -121.120666) (xy 188.038746 -121.136727) (xy 188.085056 -121.160323)
			(xy 188.127104 -121.190873) (xy 188.163855 -121.227624) (xy 188.194405 -121.269672) (xy 188.218001 -121.315982)
			(xy 188.234062 -121.365412) (xy 188.242192 -121.416747) (xy 188.242702 -121.442734) (xy 188.242192 -121.468721)
			(xy 188.381896 -121.468721) (xy 188.381896 -121.416747) (xy 188.390026 -121.365412) (xy 188.406087 -121.315982)
			(xy 188.429683 -121.269672) (xy 188.460233 -121.227624) (xy 188.496984 -121.190873) (xy 188.539032 -121.160323)
			(xy 188.585342 -121.136727) (xy 188.634772 -121.120666) (xy 188.686107 -121.112536) (xy 188.738081 -121.112536)
			(xy 188.789416 -121.120666) (xy 188.838846 -121.136727) (xy 188.885156 -121.160323) (xy 188.927204 -121.190873)
			(xy 188.963955 -121.227624) (xy 188.994505 -121.269672) (xy 189.018101 -121.315982) (xy 189.034162 -121.365412)
			(xy 189.042292 -121.416747) (xy 189.042802 -121.442734) (xy 189.042292 -121.468721) (xy 189.181742 -121.468721)
			(xy 189.181742 -121.416747) (xy 189.189872 -121.365412) (xy 189.205933 -121.315982) (xy 189.229529 -121.269672)
			(xy 189.260079 -121.227624) (xy 189.29683 -121.190873) (xy 189.338878 -121.160323) (xy 189.385188 -121.136727)
			(xy 189.434618 -121.120666) (xy 189.485953 -121.112536) (xy 189.537927 -121.112536) (xy 189.589262 -121.120666)
			(xy 189.638692 -121.136727) (xy 189.685002 -121.160323) (xy 189.72705 -121.190873) (xy 189.763801 -121.227624)
			(xy 189.794351 -121.269672) (xy 189.817947 -121.315982) (xy 189.834008 -121.365412) (xy 189.842138 -121.416747)
			(xy 189.842648 -121.442734) (xy 189.842138 -121.468721) (xy 189.981842 -121.468721) (xy 189.981842 -121.416747)
			(xy 189.989972 -121.365412) (xy 190.006033 -121.315982) (xy 190.029629 -121.269672) (xy 190.060179 -121.227624)
			(xy 190.09693 -121.190873) (xy 190.138978 -121.160323) (xy 190.185288 -121.136727) (xy 190.234718 -121.120666)
			(xy 190.286053 -121.112536) (xy 190.338027 -121.112536) (xy 190.389362 -121.120666) (xy 190.438792 -121.136727)
			(xy 190.485102 -121.160323) (xy 190.52715 -121.190873) (xy 190.563901 -121.227624) (xy 190.594451 -121.269672)
			(xy 190.618047 -121.315982) (xy 190.634108 -121.365412) (xy 190.642238 -121.416747) (xy 190.642748 -121.442734)
			(xy 190.642238 -121.468721) (xy 190.781688 -121.468721) (xy 190.781688 -121.416747) (xy 190.789818 -121.365412)
			(xy 190.805879 -121.315982) (xy 190.829475 -121.269672) (xy 190.860025 -121.227624) (xy 190.896776 -121.190873)
			(xy 190.938824 -121.160323) (xy 190.985134 -121.136727) (xy 191.034564 -121.120666) (xy 191.085899 -121.112536)
			(xy 191.137873 -121.112536) (xy 191.189208 -121.120666) (xy 191.238638 -121.136727) (xy 191.284948 -121.160323)
			(xy 191.326996 -121.190873) (xy 191.363747 -121.227624) (xy 191.394297 -121.269672) (xy 191.417893 -121.315982)
			(xy 191.433954 -121.365412) (xy 191.442084 -121.416747) (xy 191.442594 -121.442734) (xy 191.442084 -121.468721)
			(xy 191.581788 -121.468721) (xy 191.581788 -121.416747) (xy 191.589918 -121.365412) (xy 191.605979 -121.315982)
			(xy 191.629575 -121.269672) (xy 191.660125 -121.227624) (xy 191.696876 -121.190873) (xy 191.738924 -121.160323)
			(xy 191.785234 -121.136727) (xy 191.834664 -121.120666) (xy 191.885999 -121.112536) (xy 191.937973 -121.112536)
			(xy 191.989308 -121.120666) (xy 192.038738 -121.136727) (xy 192.085048 -121.160323) (xy 192.127096 -121.190873)
			(xy 192.163847 -121.227624) (xy 192.194397 -121.269672) (xy 192.217993 -121.315982) (xy 192.234054 -121.365412)
			(xy 192.242184 -121.416747) (xy 192.242694 -121.442734) (xy 192.242184 -121.468721) (xy 192.381888 -121.468721)
			(xy 192.381888 -121.416747) (xy 192.390018 -121.365412) (xy 192.406079 -121.315982) (xy 192.429675 -121.269672)
			(xy 192.460225 -121.227624) (xy 192.496976 -121.190873) (xy 192.539024 -121.160323) (xy 192.585334 -121.136727)
			(xy 192.634764 -121.120666) (xy 192.686099 -121.112536) (xy 192.738073 -121.112536) (xy 192.789408 -121.120666)
			(xy 192.838838 -121.136727) (xy 192.885148 -121.160323) (xy 192.927196 -121.190873) (xy 192.963947 -121.227624)
			(xy 192.994497 -121.269672) (xy 193.018093 -121.315982) (xy 193.034154 -121.365412) (xy 193.042284 -121.416747)
			(xy 193.042794 -121.442734) (xy 193.042284 -121.468721) (xy 193.181734 -121.468721) (xy 193.181734 -121.416747)
			(xy 193.189864 -121.365412) (xy 193.205925 -121.315982) (xy 193.229521 -121.269672) (xy 193.260071 -121.227624)
			(xy 193.296822 -121.190873) (xy 193.33887 -121.160323) (xy 193.38518 -121.136727) (xy 193.43461 -121.120666)
			(xy 193.485945 -121.112536) (xy 193.537919 -121.112536) (xy 193.589254 -121.120666) (xy 193.638684 -121.136727)
			(xy 193.684994 -121.160323) (xy 193.727042 -121.190873) (xy 193.763793 -121.227624) (xy 193.794343 -121.269672)
			(xy 193.817939 -121.315982) (xy 193.834 -121.365412) (xy 193.84213 -121.416747) (xy 193.84264 -121.442734)
			(xy 193.84213 -121.468721) (xy 193.834 -121.520056) (xy 193.817939 -121.569486) (xy 193.794343 -121.615796)
			(xy 193.763793 -121.657844) (xy 193.727042 -121.694595) (xy 193.684994 -121.725145) (xy 193.638684 -121.748741)
			(xy 193.589254 -121.764802) (xy 193.537919 -121.772932) (xy 193.485945 -121.772932) (xy 193.43461 -121.764802)
			(xy 193.38518 -121.748741) (xy 193.33887 -121.725145) (xy 193.296822 -121.694595) (xy 193.260071 -121.657844)
			(xy 193.229521 -121.615796) (xy 193.205925 -121.569486) (xy 193.189864 -121.520056) (xy 193.181734 -121.468721)
			(xy 193.042284 -121.468721) (xy 193.034154 -121.520056) (xy 193.018093 -121.569486) (xy 192.994497 -121.615796)
			(xy 192.963947 -121.657844) (xy 192.927196 -121.694595) (xy 192.885148 -121.725145) (xy 192.838838 -121.748741)
			(xy 192.789408 -121.764802) (xy 192.738073 -121.772932) (xy 192.686099 -121.772932) (xy 192.634764 -121.764802)
			(xy 192.585334 -121.748741) (xy 192.539024 -121.725145) (xy 192.496976 -121.694595) (xy 192.460225 -121.657844)
			(xy 192.429675 -121.615796) (xy 192.406079 -121.569486) (xy 192.390018 -121.520056) (xy 192.381888 -121.468721)
			(xy 192.242184 -121.468721) (xy 192.234054 -121.520056) (xy 192.217993 -121.569486) (xy 192.194397 -121.615796)
			(xy 192.163847 -121.657844) (xy 192.127096 -121.694595) (xy 192.085048 -121.725145) (xy 192.038738 -121.748741)
			(xy 191.989308 -121.764802) (xy 191.937973 -121.772932) (xy 191.885999 -121.772932) (xy 191.834664 -121.764802)
			(xy 191.785234 -121.748741) (xy 191.738924 -121.725145) (xy 191.696876 -121.694595) (xy 191.660125 -121.657844)
			(xy 191.629575 -121.615796) (xy 191.605979 -121.569486) (xy 191.589918 -121.520056) (xy 191.581788 -121.468721)
			(xy 191.442084 -121.468721) (xy 191.433954 -121.520056) (xy 191.417893 -121.569486) (xy 191.394297 -121.615796)
			(xy 191.363747 -121.657844) (xy 191.326996 -121.694595) (xy 191.284948 -121.725145) (xy 191.238638 -121.748741)
			(xy 191.189208 -121.764802) (xy 191.137873 -121.772932) (xy 191.085899 -121.772932) (xy 191.034564 -121.764802)
			(xy 190.985134 -121.748741) (xy 190.938824 -121.725145) (xy 190.896776 -121.694595) (xy 190.860025 -121.657844)
			(xy 190.829475 -121.615796) (xy 190.805879 -121.569486) (xy 190.789818 -121.520056) (xy 190.781688 -121.468721)
			(xy 190.642238 -121.468721) (xy 190.634108 -121.520056) (xy 190.618047 -121.569486) (xy 190.594451 -121.615796)
			(xy 190.563901 -121.657844) (xy 190.52715 -121.694595) (xy 190.485102 -121.725145) (xy 190.438792 -121.748741)
			(xy 190.389362 -121.764802) (xy 190.338027 -121.772932) (xy 190.286053 -121.772932) (xy 190.234718 -121.764802)
			(xy 190.185288 -121.748741) (xy 190.138978 -121.725145) (xy 190.09693 -121.694595) (xy 190.060179 -121.657844)
			(xy 190.029629 -121.615796) (xy 190.006033 -121.569486) (xy 189.989972 -121.520056) (xy 189.981842 -121.468721)
			(xy 189.842138 -121.468721) (xy 189.834008 -121.520056) (xy 189.817947 -121.569486) (xy 189.794351 -121.615796)
			(xy 189.763801 -121.657844) (xy 189.72705 -121.694595) (xy 189.685002 -121.725145) (xy 189.638692 -121.748741)
			(xy 189.589262 -121.764802) (xy 189.537927 -121.772932) (xy 189.485953 -121.772932) (xy 189.434618 -121.764802)
			(xy 189.385188 -121.748741) (xy 189.338878 -121.725145) (xy 189.29683 -121.694595) (xy 189.260079 -121.657844)
			(xy 189.229529 -121.615796) (xy 189.205933 -121.569486) (xy 189.189872 -121.520056) (xy 189.181742 -121.468721)
			(xy 189.042292 -121.468721) (xy 189.034162 -121.520056) (xy 189.018101 -121.569486) (xy 188.994505 -121.615796)
			(xy 188.963955 -121.657844) (xy 188.927204 -121.694595) (xy 188.885156 -121.725145) (xy 188.838846 -121.748741)
			(xy 188.789416 -121.764802) (xy 188.738081 -121.772932) (xy 188.686107 -121.772932) (xy 188.634772 -121.764802)
			(xy 188.585342 -121.748741) (xy 188.539032 -121.725145) (xy 188.496984 -121.694595) (xy 188.460233 -121.657844)
			(xy 188.429683 -121.615796) (xy 188.406087 -121.569486) (xy 188.390026 -121.520056) (xy 188.381896 -121.468721)
			(xy 188.242192 -121.468721) (xy 188.234062 -121.520056) (xy 188.218001 -121.569486) (xy 188.194405 -121.615796)
			(xy 188.163855 -121.657844) (xy 188.127104 -121.694595) (xy 188.085056 -121.725145) (xy 188.038746 -121.748741)
			(xy 187.989316 -121.764802) (xy 187.937981 -121.772932) (xy 187.886007 -121.772932) (xy 187.834672 -121.764802)
			(xy 187.785242 -121.748741) (xy 187.738932 -121.725145) (xy 187.696884 -121.694595) (xy 187.660133 -121.657844)
			(xy 187.629583 -121.615796) (xy 187.605987 -121.569486) (xy 187.589926 -121.520056) (xy 187.581796 -121.468721)
			(xy 187.442092 -121.468721) (xy 187.433962 -121.520056) (xy 187.417901 -121.569486) (xy 187.394305 -121.615796)
			(xy 187.363755 -121.657844) (xy 187.327004 -121.694595) (xy 187.284956 -121.725145) (xy 187.238646 -121.748741)
			(xy 187.189216 -121.764802) (xy 187.137881 -121.772932) (xy 187.085907 -121.772932) (xy 187.034572 -121.764802)
			(xy 186.985142 -121.748741) (xy 186.938832 -121.725145) (xy 186.896784 -121.694595) (xy 186.860033 -121.657844)
			(xy 186.829483 -121.615796) (xy 186.805887 -121.569486) (xy 186.789826 -121.520056) (xy 186.781696 -121.468721)
			(xy 186.642246 -121.468721) (xy 186.634116 -121.520056) (xy 186.618055 -121.569486) (xy 186.594459 -121.615796)
			(xy 186.563909 -121.657844) (xy 186.527158 -121.694595) (xy 186.48511 -121.725145) (xy 186.4388 -121.748741)
			(xy 186.38937 -121.764802) (xy 186.338035 -121.772932) (xy 186.286061 -121.772932) (xy 186.234726 -121.764802)
			(xy 186.185296 -121.748741) (xy 186.138986 -121.725145) (xy 186.096938 -121.694595) (xy 186.060187 -121.657844)
			(xy 186.029637 -121.615796) (xy 186.006041 -121.569486) (xy 185.98998 -121.520056) (xy 185.98185 -121.468721)
			(xy 185.062366 -121.468721) (xy 185.054236 -121.520056) (xy 185.038175 -121.569486) (xy 185.014579 -121.615796)
			(xy 184.984029 -121.657844) (xy 184.947278 -121.694595) (xy 184.90523 -121.725145) (xy 184.85892 -121.748741)
			(xy 184.80949 -121.764802) (xy 184.758155 -121.772932) (xy 184.706181 -121.772932) (xy 184.654846 -121.764802)
			(xy 184.605416 -121.748741) (xy 184.559106 -121.725145) (xy 184.517058 -121.694595) (xy 184.480307 -121.657844)
			(xy 184.449757 -121.615796) (xy 184.426161 -121.569486) (xy 184.4101 -121.520056) (xy 184.40197 -121.468721)
			(xy 184.26252 -121.468721) (xy 184.25439 -121.520056) (xy 184.238329 -121.569486) (xy 184.214733 -121.615796)
			(xy 184.184183 -121.657844) (xy 184.147432 -121.694595) (xy 184.105384 -121.725145) (xy 184.059074 -121.748741)
			(xy 184.009644 -121.764802) (xy 183.958309 -121.772932) (xy 183.906335 -121.772932) (xy 183.855 -121.764802)
			(xy 183.80557 -121.748741) (xy 183.75926 -121.725145) (xy 183.717212 -121.694595) (xy 183.680461 -121.657844)
			(xy 183.649911 -121.615796) (xy 183.626315 -121.569486) (xy 183.610254 -121.520056) (xy 183.602124 -121.468721)
			(xy 183.46242 -121.468721) (xy 183.45429 -121.520056) (xy 183.438229 -121.569486) (xy 183.414633 -121.615796)
			(xy 183.384083 -121.657844) (xy 183.347332 -121.694595) (xy 183.305284 -121.725145) (xy 183.258974 -121.748741)
			(xy 183.209544 -121.764802) (xy 183.158209 -121.772932) (xy 183.106235 -121.772932) (xy 183.0549 -121.764802)
			(xy 183.00547 -121.748741) (xy 182.95916 -121.725145) (xy 182.917112 -121.694595) (xy 182.880361 -121.657844)
			(xy 182.849811 -121.615796) (xy 182.826215 -121.569486) (xy 182.810154 -121.520056) (xy 182.802024 -121.468721)
			(xy 182.66232 -121.468721) (xy 182.65419 -121.520056) (xy 182.638129 -121.569486) (xy 182.614533 -121.615796)
			(xy 182.583983 -121.657844) (xy 182.547232 -121.694595) (xy 182.505184 -121.725145) (xy 182.458874 -121.748741)
			(xy 182.409444 -121.764802) (xy 182.358109 -121.772932) (xy 182.306135 -121.772932) (xy 182.2548 -121.764802)
			(xy 182.20537 -121.748741) (xy 182.15906 -121.725145) (xy 182.117012 -121.694595) (xy 182.080261 -121.657844)
			(xy 182.049711 -121.615796) (xy 182.026115 -121.569486) (xy 182.010054 -121.520056) (xy 182.001924 -121.468721)
			(xy 181.862474 -121.468721) (xy 181.854344 -121.520056) (xy 181.838283 -121.569486) (xy 181.814687 -121.615796)
			(xy 181.784137 -121.657844) (xy 181.747386 -121.694595) (xy 181.705338 -121.725145) (xy 181.659028 -121.748741)
			(xy 181.609598 -121.764802) (xy 181.558263 -121.772932) (xy 181.506289 -121.772932) (xy 181.454954 -121.764802)
			(xy 181.405524 -121.748741) (xy 181.359214 -121.725145) (xy 181.317166 -121.694595) (xy 181.280415 -121.657844)
			(xy 181.249865 -121.615796) (xy 181.226269 -121.569486) (xy 181.210208 -121.520056) (xy 181.202078 -121.468721)
			(xy 181.062374 -121.468721) (xy 181.054244 -121.520056) (xy 181.038183 -121.569486) (xy 181.014587 -121.615796)
			(xy 180.984037 -121.657844) (xy 180.947286 -121.694595) (xy 180.905238 -121.725145) (xy 180.858928 -121.748741)
			(xy 180.809498 -121.764802) (xy 180.758163 -121.772932) (xy 180.706189 -121.772932) (xy 180.654854 -121.764802)
			(xy 180.605424 -121.748741) (xy 180.559114 -121.725145) (xy 180.517066 -121.694595) (xy 180.480315 -121.657844)
			(xy 180.449765 -121.615796) (xy 180.426169 -121.569486) (xy 180.410108 -121.520056) (xy 180.401978 -121.468721)
			(xy 180.262528 -121.468721) (xy 180.254398 -121.520056) (xy 180.238337 -121.569486) (xy 180.214741 -121.615796)
			(xy 180.184191 -121.657844) (xy 180.14744 -121.694595) (xy 180.105392 -121.725145) (xy 180.059082 -121.748741)
			(xy 180.009652 -121.764802) (xy 179.958317 -121.772932) (xy 179.906343 -121.772932) (xy 179.855008 -121.764802)
			(xy 179.805578 -121.748741) (xy 179.759268 -121.725145) (xy 179.71722 -121.694595) (xy 179.680469 -121.657844)
			(xy 179.649919 -121.615796) (xy 179.626323 -121.569486) (xy 179.610262 -121.520056) (xy 179.602132 -121.468721)
			(xy 179.462428 -121.468721) (xy 179.454298 -121.520056) (xy 179.438237 -121.569486) (xy 179.414641 -121.615796)
			(xy 179.384091 -121.657844) (xy 179.34734 -121.694595) (xy 179.305292 -121.725145) (xy 179.258982 -121.748741)
			(xy 179.209552 -121.764802) (xy 179.158217 -121.772932) (xy 179.106243 -121.772932) (xy 179.054908 -121.764802)
			(xy 179.005478 -121.748741) (xy 178.959168 -121.725145) (xy 178.91712 -121.694595) (xy 178.880369 -121.657844)
			(xy 178.849819 -121.615796) (xy 178.826223 -121.569486) (xy 178.810162 -121.520056) (xy 178.802032 -121.468721)
			(xy 178.662328 -121.468721) (xy 178.654198 -121.520056) (xy 178.638137 -121.569486) (xy 178.614541 -121.615796)
			(xy 178.583991 -121.657844) (xy 178.54724 -121.694595) (xy 178.505192 -121.725145) (xy 178.458882 -121.748741)
			(xy 178.409452 -121.764802) (xy 178.358117 -121.772932) (xy 178.306143 -121.772932) (xy 178.254808 -121.764802)
			(xy 178.205378 -121.748741) (xy 178.159068 -121.725145) (xy 178.11702 -121.694595) (xy 178.080269 -121.657844)
			(xy 178.049719 -121.615796) (xy 178.026123 -121.569486) (xy 178.010062 -121.520056) (xy 178.001932 -121.468721)
			(xy 174.439753 -121.468721) (xy 174.439553 -121.470338) (xy 174.42431 -121.531028) (xy 174.401731 -121.589387)
			(xy 174.372157 -121.644532) (xy 174.336036 -121.695629) (xy 174.293915 -121.741904) (xy 174.246431 -121.782658)
			(xy 174.220632 -121.800366) (xy 174.210468 -121.807874) (xy 174.198614 -121.830159) (xy 174.198026 -121.842784)
			(xy 174.198026 -121.927112) (xy 174.198658 -121.939719) (xy 174.210525 -121.961966) (xy 174.220632 -121.96953)
			(xy 174.246406 -121.987271) (xy 174.293886 -122.028024) (xy 174.336006 -122.074296) (xy 174.372127 -122.125388)
			(xy 174.401703 -122.180528) (xy 174.424287 -122.238881) (xy 174.431811 -122.268821) (xy 177.202086 -122.268821)
			(xy 177.202086 -122.216847) (xy 177.210216 -122.165512) (xy 177.226277 -122.116082) (xy 177.249873 -122.069772)
			(xy 177.280423 -122.027724) (xy 177.317174 -121.990973) (xy 177.359222 -121.960423) (xy 177.405532 -121.936827)
			(xy 177.454962 -121.920766) (xy 177.506297 -121.912636) (xy 177.558271 -121.912636) (xy 177.609606 -121.920766)
			(xy 177.659036 -121.936827) (xy 177.705346 -121.960423) (xy 177.747394 -121.990973) (xy 177.784145 -122.027724)
			(xy 177.814695 -122.069772) (xy 177.838291 -122.116082) (xy 177.854352 -122.165512) (xy 177.862482 -122.216847)
			(xy 177.862992 -122.242834) (xy 177.862482 -122.268821) (xy 178.001932 -122.268821) (xy 178.001932 -122.216847)
			(xy 178.010062 -122.165512) (xy 178.026123 -122.116082) (xy 178.049719 -122.069772) (xy 178.080269 -122.027724)
			(xy 178.11702 -121.990973) (xy 178.159068 -121.960423) (xy 178.205378 -121.936827) (xy 178.254808 -121.920766)
			(xy 178.306143 -121.912636) (xy 178.358117 -121.912636) (xy 178.409452 -121.920766) (xy 178.458882 -121.936827)
			(xy 178.505192 -121.960423) (xy 178.54724 -121.990973) (xy 178.583991 -122.027724) (xy 178.614541 -122.069772)
			(xy 178.638137 -122.116082) (xy 178.654198 -122.165512) (xy 178.662328 -122.216847) (xy 178.662838 -122.242834)
			(xy 178.662328 -122.268821) (xy 178.802032 -122.268821) (xy 178.802032 -122.216847) (xy 178.810162 -122.165512)
			(xy 178.826223 -122.116082) (xy 178.849819 -122.069772) (xy 178.880369 -122.027724) (xy 178.91712 -121.990973)
			(xy 178.959168 -121.960423) (xy 179.005478 -121.936827) (xy 179.054908 -121.920766) (xy 179.106243 -121.912636)
			(xy 179.158217 -121.912636) (xy 179.209552 -121.920766) (xy 179.258982 -121.936827) (xy 179.305292 -121.960423)
			(xy 179.34734 -121.990973) (xy 179.384091 -122.027724) (xy 179.414641 -122.069772) (xy 179.438237 -122.116082)
			(xy 179.454298 -122.165512) (xy 179.462428 -122.216847) (xy 179.462938 -122.242834) (xy 179.462428 -122.268821)
			(xy 179.602132 -122.268821) (xy 179.602132 -122.216847) (xy 179.610262 -122.165512) (xy 179.626323 -122.116082)
			(xy 179.649919 -122.069772) (xy 179.680469 -122.027724) (xy 179.71722 -121.990973) (xy 179.759268 -121.960423)
			(xy 179.805578 -121.936827) (xy 179.855008 -121.920766) (xy 179.906343 -121.912636) (xy 179.958317 -121.912636)
			(xy 180.009652 -121.920766) (xy 180.059082 -121.936827) (xy 180.105392 -121.960423) (xy 180.14744 -121.990973)
			(xy 180.184191 -122.027724) (xy 180.214741 -122.069772) (xy 180.238337 -122.116082) (xy 180.254398 -122.165512)
			(xy 180.262528 -122.216847) (xy 180.263038 -122.242834) (xy 180.262528 -122.268821) (xy 181.202078 -122.268821)
			(xy 181.202078 -122.216847) (xy 181.210208 -122.165512) (xy 181.226269 -122.116082) (xy 181.249865 -122.069772)
			(xy 181.280415 -122.027724) (xy 181.317166 -121.990973) (xy 181.359214 -121.960423) (xy 181.405524 -121.936827)
			(xy 181.454954 -121.920766) (xy 181.506289 -121.912636) (xy 181.558263 -121.912636) (xy 181.609598 -121.920766)
			(xy 181.659028 -121.936827) (xy 181.705338 -121.960423) (xy 181.747386 -121.990973) (xy 181.784137 -122.027724)
			(xy 181.814687 -122.069772) (xy 181.838283 -122.116082) (xy 181.854344 -122.165512) (xy 181.862474 -122.216847)
			(xy 181.862984 -122.242834) (xy 181.862474 -122.268821) (xy 182.001924 -122.268821) (xy 182.001924 -122.216847)
			(xy 182.010054 -122.165512) (xy 182.026115 -122.116082) (xy 182.049711 -122.069772) (xy 182.080261 -122.027724)
			(xy 182.117012 -121.990973) (xy 182.15906 -121.960423) (xy 182.20537 -121.936827) (xy 182.2548 -121.920766)
			(xy 182.306135 -121.912636) (xy 182.358109 -121.912636) (xy 182.409444 -121.920766) (xy 182.458874 -121.936827)
			(xy 182.505184 -121.960423) (xy 182.547232 -121.990973) (xy 182.583983 -122.027724) (xy 182.614533 -122.069772)
			(xy 182.638129 -122.116082) (xy 182.65419 -122.165512) (xy 182.66232 -122.216847) (xy 182.66283 -122.242834)
			(xy 182.66232 -122.268821) (xy 182.802024 -122.268821) (xy 182.802024 -122.216847) (xy 182.810154 -122.165512)
			(xy 182.826215 -122.116082) (xy 182.849811 -122.069772) (xy 182.880361 -122.027724) (xy 182.917112 -121.990973)
			(xy 182.95916 -121.960423) (xy 183.00547 -121.936827) (xy 183.0549 -121.920766) (xy 183.106235 -121.912636)
			(xy 183.158209 -121.912636) (xy 183.209544 -121.920766) (xy 183.258974 -121.936827) (xy 183.305284 -121.960423)
			(xy 183.347332 -121.990973) (xy 183.384083 -122.027724) (xy 183.414633 -122.069772) (xy 183.438229 -122.116082)
			(xy 183.45429 -122.165512) (xy 183.46242 -122.216847) (xy 183.46293 -122.242834) (xy 183.46242 -122.268821)
			(xy 183.602124 -122.268821) (xy 183.602124 -122.216847) (xy 183.610254 -122.165512) (xy 183.626315 -122.116082)
			(xy 183.649911 -122.069772) (xy 183.680461 -122.027724) (xy 183.717212 -121.990973) (xy 183.75926 -121.960423)
			(xy 183.80557 -121.936827) (xy 183.855 -121.920766) (xy 183.906335 -121.912636) (xy 183.958309 -121.912636)
			(xy 184.009644 -121.920766) (xy 184.059074 -121.936827) (xy 184.105384 -121.960423) (xy 184.147432 -121.990973)
			(xy 184.184183 -122.027724) (xy 184.214733 -122.069772) (xy 184.238329 -122.116082) (xy 184.25439 -122.165512)
			(xy 184.26252 -122.216847) (xy 184.26303 -122.242834) (xy 184.26252 -122.268821) (xy 184.40197 -122.268821)
			(xy 184.40197 -122.216847) (xy 184.4101 -122.165512) (xy 184.426161 -122.116082) (xy 184.449757 -122.069772)
			(xy 184.480307 -122.027724) (xy 184.517058 -121.990973) (xy 184.559106 -121.960423) (xy 184.605416 -121.936827)
			(xy 184.654846 -121.920766) (xy 184.706181 -121.912636) (xy 184.758155 -121.912636) (xy 184.80949 -121.920766)
			(xy 184.85892 -121.936827) (xy 184.90523 -121.960423) (xy 184.947278 -121.990973) (xy 184.984029 -122.027724)
			(xy 185.014579 -122.069772) (xy 185.038175 -122.116082) (xy 185.054236 -122.165512) (xy 185.062366 -122.216847)
			(xy 185.062876 -122.242834) (xy 185.062366 -122.268821) (xy 185.98185 -122.268821) (xy 185.98185 -122.216847)
			(xy 185.98998 -122.165512) (xy 186.006041 -122.116082) (xy 186.029637 -122.069772) (xy 186.060187 -122.027724)
			(xy 186.096938 -121.990973) (xy 186.138986 -121.960423) (xy 186.185296 -121.936827) (xy 186.234726 -121.920766)
			(xy 186.286061 -121.912636) (xy 186.338035 -121.912636) (xy 186.38937 -121.920766) (xy 186.4388 -121.936827)
			(xy 186.48511 -121.960423) (xy 186.527158 -121.990973) (xy 186.563909 -122.027724) (xy 186.594459 -122.069772)
			(xy 186.618055 -122.116082) (xy 186.634116 -122.165512) (xy 186.642246 -122.216847) (xy 186.642756 -122.242834)
			(xy 186.642246 -122.268821) (xy 186.781696 -122.268821) (xy 186.781696 -122.216847) (xy 186.789826 -122.165512)
			(xy 186.805887 -122.116082) (xy 186.829483 -122.069772) (xy 186.860033 -122.027724) (xy 186.896784 -121.990973)
			(xy 186.938832 -121.960423) (xy 186.985142 -121.936827) (xy 187.034572 -121.920766) (xy 187.085907 -121.912636)
			(xy 187.137881 -121.912636) (xy 187.189216 -121.920766) (xy 187.238646 -121.936827) (xy 187.284956 -121.960423)
			(xy 187.327004 -121.990973) (xy 187.363755 -122.027724) (xy 187.394305 -122.069772) (xy 187.417901 -122.116082)
			(xy 187.433962 -122.165512) (xy 187.442092 -122.216847) (xy 187.442602 -122.242834) (xy 187.442092 -122.268821)
			(xy 187.581796 -122.268821) (xy 187.581796 -122.216847) (xy 187.589926 -122.165512) (xy 187.605987 -122.116082)
			(xy 187.629583 -122.069772) (xy 187.660133 -122.027724) (xy 187.696884 -121.990973) (xy 187.738932 -121.960423)
			(xy 187.785242 -121.936827) (xy 187.834672 -121.920766) (xy 187.886007 -121.912636) (xy 187.937981 -121.912636)
			(xy 187.989316 -121.920766) (xy 188.038746 -121.936827) (xy 188.085056 -121.960423) (xy 188.127104 -121.990973)
			(xy 188.163855 -122.027724) (xy 188.194405 -122.069772) (xy 188.218001 -122.116082) (xy 188.234062 -122.165512)
			(xy 188.242192 -122.216847) (xy 188.242702 -122.242834) (xy 188.242192 -122.268821) (xy 188.381896 -122.268821)
			(xy 188.381896 -122.216847) (xy 188.390026 -122.165512) (xy 188.406087 -122.116082) (xy 188.429683 -122.069772)
			(xy 188.460233 -122.027724) (xy 188.496984 -121.990973) (xy 188.539032 -121.960423) (xy 188.585342 -121.936827)
			(xy 188.634772 -121.920766) (xy 188.686107 -121.912636) (xy 188.738081 -121.912636) (xy 188.789416 -121.920766)
			(xy 188.838846 -121.936827) (xy 188.885156 -121.960423) (xy 188.927204 -121.990973) (xy 188.963955 -122.027724)
			(xy 188.994505 -122.069772) (xy 189.018101 -122.116082) (xy 189.034162 -122.165512) (xy 189.042292 -122.216847)
			(xy 189.042802 -122.242834) (xy 189.042292 -122.268821) (xy 189.181742 -122.268821) (xy 189.181742 -122.216847)
			(xy 189.189872 -122.165512) (xy 189.205933 -122.116082) (xy 189.229529 -122.069772) (xy 189.260079 -122.027724)
			(xy 189.29683 -121.990973) (xy 189.338878 -121.960423) (xy 189.385188 -121.936827) (xy 189.434618 -121.920766)
			(xy 189.485953 -121.912636) (xy 189.537927 -121.912636) (xy 189.589262 -121.920766) (xy 189.638692 -121.936827)
			(xy 189.685002 -121.960423) (xy 189.72705 -121.990973) (xy 189.763801 -122.027724) (xy 189.794351 -122.069772)
			(xy 189.817947 -122.116082) (xy 189.834008 -122.165512) (xy 189.842138 -122.216847) (xy 189.842648 -122.242834)
			(xy 189.842138 -122.268821) (xy 189.981842 -122.268821) (xy 189.981842 -122.216847) (xy 189.989972 -122.165512)
			(xy 190.006033 -122.116082) (xy 190.029629 -122.069772) (xy 190.060179 -122.027724) (xy 190.09693 -121.990973)
			(xy 190.138978 -121.960423) (xy 190.185288 -121.936827) (xy 190.234718 -121.920766) (xy 190.286053 -121.912636)
			(xy 190.338027 -121.912636) (xy 190.389362 -121.920766) (xy 190.438792 -121.936827) (xy 190.485102 -121.960423)
			(xy 190.52715 -121.990973) (xy 190.563901 -122.027724) (xy 190.594451 -122.069772) (xy 190.618047 -122.116082)
			(xy 190.634108 -122.165512) (xy 190.642238 -122.216847) (xy 190.642748 -122.242834) (xy 190.642238 -122.268821)
			(xy 191.581788 -122.268821) (xy 191.581788 -122.216847) (xy 191.589918 -122.165512) (xy 191.605979 -122.116082)
			(xy 191.629575 -122.069772) (xy 191.660125 -122.027724) (xy 191.696876 -121.990973) (xy 191.738924 -121.960423)
			(xy 191.785234 -121.936827) (xy 191.834664 -121.920766) (xy 191.885999 -121.912636) (xy 191.937973 -121.912636)
			(xy 191.989308 -121.920766) (xy 192.038738 -121.936827) (xy 192.085048 -121.960423) (xy 192.127096 -121.990973)
			(xy 192.163847 -122.027724) (xy 192.194397 -122.069772) (xy 192.217993 -122.116082) (xy 192.234054 -122.165512)
			(xy 192.242184 -122.216847) (xy 192.242694 -122.242834) (xy 192.242184 -122.268821) (xy 192.381888 -122.268821)
			(xy 192.381888 -122.216847) (xy 192.390018 -122.165512) (xy 192.406079 -122.116082) (xy 192.429675 -122.069772)
			(xy 192.460225 -122.027724) (xy 192.496976 -121.990973) (xy 192.539024 -121.960423) (xy 192.585334 -121.936827)
			(xy 192.634764 -121.920766) (xy 192.686099 -121.912636) (xy 192.738073 -121.912636) (xy 192.789408 -121.920766)
			(xy 192.838838 -121.936827) (xy 192.885148 -121.960423) (xy 192.927196 -121.990973) (xy 192.963947 -122.027724)
			(xy 192.994497 -122.069772) (xy 193.018093 -122.116082) (xy 193.034154 -122.165512) (xy 193.042284 -122.216847)
			(xy 193.042794 -122.242834) (xy 193.042284 -122.268821) (xy 193.181734 -122.268821) (xy 193.181734 -122.216847)
			(xy 193.189864 -122.165512) (xy 193.205925 -122.116082) (xy 193.229521 -122.069772) (xy 193.260071 -122.027724)
			(xy 193.296822 -121.990973) (xy 193.33887 -121.960423) (xy 193.38518 -121.936827) (xy 193.43461 -121.920766)
			(xy 193.485945 -121.912636) (xy 193.537919 -121.912636) (xy 193.589254 -121.920766) (xy 193.638684 -121.936827)
			(xy 193.684994 -121.960423) (xy 193.727042 -121.990973) (xy 193.763793 -122.027724) (xy 193.794343 -122.069772)
			(xy 193.817939 -122.116082) (xy 193.834 -122.165512) (xy 193.84213 -122.216847) (xy 193.84264 -122.242834)
			(xy 193.84213 -122.268821) (xy 193.981834 -122.268821) (xy 193.981834 -122.216847) (xy 193.989964 -122.165512)
			(xy 194.006025 -122.116082) (xy 194.029621 -122.069772) (xy 194.060171 -122.027724) (xy 194.096922 -121.990973)
			(xy 194.13897 -121.960423) (xy 194.18528 -121.936827) (xy 194.23471 -121.920766) (xy 194.286045 -121.912636)
			(xy 194.338019 -121.912636) (xy 194.389354 -121.920766) (xy 194.438784 -121.936827) (xy 194.485094 -121.960423)
			(xy 194.527142 -121.990973) (xy 194.563893 -122.027724) (xy 194.594443 -122.069772) (xy 194.618039 -122.116082)
			(xy 194.6341 -122.165512) (xy 194.64223 -122.216847) (xy 194.64274 -122.242834) (xy 194.64223 -122.268821)
			(xy 194.6341 -122.320156) (xy 194.618039 -122.369586) (xy 194.594443 -122.415896) (xy 194.563893 -122.457944)
			(xy 194.527142 -122.494695) (xy 194.485094 -122.525245) (xy 194.438784 -122.548841) (xy 194.389354 -122.564902)
			(xy 194.338019 -122.573032) (xy 194.286045 -122.573032) (xy 194.23471 -122.564902) (xy 194.18528 -122.548841)
			(xy 194.13897 -122.525245) (xy 194.096922 -122.494695) (xy 194.060171 -122.457944) (xy 194.029621 -122.415896)
			(xy 194.006025 -122.369586) (xy 193.989964 -122.320156) (xy 193.981834 -122.268821) (xy 193.84213 -122.268821)
			(xy 193.834 -122.320156) (xy 193.817939 -122.369586) (xy 193.794343 -122.415896) (xy 193.763793 -122.457944)
			(xy 193.727042 -122.494695) (xy 193.684994 -122.525245) (xy 193.638684 -122.548841) (xy 193.589254 -122.564902)
			(xy 193.537919 -122.573032) (xy 193.485945 -122.573032) (xy 193.43461 -122.564902) (xy 193.38518 -122.548841)
			(xy 193.33887 -122.525245) (xy 193.296822 -122.494695) (xy 193.260071 -122.457944) (xy 193.229521 -122.415896)
			(xy 193.205925 -122.369586) (xy 193.189864 -122.320156) (xy 193.181734 -122.268821) (xy 193.042284 -122.268821)
			(xy 193.034154 -122.320156) (xy 193.018093 -122.369586) (xy 192.994497 -122.415896) (xy 192.963947 -122.457944)
			(xy 192.927196 -122.494695) (xy 192.885148 -122.525245) (xy 192.838838 -122.548841) (xy 192.789408 -122.564902)
			(xy 192.738073 -122.573032) (xy 192.686099 -122.573032) (xy 192.634764 -122.564902) (xy 192.585334 -122.548841)
			(xy 192.539024 -122.525245) (xy 192.496976 -122.494695) (xy 192.460225 -122.457944) (xy 192.429675 -122.415896)
			(xy 192.406079 -122.369586) (xy 192.390018 -122.320156) (xy 192.381888 -122.268821) (xy 192.242184 -122.268821)
			(xy 192.234054 -122.320156) (xy 192.217993 -122.369586) (xy 192.194397 -122.415896) (xy 192.163847 -122.457944)
			(xy 192.127096 -122.494695) (xy 192.085048 -122.525245) (xy 192.038738 -122.548841) (xy 191.989308 -122.564902)
			(xy 191.937973 -122.573032) (xy 191.885999 -122.573032) (xy 191.834664 -122.564902) (xy 191.785234 -122.548841)
			(xy 191.738924 -122.525245) (xy 191.696876 -122.494695) (xy 191.660125 -122.457944) (xy 191.629575 -122.415896)
			(xy 191.605979 -122.369586) (xy 191.589918 -122.320156) (xy 191.581788 -122.268821) (xy 190.642238 -122.268821)
			(xy 190.634108 -122.320156) (xy 190.618047 -122.369586) (xy 190.594451 -122.415896) (xy 190.563901 -122.457944)
			(xy 190.52715 -122.494695) (xy 190.485102 -122.525245) (xy 190.438792 -122.548841) (xy 190.389362 -122.564902)
			(xy 190.338027 -122.573032) (xy 190.286053 -122.573032) (xy 190.234718 -122.564902) (xy 190.185288 -122.548841)
			(xy 190.138978 -122.525245) (xy 190.09693 -122.494695) (xy 190.060179 -122.457944) (xy 190.029629 -122.415896)
			(xy 190.006033 -122.369586) (xy 189.989972 -122.320156) (xy 189.981842 -122.268821) (xy 189.842138 -122.268821)
			(xy 189.834008 -122.320156) (xy 189.817947 -122.369586) (xy 189.794351 -122.415896) (xy 189.763801 -122.457944)
			(xy 189.72705 -122.494695) (xy 189.685002 -122.525245) (xy 189.638692 -122.548841) (xy 189.589262 -122.564902)
			(xy 189.537927 -122.573032) (xy 189.485953 -122.573032) (xy 189.434618 -122.564902) (xy 189.385188 -122.548841)
			(xy 189.338878 -122.525245) (xy 189.29683 -122.494695) (xy 189.260079 -122.457944) (xy 189.229529 -122.415896)
			(xy 189.205933 -122.369586) (xy 189.189872 -122.320156) (xy 189.181742 -122.268821) (xy 189.042292 -122.268821)
			(xy 189.034162 -122.320156) (xy 189.018101 -122.369586) (xy 188.994505 -122.415896) (xy 188.963955 -122.457944)
			(xy 188.927204 -122.494695) (xy 188.885156 -122.525245) (xy 188.838846 -122.548841) (xy 188.789416 -122.564902)
			(xy 188.738081 -122.573032) (xy 188.686107 -122.573032) (xy 188.634772 -122.564902) (xy 188.585342 -122.548841)
			(xy 188.539032 -122.525245) (xy 188.496984 -122.494695) (xy 188.460233 -122.457944) (xy 188.429683 -122.415896)
			(xy 188.406087 -122.369586) (xy 188.390026 -122.320156) (xy 188.381896 -122.268821) (xy 188.242192 -122.268821)
			(xy 188.234062 -122.320156) (xy 188.218001 -122.369586) (xy 188.194405 -122.415896) (xy 188.163855 -122.457944)
			(xy 188.127104 -122.494695) (xy 188.085056 -122.525245) (xy 188.038746 -122.548841) (xy 187.989316 -122.564902)
			(xy 187.937981 -122.573032) (xy 187.886007 -122.573032) (xy 187.834672 -122.564902) (xy 187.785242 -122.548841)
			(xy 187.738932 -122.525245) (xy 187.696884 -122.494695) (xy 187.660133 -122.457944) (xy 187.629583 -122.415896)
			(xy 187.605987 -122.369586) (xy 187.589926 -122.320156) (xy 187.581796 -122.268821) (xy 187.442092 -122.268821)
			(xy 187.433962 -122.320156) (xy 187.417901 -122.369586) (xy 187.394305 -122.415896) (xy 187.363755 -122.457944)
			(xy 187.327004 -122.494695) (xy 187.284956 -122.525245) (xy 187.238646 -122.548841) (xy 187.189216 -122.564902)
			(xy 187.137881 -122.573032) (xy 187.085907 -122.573032) (xy 187.034572 -122.564902) (xy 186.985142 -122.548841)
			(xy 186.938832 -122.525245) (xy 186.896784 -122.494695) (xy 186.860033 -122.457944) (xy 186.829483 -122.415896)
			(xy 186.805887 -122.369586) (xy 186.789826 -122.320156) (xy 186.781696 -122.268821) (xy 186.642246 -122.268821)
			(xy 186.634116 -122.320156) (xy 186.618055 -122.369586) (xy 186.594459 -122.415896) (xy 186.563909 -122.457944)
			(xy 186.527158 -122.494695) (xy 186.48511 -122.525245) (xy 186.4388 -122.548841) (xy 186.38937 -122.564902)
			(xy 186.338035 -122.573032) (xy 186.286061 -122.573032) (xy 186.234726 -122.564902) (xy 186.185296 -122.548841)
			(xy 186.138986 -122.525245) (xy 186.096938 -122.494695) (xy 186.060187 -122.457944) (xy 186.029637 -122.415896)
			(xy 186.006041 -122.369586) (xy 185.98998 -122.320156) (xy 185.98185 -122.268821) (xy 185.062366 -122.268821)
			(xy 185.054236 -122.320156) (xy 185.038175 -122.369586) (xy 185.014579 -122.415896) (xy 184.984029 -122.457944)
			(xy 184.947278 -122.494695) (xy 184.90523 -122.525245) (xy 184.85892 -122.548841) (xy 184.80949 -122.564902)
			(xy 184.758155 -122.573032) (xy 184.706181 -122.573032) (xy 184.654846 -122.564902) (xy 184.605416 -122.548841)
			(xy 184.559106 -122.525245) (xy 184.517058 -122.494695) (xy 184.480307 -122.457944) (xy 184.449757 -122.415896)
			(xy 184.426161 -122.369586) (xy 184.4101 -122.320156) (xy 184.40197 -122.268821) (xy 184.26252 -122.268821)
			(xy 184.25439 -122.320156) (xy 184.238329 -122.369586) (xy 184.214733 -122.415896) (xy 184.184183 -122.457944)
			(xy 184.147432 -122.494695) (xy 184.105384 -122.525245) (xy 184.059074 -122.548841) (xy 184.009644 -122.564902)
			(xy 183.958309 -122.573032) (xy 183.906335 -122.573032) (xy 183.855 -122.564902) (xy 183.80557 -122.548841)
			(xy 183.75926 -122.525245) (xy 183.717212 -122.494695) (xy 183.680461 -122.457944) (xy 183.649911 -122.415896)
			(xy 183.626315 -122.369586) (xy 183.610254 -122.320156) (xy 183.602124 -122.268821) (xy 183.46242 -122.268821)
			(xy 183.45429 -122.320156) (xy 183.438229 -122.369586) (xy 183.414633 -122.415896) (xy 183.384083 -122.457944)
			(xy 183.347332 -122.494695) (xy 183.305284 -122.525245) (xy 183.258974 -122.548841) (xy 183.209544 -122.564902)
			(xy 183.158209 -122.573032) (xy 183.106235 -122.573032) (xy 183.0549 -122.564902) (xy 183.00547 -122.548841)
			(xy 182.95916 -122.525245) (xy 182.917112 -122.494695) (xy 182.880361 -122.457944) (xy 182.849811 -122.415896)
			(xy 182.826215 -122.369586) (xy 182.810154 -122.320156) (xy 182.802024 -122.268821) (xy 182.66232 -122.268821)
			(xy 182.65419 -122.320156) (xy 182.638129 -122.369586) (xy 182.614533 -122.415896) (xy 182.583983 -122.457944)
			(xy 182.547232 -122.494695) (xy 182.505184 -122.525245) (xy 182.458874 -122.548841) (xy 182.409444 -122.564902)
			(xy 182.358109 -122.573032) (xy 182.306135 -122.573032) (xy 182.2548 -122.564902) (xy 182.20537 -122.548841)
			(xy 182.15906 -122.525245) (xy 182.117012 -122.494695) (xy 182.080261 -122.457944) (xy 182.049711 -122.415896)
			(xy 182.026115 -122.369586) (xy 182.010054 -122.320156) (xy 182.001924 -122.268821) (xy 181.862474 -122.268821)
			(xy 181.854344 -122.320156) (xy 181.838283 -122.369586) (xy 181.814687 -122.415896) (xy 181.784137 -122.457944)
			(xy 181.747386 -122.494695) (xy 181.705338 -122.525245) (xy 181.659028 -122.548841) (xy 181.609598 -122.564902)
			(xy 181.558263 -122.573032) (xy 181.506289 -122.573032) (xy 181.454954 -122.564902) (xy 181.405524 -122.548841)
			(xy 181.359214 -122.525245) (xy 181.317166 -122.494695) (xy 181.280415 -122.457944) (xy 181.249865 -122.415896)
			(xy 181.226269 -122.369586) (xy 181.210208 -122.320156) (xy 181.202078 -122.268821) (xy 180.262528 -122.268821)
			(xy 180.254398 -122.320156) (xy 180.238337 -122.369586) (xy 180.214741 -122.415896) (xy 180.184191 -122.457944)
			(xy 180.14744 -122.494695) (xy 180.105392 -122.525245) (xy 180.059082 -122.548841) (xy 180.009652 -122.564902)
			(xy 179.958317 -122.573032) (xy 179.906343 -122.573032) (xy 179.855008 -122.564902) (xy 179.805578 -122.548841)
			(xy 179.759268 -122.525245) (xy 179.71722 -122.494695) (xy 179.680469 -122.457944) (xy 179.649919 -122.415896)
			(xy 179.626323 -122.369586) (xy 179.610262 -122.320156) (xy 179.602132 -122.268821) (xy 179.462428 -122.268821)
			(xy 179.454298 -122.320156) (xy 179.438237 -122.369586) (xy 179.414641 -122.415896) (xy 179.384091 -122.457944)
			(xy 179.34734 -122.494695) (xy 179.305292 -122.525245) (xy 179.258982 -122.548841) (xy 179.209552 -122.564902)
			(xy 179.158217 -122.573032) (xy 179.106243 -122.573032) (xy 179.054908 -122.564902) (xy 179.005478 -122.548841)
			(xy 178.959168 -122.525245) (xy 178.91712 -122.494695) (xy 178.880369 -122.457944) (xy 178.849819 -122.415896)
			(xy 178.826223 -122.369586) (xy 178.810162 -122.320156) (xy 178.802032 -122.268821) (xy 178.662328 -122.268821)
			(xy 178.654198 -122.320156) (xy 178.638137 -122.369586) (xy 178.614541 -122.415896) (xy 178.583991 -122.457944)
			(xy 178.54724 -122.494695) (xy 178.505192 -122.525245) (xy 178.458882 -122.548841) (xy 178.409452 -122.564902)
			(xy 178.358117 -122.573032) (xy 178.306143 -122.573032) (xy 178.254808 -122.564902) (xy 178.205378 -122.548841)
			(xy 178.159068 -122.525245) (xy 178.11702 -122.494695) (xy 178.080269 -122.457944) (xy 178.049719 -122.415896)
			(xy 178.026123 -122.369586) (xy 178.010062 -122.320156) (xy 178.001932 -122.268821) (xy 177.862482 -122.268821)
			(xy 177.854352 -122.320156) (xy 177.838291 -122.369586) (xy 177.814695 -122.415896) (xy 177.784145 -122.457944)
			(xy 177.747394 -122.494695) (xy 177.705346 -122.525245) (xy 177.659036 -122.548841) (xy 177.609606 -122.564902)
			(xy 177.558271 -122.573032) (xy 177.506297 -122.573032) (xy 177.454962 -122.564902) (xy 177.405532 -122.548841)
			(xy 177.359222 -122.525245) (xy 177.317174 -122.494695) (xy 177.280423 -122.457944) (xy 177.249873 -122.415896)
			(xy 177.226277 -122.369586) (xy 177.210216 -122.320156) (xy 177.202086 -122.268821) (xy 174.431811 -122.268821)
			(xy 174.439538 -122.299565) (xy 174.447225 -122.361662) (xy 174.447708 -122.392948) (xy 174.447173 -122.426163)
			(xy 174.438524 -122.492028) (xy 174.421367 -122.556204) (xy 174.395995 -122.617598) (xy 174.362839 -122.675162)
			(xy 174.322466 -122.727916) (xy 174.275563 -122.774959) (xy 174.222931 -122.81549) (xy 174.19447 -122.832622)
			(xy 174.187201 -122.837237) (xy 174.176083 -122.850378) (xy 174.169917 -122.866448) (xy 174.169324 -122.87504)
			(xy 174.16653 -122.9614) (xy 174.166551 -122.970038) (xy 174.171737 -122.986505) (xy 174.182127 -123.000291)
			(xy 174.189136 -123.005342) (xy 174.18939 -123.005342) (xy 174.214747 -123.02271) (xy 174.261514 -123.062589)
			(xy 174.267109 -123.068667) (xy 176.401986 -123.068667) (xy 176.401986 -123.016693) (xy 176.410116 -122.965358)
			(xy 176.426177 -122.915928) (xy 176.449773 -122.869618) (xy 176.480323 -122.82757) (xy 176.517074 -122.790819)
			(xy 176.559122 -122.760269) (xy 176.605432 -122.736673) (xy 176.654862 -122.720612) (xy 176.706197 -122.712482)
			(xy 176.758171 -122.712482) (xy 176.809506 -122.720612) (xy 176.858936 -122.736673) (xy 176.905246 -122.760269)
			(xy 176.947294 -122.790819) (xy 176.984045 -122.82757) (xy 177.014595 -122.869618) (xy 177.038191 -122.915928)
			(xy 177.054252 -122.965358) (xy 177.062382 -123.016693) (xy 177.062892 -123.04268) (xy 177.062382 -123.068667)
			(xy 177.202086 -123.068667) (xy 177.202086 -123.016693) (xy 177.210216 -122.965358) (xy 177.226277 -122.915928)
			(xy 177.249873 -122.869618) (xy 177.280423 -122.82757) (xy 177.317174 -122.790819) (xy 177.359222 -122.760269)
			(xy 177.405532 -122.736673) (xy 177.454962 -122.720612) (xy 177.506297 -122.712482) (xy 177.558271 -122.712482)
			(xy 177.609606 -122.720612) (xy 177.659036 -122.736673) (xy 177.705346 -122.760269) (xy 177.747394 -122.790819)
			(xy 177.784145 -122.82757) (xy 177.814695 -122.869618) (xy 177.838291 -122.915928) (xy 177.854352 -122.965358)
			(xy 177.862482 -123.016693) (xy 177.862992 -123.04268) (xy 177.862482 -123.068667) (xy 179.602132 -123.068667)
			(xy 179.602132 -123.016693) (xy 179.610262 -122.965358) (xy 179.626323 -122.915928) (xy 179.649919 -122.869618)
			(xy 179.680469 -122.82757) (xy 179.71722 -122.790819) (xy 179.759268 -122.760269) (xy 179.805578 -122.736673)
			(xy 179.855008 -122.720612) (xy 179.906343 -122.712482) (xy 179.958317 -122.712482) (xy 180.009652 -122.720612)
			(xy 180.059082 -122.736673) (xy 180.105392 -122.760269) (xy 180.14744 -122.790819) (xy 180.184191 -122.82757)
			(xy 180.214741 -122.869618) (xy 180.238337 -122.915928) (xy 180.254398 -122.965358) (xy 180.262528 -123.016693)
			(xy 180.263038 -123.04268) (xy 180.262528 -123.068667) (xy 180.401978 -123.068667) (xy 180.401978 -123.016693)
			(xy 180.410108 -122.965358) (xy 180.426169 -122.915928) (xy 180.449765 -122.869618) (xy 180.480315 -122.82757)
			(xy 180.517066 -122.790819) (xy 180.559114 -122.760269) (xy 180.605424 -122.736673) (xy 180.654854 -122.720612)
			(xy 180.706189 -122.712482) (xy 180.758163 -122.712482) (xy 180.809498 -122.720612) (xy 180.858928 -122.736673)
			(xy 180.905238 -122.760269) (xy 180.947286 -122.790819) (xy 180.984037 -122.82757) (xy 181.014587 -122.869618)
			(xy 181.038183 -122.915928) (xy 181.054244 -122.965358) (xy 181.062374 -123.016693) (xy 181.062884 -123.04268)
			(xy 181.062374 -123.068667) (xy 182.802024 -123.068667) (xy 182.802024 -123.016693) (xy 182.810154 -122.965358)
			(xy 182.826215 -122.915928) (xy 182.849811 -122.869618) (xy 182.880361 -122.82757) (xy 182.917112 -122.790819)
			(xy 182.95916 -122.760269) (xy 183.00547 -122.736673) (xy 183.0549 -122.720612) (xy 183.106235 -122.712482)
			(xy 183.158209 -122.712482) (xy 183.209544 -122.720612) (xy 183.258974 -122.736673) (xy 183.305284 -122.760269)
			(xy 183.347332 -122.790819) (xy 183.384083 -122.82757) (xy 183.414633 -122.869618) (xy 183.438229 -122.915928)
			(xy 183.45429 -122.965358) (xy 183.46242 -123.016693) (xy 183.46293 -123.04268) (xy 183.46242 -123.068667)
			(xy 183.602124 -123.068667) (xy 183.602124 -123.016693) (xy 183.610254 -122.965358) (xy 183.626315 -122.915928)
			(xy 183.649911 -122.869618) (xy 183.680461 -122.82757) (xy 183.717212 -122.790819) (xy 183.75926 -122.760269)
			(xy 183.80557 -122.736673) (xy 183.855 -122.720612) (xy 183.906335 -122.712482) (xy 183.958309 -122.712482)
			(xy 184.009644 -122.720612) (xy 184.059074 -122.736673) (xy 184.105384 -122.760269) (xy 184.147432 -122.790819)
			(xy 184.184183 -122.82757) (xy 184.214733 -122.869618) (xy 184.238329 -122.915928) (xy 184.25439 -122.965358)
			(xy 184.26252 -123.016693) (xy 184.26303 -123.04268) (xy 184.26252 -123.068667) (xy 184.40197 -123.068667)
			(xy 184.40197 -123.016693) (xy 184.4101 -122.965358) (xy 184.426161 -122.915928) (xy 184.449757 -122.869618)
			(xy 184.480307 -122.82757) (xy 184.517058 -122.790819) (xy 184.559106 -122.760269) (xy 184.605416 -122.736673)
			(xy 184.654846 -122.720612) (xy 184.706181 -122.712482) (xy 184.758155 -122.712482) (xy 184.80949 -122.720612)
			(xy 184.85892 -122.736673) (xy 184.90523 -122.760269) (xy 184.947278 -122.790819) (xy 184.984029 -122.82757)
			(xy 185.014579 -122.869618) (xy 185.038175 -122.915928) (xy 185.054236 -122.965358) (xy 185.062366 -123.016693)
			(xy 185.062876 -123.04268) (xy 185.062366 -123.068667) (xy 186.781696 -123.068667) (xy 186.781696 -123.016693)
			(xy 186.789826 -122.965358) (xy 186.805887 -122.915928) (xy 186.829483 -122.869618) (xy 186.860033 -122.82757)
			(xy 186.896784 -122.790819) (xy 186.938832 -122.760269) (xy 186.985142 -122.736673) (xy 187.034572 -122.720612)
			(xy 187.085907 -122.712482) (xy 187.137881 -122.712482) (xy 187.189216 -122.720612) (xy 187.238646 -122.736673)
			(xy 187.284956 -122.760269) (xy 187.327004 -122.790819) (xy 187.363755 -122.82757) (xy 187.394305 -122.869618)
			(xy 187.417901 -122.915928) (xy 187.433962 -122.965358) (xy 187.442092 -123.016693) (xy 187.442602 -123.04268)
			(xy 187.442092 -123.068667) (xy 188.381896 -123.068667) (xy 188.381896 -123.016693) (xy 188.390026 -122.965358)
			(xy 188.406087 -122.915928) (xy 188.429683 -122.869618) (xy 188.460233 -122.82757) (xy 188.496984 -122.790819)
			(xy 188.539032 -122.760269) (xy 188.585342 -122.736673) (xy 188.634772 -122.720612) (xy 188.686107 -122.712482)
			(xy 188.738081 -122.712482) (xy 188.789416 -122.720612) (xy 188.838846 -122.736673) (xy 188.885156 -122.760269)
			(xy 188.927204 -122.790819) (xy 188.963955 -122.82757) (xy 188.994505 -122.869618) (xy 189.018101 -122.915928)
			(xy 189.034162 -122.965358) (xy 189.042292 -123.016693) (xy 189.042802 -123.04268) (xy 189.042292 -123.068667)
			(xy 189.181742 -123.068667) (xy 189.181742 -123.016693) (xy 189.189872 -122.965358) (xy 189.205933 -122.915928)
			(xy 189.229529 -122.869618) (xy 189.260079 -122.82757) (xy 189.29683 -122.790819) (xy 189.338878 -122.760269)
			(xy 189.385188 -122.736673) (xy 189.434618 -122.720612) (xy 189.485953 -122.712482) (xy 189.537927 -122.712482)
			(xy 189.589262 -122.720612) (xy 189.638692 -122.736673) (xy 189.685002 -122.760269) (xy 189.72705 -122.790819)
			(xy 189.763801 -122.82757) (xy 189.794351 -122.869618) (xy 189.817947 -122.915928) (xy 189.834008 -122.965358)
			(xy 189.842138 -123.016693) (xy 189.842648 -123.04268) (xy 189.842138 -123.068667) (xy 189.981842 -123.068667)
			(xy 189.981842 -123.016693) (xy 189.989972 -122.965358) (xy 190.006033 -122.915928) (xy 190.029629 -122.869618)
			(xy 190.060179 -122.82757) (xy 190.09693 -122.790819) (xy 190.138978 -122.760269) (xy 190.185288 -122.736673)
			(xy 190.234718 -122.720612) (xy 190.286053 -122.712482) (xy 190.338027 -122.712482) (xy 190.389362 -122.720612)
			(xy 190.438792 -122.736673) (xy 190.485102 -122.760269) (xy 190.52715 -122.790819) (xy 190.563901 -122.82757)
			(xy 190.594451 -122.869618) (xy 190.618047 -122.915928) (xy 190.634108 -122.965358) (xy 190.642238 -123.016693)
			(xy 190.642748 -123.04268) (xy 190.642238 -123.068667) (xy 190.781688 -123.068667) (xy 190.781688 -123.016693)
			(xy 190.789818 -122.965358) (xy 190.805879 -122.915928) (xy 190.829475 -122.869618) (xy 190.860025 -122.82757)
			(xy 190.896776 -122.790819) (xy 190.938824 -122.760269) (xy 190.985134 -122.736673) (xy 191.034564 -122.720612)
			(xy 191.085899 -122.712482) (xy 191.137873 -122.712482) (xy 191.189208 -122.720612) (xy 191.238638 -122.736673)
			(xy 191.284948 -122.760269) (xy 191.326996 -122.790819) (xy 191.363747 -122.82757) (xy 191.394297 -122.869618)
			(xy 191.417893 -122.915928) (xy 191.433954 -122.965358) (xy 191.442084 -123.016693) (xy 191.442594 -123.04268)
			(xy 191.442084 -123.068667) (xy 191.581788 -123.068667) (xy 191.581788 -123.016693) (xy 191.589918 -122.965358)
			(xy 191.605979 -122.915928) (xy 191.629575 -122.869618) (xy 191.660125 -122.82757) (xy 191.696876 -122.790819)
			(xy 191.738924 -122.760269) (xy 191.785234 -122.736673) (xy 191.834664 -122.720612) (xy 191.885999 -122.712482)
			(xy 191.937973 -122.712482) (xy 191.989308 -122.720612) (xy 192.038738 -122.736673) (xy 192.085048 -122.760269)
			(xy 192.127096 -122.790819) (xy 192.132302 -122.796025) (xy 197.987148 -122.796025) (xy 197.987148 -122.742727)
			(xy 197.995091 -122.690023) (xy 198.010801 -122.639093) (xy 198.033927 -122.591072) (xy 198.063951 -122.547035)
			(xy 198.100203 -122.507964) (xy 198.141874 -122.474733) (xy 198.188032 -122.448084) (xy 198.237646 -122.428612)
			(xy 198.289608 -122.416752) (xy 198.342758 -122.412769) (xy 198.395908 -122.416752) (xy 198.44787 -122.428612)
			(xy 198.497484 -122.448084) (xy 198.543642 -122.474733) (xy 198.585313 -122.507964) (xy 198.621565 -122.547035)
			(xy 198.651589 -122.591072) (xy 198.674715 -122.639093) (xy 198.690425 -122.690023) (xy 198.698368 -122.742727)
			(xy 198.698866 -122.769376) (xy 198.698368 -122.796025) (xy 198.690425 -122.848729) (xy 198.674715 -122.899659)
			(xy 198.651589 -122.94768) (xy 198.621565 -122.991717) (xy 198.585313 -123.030788) (xy 198.543642 -123.064019)
			(xy 198.497484 -123.090668) (xy 198.44787 -123.11014) (xy 198.395908 -123.122) (xy 198.342758 -123.125984)
			(xy 198.289608 -123.122) (xy 198.237646 -123.11014) (xy 198.188032 -123.090668) (xy 198.141874 -123.064019)
			(xy 198.100203 -123.030788) (xy 198.063951 -122.991717) (xy 198.033927 -122.94768) (xy 198.010801 -122.899659)
			(xy 197.995091 -122.848729) (xy 197.987148 -122.796025) (xy 192.132302 -122.796025) (xy 192.163847 -122.82757)
			(xy 192.194397 -122.869618) (xy 192.217993 -122.915928) (xy 192.234054 -122.965358) (xy 192.242184 -123.016693)
			(xy 192.242694 -123.04268) (xy 192.242184 -123.068667) (xy 192.234054 -123.120002) (xy 192.217993 -123.169432)
			(xy 192.194397 -123.215742) (xy 192.163847 -123.25779) (xy 192.127096 -123.294541) (xy 192.085048 -123.325091)
			(xy 192.038738 -123.348687) (xy 191.989308 -123.364748) (xy 191.937973 -123.372878) (xy 191.885999 -123.372878)
			(xy 191.834664 -123.364748) (xy 191.785234 -123.348687) (xy 191.738924 -123.325091) (xy 191.696876 -123.294541)
			(xy 191.660125 -123.25779) (xy 191.629575 -123.215742) (xy 191.605979 -123.169432) (xy 191.589918 -123.120002)
			(xy 191.581788 -123.068667) (xy 191.442084 -123.068667) (xy 191.433954 -123.120002) (xy 191.417893 -123.169432)
			(xy 191.394297 -123.215742) (xy 191.363747 -123.25779) (xy 191.326996 -123.294541) (xy 191.284948 -123.325091)
			(xy 191.238638 -123.348687) (xy 191.189208 -123.364748) (xy 191.137873 -123.372878) (xy 191.085899 -123.372878)
			(xy 191.034564 -123.364748) (xy 190.985134 -123.348687) (xy 190.938824 -123.325091) (xy 190.896776 -123.294541)
			(xy 190.860025 -123.25779) (xy 190.829475 -123.215742) (xy 190.805879 -123.169432) (xy 190.789818 -123.120002)
			(xy 190.781688 -123.068667) (xy 190.642238 -123.068667) (xy 190.634108 -123.120002) (xy 190.618047 -123.169432)
			(xy 190.594451 -123.215742) (xy 190.563901 -123.25779) (xy 190.52715 -123.294541) (xy 190.485102 -123.325091)
			(xy 190.438792 -123.348687) (xy 190.389362 -123.364748) (xy 190.338027 -123.372878) (xy 190.286053 -123.372878)
			(xy 190.234718 -123.364748) (xy 190.185288 -123.348687) (xy 190.138978 -123.325091) (xy 190.09693 -123.294541)
			(xy 190.060179 -123.25779) (xy 190.029629 -123.215742) (xy 190.006033 -123.169432) (xy 189.989972 -123.120002)
			(xy 189.981842 -123.068667) (xy 189.842138 -123.068667) (xy 189.834008 -123.120002) (xy 189.817947 -123.169432)
			(xy 189.794351 -123.215742) (xy 189.763801 -123.25779) (xy 189.72705 -123.294541) (xy 189.685002 -123.325091)
			(xy 189.638692 -123.348687) (xy 189.589262 -123.364748) (xy 189.537927 -123.372878) (xy 189.485953 -123.372878)
			(xy 189.434618 -123.364748) (xy 189.385188 -123.348687) (xy 189.338878 -123.325091) (xy 189.29683 -123.294541)
			(xy 189.260079 -123.25779) (xy 189.229529 -123.215742) (xy 189.205933 -123.169432) (xy 189.189872 -123.120002)
			(xy 189.181742 -123.068667) (xy 189.042292 -123.068667) (xy 189.034162 -123.120002) (xy 189.018101 -123.169432)
			(xy 188.994505 -123.215742) (xy 188.963955 -123.25779) (xy 188.927204 -123.294541) (xy 188.885156 -123.325091)
			(xy 188.838846 -123.348687) (xy 188.789416 -123.364748) (xy 188.738081 -123.372878) (xy 188.686107 -123.372878)
			(xy 188.634772 -123.364748) (xy 188.585342 -123.348687) (xy 188.539032 -123.325091) (xy 188.496984 -123.294541)
			(xy 188.460233 -123.25779) (xy 188.429683 -123.215742) (xy 188.406087 -123.169432) (xy 188.390026 -123.120002)
			(xy 188.381896 -123.068667) (xy 187.442092 -123.068667) (xy 187.433962 -123.120002) (xy 187.417901 -123.169432)
			(xy 187.394305 -123.215742) (xy 187.363755 -123.25779) (xy 187.327004 -123.294541) (xy 187.284956 -123.325091)
			(xy 187.238646 -123.348687) (xy 187.189216 -123.364748) (xy 187.137881 -123.372878) (xy 187.085907 -123.372878)
			(xy 187.034572 -123.364748) (xy 186.985142 -123.348687) (xy 186.938832 -123.325091) (xy 186.896784 -123.294541)
			(xy 186.860033 -123.25779) (xy 186.829483 -123.215742) (xy 186.805887 -123.169432) (xy 186.789826 -123.120002)
			(xy 186.781696 -123.068667) (xy 185.062366 -123.068667) (xy 185.054236 -123.120002) (xy 185.038175 -123.169432)
			(xy 185.014579 -123.215742) (xy 184.984029 -123.25779) (xy 184.947278 -123.294541) (xy 184.90523 -123.325091)
			(xy 184.85892 -123.348687) (xy 184.80949 -123.364748) (xy 184.758155 -123.372878) (xy 184.706181 -123.372878)
			(xy 184.654846 -123.364748) (xy 184.605416 -123.348687) (xy 184.559106 -123.325091) (xy 184.517058 -123.294541)
			(xy 184.480307 -123.25779) (xy 184.449757 -123.215742) (xy 184.426161 -123.169432) (xy 184.4101 -123.120002)
			(xy 184.40197 -123.068667) (xy 184.26252 -123.068667) (xy 184.25439 -123.120002) (xy 184.238329 -123.169432)
			(xy 184.214733 -123.215742) (xy 184.184183 -123.25779) (xy 184.147432 -123.294541) (xy 184.105384 -123.325091)
			(xy 184.059074 -123.348687) (xy 184.009644 -123.364748) (xy 183.958309 -123.372878) (xy 183.906335 -123.372878)
			(xy 183.855 -123.364748) (xy 183.80557 -123.348687) (xy 183.75926 -123.325091) (xy 183.717212 -123.294541)
			(xy 183.680461 -123.25779) (xy 183.649911 -123.215742) (xy 183.626315 -123.169432) (xy 183.610254 -123.120002)
			(xy 183.602124 -123.068667) (xy 183.46242 -123.068667) (xy 183.45429 -123.120002) (xy 183.438229 -123.169432)
			(xy 183.414633 -123.215742) (xy 183.384083 -123.25779) (xy 183.347332 -123.294541) (xy 183.305284 -123.325091)
			(xy 183.258974 -123.348687) (xy 183.209544 -123.364748) (xy 183.158209 -123.372878) (xy 183.106235 -123.372878)
			(xy 183.0549 -123.364748) (xy 183.00547 -123.348687) (xy 182.95916 -123.325091) (xy 182.917112 -123.294541)
			(xy 182.880361 -123.25779) (xy 182.849811 -123.215742) (xy 182.826215 -123.169432) (xy 182.810154 -123.120002)
			(xy 182.802024 -123.068667) (xy 181.062374 -123.068667) (xy 181.054244 -123.120002) (xy 181.038183 -123.169432)
			(xy 181.014587 -123.215742) (xy 180.984037 -123.25779) (xy 180.947286 -123.294541) (xy 180.905238 -123.325091)
			(xy 180.858928 -123.348687) (xy 180.809498 -123.364748) (xy 180.758163 -123.372878) (xy 180.706189 -123.372878)
			(xy 180.654854 -123.364748) (xy 180.605424 -123.348687) (xy 180.559114 -123.325091) (xy 180.517066 -123.294541)
			(xy 180.480315 -123.25779) (xy 180.449765 -123.215742) (xy 180.426169 -123.169432) (xy 180.410108 -123.120002)
			(xy 180.401978 -123.068667) (xy 180.262528 -123.068667) (xy 180.254398 -123.120002) (xy 180.238337 -123.169432)
			(xy 180.214741 -123.215742) (xy 180.184191 -123.25779) (xy 180.14744 -123.294541) (xy 180.105392 -123.325091)
			(xy 180.059082 -123.348687) (xy 180.009652 -123.364748) (xy 179.958317 -123.372878) (xy 179.906343 -123.372878)
			(xy 179.855008 -123.364748) (xy 179.805578 -123.348687) (xy 179.759268 -123.325091) (xy 179.71722 -123.294541)
			(xy 179.680469 -123.25779) (xy 179.649919 -123.215742) (xy 179.626323 -123.169432) (xy 179.610262 -123.120002)
			(xy 179.602132 -123.068667) (xy 177.862482 -123.068667) (xy 177.854352 -123.120002) (xy 177.838291 -123.169432)
			(xy 177.814695 -123.215742) (xy 177.784145 -123.25779) (xy 177.747394 -123.294541) (xy 177.705346 -123.325091)
			(xy 177.659036 -123.348687) (xy 177.609606 -123.364748) (xy 177.558271 -123.372878) (xy 177.506297 -123.372878)
			(xy 177.454962 -123.364748) (xy 177.405532 -123.348687) (xy 177.359222 -123.325091) (xy 177.317174 -123.294541)
			(xy 177.280423 -123.25779) (xy 177.249873 -123.215742) (xy 177.226277 -123.169432) (xy 177.210216 -123.120002)
			(xy 177.202086 -123.068667) (xy 177.062382 -123.068667) (xy 177.054252 -123.120002) (xy 177.038191 -123.169432)
			(xy 177.014595 -123.215742) (xy 176.984045 -123.25779) (xy 176.947294 -123.294541) (xy 176.905246 -123.325091)
			(xy 176.858936 -123.348687) (xy 176.809506 -123.364748) (xy 176.758171 -123.372878) (xy 176.706197 -123.372878)
			(xy 176.654862 -123.364748) (xy 176.605432 -123.348687) (xy 176.559122 -123.325091) (xy 176.517074 -123.294541)
			(xy 176.480323 -123.25779) (xy 176.449773 -123.215742) (xy 176.426177 -123.169432) (xy 176.410116 -123.120002)
			(xy 176.401986 -123.068667) (xy 174.267109 -123.068667) (xy 174.303141 -123.107807) (xy 174.339024 -123.157707)
			(xy 174.354236 -123.184412) (xy 174.358907 -123.192163) (xy 174.372567 -123.204012) (xy 174.380906 -123.207526)
			(xy 174.409354 -123.218194) (xy 174.417949 -123.221025) (xy 174.436031 -123.221172) (xy 174.44466 -123.218448)
			(xy 174.47251 -123.208799) (xy 174.529873 -123.195247) (xy 174.588417 -123.188407) (xy 174.617888 -123.187968)
			(xy 174.618142 -123.187968) (xy 174.647966 -123.188417) (xy 174.707203 -123.195414) (xy 174.765213 -123.209297)
			(xy 174.8212 -123.229874) (xy 174.874394 -123.256862) (xy 174.924064 -123.289891) (xy 174.947072 -123.308872)
			(xy 174.954155 -123.314308) (xy 174.970918 -123.320415) (xy 174.979838 -123.32081) (xy 175.010064 -123.32081)
			(xy 175.019079 -123.320434) (xy 175.035996 -123.314199) (xy 175.043084 -123.308618) (xy 175.066204 -123.289296)
			(xy 175.116183 -123.255638) (xy 175.169791 -123.228127) (xy 175.226277 -123.207149) (xy 175.284848 -123.192999)
			(xy 175.34468 -123.185874) (xy 175.374808 -123.185428) (xy 175.406771 -123.185858) (xy 175.470193 -123.193871)
			(xy 175.53211 -123.20977) (xy 175.591547 -123.233303) (xy 175.647565 -123.264101) (xy 175.699282 -123.301676)
			(xy 175.745882 -123.345436) (xy 175.786629 -123.394693) (xy 175.820882 -123.448667) (xy 175.8481 -123.506509)
			(xy 175.867854 -123.567307) (xy 175.879833 -123.6301) (xy 175.883847 -123.6939) (xy 175.879833 -123.7577)
			(xy 175.867854 -123.820493) (xy 175.852169 -123.868767) (xy 176.401986 -123.868767) (xy 176.401986 -123.816793)
			(xy 176.410116 -123.765458) (xy 176.426177 -123.716028) (xy 176.449773 -123.669718) (xy 176.480323 -123.62767)
			(xy 176.517074 -123.590919) (xy 176.559122 -123.560369) (xy 176.605432 -123.536773) (xy 176.654862 -123.520712)
			(xy 176.706197 -123.512582) (xy 176.758171 -123.512582) (xy 176.809506 -123.520712) (xy 176.858936 -123.536773)
			(xy 176.905246 -123.560369) (xy 176.947294 -123.590919) (xy 176.984045 -123.62767) (xy 177.014595 -123.669718)
			(xy 177.038191 -123.716028) (xy 177.054252 -123.765458) (xy 177.062382 -123.816793) (xy 177.062892 -123.84278)
			(xy 177.062382 -123.868767) (xy 177.202086 -123.868767) (xy 177.202086 -123.816793) (xy 177.210216 -123.765458)
			(xy 177.226277 -123.716028) (xy 177.249873 -123.669718) (xy 177.280423 -123.62767) (xy 177.317174 -123.590919)
			(xy 177.359222 -123.560369) (xy 177.405532 -123.536773) (xy 177.454962 -123.520712) (xy 177.506297 -123.512582)
			(xy 177.558271 -123.512582) (xy 177.609606 -123.520712) (xy 177.659036 -123.536773) (xy 177.705346 -123.560369)
			(xy 177.747394 -123.590919) (xy 177.784145 -123.62767) (xy 177.814695 -123.669718) (xy 177.838291 -123.716028)
			(xy 177.854352 -123.765458) (xy 177.862482 -123.816793) (xy 177.862992 -123.84278) (xy 177.862482 -123.868767)
			(xy 183.602124 -123.868767) (xy 183.602124 -123.816793) (xy 183.610254 -123.765458) (xy 183.626315 -123.716028)
			(xy 183.649911 -123.669718) (xy 183.680461 -123.62767) (xy 183.717212 -123.590919) (xy 183.75926 -123.560369)
			(xy 183.80557 -123.536773) (xy 183.855 -123.520712) (xy 183.906335 -123.512582) (xy 183.958309 -123.512582)
			(xy 184.009644 -123.520712) (xy 184.059074 -123.536773) (xy 184.105384 -123.560369) (xy 184.147432 -123.590919)
			(xy 184.184183 -123.62767) (xy 184.214733 -123.669718) (xy 184.238329 -123.716028) (xy 184.25439 -123.765458)
			(xy 184.26252 -123.816793) (xy 184.26303 -123.84278) (xy 184.26252 -123.868767) (xy 184.40197 -123.868767)
			(xy 184.40197 -123.816793) (xy 184.4101 -123.765458) (xy 184.426161 -123.716028) (xy 184.449757 -123.669718)
			(xy 184.480307 -123.62767) (xy 184.517058 -123.590919) (xy 184.559106 -123.560369) (xy 184.605416 -123.536773)
			(xy 184.654846 -123.520712) (xy 184.706181 -123.512582) (xy 184.758155 -123.512582) (xy 184.80949 -123.520712)
			(xy 184.85892 -123.536773) (xy 184.90523 -123.560369) (xy 184.947278 -123.590919) (xy 184.984029 -123.62767)
			(xy 185.014579 -123.669718) (xy 185.038175 -123.716028) (xy 185.054236 -123.765458) (xy 185.062366 -123.816793)
			(xy 185.062876 -123.84278) (xy 185.062366 -123.868767) (xy 186.781696 -123.868767) (xy 186.781696 -123.816793)
			(xy 186.789826 -123.765458) (xy 186.805887 -123.716028) (xy 186.829483 -123.669718) (xy 186.860033 -123.62767)
			(xy 186.896784 -123.590919) (xy 186.938832 -123.560369) (xy 186.985142 -123.536773) (xy 187.034572 -123.520712)
			(xy 187.085907 -123.512582) (xy 187.137881 -123.512582) (xy 187.189216 -123.520712) (xy 187.238646 -123.536773)
			(xy 187.284956 -123.560369) (xy 187.327004 -123.590919) (xy 187.363755 -123.62767) (xy 187.394305 -123.669718)
			(xy 187.417901 -123.716028) (xy 187.433962 -123.765458) (xy 187.442092 -123.816793) (xy 187.442602 -123.84278)
			(xy 187.442092 -123.868767) (xy 187.433962 -123.920102) (xy 187.417901 -123.969532) (xy 187.394305 -124.015842)
			(xy 187.363755 -124.05789) (xy 187.327004 -124.094641) (xy 187.284956 -124.125191) (xy 187.238646 -124.148787)
			(xy 187.189216 -124.164848) (xy 187.137881 -124.172978) (xy 187.085907 -124.172978) (xy 187.034572 -124.164848)
			(xy 186.985142 -124.148787) (xy 186.938832 -124.125191) (xy 186.896784 -124.094641) (xy 186.860033 -124.05789)
			(xy 186.829483 -124.015842) (xy 186.805887 -123.969532) (xy 186.789826 -123.920102) (xy 186.781696 -123.868767)
			(xy 185.062366 -123.868767) (xy 185.054236 -123.920102) (xy 185.038175 -123.969532) (xy 185.014579 -124.015842)
			(xy 184.984029 -124.05789) (xy 184.947278 -124.094641) (xy 184.90523 -124.125191) (xy 184.85892 -124.148787)
			(xy 184.80949 -124.164848) (xy 184.758155 -124.172978) (xy 184.706181 -124.172978) (xy 184.654846 -124.164848)
			(xy 184.605416 -124.148787) (xy 184.559106 -124.125191) (xy 184.517058 -124.094641) (xy 184.480307 -124.05789)
			(xy 184.449757 -124.015842) (xy 184.426161 -123.969532) (xy 184.4101 -123.920102) (xy 184.40197 -123.868767)
			(xy 184.26252 -123.868767) (xy 184.25439 -123.920102) (xy 184.238329 -123.969532) (xy 184.214733 -124.015842)
			(xy 184.184183 -124.05789) (xy 184.147432 -124.094641) (xy 184.105384 -124.125191) (xy 184.059074 -124.148787)
			(xy 184.009644 -124.164848) (xy 183.958309 -124.172978) (xy 183.906335 -124.172978) (xy 183.855 -124.164848)
			(xy 183.80557 -124.148787) (xy 183.75926 -124.125191) (xy 183.717212 -124.094641) (xy 183.680461 -124.05789)
			(xy 183.649911 -124.015842) (xy 183.626315 -123.969532) (xy 183.610254 -123.920102) (xy 183.602124 -123.868767)
			(xy 177.862482 -123.868767) (xy 177.854352 -123.920102) (xy 177.838291 -123.969532) (xy 177.814695 -124.015842)
			(xy 177.784145 -124.05789) (xy 177.747394 -124.094641) (xy 177.705346 -124.125191) (xy 177.659036 -124.148787)
			(xy 177.609606 -124.164848) (xy 177.558271 -124.172978) (xy 177.506297 -124.172978) (xy 177.454962 -124.164848)
			(xy 177.405532 -124.148787) (xy 177.359222 -124.125191) (xy 177.317174 -124.094641) (xy 177.280423 -124.05789)
			(xy 177.249873 -124.015842) (xy 177.226277 -123.969532) (xy 177.210216 -123.920102) (xy 177.202086 -123.868767)
			(xy 177.062382 -123.868767) (xy 177.054252 -123.920102) (xy 177.038191 -123.969532) (xy 177.014595 -124.015842)
			(xy 176.984045 -124.05789) (xy 176.947294 -124.094641) (xy 176.905246 -124.125191) (xy 176.858936 -124.148787)
			(xy 176.809506 -124.164848) (xy 176.758171 -124.172978) (xy 176.706197 -124.172978) (xy 176.654862 -124.164848)
			(xy 176.605432 -124.148787) (xy 176.559122 -124.125191) (xy 176.517074 -124.094641) (xy 176.480323 -124.05789)
			(xy 176.449773 -124.015842) (xy 176.426177 -123.969532) (xy 176.410116 -123.920102) (xy 176.401986 -123.868767)
			(xy 175.852169 -123.868767) (xy 175.8481 -123.881291) (xy 175.820882 -123.939133) (xy 175.786629 -123.993107)
			(xy 175.745882 -124.042364) (xy 175.699282 -124.086124) (xy 175.647565 -124.123699) (xy 175.591547 -124.154497)
			(xy 175.53211 -124.17803) (xy 175.470193 -124.193929) (xy 175.406771 -124.201942) (xy 175.374808 -124.202444)
			(xy 175.374554 -124.202444) (xy 175.34473 -124.201995) (xy 175.285493 -124.194997) (xy 175.227483 -124.181114)
			(xy 175.171496 -124.160537) (xy 175.118302 -124.133549) (xy 175.068632 -124.100521) (xy 175.045624 -124.08154)
			(xy 175.038541 -124.076104) (xy 175.021778 -124.069997) (xy 175.012858 -124.069602) (xy 174.982632 -124.069602)
			(xy 174.973617 -124.069974) (xy 174.956699 -124.076211) (xy 174.949612 -124.081794) (xy 174.926495 -124.10112)
			(xy 174.876515 -124.134777) (xy 174.822906 -124.162287) (xy 174.76642 -124.183264) (xy 174.707849 -124.197414)
			(xy 174.648016 -124.204539) (xy 174.617888 -124.204984) (xy 174.587703 -124.204539) (xy 174.527758 -124.197386)
			(xy 174.469082 -124.183183) (xy 174.412502 -124.162129) (xy 174.358814 -124.134521) (xy 174.308775 -124.100747)
			(xy 174.263089 -124.061284) (xy 174.222399 -124.016687) (xy 174.187279 -123.967583) (xy 174.172372 -123.941332)
			(xy 174.167713 -123.933573) (xy 174.154044 -123.921729) (xy 174.145702 -123.918218) (xy 174.117254 -123.90755)
			(xy 174.10867 -123.904674) (xy 174.090578 -123.904558) (xy 174.081948 -123.907296) (xy 174.054098 -123.916945)
			(xy 173.996735 -123.930496) (xy 173.938191 -123.937336) (xy 173.90872 -123.937776) (xy 173.877987 -123.937343)
			(xy 173.816969 -123.929937) (xy 173.757289 -123.915228) (xy 173.699817 -123.893433) (xy 173.645392 -123.864869)
			(xy 173.594806 -123.829952) (xy 173.548799 -123.789193) (xy 173.50804 -123.743184) (xy 173.473125 -123.692598)
			(xy 173.444562 -123.638172) (xy 173.422768 -123.580699) (xy 173.408061 -123.521019) (xy 173.400656 -123.460001)
			(xy 173.400212 -123.429268) (xy 169.149268 -123.429268) (xy 170.527683 -124.807683) (xy 172.259492 -124.807683)
			(xy 172.259492 -124.743761) (xy 172.267503 -124.680343) (xy 172.2834 -124.618429) (xy 172.306932 -124.558996)
			(xy 172.337726 -124.502981) (xy 172.375299 -124.451266) (xy 172.419056 -124.404669) (xy 172.468309 -124.363924)
			(xy 172.52228 -124.329673) (xy 172.580119 -124.302456) (xy 172.640912 -124.282703) (xy 172.703702 -124.270725)
			(xy 172.767498 -124.266712) (xy 172.831294 -124.270725) (xy 172.894084 -124.282703) (xy 172.954877 -124.302456)
			(xy 173.012716 -124.329673) (xy 173.066687 -124.363924) (xy 173.11594 -124.404669) (xy 173.159697 -124.451266)
			(xy 173.17896 -124.47778) (xy 188.381386 -124.47778) (xy 188.381935 -124.45048) (xy 188.390895 -124.39662)
			(xy 188.408602 -124.34497) (xy 188.43457 -124.296941) (xy 188.468093 -124.253843) (xy 188.487812 -124.234956)
			(xy 188.49513 -124.227393) (xy 188.503537 -124.208127) (xy 188.504068 -124.197618) (xy 188.504068 -124.122942)
			(xy 188.503581 -124.11242) (xy 188.495184 -124.093128) (xy 188.487812 -124.085604) (xy 188.468139 -124.066678)
			(xy 188.434663 -124.023561) (xy 188.408712 -123.975538) (xy 188.390989 -123.923909) (xy 188.381975 -123.870072)
			(xy 188.381386 -123.84278) (xy 188.381896 -123.816793) (xy 188.390026 -123.765458) (xy 188.406087 -123.716028)
			(xy 188.429683 -123.669718) (xy 188.460233 -123.62767) (xy 188.496984 -123.590919) (xy 188.539032 -123.560369)
			(xy 188.585342 -123.536773) (xy 188.634772 -123.520712) (xy 188.686107 -123.512582) (xy 188.738081 -123.512582)
			(xy 188.789416 -123.520712) (xy 188.838846 -123.536773) (xy 188.885156 -123.560369) (xy 188.927204 -123.590919)
			(xy 188.963955 -123.62767) (xy 188.994505 -123.669718) (xy 189.018101 -123.716028) (xy 189.034162 -123.765458)
			(xy 189.042292 -123.816793) (xy 189.042802 -123.84278) (xy 189.04232 -123.868767) (xy 190.781688 -123.868767)
			(xy 190.781688 -123.816793) (xy 190.789818 -123.765458) (xy 190.805879 -123.716028) (xy 190.829475 -123.669718)
			(xy 190.860025 -123.62767) (xy 190.896776 -123.590919) (xy 190.938824 -123.560369) (xy 190.985134 -123.536773)
			(xy 191.034564 -123.520712) (xy 191.085899 -123.512582) (xy 191.137873 -123.512582) (xy 191.189208 -123.520712)
			(xy 191.238638 -123.536773) (xy 191.284948 -123.560369) (xy 191.326996 -123.590919) (xy 191.363747 -123.62767)
			(xy 191.394297 -123.669718) (xy 191.417893 -123.716028) (xy 191.433954 -123.765458) (xy 191.442084 -123.816793)
			(xy 191.442594 -123.84278) (xy 191.442084 -123.868767) (xy 193.981834 -123.868767) (xy 193.981834 -123.816793)
			(xy 193.989964 -123.765458) (xy 194.006025 -123.716028) (xy 194.029621 -123.669718) (xy 194.060171 -123.62767)
			(xy 194.096922 -123.590919) (xy 194.13897 -123.560369) (xy 194.18528 -123.536773) (xy 194.23471 -123.520712)
			(xy 194.286045 -123.512582) (xy 194.338019 -123.512582) (xy 194.389354 -123.520712) (xy 194.438784 -123.536773)
			(xy 194.485094 -123.560369) (xy 194.527142 -123.590919) (xy 194.563893 -123.62767) (xy 194.594443 -123.669718)
			(xy 194.618039 -123.716028) (xy 194.6341 -123.765458) (xy 194.64223 -123.816793) (xy 194.64274 -123.84278)
			(xy 194.64223 -123.868767) (xy 194.6341 -123.920102) (xy 194.618039 -123.969532) (xy 194.594443 -124.015842)
			(xy 194.563893 -124.05789) (xy 194.527142 -124.094641) (xy 194.485094 -124.125191) (xy 194.438784 -124.148787)
			(xy 194.389354 -124.164848) (xy 194.338019 -124.172978) (xy 194.286045 -124.172978) (xy 194.23471 -124.164848)
			(xy 194.18528 -124.148787) (xy 194.13897 -124.125191) (xy 194.096922 -124.094641) (xy 194.060171 -124.05789)
			(xy 194.029621 -124.015842) (xy 194.006025 -123.969532) (xy 193.989964 -123.920102) (xy 193.981834 -123.868767)
			(xy 191.442084 -123.868767) (xy 191.433954 -123.920102) (xy 191.417893 -123.969532) (xy 191.394297 -124.015842)
			(xy 191.363747 -124.05789) (xy 191.326996 -124.094641) (xy 191.284948 -124.125191) (xy 191.238638 -124.148787)
			(xy 191.189208 -124.164848) (xy 191.137873 -124.172978) (xy 191.085899 -124.172978) (xy 191.034564 -124.164848)
			(xy 190.985134 -124.148787) (xy 190.938824 -124.125191) (xy 190.896776 -124.094641) (xy 190.860025 -124.05789)
			(xy 190.829475 -124.015842) (xy 190.805879 -123.969532) (xy 190.789818 -123.920102) (xy 190.781688 -123.868767)
			(xy 189.04232 -123.868767) (xy 189.042296 -123.870082) (xy 189.033326 -123.923944) (xy 189.015609 -123.975594)
			(xy 188.989631 -124.023623) (xy 188.9561 -124.066718) (xy 188.936376 -124.085604) (xy 188.929029 -124.093143)
			(xy 188.92064 -124.112428) (xy 188.92012 -124.122942) (xy 188.92012 -124.197618) (xy 188.920632 -124.208138)
			(xy 188.929012 -124.22743) (xy 188.936376 -124.234956) (xy 188.956027 -124.253903) (xy 188.989506 -124.297014)
			(xy 189.015461 -124.345032) (xy 189.033189 -124.396656) (xy 189.04221 -124.450489) (xy 189.042802 -124.47778)
			(xy 189.042292 -124.503767) (xy 189.034162 -124.555102) (xy 189.018101 -124.604532) (xy 188.994505 -124.650842)
			(xy 188.963955 -124.69289) (xy 188.930907 -124.725938) (xy 195.678552 -124.725938) (xy 195.679058 -124.693167)
			(xy 195.687497 -124.62817) (xy 195.704215 -124.564796) (xy 195.728935 -124.504094) (xy 195.761247 -124.44707)
			(xy 195.800617 -124.394669) (xy 195.84639 -124.347759) (xy 195.897811 -124.307117) (xy 195.954025 -124.273416)
			(xy 195.98386 -124.259848) (xy 195.984114 -124.259848) (xy 195.992224 -124.255773) (xy 196.005177 -124.24308)
			(xy 196.01293 -124.226685) (xy 196.014086 -124.217684) (xy 196.02196 -124.128784) (xy 196.022379 -124.11967)
			(xy 196.017505 -124.102103) (xy 196.006762 -124.087373) (xy 195.999354 -124.082048) (xy 195.978744 -124.0678)
			(xy 195.941314 -124.034493) (xy 195.908922 -123.99627) (xy 195.882207 -123.953884) (xy 195.861695 -123.908172)
			(xy 195.847793 -123.860036) (xy 195.840774 -123.810427) (xy 195.84035 -123.785376) (xy 195.840848 -123.758727)
			(xy 195.848791 -123.706023) (xy 195.864501 -123.655093) (xy 195.887627 -123.607072) (xy 195.917651 -123.563035)
			(xy 195.953903 -123.523964) (xy 195.995574 -123.490733) (xy 196.041732 -123.464084) (xy 196.091346 -123.444612)
			(xy 196.143308 -123.432752) (xy 196.196458 -123.428769) (xy 196.249608 -123.432752) (xy 196.30157 -123.444612)
			(xy 196.351184 -123.464084) (xy 196.397342 -123.490733) (xy 196.439013 -123.523964) (xy 196.475265 -123.563035)
			(xy 196.505289 -123.607072) (xy 196.528415 -123.655093) (xy 196.544125 -123.706023) (xy 196.552068 -123.758727)
			(xy 196.552566 -123.785376) (xy 196.552133 -123.810938) (xy 196.544801 -123.861533) (xy 196.530312 -123.910561)
			(xy 196.508965 -123.957015) (xy 196.481197 -123.99994) (xy 196.447579 -124.038456) (xy 196.408801 -124.071771)
			(xy 196.387466 -124.085858) (xy 196.380017 -124.091073) (xy 196.369084 -124.105587) (xy 196.363878 -124.122996)
			(xy 196.364098 -124.132086) (xy 196.370194 -124.22124) (xy 196.371203 -124.230256) (xy 196.378658 -124.246781)
			(xy 196.391362 -124.259714) (xy 196.399404 -124.263912) (xy 196.399658 -124.263912) (xy 196.4287 -124.277843)
			(xy 196.483342 -124.311949) (xy 196.53324 -124.352681) (xy 196.557707 -124.378445) (xy 198.079858 -124.378445)
			(xy 198.079858 -124.325147) (xy 198.087801 -124.272443) (xy 198.103511 -124.221513) (xy 198.126637 -124.173492)
			(xy 198.156661 -124.129455) (xy 198.192913 -124.090384) (xy 198.234584 -124.057153) (xy 198.280742 -124.030504)
			(xy 198.330356 -124.011032) (xy 198.382318 -123.999172) (xy 198.435468 -123.995189) (xy 198.488618 -123.999172)
			(xy 198.54058 -124.011032) (xy 198.590194 -124.030504) (xy 198.636352 -124.057153) (xy 198.678023 -124.090384)
			(xy 198.714275 -124.129455) (xy 198.744299 -124.173492) (xy 198.767425 -124.221513) (xy 198.783135 -124.272443)
			(xy 198.791078 -124.325147) (xy 198.791576 -124.351796) (xy 198.791078 -124.378445) (xy 198.783135 -124.431149)
			(xy 198.767425 -124.482079) (xy 198.744299 -124.5301) (xy 198.714275 -124.574137) (xy 198.678023 -124.613208)
			(xy 198.636352 -124.646439) (xy 198.604316 -124.664935) (xy 199.413362 -124.664935) (xy 199.413362 -124.601013)
			(xy 199.421373 -124.537595) (xy 199.43727 -124.475681) (xy 199.460802 -124.416248) (xy 199.491596 -124.360233)
			(xy 199.529169 -124.308518) (xy 199.572926 -124.261921) (xy 199.622179 -124.221176) (xy 199.67615 -124.186925)
			(xy 199.733989 -124.159708) (xy 199.794782 -124.139955) (xy 199.857572 -124.127977) (xy 199.921368 -124.123964)
			(xy 199.985164 -124.127977) (xy 200.047954 -124.139955) (xy 200.108747 -124.159708) (xy 200.166586 -124.186925)
			(xy 200.220557 -124.221176) (xy 200.26981 -124.261921) (xy 200.313567 -124.308518) (xy 200.35114 -124.360233)
			(xy 200.381934 -124.416248) (xy 200.405466 -124.475681) (xy 200.421363 -124.537595) (xy 200.429374 -124.601013)
			(xy 200.429876 -124.632974) (xy 200.429374 -124.664935) (xy 200.421363 -124.728353) (xy 200.405466 -124.790267)
			(xy 200.401067 -124.801376) (xy 203.136754 -124.801376) (xy 203.137252 -124.76891) (xy 203.145509 -124.704505)
			(xy 203.161899 -124.641675) (xy 203.186154 -124.581444) (xy 203.21788 -124.52479) (xy 203.25656 -124.472637)
			(xy 203.301566 -124.425832) (xy 203.352164 -124.385138) (xy 203.407532 -124.351218) (xy 203.466767 -124.324622)
			(xy 203.497688 -124.314712) (xy 203.505967 -124.311813) (xy 203.520056 -124.301392) (xy 203.529775 -124.286809)
			(xy 203.532232 -124.27839) (xy 203.556616 -124.1806) (xy 203.549758 -124.1552) (xy 203.540106 -124.145548)
			(xy 203.516864 -124.1216) (xy 203.476148 -124.068725) (xy 203.442699 -124.010978) (xy 203.417094 -123.949351)
			(xy 203.399772 -123.884903) (xy 203.391031 -123.818743) (xy 203.3905 -123.785376) (xy 203.391002 -123.753415)
			(xy 203.399013 -123.689997) (xy 203.41491 -123.628083) (xy 203.438442 -123.56865) (xy 203.469236 -123.512635)
			(xy 203.506809 -123.46092) (xy 203.550566 -123.414323) (xy 203.599819 -123.373578) (xy 203.65379 -123.339327)
			(xy 203.711629 -123.31211) (xy 203.772422 -123.292357) (xy 203.835212 -123.280379) (xy 203.899008 -123.276366)
			(xy 203.962804 -123.280379) (xy 204.025594 -123.292357) (xy 204.086387 -123.31211) (xy 204.144226 -123.339327)
			(xy 204.198197 -123.373578) (xy 204.24745 -123.414323) (xy 204.291207 -123.46092) (xy 204.32878 -123.512635)
			(xy 204.359574 -123.56865) (xy 204.383106 -123.628083) (xy 204.399003 -123.689997) (xy 204.407014 -123.753415)
			(xy 204.407069 -123.756928) (xy 207.244186 -123.756928) (xy 207.248257 -123.701306) (xy 207.260383 -123.646869)
			(xy 207.280306 -123.594778) (xy 207.307602 -123.546143) (xy 207.341688 -123.502) (xy 207.381837 -123.463291)
			(xy 207.427195 -123.43084) (xy 207.476795 -123.405339) (xy 207.529579 -123.387332) (xy 207.584422 -123.377202)
			(xy 207.640156 -123.375165) (xy 207.695593 -123.381265) (xy 207.74955 -123.395371) (xy 207.800879 -123.417183)
			(xy 207.848485 -123.446237) (xy 207.891353 -123.481912) (xy 207.92857 -123.523449) (xy 207.959343 -123.569962)
			(xy 207.983015 -123.620459) (xy 207.999083 -123.673866) (xy 208.007203 -123.729042) (xy 208.007712 -123.756928)
			(xy 208.007203 -123.784814) (xy 207.999083 -123.83999) (xy 207.983015 -123.893397) (xy 207.959343 -123.943894)
			(xy 207.92857 -123.990407) (xy 207.891353 -124.031944) (xy 207.848485 -124.067619) (xy 207.800879 -124.096673)
			(xy 207.74955 -124.118485) (xy 207.695593 -124.132591) (xy 207.640156 -124.138691) (xy 207.584422 -124.136654)
			(xy 207.529579 -124.126524) (xy 207.476795 -124.108517) (xy 207.427195 -124.083016) (xy 207.381837 -124.050565)
			(xy 207.341688 -124.011856) (xy 207.307602 -123.967713) (xy 207.280306 -123.919078) (xy 207.260383 -123.866987)
			(xy 207.248257 -123.81255) (xy 207.244186 -123.756928) (xy 204.407069 -123.756928) (xy 204.407516 -123.785376)
			(xy 204.406996 -123.817842) (xy 204.398745 -123.882247) (xy 204.38236 -123.945077) (xy 204.358108 -124.005309)
			(xy 204.326385 -124.061964) (xy 204.287707 -124.114118) (xy 204.242702 -124.160923) (xy 204.192105 -124.201616)
			(xy 204.136738 -124.235537) (xy 204.100222 -124.251931) (xy 209.549994 -124.251931) (xy 209.549994 -124.188009)
			(xy 209.558005 -124.124591) (xy 209.573902 -124.062677) (xy 209.597434 -124.003244) (xy 209.628228 -123.947229)
			(xy 209.665801 -123.895514) (xy 209.709558 -123.848917) (xy 209.758811 -123.808172) (xy 209.812782 -123.773921)
			(xy 209.870621 -123.746704) (xy 209.931414 -123.726951) (xy 209.994204 -123.714973) (xy 210.058 -123.71096)
			(xy 210.121796 -123.714973) (xy 210.184586 -123.726951) (xy 210.245379 -123.746704) (xy 210.303218 -123.773921)
			(xy 210.357189 -123.808172) (xy 210.406442 -123.848917) (xy 210.450199 -123.895514) (xy 210.487772 -123.947229)
			(xy 210.518566 -124.003244) (xy 210.542098 -124.062677) (xy 210.557995 -124.124591) (xy 210.566006 -124.188009)
			(xy 210.566508 -124.21997) (xy 210.566006 -124.251931) (xy 210.557995 -124.315349) (xy 210.542098 -124.377263)
			(xy 210.518566 -124.436696) (xy 210.487772 -124.492711) (xy 210.450199 -124.544426) (xy 210.406442 -124.591023)
			(xy 210.357189 -124.631768) (xy 210.303218 -124.666019) (xy 210.245379 -124.693236) (xy 210.184586 -124.712989)
			(xy 210.121796 -124.724967) (xy 210.058 -124.728981) (xy 209.994204 -124.724967) (xy 209.931414 -124.712989)
			(xy 209.870621 -124.693236) (xy 209.812782 -124.666019) (xy 209.758811 -124.631768) (xy 209.709558 -124.591023)
			(xy 209.665801 -124.544426) (xy 209.628228 -124.492711) (xy 209.597434 -124.436696) (xy 209.573902 -124.377263)
			(xy 209.558005 -124.315349) (xy 209.549994 -124.251931) (xy 204.100222 -124.251931) (xy 204.077503 -124.262131)
			(xy 204.046582 -124.27204) (xy 204.038284 -124.274892) (xy 204.024197 -124.285334) (xy 204.014488 -124.299935)
			(xy 204.012038 -124.308362) (xy 203.987654 -124.406152) (xy 203.994512 -124.431552) (xy 204.004164 -124.441204)
			(xy 204.027444 -124.465116) (xy 204.068154 -124.518) (xy 204.101595 -124.575756) (xy 204.127193 -124.63739)
			(xy 204.144508 -124.701843) (xy 204.153243 -124.768007) (xy 204.15377 -124.801376) (xy 204.153252 -124.83258)
			(xy 204.145603 -124.894517) (xy 204.145021 -124.896837) (xy 207.109816 -124.896837) (xy 207.109816 -124.832915)
			(xy 207.117827 -124.769497) (xy 207.133724 -124.707583) (xy 207.157256 -124.64815) (xy 207.18805 -124.592135)
			(xy 207.225623 -124.54042) (xy 207.26938 -124.493823) (xy 207.318633 -124.453078) (xy 207.372604 -124.418827)
			(xy 207.430443 -124.39161) (xy 207.491236 -124.371857) (xy 207.554026 -124.359879) (xy 207.617822 -124.355866)
			(xy 207.681618 -124.359879) (xy 207.744408 -124.371857) (xy 207.805201 -124.39161) (xy 207.86304 -124.418827)
			(xy 207.917011 -124.453078) (xy 207.966264 -124.493823) (xy 208.010021 -124.54042) (xy 208.047594 -124.592135)
			(xy 208.078388 -124.64815) (xy 208.10192 -124.707583) (xy 208.117817 -124.769497) (xy 208.125828 -124.832915)
			(xy 208.12633 -124.864876) (xy 208.125828 -124.896837) (xy 208.117817 -124.960255) (xy 208.10192 -125.022169)
			(xy 208.078388 -125.081602) (xy 208.047594 -125.137617) (xy 208.010021 -125.189332) (xy 207.966264 -125.235929)
			(xy 207.917011 -125.276674) (xy 207.86304 -125.310925) (xy 207.805201 -125.338142) (xy 207.744408 -125.357895)
			(xy 207.681618 -125.369873) (xy 207.617822 -125.373887) (xy 207.554026 -125.369873) (xy 207.491236 -125.357895)
			(xy 207.430443 -125.338142) (xy 207.372604 -125.310925) (xy 207.318633 -125.276674) (xy 207.26938 -125.235929)
			(xy 207.225623 -125.189332) (xy 207.18805 -125.137617) (xy 207.157256 -125.081602) (xy 207.133724 -125.022169)
			(xy 207.117827 -124.960255) (xy 207.109816 -124.896837) (xy 204.145021 -124.896837) (xy 204.130429 -124.955052)
			(xy 204.107958 -125.013274) (xy 204.078528 -125.068307) (xy 204.042582 -125.119324) (xy 204.000661 -125.165556)
			(xy 203.953396 -125.206308) (xy 203.92771 -125.224032) (xy 203.917558 -125.231553) (xy 203.905699 -125.253828)
			(xy 203.905104 -125.26645) (xy 203.905612 -125.351286) (xy 203.906252 -125.363741) (xy 203.917982 -125.385718)
			(xy 203.927964 -125.393196) (xy 203.927964 -125.39345) (xy 203.928472 -125.39345) (xy 203.954342 -125.411136)
			(xy 204.001919 -125.451927) (xy 204.044125 -125.498253) (xy 204.080321 -125.549412) (xy 204.109959 -125.60463)
			(xy 204.132591 -125.66307) (xy 204.147872 -125.723847) (xy 204.155573 -125.786041) (xy 204.156056 -125.817376)
			(xy 206.022448 -125.817376) (xy 206.02295 -125.785415) (xy 206.030961 -125.721997) (xy 206.046858 -125.660083)
			(xy 206.07039 -125.60065) (xy 206.101184 -125.544635) (xy 206.138757 -125.49292) (xy 206.182514 -125.446323)
			(xy 206.231767 -125.405578) (xy 206.285738 -125.371327) (xy 206.343577 -125.34411) (xy 206.40437 -125.324357)
			(xy 206.46716 -125.312379) (xy 206.530956 -125.308366) (xy 206.594752 -125.312379) (xy 206.657542 -125.324357)
			(xy 206.718335 -125.34411) (xy 206.776174 -125.371327) (xy 206.830145 -125.405578) (xy 206.879398 -125.446323)
			(xy 206.923155 -125.49292) (xy 206.960728 -125.544635) (xy 206.991522 -125.60065) (xy 207.015054 -125.660083)
			(xy 207.030951 -125.721997) (xy 207.038962 -125.785415) (xy 207.039464 -125.817376) (xy 207.039075 -125.846813)
			(xy 207.032271 -125.905293) (xy 207.01875 -125.962593) (xy 206.998695 -126.017946) (xy 206.972374 -126.070609)
			(xy 206.971734 -126.071587) (xy 207.262978 -126.071587) (xy 207.262978 -126.007665) (xy 207.270989 -125.944247)
			(xy 207.286886 -125.882333) (xy 207.310418 -125.8229) (xy 207.341212 -125.766885) (xy 207.378785 -125.71517)
			(xy 207.422542 -125.668573) (xy 207.471795 -125.627828) (xy 207.525766 -125.593577) (xy 207.583605 -125.56636)
			(xy 207.644398 -125.546607) (xy 207.707188 -125.534629) (xy 207.770984 -125.530616) (xy 207.83478 -125.534629)
			(xy 207.89757 -125.546607) (xy 207.958363 -125.56636) (xy 208.016202 -125.593577) (xy 208.070173 -125.627828)
			(xy 208.119426 -125.668573) (xy 208.163183 -125.71517) (xy 208.200756 -125.766885) (xy 208.23155 -125.8229)
			(xy 208.255082 -125.882333) (xy 208.270979 -125.944247) (xy 208.27899 -126.007665) (xy 208.279492 -126.039626)
			(xy 208.27899 -126.071587) (xy 208.270979 -126.135005) (xy 208.255082 -126.196919) (xy 208.23155 -126.256352)
			(xy 208.200756 -126.312367) (xy 208.163183 -126.364082) (xy 208.119426 -126.410679) (xy 208.070173 -126.451424)
			(xy 208.016202 -126.485675) (xy 207.958363 -126.512892) (xy 207.89757 -126.532645) (xy 207.83478 -126.544623)
			(xy 207.770984 -126.548637) (xy 207.707188 -126.544623) (xy 207.644398 -126.532645) (xy 207.583605 -126.512892)
			(xy 207.525766 -126.485675) (xy 207.471795 -126.451424) (xy 207.422542 -126.410679) (xy 207.378785 -126.364082)
			(xy 207.341212 -126.312367) (xy 207.310418 -126.256352) (xy 207.286886 -126.196919) (xy 207.270989 -126.135005)
			(xy 207.262978 -126.071587) (xy 206.971734 -126.071587) (xy 206.94014 -126.119875) (xy 206.921608 -126.14275)
			(xy 206.916061 -126.150049) (xy 206.910079 -126.167365) (xy 206.909924 -126.176532) (xy 206.910686 -126.207012)
			(xy 206.91133 -126.216137) (xy 206.918222 -126.233065) (xy 206.924148 -126.240032) (xy 206.945102 -126.263534)
			(xy 206.981616 -126.314833) (xy 207.011519 -126.370247) (xy 207.034354 -126.428928) (xy 207.049772 -126.489978)
			(xy 207.057538 -126.552464) (xy 207.058006 -126.583948) (xy 207.057504 -126.615909) (xy 207.049493 -126.679327)
			(xy 207.033596 -126.741241) (xy 207.010064 -126.800674) (xy 206.97927 -126.856689) (xy 206.941697 -126.908404)
			(xy 206.89794 -126.955001) (xy 206.848687 -126.995746) (xy 206.794716 -127.029997) (xy 206.736877 -127.057214)
			(xy 206.676084 -127.076967) (xy 206.613294 -127.088945) (xy 206.549498 -127.092959) (xy 206.485702 -127.088945)
			(xy 206.422912 -127.076967) (xy 206.362119 -127.057214) (xy 206.30428 -127.029997) (xy 206.250309 -126.995746)
			(xy 206.201056 -126.955001) (xy 206.157299 -126.908404) (xy 206.119726 -126.856689) (xy 206.088932 -126.800674)
			(xy 206.0654 -126.741241) (xy 206.049503 -126.679327) (xy 206.041492 -126.615909) (xy 206.04099 -126.583948)
			(xy 206.041403 -126.554512) (xy 206.048204 -126.496034) (xy 206.061721 -126.438734) (xy 206.081772 -126.383381)
			(xy 206.108088 -126.330718) (xy 206.140316 -126.28145) (xy 206.158846 -126.258574) (xy 206.164377 -126.251265)
			(xy 206.17037 -126.233956) (xy 206.17053 -126.224792) (xy 206.169768 -126.194312) (xy 206.169171 -126.185181)
			(xy 206.162247 -126.168254) (xy 206.156306 -126.161292) (xy 206.135356 -126.137787) (xy 206.098843 -126.086488)
			(xy 206.06894 -126.031074) (xy 206.046105 -125.972394) (xy 206.030685 -125.911345) (xy 206.022918 -125.848859)
			(xy 206.022448 -125.817376) (xy 204.156056 -125.817376) (xy 204.155554 -125.849337) (xy 204.147543 -125.912755)
			(xy 204.131646 -125.974669) (xy 204.108114 -126.034102) (xy 204.07732 -126.090117) (xy 204.039747 -126.141832)
			(xy 203.99599 -126.188429) (xy 203.946737 -126.229174) (xy 203.892766 -126.263425) (xy 203.834927 -126.290642)
			(xy 203.774134 -126.310395) (xy 203.711344 -126.322373) (xy 203.647548 -126.326387) (xy 203.583752 -126.322373)
			(xy 203.520962 -126.310395) (xy 203.460169 -126.290642) (xy 203.40233 -126.263425) (xy 203.348359 -126.229174)
			(xy 203.299106 -126.188429) (xy 203.255349 -126.141832) (xy 203.217776 -126.090117) (xy 203.186982 -126.034102)
			(xy 203.16345 -125.974669) (xy 203.147553 -125.912755) (xy 203.139542 -125.849337) (xy 203.13904 -125.817376)
			(xy 203.139516 -125.786171) (xy 203.147172 -125.724232) (xy 203.162352 -125.663695) (xy 203.184829 -125.605473)
			(xy 203.214264 -125.55044) (xy 203.250216 -125.499424) (xy 203.292142 -125.453194) (xy 203.339412 -125.412443)
			(xy 203.3651 -125.39472) (xy 203.37523 -125.387175) (xy 203.3871 -125.364918) (xy 203.387706 -125.352302)
			(xy 203.387198 -125.267466) (xy 203.386523 -125.255016) (xy 203.374817 -125.233039) (xy 203.364846 -125.225556)
			(xy 203.364846 -125.225302) (xy 203.364338 -125.225302) (xy 203.338495 -125.207579) (xy 203.290917 -125.166794)
			(xy 203.248709 -125.120474) (xy 203.21251 -125.06932) (xy 203.182869 -125.014108) (xy 203.160233 -124.955672)
			(xy 203.144946 -124.894899) (xy 203.13724 -124.832709) (xy 203.136754 -124.801376) (xy 200.401067 -124.801376)
			(xy 200.381934 -124.8497) (xy 200.35114 -124.905715) (xy 200.313567 -124.95743) (xy 200.26981 -125.004027)
			(xy 200.220557 -125.044772) (xy 200.166586 -125.079023) (xy 200.108747 -125.10624) (xy 200.047954 -125.125993)
			(xy 199.985164 -125.137971) (xy 199.921368 -125.141985) (xy 199.857572 -125.137971) (xy 199.794782 -125.125993)
			(xy 199.733989 -125.10624) (xy 199.67615 -125.079023) (xy 199.622179 -125.044772) (xy 199.572926 -125.004027)
			(xy 199.529169 -124.95743) (xy 199.491596 -124.905715) (xy 199.460802 -124.8497) (xy 199.43727 -124.790267)
			(xy 199.421373 -124.728353) (xy 199.413362 -124.664935) (xy 198.604316 -124.664935) (xy 198.590194 -124.673088)
			(xy 198.54058 -124.69256) (xy 198.488618 -124.70442) (xy 198.435468 -124.708404) (xy 198.382318 -124.70442)
			(xy 198.330356 -124.69256) (xy 198.280742 -124.673088) (xy 198.234584 -124.646439) (xy 198.192913 -124.613208)
			(xy 198.156661 -124.574137) (xy 198.126637 -124.5301) (xy 198.103511 -124.482079) (xy 198.087801 -124.431149)
			(xy 198.079858 -124.378445) (xy 196.557707 -124.378445) (xy 196.577595 -124.399388) (xy 196.615697 -124.451322)
			(xy 196.646937 -124.507652) (xy 196.670814 -124.567475) (xy 196.686946 -124.629835) (xy 196.695074 -124.693732)
			(xy 196.695568 -124.725938) (xy 196.695079 -124.756989) (xy 196.687502 -124.818626) (xy 196.672476 -124.878883)
			(xy 196.650227 -124.936862) (xy 196.621084 -124.991701) (xy 196.585481 -125.042584) (xy 196.543948 -125.088754)
			(xy 196.497104 -125.129523) (xy 196.445644 -125.164287) (xy 196.4182 -125.17882) (xy 196.405246 -125.185424)
			(xy 196.390514 -125.209808) (xy 196.391276 -125.315472) (xy 196.391793 -125.324832) (xy 196.398741 -125.342225)
			(xy 196.411492 -125.355945) (xy 196.419724 -125.36043) (xy 196.419978 -125.360684) (xy 196.448108 -125.37493)
			(xy 196.500889 -125.409433) (xy 196.548998 -125.450199) (xy 196.591695 -125.496602) (xy 196.628325 -125.547929)
			(xy 196.658326 -125.603393) (xy 196.681237 -125.662141) (xy 196.696706 -125.723272) (xy 196.704496 -125.785847)
			(xy 196.704966 -125.817376) (xy 196.704464 -125.849337) (xy 196.696453 -125.912755) (xy 196.680556 -125.974669)
			(xy 196.657024 -126.034102) (xy 196.62623 -126.090117) (xy 196.588657 -126.141832) (xy 196.5449 -126.188429)
			(xy 196.495647 -126.229174) (xy 196.441676 -126.263425) (xy 196.383837 -126.290642) (xy 196.323044 -126.310395)
			(xy 196.260254 -126.322373) (xy 196.196458 -126.326387) (xy 196.132662 -126.322373) (xy 196.069872 -126.310395)
			(xy 196.009079 -126.290642) (xy 195.95124 -126.263425) (xy 195.897269 -126.229174) (xy 195.848016 -126.188429)
			(xy 195.804259 -126.141832) (xy 195.766686 -126.090117) (xy 195.735892 -126.034102) (xy 195.71236 -125.974669)
			(xy 195.696463 -125.912755) (xy 195.688452 -125.849337) (xy 195.68795 -125.817376) (xy 195.688441 -125.786325)
			(xy 195.696017 -125.724687) (xy 195.711041 -125.66443) (xy 195.73329 -125.606451) (xy 195.762433 -125.551612)
			(xy 195.798035 -125.500729) (xy 195.839568 -125.454559) (xy 195.886413 -125.413789) (xy 195.937874 -125.379027)
			(xy 195.965318 -125.364494) (xy 195.978272 -125.35789) (xy 195.993004 -125.333506) (xy 195.992242 -125.227842)
			(xy 195.991706 -125.218485) (xy 195.984765 -125.201093) (xy 195.972022 -125.187371) (xy 195.963794 -125.182884)
			(xy 195.96354 -125.18263) (xy 195.93542 -125.168365) (xy 195.882638 -125.133865) (xy 195.834529 -125.093102)
			(xy 195.791831 -125.046702) (xy 195.7552 -124.995377) (xy 195.725198 -124.939915) (xy 195.702285 -124.881169)
			(xy 195.686815 -124.82004) (xy 195.679023 -124.757466) (xy 195.678552 -124.725938) (xy 188.930907 -124.725938)
			(xy 188.927204 -124.729641) (xy 188.885156 -124.760191) (xy 188.838846 -124.783787) (xy 188.789416 -124.799848)
			(xy 188.738081 -124.807978) (xy 188.686107 -124.807978) (xy 188.634772 -124.799848) (xy 188.585342 -124.783787)
			(xy 188.539032 -124.760191) (xy 188.496984 -124.729641) (xy 188.460233 -124.69289) (xy 188.429683 -124.650842)
			(xy 188.406087 -124.604532) (xy 188.390026 -124.555102) (xy 188.381896 -124.503767) (xy 188.381386 -124.47778)
			(xy 173.17896 -124.47778) (xy 173.19727 -124.502981) (xy 173.228064 -124.558996) (xy 173.251596 -124.618429)
			(xy 173.267493 -124.680343) (xy 173.275504 -124.743761) (xy 173.276006 -124.775722) (xy 173.275504 -124.807683)
			(xy 173.267493 -124.871101) (xy 173.251596 -124.933015) (xy 173.228064 -124.992448) (xy 173.19727 -125.048463)
			(xy 173.159697 -125.100178) (xy 173.11594 -125.146775) (xy 173.066687 -125.18752) (xy 173.012716 -125.221771)
			(xy 172.954877 -125.248988) (xy 172.894084 -125.268741) (xy 172.831294 -125.280719) (xy 172.767498 -125.284733)
			(xy 172.703702 -125.280719) (xy 172.640912 -125.268741) (xy 172.580119 -125.248988) (xy 172.52228 -125.221771)
			(xy 172.468309 -125.18752) (xy 172.419056 -125.146775) (xy 172.375299 -125.100178) (xy 172.337726 -125.048463)
			(xy 172.306932 -124.992448) (xy 172.2834 -124.933015) (xy 172.267503 -124.871101) (xy 172.259492 -124.807683)
			(xy 170.527683 -124.807683) (xy 171.649093 -125.929093) (xy 172.520096 -125.929093) (xy 172.520096 -125.865171)
			(xy 172.528107 -125.801753) (xy 172.544004 -125.739839) (xy 172.567536 -125.680406) (xy 172.59833 -125.624391)
			(xy 172.635903 -125.572676) (xy 172.67966 -125.526079) (xy 172.728913 -125.485334) (xy 172.782884 -125.451083)
			(xy 172.840723 -125.423866) (xy 172.901516 -125.404113) (xy 172.964306 -125.392135) (xy 173.028102 -125.388122)
			(xy 173.091898 -125.392135) (xy 173.154688 -125.404113) (xy 173.215481 -125.423866) (xy 173.27332 -125.451083)
			(xy 173.327291 -125.485334) (xy 173.376544 -125.526079) (xy 173.420301 -125.572676) (xy 173.455219 -125.620737)
			(xy 187.114682 -125.620737) (xy 187.114682 -125.556815) (xy 187.122693 -125.493397) (xy 187.13859 -125.431483)
			(xy 187.162122 -125.37205) (xy 187.192916 -125.316035) (xy 187.230489 -125.26432) (xy 187.274246 -125.217723)
			(xy 187.323499 -125.176978) (xy 187.37747 -125.142727) (xy 187.435309 -125.11551) (xy 187.496102 -125.095757)
			(xy 187.558892 -125.083779) (xy 187.622688 -125.079766) (xy 187.686484 -125.083779) (xy 187.749274 -125.095757)
			(xy 187.810067 -125.11551) (xy 187.867906 -125.142727) (xy 187.921877 -125.176978) (xy 187.97113 -125.217723)
			(xy 188.014887 -125.26432) (xy 188.05246 -125.316035) (xy 188.083254 -125.37205) (xy 188.106786 -125.431483)
			(xy 188.122683 -125.493397) (xy 188.130694 -125.556815) (xy 188.131196 -125.588776) (xy 188.130694 -125.620737)
			(xy 188.122683 -125.684155) (xy 188.106786 -125.746069) (xy 188.083254 -125.805502) (xy 188.073119 -125.823937)
			(xy 189.580768 -125.823937) (xy 189.580768 -125.760015) (xy 189.588779 -125.696597) (xy 189.604676 -125.634683)
			(xy 189.628208 -125.57525) (xy 189.659002 -125.519235) (xy 189.696575 -125.46752) (xy 189.740332 -125.420923)
			(xy 189.789585 -125.380178) (xy 189.843556 -125.345927) (xy 189.901395 -125.31871) (xy 189.962188 -125.298957)
			(xy 190.024978 -125.286979) (xy 190.088774 -125.282966) (xy 190.15257 -125.286979) (xy 190.21536 -125.298957)
			(xy 190.276153 -125.31871) (xy 190.333992 -125.345927) (xy 190.387963 -125.380178) (xy 190.437216 -125.420923)
			(xy 190.480973 -125.46752) (xy 190.518546 -125.519235) (xy 190.54934 -125.57525) (xy 190.572872 -125.634683)
			(xy 190.588769 -125.696597) (xy 190.59678 -125.760015) (xy 190.597282 -125.791976) (xy 190.59682 -125.821397)
			(xy 190.818002 -125.821397) (xy 190.818002 -125.757475) (xy 190.826013 -125.694057) (xy 190.84191 -125.632143)
			(xy 190.865442 -125.57271) (xy 190.896236 -125.516695) (xy 190.933809 -125.46498) (xy 190.977566 -125.418383)
			(xy 191.026819 -125.377638) (xy 191.08079 -125.343387) (xy 191.138629 -125.31617) (xy 191.199422 -125.296417)
			(xy 191.262212 -125.284439) (xy 191.326008 -125.280426) (xy 191.389804 -125.284439) (xy 191.452594 -125.296417)
			(xy 191.513387 -125.31617) (xy 191.571226 -125.343387) (xy 191.625197 -125.377638) (xy 191.67445 -125.418383)
			(xy 191.676041 -125.420077) (xy 193.243194 -125.420077) (xy 193.243194 -125.356155) (xy 193.251205 -125.292737)
			(xy 193.267102 -125.230823) (xy 193.290634 -125.17139) (xy 193.321428 -125.115375) (xy 193.359001 -125.06366)
			(xy 193.402758 -125.017063) (xy 193.452011 -124.976318) (xy 193.505982 -124.942067) (xy 193.563821 -124.91485)
			(xy 193.624614 -124.895097) (xy 193.687404 -124.883119) (xy 193.7512 -124.879106) (xy 193.814996 -124.883119)
			(xy 193.877786 -124.895097) (xy 193.938579 -124.91485) (xy 193.996418 -124.942067) (xy 194.050389 -124.976318)
			(xy 194.099642 -125.017063) (xy 194.143399 -125.06366) (xy 194.180972 -125.115375) (xy 194.211766 -125.17139)
			(xy 194.235298 -125.230823) (xy 194.251195 -125.292737) (xy 194.259206 -125.356155) (xy 194.259708 -125.388116)
			(xy 194.259206 -125.420077) (xy 194.251195 -125.483495) (xy 194.235298 -125.545409) (xy 194.211766 -125.604842)
			(xy 194.180972 -125.660857) (xy 194.143399 -125.712572) (xy 194.099642 -125.759169) (xy 194.050389 -125.799914)
			(xy 193.996418 -125.834165) (xy 193.938579 -125.861382) (xy 193.877786 -125.881135) (xy 193.814996 -125.893113)
			(xy 193.7512 -125.897127) (xy 193.687404 -125.893113) (xy 193.624614 -125.881135) (xy 193.563821 -125.861382)
			(xy 193.505982 -125.834165) (xy 193.452011 -125.799914) (xy 193.402758 -125.759169) (xy 193.359001 -125.712572)
			(xy 193.321428 -125.660857) (xy 193.290634 -125.604842) (xy 193.267102 -125.545409) (xy 193.251205 -125.483495)
			(xy 193.243194 -125.420077) (xy 191.676041 -125.420077) (xy 191.718207 -125.46498) (xy 191.75578 -125.516695)
			(xy 191.786574 -125.57271) (xy 191.810106 -125.632143) (xy 191.826003 -125.694057) (xy 191.834014 -125.757475)
			(xy 191.834516 -125.789436) (xy 191.834014 -125.821397) (xy 191.826003 -125.884815) (xy 191.810106 -125.946729)
			(xy 191.786574 -126.006162) (xy 191.75578 -126.062177) (xy 191.718207 -126.113892) (xy 191.67445 -126.160489)
			(xy 191.625197 -126.201234) (xy 191.571226 -126.235485) (xy 191.513387 -126.262702) (xy 191.452594 -126.282455)
			(xy 191.389804 -126.294433) (xy 191.326008 -126.298447) (xy 191.262212 -126.294433) (xy 191.199422 -126.282455)
			(xy 191.138629 -126.262702) (xy 191.08079 -126.235485) (xy 191.026819 -126.201234) (xy 190.977566 -126.160489)
			(xy 190.933809 -126.113892) (xy 190.896236 -126.062177) (xy 190.865442 -126.006162) (xy 190.84191 -125.946729)
			(xy 190.826013 -125.884815) (xy 190.818002 -125.821397) (xy 190.59682 -125.821397) (xy 190.59678 -125.823937)
			(xy 190.588769 -125.887355) (xy 190.572872 -125.949269) (xy 190.54934 -126.008702) (xy 190.518546 -126.064717)
			(xy 190.480973 -126.116432) (xy 190.437216 -126.163029) (xy 190.387963 -126.203774) (xy 190.333992 -126.238025)
			(xy 190.276153 -126.265242) (xy 190.21536 -126.284995) (xy 190.15257 -126.296973) (xy 190.088774 -126.300987)
			(xy 190.024978 -126.296973) (xy 189.962188 -126.284995) (xy 189.901395 -126.265242) (xy 189.843556 -126.238025)
			(xy 189.789585 -126.203774) (xy 189.740332 -126.163029) (xy 189.696575 -126.116432) (xy 189.659002 -126.064717)
			(xy 189.628208 -126.008702) (xy 189.604676 -125.949269) (xy 189.588779 -125.887355) (xy 189.580768 -125.823937)
			(xy 188.073119 -125.823937) (xy 188.05246 -125.861517) (xy 188.014887 -125.913232) (xy 187.97113 -125.959829)
			(xy 187.921877 -126.000574) (xy 187.867906 -126.034825) (xy 187.810067 -126.062042) (xy 187.749274 -126.081795)
			(xy 187.686484 -126.093773) (xy 187.622688 -126.097787) (xy 187.558892 -126.093773) (xy 187.496102 -126.081795)
			(xy 187.435309 -126.062042) (xy 187.37747 -126.034825) (xy 187.323499 -126.000574) (xy 187.274246 -125.959829)
			(xy 187.230489 -125.913232) (xy 187.192916 -125.861517) (xy 187.162122 -125.805502) (xy 187.13859 -125.746069)
			(xy 187.122693 -125.684155) (xy 187.114682 -125.620737) (xy 173.455219 -125.620737) (xy 173.457874 -125.624391)
			(xy 173.488668 -125.680406) (xy 173.5122 -125.739839) (xy 173.528097 -125.801753) (xy 173.536108 -125.865171)
			(xy 173.53661 -125.897132) (xy 173.536108 -125.929093) (xy 173.528097 -125.992511) (xy 173.5122 -126.054425)
			(xy 173.488668 -126.113858) (xy 173.457874 -126.169873) (xy 173.420301 -126.221588) (xy 173.376544 -126.268185)
			(xy 173.327291 -126.30893) (xy 173.27332 -126.343181) (xy 173.215481 -126.370398) (xy 173.154688 -126.390151)
			(xy 173.091898 -126.402129) (xy 173.028102 -126.406143) (xy 172.964306 -126.402129) (xy 172.901516 -126.390151)
			(xy 172.840723 -126.370398) (xy 172.782884 -126.343181) (xy 172.728913 -126.30893) (xy 172.67966 -126.268185)
			(xy 172.635903 -126.221588) (xy 172.59833 -126.169873) (xy 172.567536 -126.113858) (xy 172.544004 -126.054425)
			(xy 172.528107 -125.992511) (xy 172.520096 -125.929093) (xy 171.649093 -125.929093) (xy 172.79493 -127.07493)
			(xy 172.795692 -127.075692) (xy 172.802334 -127.081531) (xy 172.818489 -127.088694) (xy 172.836116 -127.089951)
			(xy 172.844714 -127.087884) (xy 172.930058 -127.063754) (xy 172.93651 -127.061734) (xy 172.948098 -127.054779)
			(xy 172.952918 -127.050038) (xy 172.957417 -127.045091) (xy 172.963847 -127.033372) (xy 172.965618 -127.026924)
			(xy 172.965618 -127.026416) (xy 172.973241 -126.996452) (xy 172.994781 -126.938495) (xy 173.023184 -126.883574)
			(xy 173.058033 -126.8325) (xy 173.098813 -126.786024) (xy 173.144923 -126.744831) (xy 173.195685 -126.709529)
			(xy 173.25035 -126.680637) (xy 173.308113 -126.658581) (xy 173.368123 -126.643686) (xy 173.429495 -126.636172)
			(xy 173.46041 -126.635764) (xy 173.492626 -126.636262) (xy 173.556541 -126.644403) (xy 173.618915 -126.660555)
			(xy 173.678748 -126.684457) (xy 173.735083 -126.715727) (xy 173.787015 -126.753864) (xy 173.833713 -126.798257)
			(xy 173.874429 -126.848193) (xy 173.908509 -126.902874) (xy 173.922436 -126.931928) (xy 173.927144 -126.939055)
			(xy 173.940314 -126.949917) (xy 173.956326 -126.955837) (xy 173.964854 -126.956312) (xy 174.03191 -126.954788)
			(xy 174.060358 -126.954026) (xy 174.070131 -126.953328) (xy 174.088095 -126.945547) (xy 174.101862 -126.93163)
			(xy 174.106078 -126.922784) (xy 174.106078 -126.922276) (xy 174.119244 -126.891567) (xy 174.152474 -126.833598)
			(xy 174.193004 -126.780476) (xy 174.240137 -126.733116) (xy 174.293063 -126.692332) (xy 174.350872 -126.658824)
			(xy 174.412568 -126.633171) (xy 174.477091 -126.615812) (xy 174.543331 -126.607046) (xy 174.57674 -126.606554)
			(xy 174.60747 -126.60702) (xy 174.668482 -126.614432) (xy 174.728156 -126.629144) (xy 174.785622 -126.650941)
			(xy 174.840042 -126.679505) (xy 174.890622 -126.714419) (xy 174.936626 -126.755176) (xy 174.977382 -126.801179)
			(xy 174.978041 -126.802134) (xy 198.462646 -126.802134) (xy 198.463125 -126.772217) (xy 198.470143 -126.712797)
			(xy 198.484086 -126.654611) (xy 198.504762 -126.598463) (xy 198.531883 -126.54513) (xy 198.565077 -126.495348)
			(xy 198.603883 -126.449806) (xy 198.647766 -126.409133) (xy 198.671688 -126.391162) (xy 198.681004 -126.383601)
			(xy 198.691875 -126.36225) (xy 198.692516 -126.350268) (xy 198.69277 -126.256034) (xy 198.681848 -126.234698)
			(xy 198.671942 -126.227332) (xy 198.644804 -126.20673) (xy 198.59577 -126.159421) (xy 198.55349 -126.10599)
			(xy 198.518721 -126.047393) (xy 198.492086 -125.984679) (xy 198.474061 -125.91897) (xy 198.464969 -125.851444)
			(xy 198.464424 -125.817376) (xy 198.464815 -125.786642) (xy 198.472227 -125.725623) (xy 198.48694 -125.665942)
			(xy 198.50874 -125.60847) (xy 198.537308 -125.554044) (xy 198.572229 -125.503459) (xy 198.612992 -125.457452)
			(xy 198.659003 -125.416694) (xy 198.709592 -125.381779) (xy 198.764021 -125.353217) (xy 198.821496 -125.331424)
			(xy 198.881178 -125.316717) (xy 198.942198 -125.309312) (xy 198.972932 -125.308868) (xy 199.005291 -125.309387)
			(xy 199.069488 -125.317586) (xy 199.132126 -125.333862) (xy 199.192194 -125.357951) (xy 199.248722 -125.389463)
			(xy 199.300796 -125.427891) (xy 199.347576 -125.472613) (xy 199.388307 -125.522907) (xy 199.405748 -125.550168)
			(xy 199.410579 -125.557336) (xy 199.424007 -125.568199) (xy 199.440292 -125.573957) (xy 199.448928 -125.574298)
			(xy 199.535288 -125.574298) (xy 199.54392 -125.573924) (xy 199.560196 -125.568165) (xy 199.573638 -125.557331)
			(xy 199.578468 -125.550168) (xy 199.595917 -125.522912) (xy 199.636649 -125.47262) (xy 199.683429 -125.4279)
			(xy 199.735503 -125.389472) (xy 199.792029 -125.357957) (xy 199.852095 -125.333864) (xy 199.91473 -125.317582)
			(xy 199.978925 -125.309374) (xy 200.011284 -125.308868) (xy 200.042014 -125.309371) (xy 200.103025 -125.316777)
			(xy 200.162699 -125.331483) (xy 200.220166 -125.353275) (xy 200.274586 -125.381835) (xy 200.325168 -125.416746)
			(xy 200.371172 -125.457499) (xy 200.411929 -125.503501) (xy 200.446844 -125.554079) (xy 200.475408 -125.608498)
			(xy 200.497205 -125.665962) (xy 200.511916 -125.725635) (xy 200.519327 -125.786646) (xy 200.519792 -125.817376)
			(xy 200.519345 -125.848825) (xy 200.511572 -125.911241) (xy 200.496167 -125.972224) (xy 200.473364 -126.030844)
			(xy 200.443511 -126.086206) (xy 200.407063 -126.137468) (xy 200.364576 -126.183847) (xy 200.316697 -126.224637)
			(xy 200.290684 -126.242318) (xy 200.28027 -126.249176) (xy 200.268332 -126.270258) (xy 200.263506 -126.377192)
			(xy 200.27392 -126.39929) (xy 200.283572 -126.40691) (xy 200.309072 -126.427605) (xy 200.354984 -126.474565)
			(xy 200.394471 -126.527043) (xy 200.426878 -126.584165) (xy 200.451665 -126.644983) (xy 200.468419 -126.708485)
			(xy 200.476864 -126.773615) (xy 200.477374 -126.806452) (xy 200.477374 -126.806706) (xy 200.477209 -126.824675)
			(xy 200.474667 -126.860522) (xy 200.472294 -126.878334) (xy 200.471416 -126.887089) (xy 200.475004 -126.904302)
			(xy 200.484203 -126.919287) (xy 200.490836 -126.92507) (xy 200.569322 -126.98857) (xy 200.595992 -126.992634)
			(xy 200.608692 -126.987808) (xy 200.637362 -126.977496) (xy 200.696549 -126.963022) (xy 200.757043 -126.95574)
			(xy 200.787508 -126.955296) (xy 200.787762 -126.955296) (xy 200.819306 -126.955727) (xy 200.88191 -126.963526)
			(xy 200.943068 -126.979009) (xy 201.001841 -127.001938) (xy 201.057327 -127.031961) (xy 201.108674 -127.068616)
			(xy 201.155092 -127.111341) (xy 201.195868 -127.15948) (xy 201.230377 -127.212293) (xy 201.258088 -127.268968)
			(xy 201.278576 -127.328637) (xy 201.291526 -127.390381) (xy 201.296739 -127.453253) (xy 201.294135 -127.516287)
			(xy 201.283755 -127.578514) (xy 201.265756 -127.63898) (xy 201.240417 -127.696755) (xy 201.208126 -127.750953)
			(xy 201.169379 -127.800739) (xy 201.124771 -127.845351) (xy 201.074987 -127.884102) (xy 201.020793 -127.916398)
			(xy 200.96302 -127.941742) (xy 200.902555 -127.959745) (xy 200.840328 -127.970131) (xy 200.777295 -127.97274)
			(xy 200.714422 -127.967532) (xy 200.652677 -127.954587) (xy 200.593007 -127.934104) (xy 200.536329 -127.906398)
			(xy 200.483513 -127.871893) (xy 200.435371 -127.831121) (xy 200.392642 -127.784706) (xy 200.355983 -127.733363)
			(xy 200.325956 -127.67788) (xy 200.303022 -127.619108) (xy 200.287534 -127.557951) (xy 200.27973 -127.495348)
			(xy 200.279254 -127.463804) (xy 200.279254 -127.46355) (xy 200.279414 -127.445581) (xy 200.281959 -127.409734)
			(xy 200.284334 -127.391922) (xy 200.285235 -127.383169) (xy 200.281635 -127.365954) (xy 200.272427 -127.350968)
			(xy 200.265792 -127.345186) (xy 200.187306 -127.281686) (xy 200.160636 -127.277622) (xy 200.147936 -127.282448)
			(xy 200.119262 -127.292751) (xy 200.060078 -127.307228) (xy 199.999585 -127.314514) (xy 199.96912 -127.31496)
			(xy 199.968866 -127.31496) (xy 199.938289 -127.314491) (xy 199.877579 -127.307143) (xy 199.818187 -127.292568)
			(xy 199.760972 -127.270978) (xy 199.706757 -127.242683) (xy 199.656327 -127.208092) (xy 199.610408 -127.167704)
			(xy 199.569662 -127.122102) (xy 199.551798 -127.097282) (xy 199.544686 -127.087122) (xy 199.522842 -127.075692)
			(xy 199.414892 -127.075184) (xy 199.392794 -127.086614) (xy 199.385682 -127.096774) (xy 199.367761 -127.121204)
			(xy 199.327034 -127.166065) (xy 199.281265 -127.205768) (xy 199.231102 -127.239752) (xy 199.177257 -127.267534)
			(xy 199.120491 -127.288721) (xy 199.061611 -127.303013) (xy 199.001449 -127.310207) (xy 198.971154 -127.310642)
			(xy 198.940423 -127.310188) (xy 198.879411 -127.302775) (xy 198.819736 -127.288062) (xy 198.76227 -127.266264)
			(xy 198.70785 -127.237699) (xy 198.657269 -127.202784) (xy 198.611265 -127.162027) (xy 198.570509 -127.116022)
			(xy 198.535594 -127.06544) (xy 198.507031 -127.011019) (xy 198.485234 -126.953552) (xy 198.470523 -126.893878)
			(xy 198.463112 -126.832865) (xy 198.462646 -126.802134) (xy 174.978041 -126.802134) (xy 175.012296 -126.85176)
			(xy 175.04086 -126.90618) (xy 175.062657 -126.963646) (xy 175.077368 -127.02332) (xy 175.08478 -127.084332)
			(xy 175.085248 -127.115062) (xy 175.08486 -127.143177) (xy 175.078626 -127.19906) (xy 175.072802 -127.226568)
			(xy 175.072802 -127.226822) (xy 175.070973 -127.238058) (xy 175.076133 -127.260199) (xy 175.082708 -127.269494)
			(xy 175.1076 -127.300228) (xy 175.1076 -127.300736) (xy 175.132746 -127.332232) (xy 175.136342 -127.336306)
			(xy 175.144927 -127.342963) (xy 175.149764 -127.34544) (xy 175.150018 -127.34544) (xy 175.15518 -127.347766)
			(xy 175.166204 -127.350338) (xy 175.171862 -127.35052) (xy 189.008258 -127.35052) (xy 189.018323 -127.350954)
			(xy 189.03691 -127.358686) (xy 189.044326 -127.365506) (xy 189.753705 -128.074885) (xy 190.665602 -128.074885)
			(xy 190.665602 -128.010963) (xy 190.673613 -127.947545) (xy 190.68951 -127.885631) (xy 190.713042 -127.826198)
			(xy 190.743836 -127.770183) (xy 190.781409 -127.718468) (xy 190.825166 -127.671871) (xy 190.874419 -127.631126)
			(xy 190.92839 -127.596875) (xy 190.986229 -127.569658) (xy 191.047022 -127.549905) (xy 191.109812 -127.537927)
			(xy 191.173608 -127.533914) (xy 191.237404 -127.537927) (xy 191.300194 -127.549905) (xy 191.360987 -127.569658)
			(xy 191.418826 -127.596875) (xy 191.472797 -127.631126) (xy 191.478708 -127.636016) (xy 196.366892 -127.636016)
			(xy 196.367353 -127.605284) (xy 196.37476 -127.544269) (xy 196.389467 -127.484591) (xy 196.411261 -127.427121)
			(xy 196.439823 -127.372697) (xy 196.474738 -127.322113) (xy 196.515495 -127.276106) (xy 196.5615 -127.235347)
			(xy 196.612083 -127.200432) (xy 196.666506 -127.171868) (xy 196.723975 -127.150072) (xy 196.783653 -127.135362)
			(xy 196.844668 -127.127954) (xy 196.8754 -127.127508) (xy 196.908552 -127.128098) (xy 196.974291 -127.136728)
			(xy 197.038352 -127.153829) (xy 197.099647 -127.17911) (xy 197.157136 -127.212142) (xy 197.209844 -127.252366)
			(xy 197.256878 -127.2991) (xy 197.29744 -127.351549) (xy 197.330841 -127.408825) (xy 197.356515 -127.469956)
			(xy 197.374026 -127.533906) (xy 197.379082 -127.566674) (xy 197.380549 -127.57515) (xy 197.388328 -127.590477)
			(xy 197.394322 -127.596646) (xy 197.415658 -127.616966) (xy 197.422112 -127.622555) (xy 197.437675 -127.629548)
			(xy 197.446138 -127.630682) (xy 197.477339 -127.634019) (xy 197.538657 -127.647343) (xy 197.59787 -127.668111)
			(xy 197.654078 -127.696005) (xy 197.706427 -127.730603) (xy 197.754122 -127.771378) (xy 197.796439 -127.817712)
			(xy 197.832734 -127.868899) (xy 197.862455 -127.924163) (xy 197.885152 -127.982663) (xy 197.90048 -128.043512)
			(xy 197.901163 -128.04902) (xy 202.862688 -128.04902) (xy 202.863174 -128.017187) (xy 202.8711 -127.954016)
			(xy 202.886857 -127.89233) (xy 202.910196 -127.833096) (xy 202.940753 -127.777242) (xy 202.978048 -127.725644)
			(xy 203.021498 -127.679108) (xy 203.070421 -127.638366) (xy 203.12405 -127.604055) (xy 203.181546 -127.576712)
			(xy 203.242007 -127.556767) (xy 203.273152 -127.550164) (xy 203.273406 -127.550164) (xy 203.285293 -127.547041)
			(xy 203.304402 -127.53165) (xy 203.309982 -127.5207) (xy 203.348336 -127.432308) (xy 203.346304 -127.407416)
			(xy 203.3397 -127.396748) (xy 203.321507 -127.366406) (xy 203.292825 -127.301734) (xy 203.273395 -127.233708)
			(xy 203.263595 -127.163643) (xy 203.262992 -127.12827) (xy 203.262992 -127.128016) (xy 203.263494 -127.096055)
			(xy 203.271505 -127.032637) (xy 203.287402 -126.970723) (xy 203.310934 -126.91129) (xy 203.341728 -126.855275)
			(xy 203.379301 -126.80356) (xy 203.423058 -126.756963) (xy 203.472311 -126.716218) (xy 203.526282 -126.681967)
			(xy 203.584121 -126.65475) (xy 203.644914 -126.634997) (xy 203.707704 -126.623019) (xy 203.7715 -126.619006)
			(xy 203.835296 -126.623019) (xy 203.898086 -126.634997) (xy 203.958879 -126.65475) (xy 204.016718 -126.681967)
			(xy 204.070689 -126.716218) (xy 204.119942 -126.756963) (xy 204.163699 -126.80356) (xy 204.201272 -126.855275)
			(xy 204.232066 -126.91129) (xy 204.255598 -126.970723) (xy 204.271495 -127.032637) (xy 204.279506 -127.096055)
			(xy 204.280008 -127.128016) (xy 204.279559 -127.15985) (xy 204.271628 -127.223023) (xy 204.26195 -127.2609)
			(xy 209.868747 -127.2609) (xy 209.872761 -127.1971) (xy 209.88474 -127.134306) (xy 209.904494 -127.073508)
			(xy 209.931712 -127.015666) (xy 209.965965 -126.961691) (xy 210.006712 -126.912434) (xy 210.053312 -126.868673)
			(xy 210.105028 -126.831098) (xy 210.161047 -126.8003) (xy 210.220483 -126.776766) (xy 210.282401 -126.760867)
			(xy 210.345823 -126.752853) (xy 210.377786 -126.75235) (xy 210.408531 -126.752806) (xy 210.469571 -126.760229)
			(xy 210.529271 -126.774957) (xy 210.58676 -126.796774) (xy 210.641199 -126.825363) (xy 210.691795 -126.860306)
			(xy 210.715098 -126.880366) (xy 210.724169 -126.887762) (xy 210.746689 -126.894054) (xy 210.769666 -126.889721)
			(xy 210.77936 -126.88316) (xy 210.804297 -126.865104) (xy 210.858788 -126.836452) (xy 210.917175 -126.816928)
			(xy 210.97794 -126.807039) (xy 211.008722 -126.806452) (xy 211.035969 -126.80702) (xy 211.089909 -126.814778)
			(xy 211.142196 -126.830133) (xy 211.191765 -126.852773) (xy 211.237608 -126.882237) (xy 211.278791 -126.917925)
			(xy 211.314476 -126.95911) (xy 211.343937 -127.004955) (xy 211.366574 -127.054525) (xy 211.381927 -127.106813)
			(xy 211.389682 -127.160753) (xy 211.389682 -127.215247) (xy 211.381927 -127.269187) (xy 211.366574 -127.321475)
			(xy 211.343937 -127.371045) (xy 211.314476 -127.41689) (xy 211.278791 -127.458075) (xy 211.237608 -127.493763)
			(xy 211.191765 -127.523227) (xy 211.142196 -127.545867) (xy 211.089909 -127.561222) (xy 211.035969 -127.56898)
			(xy 211.008722 -127.569468) (xy 210.982352 -127.569039) (xy 210.930112 -127.561797) (xy 210.879369 -127.547419)
			(xy 210.855052 -127.53721) (xy 210.84415 -127.533012) (xy 210.820832 -127.533944) (xy 210.80031 -127.545054)
			(xy 210.793076 -127.554228) (xy 210.775157 -127.57877) (xy 210.734444 -127.623884) (xy 210.688642 -127.663821)
			(xy 210.638405 -127.698012) (xy 210.584449 -127.725968) (xy 210.527546 -127.747292) (xy 210.468505 -127.761679)
			(xy 210.40817 -127.768923) (xy 210.377786 -127.769366) (xy 210.345823 -127.768947) (xy 210.282401 -127.760933)
			(xy 210.220483 -127.745034) (xy 210.161047 -127.7215) (xy 210.105028 -127.690702) (xy 210.053312 -127.653127)
			(xy 210.006712 -127.609366) (xy 209.965965 -127.560109) (xy 209.931712 -127.506134) (xy 209.904494 -127.448292)
			(xy 209.88474 -127.387494) (xy 209.872761 -127.3247) (xy 209.868747 -127.2609) (xy 204.26195 -127.2609)
			(xy 204.255867 -127.284709) (xy 204.232523 -127.343944) (xy 204.201962 -127.399798) (xy 204.164663 -127.451396)
			(xy 204.12121 -127.497931) (xy 204.072285 -127.538673) (xy 204.018652 -127.572984) (xy 203.961154 -127.600325)
			(xy 203.90069 -127.620269) (xy 203.869544 -127.626872) (xy 203.86929 -127.626872) (xy 203.857396 -127.629976)
			(xy 203.838288 -127.64538) (xy 203.832714 -127.656336) (xy 203.79436 -127.744728) (xy 203.796392 -127.76962)
			(xy 203.802996 -127.780288) (xy 203.821162 -127.810645) (xy 203.849851 -127.875311) (xy 203.869288 -127.943333)
			(xy 203.879097 -128.013394) (xy 203.879142 -128.016) (xy 205.992982 -128.016) (xy 205.997053 -127.960378)
			(xy 206.009179 -127.905941) (xy 206.029102 -127.85385) (xy 206.056398 -127.805215) (xy 206.090484 -127.761072)
			(xy 206.130633 -127.722363) (xy 206.175991 -127.689912) (xy 206.225591 -127.664411) (xy 206.278375 -127.646404)
			(xy 206.333218 -127.636274) (xy 206.388952 -127.634237) (xy 206.444389 -127.640337) (xy 206.498346 -127.654443)
			(xy 206.549675 -127.676255) (xy 206.597281 -127.705309) (xy 206.640149 -127.740984) (xy 206.677366 -127.782521)
			(xy 206.708139 -127.829034) (xy 206.731811 -127.879531) (xy 206.747879 -127.932938) (xy 206.755999 -127.988114)
			(xy 206.756508 -128.016) (xy 206.755999 -128.043886) (xy 206.747879 -128.099062) (xy 206.731811 -128.152469)
			(xy 206.708139 -128.202966) (xy 206.677366 -128.249479) (xy 206.640149 -128.291016) (xy 206.597281 -128.326691)
			(xy 206.549675 -128.355745) (xy 206.498346 -128.377557) (xy 206.444389 -128.391663) (xy 206.388952 -128.397763)
			(xy 206.333218 -128.395726) (xy 206.278375 -128.385596) (xy 206.225591 -128.367589) (xy 206.175991 -128.342088)
			(xy 206.130633 -128.309637) (xy 206.090484 -128.270928) (xy 206.056398 -128.226785) (xy 206.029102 -128.17815)
			(xy 206.009179 -128.126059) (xy 205.997053 -128.071622) (xy 205.992982 -128.016) (xy 203.879142 -128.016)
			(xy 203.879704 -128.048766) (xy 203.879704 -128.04902) (xy 203.879245 -128.079481) (xy 203.871973 -128.139967)
			(xy 203.857526 -128.19915) (xy 203.836109 -128.256183) (xy 203.80803 -128.310247) (xy 203.77369 -128.360569)
			(xy 203.753974 -128.383792) (xy 203.753974 -128.384046) (xy 203.748632 -128.390747) (xy 203.742259 -128.406642)
			(xy 203.741448 -128.423748) (xy 203.74356 -128.432052) (xy 203.772516 -128.527302) (xy 203.791312 -128.545336)
			(xy 203.804012 -128.548892) (xy 203.835971 -128.558103) (xy 203.897386 -128.583634) (xy 203.954947 -128.616953)
			(xy 204.007674 -128.657493) (xy 204.054664 -128.704562) (xy 204.095117 -128.757356) (xy 204.128341 -128.814973)
			(xy 204.153769 -128.87643) (xy 204.170967 -128.940677) (xy 204.179642 -129.006619) (xy 204.180186 -129.039874)
			(xy 204.179684 -129.071835) (xy 204.171673 -129.135253) (xy 204.155776 -129.197167) (xy 204.132244 -129.2566)
			(xy 204.10145 -129.312615) (xy 204.063877 -129.36433) (xy 204.02012 -129.410927) (xy 203.970867 -129.451672)
			(xy 203.916896 -129.485923) (xy 203.859057 -129.51314) (xy 203.798264 -129.532893) (xy 203.735474 -129.544871)
			(xy 203.671678 -129.548885) (xy 203.607882 -129.544871) (xy 203.545092 -129.532893) (xy 203.484299 -129.51314)
			(xy 203.42646 -129.485923) (xy 203.372489 -129.451672) (xy 203.323236 -129.410927) (xy 203.279479 -129.36433)
			(xy 203.241906 -129.312615) (xy 203.211112 -129.2566) (xy 203.18758 -129.197167) (xy 203.171683 -129.135253)
			(xy 203.163672 -129.071835) (xy 203.16317 -129.039874) (xy 203.163632 -129.009413) (xy 203.170904 -128.948928)
			(xy 203.185351 -128.889745) (xy 203.206768 -128.832712) (xy 203.234846 -128.778647) (xy 203.269184 -128.728326)
			(xy 203.2889 -128.705102) (xy 203.2889 -128.704848) (xy 203.294244 -128.698147) (xy 203.300618 -128.682252)
			(xy 203.301427 -128.665146) (xy 203.299314 -128.656842) (xy 203.270358 -128.561592) (xy 203.251562 -128.543558)
			(xy 203.238862 -128.540002) (xy 203.206896 -128.530813) (xy 203.145482 -128.505279) (xy 203.08792 -128.471956)
			(xy 203.035195 -128.431413) (xy 202.988205 -128.384342) (xy 202.947753 -128.331546) (xy 202.91453 -128.273927)
			(xy 202.889103 -128.212468) (xy 202.871905 -128.148219) (xy 202.863231 -128.082276) (xy 202.862688 -128.04902)
			(xy 197.901163 -128.04902) (xy 197.908205 -128.105783) (xy 197.908672 -128.137158) (xy 197.908223 -128.167891)
			(xy 197.900818 -128.228908) (xy 197.886112 -128.288588) (xy 197.864319 -128.34606) (xy 197.835757 -128.400486)
			(xy 197.800842 -128.451071) (xy 197.760083 -128.497079) (xy 197.714076 -128.537838) (xy 197.663491 -128.572754)
			(xy 197.609065 -128.601317) (xy 197.551594 -128.62311) (xy 197.491914 -128.637817) (xy 197.430897 -128.645222)
			(xy 197.400164 -128.645666) (xy 197.36701 -128.645131) (xy 197.301268 -128.636496) (xy 197.237205 -128.61939)
			(xy 197.175908 -128.594104) (xy 197.118418 -128.561066) (xy 197.065709 -128.520836) (xy 197.018676 -128.474097)
			(xy 196.978115 -128.421642) (xy 196.944716 -128.364361) (xy 196.919045 -128.303225) (xy 196.901536 -128.239271)
			(xy 196.896482 -128.2065) (xy 196.895035 -128.198019) (xy 196.887243 -128.182693) (xy 196.881242 -128.176528)
			(xy 196.859906 -128.156208) (xy 196.853437 -128.150639) (xy 196.837885 -128.143635) (xy 196.829426 -128.142492)
			(xy 196.798219 -128.139211) (xy 196.736898 -128.125881) (xy 196.677683 -128.105108) (xy 196.621474 -128.077208)
			(xy 196.569124 -128.042605) (xy 196.521429 -128.001825) (xy 196.479113 -127.955486) (xy 196.44282 -127.904294)
			(xy 196.4131 -127.849025) (xy 196.390405 -127.79052) (xy 196.37508 -127.729668) (xy 196.367358 -127.667392)
			(xy 196.366892 -127.636016) (xy 191.478708 -127.636016) (xy 191.52205 -127.671871) (xy 191.565807 -127.718468)
			(xy 191.60338 -127.770183) (xy 191.634174 -127.826198) (xy 191.657706 -127.885631) (xy 191.673603 -127.947545)
			(xy 191.681614 -128.010963) (xy 191.682116 -128.042924) (xy 191.681614 -128.074885) (xy 191.673603 -128.138303)
			(xy 191.657706 -128.200217) (xy 191.634174 -128.25965) (xy 191.60338 -128.315665) (xy 191.565807 -128.36738)
			(xy 191.52205 -128.413977) (xy 191.472797 -128.454722) (xy 191.418826 -128.488973) (xy 191.360987 -128.51619)
			(xy 191.300194 -128.535943) (xy 191.237404 -128.547921) (xy 191.173608 -128.551935) (xy 191.109812 -128.547921)
			(xy 191.047022 -128.535943) (xy 190.986229 -128.51619) (xy 190.92839 -128.488973) (xy 190.874419 -128.454722)
			(xy 190.825166 -128.413977) (xy 190.781409 -128.36738) (xy 190.743836 -128.315665) (xy 190.713042 -128.25965)
			(xy 190.68951 -128.200217) (xy 190.673613 -128.138303) (xy 190.665602 -128.074885) (xy 189.753705 -128.074885)
			(xy 190.624925 -128.946105) (xy 199.161902 -128.946105) (xy 199.161902 -128.882183) (xy 199.169913 -128.818765)
			(xy 199.18581 -128.756851) (xy 199.209342 -128.697418) (xy 199.240136 -128.641403) (xy 199.277709 -128.589688)
			(xy 199.321466 -128.543091) (xy 199.370719 -128.502346) (xy 199.42469 -128.468095) (xy 199.482529 -128.440878)
			(xy 199.543322 -128.421125) (xy 199.606112 -128.409147) (xy 199.669908 -128.405134) (xy 199.733704 -128.409147)
			(xy 199.796494 -128.421125) (xy 199.857287 -128.440878) (xy 199.915126 -128.468095) (xy 199.969097 -128.502346)
			(xy 200.01835 -128.543091) (xy 200.062107 -128.589688) (xy 200.09968 -128.641403) (xy 200.130474 -128.697418)
			(xy 200.154006 -128.756851) (xy 200.169903 -128.818765) (xy 200.177914 -128.882183) (xy 200.178416 -128.914144)
			(xy 200.177914 -128.946105) (xy 200.169903 -129.009523) (xy 200.154006 -129.071437) (xy 200.130474 -129.13087)
			(xy 200.09968 -129.186885) (xy 200.062107 -129.2386) (xy 200.01835 -129.285197) (xy 199.969097 -129.325942)
			(xy 199.915126 -129.360193) (xy 199.857287 -129.38741) (xy 199.796494 -129.407163) (xy 199.733704 -129.419141)
			(xy 199.669908 -129.423155) (xy 199.606112 -129.419141) (xy 199.543322 -129.407163) (xy 199.482529 -129.38741)
			(xy 199.42469 -129.360193) (xy 199.370719 -129.325942) (xy 199.321466 -129.285197) (xy 199.277709 -129.2386)
			(xy 199.240136 -129.186885) (xy 199.209342 -129.13087) (xy 199.18581 -129.071437) (xy 199.169913 -129.009523)
			(xy 199.161902 -128.946105) (xy 190.624925 -128.946105) (xy 190.78067 -129.10185) (xy 190.78807 -129.108691)
			(xy 190.806669 -129.116408) (xy 190.816738 -129.116836) (xy 194.43954 -129.116836) (xy 194.471098 -129.117383)
			(xy 194.533669 -129.12567) (xy 194.594629 -129.142033) (xy 194.65294 -129.166193) (xy 194.707609 -129.197738)
			(xy 194.757706 -129.236132) (xy 194.780408 -129.25806) (xy 195.214494 -129.6924) (xy 195.223733 -129.70055)
			(xy 195.247222 -129.707852) (xy 195.259452 -129.70637) (xy 195.354448 -129.688844) (xy 195.374006 -129.67335)
			(xy 195.379086 -129.661666) (xy 195.392802 -129.632112) (xy 195.426669 -129.576449) (xy 195.467364 -129.525565)
			(xy 195.514222 -129.480292) (xy 195.566476 -129.441371) (xy 195.623271 -129.409438) (xy 195.683677 -129.385017)
			(xy 195.746707 -129.368507) (xy 195.811328 -129.360178) (xy 195.843906 -129.35966) (xy 195.874817 -129.360117)
			(xy 195.936182 -129.367612) (xy 195.996186 -129.382491) (xy 196.053944 -129.404534) (xy 196.108604 -129.433417)
			(xy 196.159359 -129.468713) (xy 196.205461 -129.509901) (xy 196.24623 -129.556375) (xy 196.264022 -129.581656)
			(xy 196.271134 -129.59207) (xy 196.293232 -129.603754) (xy 196.389498 -129.604262) (xy 196.401914 -129.603644)
			(xy 196.423878 -129.592057) (xy 196.431408 -129.582164) (xy 196.449269 -129.557217) (xy 196.490045 -129.511369)
			(xy 196.536038 -129.470756) (xy 196.586579 -129.435967) (xy 196.640937 -129.407508) (xy 196.698323 -129.385791)
			(xy 196.757903 -129.371131) (xy 196.818813 -129.36374) (xy 196.849492 -129.363216) (xy 196.880224 -129.363661)
			(xy 196.94124 -129.371069) (xy 197.000917 -129.385778) (xy 197.058387 -129.407573) (xy 197.112811 -129.436137)
			(xy 197.163394 -129.471053) (xy 197.2094 -129.511812) (xy 197.250157 -129.557819) (xy 197.285071 -129.608403)
			(xy 197.313633 -129.662827) (xy 197.335427 -129.720298) (xy 197.350134 -129.779976) (xy 197.35754 -129.840992)
			(xy 197.358 -129.871724) (xy 197.357577 -129.901179) (xy 197.350771 -129.959694) (xy 197.337252 -130.017031)
			(xy 197.332769 -130.029415) (xy 202.552294 -130.029415) (xy 202.552294 -129.965493) (xy 202.560305 -129.902075)
			(xy 202.576202 -129.840161) (xy 202.599734 -129.780728) (xy 202.630528 -129.724713) (xy 202.668101 -129.672998)
			(xy 202.711858 -129.626401) (xy 202.761111 -129.585656) (xy 202.815082 -129.551405) (xy 202.872921 -129.524188)
			(xy 202.933714 -129.504435) (xy 202.996504 -129.492457) (xy 203.0603 -129.488444) (xy 203.124096 -129.492457)
			(xy 203.186886 -129.504435) (xy 203.247679 -129.524188) (xy 203.305518 -129.551405) (xy 203.359489 -129.585656)
			(xy 203.408742 -129.626401) (xy 203.452499 -129.672998) (xy 203.490072 -129.724713) (xy 203.520866 -129.780728)
			(xy 203.544398 -129.840161) (xy 203.560295 -129.902075) (xy 203.568306 -129.965493) (xy 203.568808 -129.997454)
			(xy 203.568306 -130.029415) (xy 203.560295 -130.092833) (xy 203.544398 -130.154747) (xy 203.520866 -130.21418)
			(xy 203.490072 -130.270195) (xy 203.452499 -130.32191) (xy 203.408742 -130.368507) (xy 203.359489 -130.409252)
			(xy 203.305518 -130.443503) (xy 203.247679 -130.47072) (xy 203.186886 -130.490473) (xy 203.124096 -130.502451)
			(xy 203.0603 -130.506465) (xy 202.996504 -130.502451) (xy 202.933714 -130.490473) (xy 202.872921 -130.47072)
			(xy 202.815082 -130.443503) (xy 202.761111 -130.409252) (xy 202.711858 -130.368507) (xy 202.668101 -130.32191)
			(xy 202.630528 -130.270195) (xy 202.599734 -130.21418) (xy 202.576202 -130.154747) (xy 202.560305 -130.092833)
			(xy 202.552294 -130.029415) (xy 197.332769 -130.029415) (xy 197.317202 -130.072424) (xy 197.290889 -130.12513)
			(xy 197.258665 -130.174445) (xy 197.240144 -130.197352) (xy 197.234786 -130.204259) (xy 197.22868 -130.220627)
			(xy 197.228206 -130.229356) (xy 197.227952 -130.259074) (xy 197.22818 -130.267783) (xy 197.233774 -130.284268)
			(xy 197.238874 -130.291332) (xy 197.259696 -130.318405) (xy 197.294666 -130.377071) (xy 197.321469 -130.439891)
			(xy 197.33962 -130.505733) (xy 197.348795 -130.573413) (xy 197.349364 -130.607562) (xy 197.349364 -130.607816)
			(xy 197.348874 -130.639668) (xy 197.340925 -130.702874) (xy 197.325141 -130.764592) (xy 197.30177 -130.823853)
			(xy 197.271178 -130.879731) (xy 197.233844 -130.931348) (xy 197.190353 -130.977897) (xy 197.141387 -131.018646)
			(xy 197.087714 -131.052959) (xy 197.030174 -131.080296) (xy 196.96967 -131.10023) (xy 196.907148 -131.112449)
			(xy 196.8754 -131.115054) (xy 196.860414 -131.11607) (xy 196.836792 -131.13385) (xy 196.798692 -131.234434)
			(xy 196.795707 -131.243707) (xy 196.796182 -131.263166) (xy 196.803832 -131.281064) (xy 196.810376 -131.288282)
			(xy 197.106032 -131.583938) (xy 197.113429 -131.590786) (xy 197.132028 -131.598519) (xy 197.1421 -131.598924)
		)
		(stroke
			(width 0)
			(type solid)
		)
		(fill yes)
		(layer "In13.Cu")
		(net "P1V8_AUX")
	)
	(gr_poly
		(pts
			(xy 62.186566 -335.034128) (xy 62.193808 -335.032497) (xy 62.206971 -335.025649) (xy 62.212474 -335.020666)
			(xy 62.745874 -334.487266) (xy 62.749176 -334.481678) (xy 62.765178 -334.456532) (xy 62.767718 -334.452468)
			(xy 62.771782 -334.43926) (xy 62.773849 -334.431777) (xy 62.773855 -334.416261) (xy 62.771782 -334.40878)
			(xy 62.767718 -334.395572) (xy 62.765178 -334.391508) (xy 62.746789 -334.363351) (xy 62.716783 -334.303167)
			(xy 62.694967 -334.239553) (xy 62.681723 -334.17362) (xy 62.677281 -334.106517) (xy 62.681719 -334.039413)
			(xy 62.694959 -333.973479) (xy 62.71677 -333.909864) (xy 62.746773 -333.849677) (xy 62.765178 -333.821532)
			(xy 62.767718 -333.817468) (xy 62.771782 -333.80426) (xy 62.773849 -333.796777) (xy 62.773855 -333.781261)
			(xy 62.771782 -333.77378) (xy 62.767718 -333.760572) (xy 62.765178 -333.756508) (xy 62.746789 -333.728351)
			(xy 62.716783 -333.668167) (xy 62.694967 -333.604553) (xy 62.681723 -333.53862) (xy 62.677281 -333.471517)
			(xy 62.681719 -333.404413) (xy 62.694959 -333.338479) (xy 62.71677 -333.274864) (xy 62.746773 -333.214677)
			(xy 62.765178 -333.186532) (xy 62.767718 -333.182468) (xy 62.771782 -333.16926) (xy 62.773849 -333.161777)
			(xy 62.773855 -333.146261) (xy 62.771782 -333.13878) (xy 62.767718 -333.125572) (xy 62.765178 -333.121508)
			(xy 62.746789 -333.093351) (xy 62.716783 -333.033167) (xy 62.694967 -332.969553) (xy 62.681723 -332.90362)
			(xy 62.677281 -332.836517) (xy 62.681719 -332.769413) (xy 62.694959 -332.703479) (xy 62.71677 -332.639864)
			(xy 62.746773 -332.579677) (xy 62.765178 -332.551532) (xy 62.767718 -332.547468) (xy 62.771782 -332.53426)
			(xy 62.773849 -332.526777) (xy 62.773855 -332.511261) (xy 62.771782 -332.50378) (xy 62.767718 -332.490572)
			(xy 62.765178 -332.486508) (xy 62.746789 -332.458351) (xy 62.716783 -332.398167) (xy 62.694967 -332.334553)
			(xy 62.681723 -332.26862) (xy 62.677281 -332.201517) (xy 62.681719 -332.134413) (xy 62.694959 -332.068479)
			(xy 62.71677 -332.004864) (xy 62.746773 -331.944677) (xy 62.765178 -331.916532) (xy 62.767718 -331.912468)
			(xy 62.771782 -331.89926) (xy 62.773849 -331.891777) (xy 62.773855 -331.876261) (xy 62.771782 -331.86878)
			(xy 62.767718 -331.855572) (xy 62.765178 -331.851508) (xy 62.746789 -331.823351) (xy 62.716783 -331.763167)
			(xy 62.694967 -331.699553) (xy 62.681723 -331.63362) (xy 62.677281 -331.566517) (xy 62.681719 -331.499413)
			(xy 62.694959 -331.433479) (xy 62.71677 -331.369864) (xy 62.746773 -331.309677) (xy 62.765178 -331.281532)
			(xy 62.767718 -331.277468) (xy 62.771782 -331.26426) (xy 62.773849 -331.256777) (xy 62.773855 -331.241261)
			(xy 62.771782 -331.23378) (xy 62.767718 -331.220572) (xy 62.765178 -331.216508) (xy 62.746789 -331.188351)
			(xy 62.716783 -331.128167) (xy 62.694967 -331.064553) (xy 62.681723 -330.99862) (xy 62.677281 -330.931517)
			(xy 62.681719 -330.864413) (xy 62.694959 -330.798479) (xy 62.71677 -330.734864) (xy 62.746773 -330.674677)
			(xy 62.765178 -330.646532) (xy 62.767718 -330.642468) (xy 62.771782 -330.62926) (xy 62.773849 -330.621777)
			(xy 62.773855 -330.606261) (xy 62.771782 -330.59878) (xy 62.767718 -330.585572) (xy 62.765178 -330.581508)
			(xy 62.746789 -330.553351) (xy 62.716783 -330.493167) (xy 62.694967 -330.429553) (xy 62.681723 -330.36362)
			(xy 62.677281 -330.296517) (xy 62.681719 -330.229413) (xy 62.694959 -330.163479) (xy 62.71677 -330.099864)
			(xy 62.746773 -330.039677) (xy 62.765178 -330.011532) (xy 62.767718 -330.007468) (xy 62.771782 -329.99426)
			(xy 62.773849 -329.986777) (xy 62.773855 -329.971261) (xy 62.771782 -329.96378) (xy 62.767718 -329.950572)
			(xy 62.765178 -329.946508) (xy 62.746789 -329.918351) (xy 62.716783 -329.858167) (xy 62.694967 -329.794553)
			(xy 62.681723 -329.72862) (xy 62.677281 -329.661517) (xy 62.681719 -329.594413) (xy 62.694959 -329.528479)
			(xy 62.71677 -329.464864) (xy 62.746773 -329.404677) (xy 62.765178 -329.376532) (xy 62.767718 -329.372468)
			(xy 62.771782 -329.35926) (xy 62.773849 -329.351777) (xy 62.773855 -329.336261) (xy 62.771782 -329.32878)
			(xy 62.767718 -329.315572) (xy 62.765178 -329.311508) (xy 62.746789 -329.283351) (xy 62.716783 -329.223167)
			(xy 62.694967 -329.159553) (xy 62.681723 -329.09362) (xy 62.677281 -329.026517) (xy 62.681719 -328.959413)
			(xy 62.694959 -328.893479) (xy 62.71677 -328.829864) (xy 62.746773 -328.769677) (xy 62.765178 -328.741532)
			(xy 62.767718 -328.737468) (xy 62.771782 -328.72426) (xy 62.773849 -328.716777) (xy 62.773855 -328.701261)
			(xy 62.771782 -328.69378) (xy 62.767718 -328.680572) (xy 62.765178 -328.676508) (xy 62.74858 -328.651201)
			(xy 62.720852 -328.597403) (xy 62.699705 -328.540694) (xy 62.685438 -328.481877) (xy 62.678253 -328.421782)
			(xy 62.677802 -328.39152) (xy 62.67836 -328.357639) (xy 62.687356 -328.290477) (xy 62.70519 -328.225104)
			(xy 62.731546 -328.162679) (xy 62.765959 -328.104306) (xy 62.807819 -328.051019) (xy 62.856383 -328.003763)
			(xy 62.910793 -327.963374) (xy 62.940184 -327.946512) (xy 62.942216 -327.945496) (xy 62.94628 -327.94321)
			(xy 63.52921 -327.36028) (xy 63.536605 -327.353427) (xy 63.555204 -327.345683) (xy 63.565278 -327.345294)
			(xy 96.614996 -327.345294) (xy 96.633538 -327.352914) (xy 96.635824 -327.3552) (xy 100.032566 -327.3552)
			(xy 100.042631 -327.354765) (xy 100.061218 -327.347033) (xy 100.068634 -327.340214) (xy 100.682552 -326.726296)
			(xy 100.688953 -326.71931) (xy 100.69653 -326.701958) (xy 100.697284 -326.692514) (xy 100.697284 -326.69226)
			(xy 100.698808 -326.66233) (xy 100.708017 -326.60311) (xy 100.72413 -326.545385) (xy 100.73513 -326.517508)
			(xy 100.73894 -326.50811) (xy 100.73894 -326.277986) (xy 100.73513 -326.268588) (xy 100.723087 -326.237845)
			(xy 100.706135 -326.174031) (xy 100.697572 -326.108561) (xy 100.69703 -326.075548) (xy 100.697556 -326.042533)
			(xy 100.70611 -325.977061) (xy 100.723081 -325.91325) (xy 100.73513 -325.882508) (xy 100.73894 -325.87311)
			(xy 100.73894 -325.642986) (xy 100.73513 -325.633588) (xy 100.723087 -325.602845) (xy 100.706135 -325.539031)
			(xy 100.697572 -325.473561) (xy 100.69703 -325.440548) (xy 100.697556 -325.407533) (xy 100.70611 -325.342061)
			(xy 100.723081 -325.27825) (xy 100.73513 -325.247508) (xy 100.73894 -325.23811) (xy 100.73894 -325.046086)
			(xy 100.738734 -325.039854) (xy 100.735661 -325.027772) (xy 100.732844 -325.02221) (xy 100.732844 -325.021956)
			(xy 100.718266 -324.994013) (xy 100.69536 -324.935296) (xy 100.67989 -324.874198) (xy 100.672092 -324.811655)
			(xy 100.672087 -324.748629) (xy 100.679874 -324.686085) (xy 100.695335 -324.624984) (xy 100.718231 -324.566264)
			(xy 100.732844 -324.53834) (xy 100.732844 -324.538086) (xy 100.735639 -324.532515) (xy 100.738709 -324.520439)
			(xy 100.73894 -324.51421) (xy 100.73894 -324.411086) (xy 100.738734 -324.404854) (xy 100.735661 -324.392772)
			(xy 100.732844 -324.38721) (xy 100.732844 -324.386956) (xy 100.718266 -324.359013) (xy 100.69536 -324.300296)
			(xy 100.67989 -324.239198) (xy 100.672092 -324.176655) (xy 100.672087 -324.113629) (xy 100.679874 -324.051085)
			(xy 100.695335 -323.989984) (xy 100.718231 -323.931264) (xy 100.732844 -323.90334) (xy 100.732844 -323.903086)
			(xy 100.735639 -323.897515) (xy 100.738709 -323.885439) (xy 100.73894 -323.87921) (xy 100.73894 -323.776086)
			(xy 100.738734 -323.769854) (xy 100.735661 -323.757772) (xy 100.732844 -323.75221) (xy 100.732844 -323.751956)
			(xy 100.718266 -323.724013) (xy 100.69536 -323.665296) (xy 100.67989 -323.604198) (xy 100.672092 -323.541655)
			(xy 100.672087 -323.478629) (xy 100.679874 -323.416085) (xy 100.695335 -323.354984) (xy 100.718231 -323.296264)
			(xy 100.732844 -323.26834) (xy 100.732844 -323.268086) (xy 100.735639 -323.262515) (xy 100.738709 -323.250439)
			(xy 100.73894 -323.24421) (xy 100.73894 -323.141086) (xy 100.738734 -323.134854) (xy 100.735661 -323.122772)
			(xy 100.732844 -323.11721) (xy 100.732844 -323.116956) (xy 100.718266 -323.089013) (xy 100.69536 -323.030296)
			(xy 100.67989 -322.969198) (xy 100.672092 -322.906655) (xy 100.672087 -322.843629) (xy 100.679874 -322.781085)
			(xy 100.695335 -322.719984) (xy 100.718231 -322.661264) (xy 100.732844 -322.63334) (xy 100.732844 -322.633086)
			(xy 100.735639 -322.627515) (xy 100.738709 -322.615439) (xy 100.73894 -322.60921) (xy 100.73894 -322.506086)
			(xy 100.738734 -322.499854) (xy 100.735661 -322.487772) (xy 100.732844 -322.48221) (xy 100.732844 -322.481956)
			(xy 100.718266 -322.454013) (xy 100.69536 -322.395296) (xy 100.67989 -322.334198) (xy 100.672092 -322.271655)
			(xy 100.672087 -322.208629) (xy 100.679874 -322.146085) (xy 100.695335 -322.084984) (xy 100.718231 -322.026264)
			(xy 100.732844 -321.99834) (xy 100.732844 -321.998086) (xy 100.735639 -321.992515) (xy 100.738709 -321.980439)
			(xy 100.73894 -321.97421) (xy 100.73894 -321.871086) (xy 100.738734 -321.864854) (xy 100.735661 -321.852772)
			(xy 100.732844 -321.84721) (xy 100.732844 -321.846956) (xy 100.718269 -321.819013) (xy 100.695368 -321.760297)
			(xy 100.679901 -321.6992) (xy 100.672104 -321.63666) (xy 100.67163 -321.605148) (xy 100.672102 -321.573636)
			(xy 100.679893 -321.511094) (xy 100.695361 -321.449997) (xy 100.718269 -321.391283) (xy 100.732844 -321.36334)
			(xy 100.735672 -321.357712) (xy 100.738762 -321.345506) (xy 100.73894 -321.33921) (xy 100.73894 -305.574192)
			(xy 100.738514 -305.564124) (xy 100.730791 -305.545527) (xy 100.723954 -305.538124) (xy 96.467168 -301.281338)
			(xy 96.467168 -301.281084) (xy 96.461748 -301.269745) (xy 96.44228 -301.253902) (xy 96.430084 -301.250858)
			(xy 96.34728 -301.234348) (xy 96.336866 -301.233332) (xy 96.301814 -301.24781) (xy 96.30156 -301.248064)
			(xy 96.279985 -301.268625) (xy 96.231637 -301.30347) (xy 96.178461 -301.330377) (xy 96.121749 -301.348691)
			(xy 96.06288 -301.357967) (xy 96.033082 -301.358554) (xy 96.00583 -301.358067) (xy 95.951882 -301.350309)
			(xy 95.899587 -301.334952) (xy 95.850009 -301.312311) (xy 95.804158 -301.282845) (xy 95.762966 -301.247154)
			(xy 95.727272 -301.205965) (xy 95.697803 -301.160116) (xy 95.675157 -301.110539) (xy 95.659797 -301.058245)
			(xy 95.652035 -301.004298) (xy 95.651574 -300.977046) (xy 95.652051 -300.949873) (xy 95.659756 -300.896076)
			(xy 95.675018 -300.843916) (xy 95.697526 -300.79445) (xy 95.726826 -300.748679) (xy 95.762324 -300.707529)
			(xy 95.803303 -300.671832) (xy 95.848932 -300.642311) (xy 95.898289 -300.619564) (xy 95.950374 -300.604051)
			(xy 96.004133 -300.596086) (xy 96.031304 -300.595538) (xy 96.044004 -300.595538) (xy 96.05518 -300.589696)
			(xy 96.060713 -300.586534) (xy 96.070096 -300.577918) (xy 96.073722 -300.572678) (xy 96.120204 -300.502574)
			(xy 96.126543 -300.491779) (xy 96.128933 -300.466886) (xy 96.124776 -300.455076) (xy 95.894652 -299.899578)
			(xy 95.880695 -299.864293) (xy 95.861031 -299.791004) (xy 95.851098 -299.715776) (xy 95.850456 -299.677836)
			(xy 95.850456 -296.422318) (xy 95.850957 -296.38734) (xy 95.859379 -296.317893) (xy 95.876116 -296.24997)
			(xy 95.888048 -296.217086) (xy 95.890987 -296.208118) (xy 95.890872 -296.189264) (xy 95.883978 -296.171714)
			(xy 95.877888 -296.164508) (xy 95.862543 -296.14746) (xy 95.836621 -296.109621) (xy 95.816653 -296.068329)
			(xy 95.803089 -296.024513) (xy 95.796236 -295.979161) (xy 95.795846 -295.956228) (xy 95.796312 -295.932038)
			(xy 95.80395 -295.884265) (xy 95.819023 -295.838293) (xy 95.841154 -295.795272) (xy 95.86979 -295.756277)
			(xy 95.904215 -295.722284) (xy 95.923608 -295.707816) (xy 95.9272 -295.705149) (xy 95.933465 -295.698764)
			(xy 95.936054 -295.695116) (xy 95.94215 -295.683178) (xy 95.953034 -295.653397) (xy 95.980567 -295.596276)
			(xy 96.014329 -295.542602) (xy 96.053894 -295.49305) (xy 96.076008 -295.470326) (xy 96.26473 -295.281604)
			(xy 96.268971 -295.277125) (xy 96.275388 -295.266596) (xy 96.27743 -295.260776) (xy 96.279381 -295.253609)
			(xy 96.279522 -295.238762) (xy 96.277684 -295.231566) (xy 96.277684 -295.231058) (xy 96.276414 -295.22674)
			(xy 96.275906 -295.224708) (xy 96.27116 -295.205628) (xy 96.266058 -295.166643) (xy 96.265746 -295.146984)
			(xy 96.265746 -295.141904) (xy 96.266557 -295.117944) (xy 96.274718 -295.070704) (xy 96.290151 -295.025317)
			(xy 96.312477 -294.982894) (xy 96.34115 -294.944475) (xy 96.375468 -294.911001) (xy 96.394778 -294.896794)
			(xy 96.404684 -294.887904) (xy 96.408206 -294.883447) (xy 96.413338 -294.873315) (xy 96.414844 -294.867838)
			(xy 96.414844 -294.867584) (xy 96.416368 -294.861742) (xy 96.428154 -294.818211) (xy 96.457753 -294.733012)
			(xy 96.494041 -294.650441) (xy 96.536787 -294.571021) (xy 96.58572 -294.495256) (xy 96.640531 -294.423628)
			(xy 96.670368 -294.38981) (xy 96.674432 -294.384984) (xy 96.684084 -294.360092) (xy 96.685707 -294.355628)
			(xy 96.68749 -294.346298) (xy 96.68764 -294.34155) (xy 96.68764 -294.330628) (xy 96.687481 -294.325944)
			(xy 96.685688 -294.316744) (xy 96.684084 -294.31234) (xy 96.677734 -294.29583) (xy 96.676003 -294.291613)
			(xy 96.67128 -294.283817) (xy 96.668336 -294.280336) (xy 96.638409 -294.24624) (xy 96.583496 -294.174014)
			(xy 96.53455 -294.097619) (xy 96.491885 -294.017547) (xy 96.455775 -293.934312) (xy 96.426455 -293.84845)
			(xy 96.414844 -293.804594) (xy 96.412435 -293.796509) (xy 96.403223 -293.782391) (xy 96.39681 -293.776908)
			(xy 96.376952 -293.762508) (xy 96.341673 -293.728433) (xy 96.312295 -293.689157) (xy 96.289573 -293.645689)
			(xy 96.274092 -293.599147) (xy 96.26625 -293.55073) (xy 96.26625 -293.501682) (xy 96.274089 -293.453264)
			(xy 96.289569 -293.406722) (xy 96.312289 -293.363253) (xy 96.341666 -293.323975) (xy 96.376944 -293.289899)
			(xy 96.39681 -293.275512) (xy 96.403282 -293.270085) (xy 96.412495 -293.25594) (xy 96.414844 -293.247826)
			(xy 96.42646 -293.203972) (xy 96.45579 -293.118115) (xy 96.491904 -293.034883) (xy 96.534569 -292.954812)
			(xy 96.583511 -292.878415) (xy 96.638416 -292.806185) (xy 96.668336 -292.772084) (xy 96.671292 -292.768611)
			(xy 96.676023 -292.760817) (xy 96.677734 -292.75659) (xy 96.684084 -292.74008) (xy 96.685731 -292.735687)
			(xy 96.68753 -292.726482) (xy 96.68764 -292.721792) (xy 96.68764 -292.710616) (xy 96.68748 -292.705932)
			(xy 96.685685 -292.696733) (xy 96.684084 -292.692328) (xy 96.677734 -292.675818) (xy 96.676002 -292.671601)
			(xy 96.671277 -292.663806) (xy 96.668336 -292.660324) (xy 96.63841 -292.626227) (xy 96.583497 -292.554002)
			(xy 96.534551 -292.477607) (xy 96.491887 -292.397534) (xy 96.455779 -292.314299) (xy 96.426459 -292.228437)
			(xy 96.414844 -292.184582) (xy 96.412433 -292.176498) (xy 96.403219 -292.162383) (xy 96.39681 -292.156896)
			(xy 96.376953 -292.142496) (xy 96.341676 -292.108422) (xy 96.312299 -292.069145) (xy 96.289579 -292.025678)
			(xy 96.2741 -291.979138) (xy 96.26626 -291.930722) (xy 96.26626 -291.881675) (xy 96.274101 -291.833259)
			(xy 96.28958 -291.786719) (xy 96.312301 -291.743253) (xy 96.341678 -291.703977) (xy 96.376955 -291.669902)
			(xy 96.39681 -291.6555) (xy 96.403281 -291.650073) (xy 96.412491 -291.635926) (xy 96.414844 -291.627814)
			(xy 96.42646 -291.58396) (xy 96.455791 -291.498103) (xy 96.491906 -291.414872) (xy 96.534571 -291.334802)
			(xy 96.583514 -291.258406) (xy 96.638419 -291.186176) (xy 96.668336 -291.152072) (xy 96.671291 -291.148599)
			(xy 96.67602 -291.140804) (xy 96.677734 -291.136578) (xy 96.684084 -291.120068) (xy 96.68573 -291.115675)
			(xy 96.687527 -291.106469) (xy 96.68764 -291.10178) (xy 96.68764 -291.090604) (xy 96.687478 -291.08592)
			(xy 96.685682 -291.076722) (xy 96.684084 -291.072316) (xy 96.677734 -291.055806) (xy 96.676002 -291.05159)
			(xy 96.671275 -291.043796) (xy 96.668336 -291.040312) (xy 96.638407 -291.006217) (xy 96.58349 -290.933993)
			(xy 96.534538 -290.8576) (xy 96.491868 -290.777529) (xy 96.455753 -290.694295) (xy 96.426427 -290.608434)
			(xy 96.414844 -290.56457) (xy 96.412445 -290.556479) (xy 96.403245 -290.542343) (xy 96.39681 -290.536884)
			(xy 96.376954 -290.522484) (xy 96.341679 -290.48841) (xy 96.312304 -290.449134) (xy 96.289586 -290.405668)
			(xy 96.274108 -290.359129) (xy 96.266269 -290.310715) (xy 96.26627 -290.261669) (xy 96.274112 -290.213255)
			(xy 96.289592 -290.166717) (xy 96.312313 -290.123252) (xy 96.341689 -290.083978) (xy 96.376967 -290.049905)
			(xy 96.39681 -290.035488) (xy 96.40328 -290.030059) (xy 96.412486 -290.015912) (xy 96.414844 -290.007802)
			(xy 96.426461 -289.963948) (xy 96.455793 -289.878092) (xy 96.491908 -289.794861) (xy 96.534574 -289.714791)
			(xy 96.583517 -289.638396) (xy 96.638423 -289.566167) (xy 96.668336 -289.53206) (xy 96.67129 -289.528586)
			(xy 96.676018 -289.520791) (xy 96.677734 -289.516566) (xy 96.684084 -289.500056) (xy 96.685729 -289.495663)
			(xy 96.687524 -289.486457) (xy 96.68764 -289.481768) (xy 96.68764 -289.470592) (xy 96.687486 -289.465906)
			(xy 96.685704 -289.456703) (xy 96.684084 -289.452304) (xy 96.677734 -289.435794) (xy 96.676001 -289.431578)
			(xy 96.671273 -289.423786) (xy 96.668336 -289.4203) (xy 96.634884 -289.382095) (xy 96.574212 -289.300656)
			(xy 96.521086 -289.214105) (xy 96.475934 -289.12314) (xy 96.439118 -289.028494) (xy 96.424496 -288.979864)
			(xy 96.421604 -288.971154) (xy 96.410676 -288.956427) (xy 96.40316 -288.951162) (xy 96.380651 -288.937295)
			(xy 96.339955 -288.903551) (xy 96.305145 -288.863764) (xy 96.277107 -288.818946) (xy 96.256554 -288.77024)
			(xy 96.24401 -288.718884) (xy 96.239794 -288.666187) (xy 96.244014 -288.61349) (xy 96.256562 -288.562135)
			(xy 96.277119 -288.51343) (xy 96.305161 -288.468615) (xy 96.339974 -288.42883) (xy 96.380672 -288.39509)
			(xy 96.40316 -288.381186) (xy 96.410659 -288.375901) (xy 96.421594 -288.361187) (xy 96.424496 -288.352484)
			(xy 96.439115 -288.303853) (xy 96.475926 -288.209205) (xy 96.521079 -288.118239) (xy 96.574209 -288.031691)
			(xy 96.634888 -287.950257) (xy 96.668336 -287.912048) (xy 96.671289 -287.908574) (xy 96.676015 -287.900777)
			(xy 96.677734 -287.896554) (xy 96.684084 -287.880044) (xy 96.685728 -287.875651) (xy 96.687521 -287.866445)
			(xy 96.68764 -287.861756) (xy 96.68764 -287.85058) (xy 96.687485 -287.845895) (xy 96.685701 -287.836692)
			(xy 96.684084 -287.832292) (xy 96.677734 -287.815782) (xy 96.676 -287.811567) (xy 96.671271 -287.803776)
			(xy 96.668336 -287.800288) (xy 96.638408 -287.766192) (xy 96.583492 -287.693968) (xy 96.534542 -287.617575)
			(xy 96.491873 -287.537503) (xy 96.45576 -287.454269) (xy 96.426436 -287.368408) (xy 96.414844 -287.324546)
			(xy 96.412442 -287.316457) (xy 96.403238 -287.302327) (xy 96.39681 -287.29686) (xy 96.37695 -287.282462)
			(xy 96.341665 -287.248389) (xy 96.31228 -287.209114) (xy 96.289551 -287.165647) (xy 96.274063 -287.119106)
			(xy 96.266212 -287.070687) (xy 96.265746 -287.046162) (xy 96.266182 -287.022545) (xy 96.273446 -286.975874)
			(xy 96.28781 -286.930878) (xy 96.30893 -286.88863) (xy 96.336305 -286.850139) (xy 96.36928 -286.816321)
			(xy 96.38792 -286.801814) (xy 96.394524 -286.796988) (xy 96.414844 -286.768032) (xy 96.414844 -286.767778)
			(xy 96.427227 -286.721169) (xy 96.458891 -286.630068) (xy 96.498204 -286.541998) (xy 96.54488 -286.457598)
			(xy 96.571308 -286.417258) (xy 96.593616 -286.384489) (xy 96.642176 -286.321821) (xy 96.668336 -286.292036)
			(xy 96.674432 -286.285178) (xy 96.684084 -286.260286) (xy 96.685707 -286.255822) (xy 96.687488 -286.246492)
			(xy 96.68764 -286.241744) (xy 96.68764 -286.230568) (xy 96.687559 -286.225892) (xy 96.685901 -286.216688)
			(xy 96.684338 -286.21228) (xy 96.674686 -286.187388) (xy 96.674432 -286.187134) (xy 96.673416 -286.186118)
			(xy 96.668336 -286.18053) (xy 96.635015 -286.142457) (xy 96.574542 -286.061334) (xy 96.521556 -285.975133)
			(xy 96.476481 -285.884545) (xy 96.439678 -285.790292) (xy 96.425004 -285.741872) (xy 96.424496 -285.740348)
			(xy 96.424496 -285.739586) (xy 96.421475 -285.730681) (xy 96.409996 -285.715803) (xy 96.402144 -285.71063)
			(xy 96.401636 -285.710376) (xy 96.379323 -285.69647) (xy 96.339008 -285.662726) (xy 96.30454 -285.623028)
			(xy 96.276788 -285.578377) (xy 96.256449 -285.529897) (xy 96.244038 -285.47881) (xy 96.239865 -285.426402)
			(xy 96.244037 -285.373995) (xy 96.256448 -285.322907) (xy 96.276786 -285.274427) (xy 96.304538 -285.229775)
			(xy 96.339005 -285.190077) (xy 96.379319 -285.156332) (xy 96.401636 -285.142432) (xy 96.402144 -285.142178)
			(xy 96.408491 -285.137915) (xy 96.418566 -285.126425) (xy 96.421956 -285.119572) (xy 96.424496 -285.11246)
			(xy 96.427544 -285.102046) (xy 96.428814 -285.097982) (xy 96.430084 -285.094172) (xy 96.445213 -285.046767)
			(xy 96.482682 -284.954575) (xy 96.528106 -284.866032) (xy 96.581134 -284.781822) (xy 96.641356 -284.702597)
			(xy 96.674432 -284.66542) (xy 96.674686 -284.665166) (xy 96.684338 -284.640274) (xy 96.685897 -284.635865)
			(xy 96.687556 -284.626662) (xy 96.68764 -284.621986) (xy 96.68764 -284.61081) (xy 96.687479 -284.606126)
			(xy 96.685683 -284.596928) (xy 96.684084 -284.592522) (xy 96.677734 -284.576012) (xy 96.676002 -284.571795)
			(xy 96.671276 -284.564001) (xy 96.668336 -284.560518) (xy 96.63841 -284.526421) (xy 96.583498 -284.454196)
			(xy 96.534552 -284.3778) (xy 96.491888 -284.297728) (xy 96.455781 -284.214492) (xy 96.426461 -284.12863)
			(xy 96.414844 -284.084776) (xy 96.412432 -284.076693) (xy 96.403217 -284.062579) (xy 96.39681 -284.05709)
			(xy 96.376954 -284.04269) (xy 96.341677 -284.008616) (xy 96.312302 -283.96934) (xy 96.289583 -283.925873)
			(xy 96.274104 -283.879334) (xy 96.266264 -283.830918) (xy 96.266265 -283.781872) (xy 96.274106 -283.733457)
			(xy 96.289586 -283.686918) (xy 96.312307 -283.643452) (xy 96.341683 -283.604177) (xy 96.376961 -283.570104)
			(xy 96.39681 -283.555694) (xy 96.40328 -283.550266) (xy 96.412488 -283.536119) (xy 96.414844 -283.528008)
			(xy 96.426461 -283.484154) (xy 96.455792 -283.398298) (xy 96.491907 -283.315067) (xy 96.534573 -283.234996)
			(xy 96.583516 -283.158601) (xy 96.638421 -283.086372) (xy 96.668336 -283.052266) (xy 96.67129 -283.048793)
			(xy 96.676019 -283.040997) (xy 96.677734 -283.036772) (xy 96.684084 -283.020262) (xy 96.68573 -283.015869)
			(xy 96.687526 -283.006663) (xy 96.68764 -283.001974) (xy 96.68764 -282.990798) (xy 96.687487 -282.986112)
			(xy 96.685705 -282.976909) (xy 96.684084 -282.97251) (xy 96.677734 -282.956) (xy 96.676001 -282.951784)
			(xy 96.671274 -282.943991) (xy 96.668336 -282.940506) (xy 96.634884 -282.902301) (xy 96.574212 -282.820862)
			(xy 96.521085 -282.734312) (xy 96.475932 -282.643347) (xy 96.439116 -282.5487) (xy 96.424496 -282.50007)
			(xy 96.421605 -282.491359) (xy 96.410678 -282.476631) (xy 96.40316 -282.471368) (xy 96.38065 -282.457501)
			(xy 96.339954 -282.423757) (xy 96.305143 -282.383969) (xy 96.277104 -282.339151) (xy 96.25655 -282.290444)
			(xy 96.244006 -282.239088) (xy 96.239789 -282.18639) (xy 96.244009 -282.133692) (xy 96.256557 -282.082336)
			(xy 96.277113 -282.03363) (xy 96.305155 -281.988814) (xy 96.339969 -281.949029) (xy 96.380667 -281.915287)
			(xy 96.40316 -281.901392) (xy 96.41066 -281.896107) (xy 96.421596 -281.881394) (xy 96.424496 -281.87269)
			(xy 96.439115 -281.824059) (xy 96.475926 -281.72941) (xy 96.521078 -281.638445) (xy 96.574208 -281.551896)
			(xy 96.634886 -281.470461) (xy 96.668336 -281.432254) (xy 96.67129 -281.42878) (xy 96.676017 -281.420984)
			(xy 96.677734 -281.41676) (xy 96.684084 -281.40025) (xy 96.685729 -281.395857) (xy 96.687522 -281.386651)
			(xy 96.68764 -281.381962) (xy 96.68764 -281.370786) (xy 96.687486 -281.3661) (xy 96.685702 -281.356898)
			(xy 96.684084 -281.352498) (xy 96.677734 -281.335988) (xy 96.676 -281.331772) (xy 96.671272 -281.323981)
			(xy 96.668336 -281.320494) (xy 96.638408 -281.286398) (xy 96.583491 -281.214174) (xy 96.534541 -281.137781)
			(xy 96.491872 -281.05771) (xy 96.455758 -280.974475) (xy 96.426433 -280.888614) (xy 96.414844 -280.844752)
			(xy 96.412442 -280.836662) (xy 96.40324 -280.822531) (xy 96.39681 -280.817066) (xy 96.376148 -280.802074)
			(xy 96.339661 -280.766378) (xy 96.309607 -280.725119) (xy 96.29775 -280.702512) (xy 96.286939 -280.679635)
			(xy 96.272124 -280.631256) (xy 96.268286 -280.606246) (xy 96.267642 -280.602219) (xy 96.26522 -280.594431)
			(xy 96.26346 -280.590752) (xy 96.25203 -280.56713) (xy 96.24568 -280.561034) (xy 96.210099 -280.52548)
			(xy 96.144724 -280.449025) (xy 96.086436 -280.36704) (xy 96.035701 -280.280177) (xy 95.992923 -280.189131)
			(xy 95.958446 -280.09463) (xy 95.944944 -280.046176) (xy 95.943694 -280.041988) (xy 95.939995 -280.03407)
			(xy 95.937578 -280.030428) (xy 95.932752 -280.023316) (xy 95.910585 -280.008714) (xy 95.871037 -279.973317)
			(xy 95.837971 -279.931799) (xy 95.81232 -279.885333) (xy 95.794809 -279.835229) (xy 95.785932 -279.7829)
			(xy 95.785432 -279.756362) (xy 95.785928 -279.730635) (xy 95.794257 -279.679861) (xy 95.810721 -279.631113)
			(xy 95.834882 -279.585685) (xy 95.866098 -279.544784) (xy 95.903542 -279.509494) (xy 95.924624 -279.494742)
			(xy 95.928529 -279.491961) (xy 95.935311 -279.485189) (xy 95.938086 -279.48128) (xy 95.942404 -279.475184)
			(xy 95.955714 -279.425871) (xy 95.990083 -279.329679) (xy 96.033035 -279.237) (xy 96.084217 -279.1486)
			(xy 96.143207 -279.065206) (xy 96.209518 -278.987507) (xy 96.24568 -278.951436) (xy 96.25203 -278.94534)
			(xy 96.26346 -278.921718) (xy 96.265199 -278.918031) (xy 96.26762 -278.910246) (xy 96.268286 -278.906224)
			(xy 96.271583 -278.884329) (xy 96.283693 -278.84174) (xy 96.292416 -278.821388) (xy 96.304243 -278.796447)
			(xy 96.335511 -278.750965) (xy 96.374464 -278.711862) (xy 96.39681 -278.695658) (xy 96.403287 -278.690234)
			(xy 96.412512 -278.676091) (xy 96.414844 -278.667972) (xy 96.429095 -278.61458) (xy 96.46663 -278.510635)
			(xy 96.489774 -278.460454) (xy 96.514177 -278.410747) (xy 96.57131 -278.315883) (xy 96.637437 -278.227055)
			(xy 96.674178 -278.185626) (xy 96.680226 -278.178452) (xy 96.686996 -278.160966) (xy 96.687386 -278.15159)
			(xy 96.687386 -278.121872) (xy 96.686944 -278.112452) (xy 96.680164 -278.09487) (xy 96.674178 -278.087582)
			(xy 96.639621 -278.048886) (xy 96.576964 -277.96619) (xy 96.522161 -277.878092) (xy 96.475675 -277.785335)
			(xy 96.437898 -277.688704) (xy 96.422972 -277.639018) (xy 96.41996 -277.629954) (xy 96.408338 -277.614816)
			(xy 96.400366 -277.609554) (xy 96.378205 -277.595615) (xy 96.338186 -277.561864) (xy 96.303984 -277.522229)
			(xy 96.276454 -277.477702) (xy 96.256281 -277.429393) (xy 96.243971 -277.37851) (xy 96.239831 -277.326323)
			(xy 96.243964 -277.274135) (xy 96.256267 -277.22325) (xy 96.276433 -277.174939) (xy 96.303957 -277.130407)
			(xy 96.338154 -277.090768) (xy 96.378168 -277.057012) (xy 96.400366 -277.043134) (xy 96.40833 -277.037866)
			(xy 96.419939 -277.022725) (xy 96.422972 -277.01367) (xy 96.435312 -276.972381) (xy 96.465449 -276.89164)
			(xy 96.501651 -276.813429) (xy 96.543706 -276.738204) (xy 96.59137 -276.666402) (xy 96.617536 -276.632162)
			(xy 96.62287 -276.625558) (xy 96.628204 -276.609556) (xy 96.628204 -276.422104) (xy 96.62287 -276.406102)
			(xy 96.617536 -276.399498) (xy 96.601694 -276.378776) (xy 96.571709 -276.336087) (xy 96.557592 -276.314154)
			(xy 96.554544 -276.309582) (xy 96.205548 -275.960586) (xy 96.198698 -275.953189) (xy 96.190961 -275.934591)
			(xy 96.190562 -275.924518) (xy 96.190562 -275.49348) (xy 96.19099 -275.483413) (xy 96.198717 -275.464819)
			(xy 96.205548 -275.457412) (xy 96.545654 -275.117306) (xy 96.548956 -275.112226) (xy 96.549718 -275.110702)
			(xy 96.553528 -275.10486) (xy 96.557338 -275.091144) (xy 96.557338 -274.701508) (xy 96.553528 -274.687792)
			(xy 96.549718 -274.68195) (xy 96.52303 -274.637799) (xy 96.476894 -274.545516) (xy 96.439354 -274.449414)
			(xy 96.424496 -274.40001) (xy 96.421438 -274.390865) (xy 96.40969 -274.375593) (xy 96.401636 -274.370292)
			(xy 96.379322 -274.356386) (xy 96.339004 -274.322641) (xy 96.304534 -274.282943) (xy 96.276779 -274.23829)
			(xy 96.256439 -274.189809) (xy 96.244025 -274.13872) (xy 96.239851 -274.08631) (xy 96.244022 -274.0339)
			(xy 96.256433 -273.982811) (xy 96.27677 -273.934328) (xy 96.304522 -273.889674) (xy 96.33899 -273.849973)
			(xy 96.379305 -273.816226) (xy 96.401636 -273.802348) (xy 96.409714 -273.797073) (xy 96.421463 -273.781789)
			(xy 96.424496 -273.77263) (xy 96.438533 -273.72591) (xy 96.473599 -273.63487) (xy 96.516381 -273.54719)
			(xy 96.566563 -273.463526) (xy 96.623771 -273.384499) (xy 96.687578 -273.310697) (xy 96.722184 -273.276314)
			(xy 96.728295 -273.26987) (xy 96.735977 -273.253871) (xy 96.73717 -273.245072) (xy 96.740258 -273.220191)
			(xy 96.753502 -273.171837) (xy 96.774462 -273.126295) (xy 96.802575 -273.084784) (xy 96.819466 -273.066256)
			(xy 96.830018 -273.055437) (xy 96.852922 -273.035717) (xy 96.865186 -273.026886) (xy 96.872309 -273.021392)
			(xy 96.882473 -273.006563) (xy 96.884998 -272.99793) (xy 96.898011 -272.948841) (xy 96.931702 -272.85303)
			(xy 96.973867 -272.760634) (xy 96.998536 -272.716244) (xy 97.001629 -272.710426) (xy 97.004968 -272.697685)
			(xy 97.00514 -272.691098) (xy 97.00514 -272.001742) (xy 97.004794 -271.993318) (xy 96.999358 -271.97737)
			(xy 96.994472 -271.9705) (xy 96.989138 -271.963896) (xy 96.975168 -271.954498) (xy 96.966786 -271.952466)
			(xy 96.942359 -271.945833) (xy 96.895965 -271.925603) (xy 96.853542 -271.898) (xy 96.816252 -271.863779)
			(xy 96.785115 -271.823877) (xy 96.760984 -271.779387) (xy 96.74452 -271.731527) (xy 96.736174 -271.681607)
			(xy 96.736174 -271.630994) (xy 96.74452 -271.581074) (xy 96.760984 -271.533214) (xy 96.785114 -271.488724)
			(xy 96.816251 -271.448822) (xy 96.853541 -271.414601) (xy 96.895964 -271.386997) (xy 96.942358 -271.366767)
			(xy 96.966786 -271.360138) (xy 96.974872 -271.357731) (xy 96.988994 -271.348522) (xy 96.994472 -271.342104)
			(xy 96.999806 -271.3355) (xy 97.00514 -271.319498) (xy 97.00514 -270.38173) (xy 97.004793 -270.373307)
			(xy 96.999353 -270.357361) (xy 96.994472 -270.350488) (xy 96.989138 -270.343884) (xy 96.975168 -270.334486)
			(xy 96.966786 -270.332454) (xy 96.94236 -270.325821) (xy 96.895968 -270.305592) (xy 96.853547 -270.277989)
			(xy 96.816258 -270.243769) (xy 96.785123 -270.203868) (xy 96.760993 -270.15938) (xy 96.744531 -270.111521)
			(xy 96.736185 -270.061603) (xy 96.736186 -270.010992) (xy 96.744532 -269.961074) (xy 96.760995 -269.913216)
			(xy 96.785125 -269.868728) (xy 96.816261 -269.828827) (xy 96.853551 -269.794608) (xy 96.895972 -269.767006)
			(xy 96.942365 -269.746777) (xy 96.966786 -269.740126) (xy 96.974872 -269.737719) (xy 96.988992 -269.728508)
			(xy 96.994472 -269.722092) (xy 96.999806 -269.715488) (xy 97.00514 -269.699486) (xy 97.00514 -268.854682)
			(xy 97.005568 -268.844614) (xy 97.013291 -268.826018) (xy 97.020126 -268.818614) (xy 97.033334 -268.805406)
			(xy 97.036636 -268.80185) (xy 97.043612 -268.792417) (xy 97.048927 -268.769594) (xy 97.043606 -268.746772)
			(xy 97.036636 -268.737334) (xy 97.032826 -268.733524) (xy 97.029737 -268.730522) (xy 97.022712 -268.725538)
			(xy 97.018856 -268.723618) (xy 97.011998 -268.720316) (xy 97.003362 -268.7193) (xy 96.979041 -268.715791)
			(xy 96.931875 -268.702019) (xy 96.887524 -268.68087) (xy 96.847132 -268.652891) (xy 96.811742 -268.618805)
			(xy 96.782268 -268.579491) (xy 96.759471 -268.535964) (xy 96.743939 -268.489348) (xy 96.736074 -268.440846)
			(xy 96.735646 -268.416278) (xy 96.736118 -268.392287) (xy 96.743627 -268.344895) (xy 96.758456 -268.299261)
			(xy 96.78024 -268.256508) (xy 96.808442 -268.217688) (xy 96.84237 -268.183758) (xy 96.881187 -268.155552)
			(xy 96.923939 -268.133765) (xy 96.969571 -268.118932) (xy 97.016963 -268.11142) (xy 97.040954 -268.11097)
			(xy 97.064311 -268.111411) (xy 97.110481 -268.118525) (xy 97.155027 -268.132593) (xy 97.196908 -268.153286)
			(xy 97.235145 -268.180121) (xy 97.268846 -268.212471) (xy 97.297221 -268.249579) (xy 97.319609 -268.290579)
			(xy 97.327974 -268.312392) (xy 97.333179 -268.322197) (xy 97.350168 -268.336446) (xy 97.36074 -268.339824)
			(xy 97.401634 -268.348968) (xy 97.446846 -268.358874) (xy 97.449894 -268.359382) (xy 97.46166 -268.360615)
			(xy 97.484181 -268.353467) (xy 97.493074 -268.345666) (xy 97.493582 -268.345158) (xy 98.135948 -267.702792)
			(xy 98.140187 -267.698312) (xy 98.146599 -267.687782) (xy 98.148648 -267.681964) (xy 98.152204 -267.67028)
			(xy 98.150172 -267.658088) (xy 98.148135 -267.645231) (xy 98.145974 -267.619289) (xy 98.145854 -267.606272)
			(xy 98.146327 -267.582281) (xy 98.153836 -267.534891) (xy 98.168665 -267.489258) (xy 98.19045 -267.446506)
			(xy 98.218653 -267.407688) (xy 98.252581 -267.37376) (xy 98.291398 -267.345555) (xy 98.334149 -267.323769)
			(xy 98.379781 -267.308938) (xy 98.427171 -267.301427) (xy 98.451162 -267.300964) (xy 98.464179 -267.301068)
			(xy 98.490123 -267.303232) (xy 98.502978 -267.305282) (xy 98.51517 -267.307314) (xy 98.526854 -267.303758)
			(xy 98.53269 -267.301749) (xy 98.543227 -267.295329) (xy 98.547682 -267.291058) (xy 98.69424 -267.1445)
			(xy 98.699574 -267.13815) (xy 98.701902 -267.134868) (xy 98.705599 -267.12772) (xy 98.70694 -267.123926)
			(xy 98.707963 -267.120392) (xy 98.709117 -267.113125) (xy 98.709226 -267.109448) (xy 98.709734 -267.081)
			(xy 98.710496 -267.036042) (xy 98.709854 -267.027399) (xy 98.703492 -267.011291) (xy 98.69805 -267.004546)
			(xy 98.697034 -267.00353) (xy 98.68185 -266.986517) (xy 98.656186 -266.948826) (xy 98.636422 -266.907734)
			(xy 98.622997 -266.864156) (xy 98.616211 -266.819065) (xy 98.615754 -266.796266) (xy 98.616227 -266.772275)
			(xy 98.623737 -266.724886) (xy 98.638567 -266.679254) (xy 98.660352 -266.636503) (xy 98.688555 -266.597686)
			(xy 98.722483 -266.563758) (xy 98.7613 -266.535554) (xy 98.80405 -266.513769) (xy 98.849682 -266.498938)
			(xy 98.897071 -266.491427) (xy 98.921062 -266.490958) (xy 98.946761 -266.491485) (xy 98.997435 -266.500087)
			(xy 99.045952 -266.517055) (xy 99.090941 -266.541909) (xy 99.131133 -266.573947) (xy 99.16539 -266.612265)
			(xy 99.192746 -266.655778) (xy 99.212428 -266.703259) (xy 99.223879 -266.753366) (xy 99.225862 -266.778994)
			(xy 99.225862 -266.780772) (xy 99.225862 -266.781026) (xy 99.227164 -266.790077) (xy 99.235241 -266.806467)
			(xy 99.24161 -266.81303) (xy 99.260406 -266.831064) (xy 99.29241 -266.86129) (xy 99.299678 -266.867636)
			(xy 99.317569 -266.874817) (xy 99.327208 -266.87526) (xy 99.422458 -266.87526) (xy 99.43211 -266.874244)
			(xy 99.439356 -266.872621) (xy 99.452531 -266.865785) (xy 99.458018 -266.860782) (xy 99.546156 -266.772644)
			(xy 99.551015 -266.767351) (xy 99.557836 -266.754713) (xy 99.559618 -266.747752) (xy 99.560126 -266.745466)
			(xy 99.56449 -266.72227) (xy 99.579421 -266.677495) (xy 99.601065 -266.635553) (xy 99.628908 -266.597442)
			(xy 99.662285 -266.56407) (xy 99.700402 -266.536235) (xy 99.742348 -266.514598) (xy 99.787126 -266.499676)
			(xy 99.810316 -266.495276) (xy 99.812602 -266.494768) (xy 99.819573 -266.493014) (xy 99.832212 -266.486181)
			(xy 99.837494 -266.481306) (xy 100.08235 -266.23645) (xy 100.089716 -266.227306) (xy 100.094756 -266.218388)
			(xy 100.097971 -266.198175) (xy 100.093014 -266.178317) (xy 100.087176 -266.169902) (xy 100.072719 -266.149934)
			(xy 100.049767 -266.106309) (xy 100.034128 -266.059561) (xy 100.026208 -266.010907) (xy 100.025708 -265.98626)
			(xy 100.026182 -265.962271) (xy 100.033693 -265.914885) (xy 100.048524 -265.869258) (xy 100.07031 -265.826512)
			(xy 100.098514 -265.7877) (xy 100.132443 -265.753778) (xy 100.17126 -265.725581) (xy 100.21401 -265.703802)
			(xy 100.25964 -265.68898) (xy 100.307027 -265.681477) (xy 100.331016 -265.680952) (xy 100.355619 -265.681448)
			(xy 100.404188 -265.689342) (xy 100.450863 -265.704922) (xy 100.494435 -265.727785) (xy 100.514404 -265.742166)
			(xy 100.514912 -265.742674) (xy 100.515166 -265.742674) (xy 100.522561 -265.747734) (xy 100.539736 -265.752804)
			(xy 100.548694 -265.75258) (xy 100.557838 -265.752072) (xy 100.574348 -265.744452) (xy 101.891846 -264.426954)
			(xy 101.898016 -264.420195) (xy 101.905564 -264.403537) (xy 101.906578 -264.394442) (xy 101.906578 -264.387584)
			(xy 101.905816 -264.366248) (xy 101.906259 -264.342253) (xy 101.91376 -264.294853) (xy 101.928584 -264.249211)
			(xy 101.950367 -264.20645) (xy 101.978573 -264.167623) (xy 102.012505 -264.133688) (xy 102.051329 -264.10548)
			(xy 102.094088 -264.083693) (xy 102.13973 -264.068865) (xy 102.187129 -264.061361) (xy 102.211124 -264.06094)
			(xy 102.23246 -264.061702) (xy 102.232714 -264.061702) (xy 102.243556 -264.061919) (xy 102.263836 -264.054295)
			(xy 102.27183 -264.04697) (xy 102.435914 -263.882886) (xy 102.439817 -263.878691) (xy 102.445842 -263.868948)
			(xy 102.447852 -263.863582) (xy 102.448985 -263.860256) (xy 102.45039 -263.853371) (xy 102.450646 -263.849866)
			(xy 102.450646 -263.849612) (xy 102.454202 -263.782048) (xy 102.454273 -263.772788) (xy 102.448543 -263.755195)
			(xy 102.443026 -263.747758) (xy 102.443026 -263.747504) (xy 102.427253 -263.727014) (xy 102.402114 -263.681832)
			(xy 102.384948 -263.633061) (xy 102.376245 -263.582094) (xy 102.375716 -263.556242) (xy 102.376159 -263.532247)
			(xy 102.383661 -263.484848) (xy 102.398486 -263.439206) (xy 102.420269 -263.396446) (xy 102.448475 -263.357621)
			(xy 102.482407 -263.323686) (xy 102.521231 -263.295479) (xy 102.56399 -263.273693) (xy 102.609631 -263.258865)
			(xy 102.657029 -263.25136) (xy 102.681024 -263.250934) (xy 102.706875 -263.251478) (xy 102.757838 -263.260186)
			(xy 102.806608 -263.277349) (xy 102.851793 -263.302477) (xy 102.872286 -263.318244) (xy 102.87254 -263.318244)
			(xy 102.880007 -263.323702) (xy 102.897581 -263.329422) (xy 102.90683 -263.32942) (xy 102.974394 -263.325864)
			(xy 102.983695 -263.324983) (xy 103.000762 -263.317425) (xy 103.007668 -263.311132) (xy 103.107744 -263.211056)
			(xy 103.111554 -263.206738) (xy 103.112824 -263.205214) (xy 103.118584 -263.19644) (xy 103.123178 -263.175983)
			(xy 103.121714 -263.16559) (xy 103.097838 -263.074658) (xy 103.093698 -263.063698) (xy 103.07742 -263.046883)
			(xy 103.066596 -263.0424) (xy 103.063802 -263.041638) (xy 103.040217 -263.034412) (xy 102.995583 -263.013417)
			(xy 102.95491 -262.985511) (xy 102.919258 -262.951423) (xy 102.889558 -262.912042) (xy 102.866583 -262.868394)
			(xy 102.850933 -262.821617) (xy 102.843015 -262.772931) (xy 102.842568 -262.748268) (xy 102.843041 -262.724278)
			(xy 102.850551 -262.676888) (xy 102.865381 -262.631257) (xy 102.887166 -262.588507) (xy 102.915369 -262.549691)
			(xy 102.949297 -262.515764) (xy 102.988114 -262.487562) (xy 103.030865 -262.465778) (xy 103.076496 -262.450949)
			(xy 103.123886 -262.44344) (xy 103.147876 -262.44296) (xy 103.172534 -262.443439) (xy 103.221208 -262.45138)
			(xy 103.267971 -262.467042) (xy 103.311609 -262.490018) (xy 103.350985 -262.519711) (xy 103.385075 -262.555349)
			(xy 103.412992 -262.596003) (xy 103.434011 -262.640616) (xy 103.441246 -262.664194) (xy 103.442008 -262.666988)
			(xy 103.446492 -262.677812) (xy 103.463306 -262.694088) (xy 103.474266 -262.69823) (xy 103.565198 -262.722106)
			(xy 103.575595 -262.723605) (xy 103.596073 -262.719027) (xy 103.604822 -262.713216) (xy 103.606346 -262.711946)
			(xy 103.610664 -262.708136) (xy 104.739694 -261.579106) (xy 104.747092 -261.572258) (xy 104.76569 -261.56452)
			(xy 104.775762 -261.56412) (xy 106.025696 -261.56412) (xy 106.034684 -261.563777) (xy 106.051552 -261.557571)
			(xy 106.065217 -261.545895) (xy 106.069892 -261.538212) (xy 106.113326 -261.460742) (xy 106.118856 -261.449411)
			(xy 106.119266 -261.424231) (xy 106.114088 -261.412736) (xy 106.11231 -261.409688) (xy 106.10032 -261.389362)
			(xy 106.081414 -261.346124) (xy 106.068605 -261.300705) (xy 106.062136 -261.253959) (xy 106.061764 -261.230364)
			(xy 106.062244 -261.204665) (xy 106.069905 -261.153841) (xy 106.085054 -261.104727) (xy 106.107355 -261.058419)
			(xy 106.136308 -261.015952) (xy 106.171268 -260.978275) (xy 106.211452 -260.946229) (xy 106.255964 -260.92053)
			(xy 106.303809 -260.901753) (xy 106.353918 -260.890315) (xy 106.405172 -260.886475) (xy 106.456426 -260.890315)
			(xy 106.506535 -260.901753) (xy 106.55438 -260.92053) (xy 106.598892 -260.946229) (xy 106.639076 -260.978275)
			(xy 106.674036 -261.015952) (xy 106.702989 -261.058419) (xy 106.72529 -261.104727) (xy 106.740439 -261.153841)
			(xy 106.7481 -261.204665) (xy 106.74858 -261.230364) (xy 106.748191 -261.253959) (xy 106.741733 -261.300706)
			(xy 106.728935 -261.346129) (xy 106.710038 -261.389371) (xy 106.698034 -261.409688) (xy 106.696256 -261.412736)
			(xy 106.691063 -261.424228) (xy 106.691476 -261.449412) (xy 106.697018 -261.460742) (xy 106.740452 -261.538212)
			(xy 106.745171 -261.545859) (xy 106.758836 -261.55751) (xy 106.775671 -261.563759) (xy 106.784648 -261.56412)
			(xy 107.225338 -261.56412) (xy 107.23741 -261.563454) (xy 107.258901 -261.552453) (xy 107.266486 -261.543038)
			(xy 107.289854 -261.51078) (xy 107.289854 -261.510272) (xy 107.314746 -261.47649) (xy 107.318119 -261.471549)
			(xy 107.322733 -261.460516) (xy 107.32389 -261.454646) (xy 107.324906 -261.447534) (xy 107.323382 -261.435596)
			(xy 107.321858 -261.43077) (xy 107.313807 -261.404641) (xy 107.305124 -261.350663) (xy 107.304586 -261.323328)
			(xy 107.304586 -261.317486) (xy 107.305528 -261.290788) (xy 107.314656 -261.238154) (xy 107.331824 -261.187569)
			(xy 107.356616 -261.140251) (xy 107.388436 -261.097342) (xy 107.426515 -261.059877) (xy 107.469936 -261.02876)
			(xy 107.517651 -261.004741) (xy 107.568509 -260.988399) (xy 107.621284 -260.980128) (xy 107.674704 -260.980128)
			(xy 107.727479 -260.988399) (xy 107.778337 -261.004741) (xy 107.826052 -261.02876) (xy 107.869473 -261.059877)
			(xy 107.907552 -261.097342) (xy 107.939372 -261.140251) (xy 107.964164 -261.187569) (xy 107.981332 -261.238154)
			(xy 107.99046 -261.290788) (xy 107.991402 -261.317486) (xy 107.991402 -261.323328) (xy 107.990872 -261.350664)
			(xy 107.982191 -261.404643) (xy 107.97413 -261.43077) (xy 107.972606 -261.435596) (xy 107.971082 -261.447534)
			(xy 107.972098 -261.454646) (xy 107.973214 -261.460527) (xy 107.977839 -261.471565) (xy 107.981242 -261.47649)
			(xy 108.006134 -261.510272) (xy 108.006134 -261.51078) (xy 108.029502 -261.543038) (xy 108.037109 -261.55243)
			(xy 108.058584 -261.563448) (xy 108.07065 -261.56412) (xy 108.175298 -261.56412) (xy 108.187363 -261.563441)
			(xy 108.208833 -261.552425) (xy 108.216446 -261.543038) (xy 108.239814 -261.51078) (xy 108.239814 -261.510272)
			(xy 108.264706 -261.47649) (xy 108.268076 -261.471548) (xy 108.272685 -261.460514) (xy 108.27385 -261.454646)
			(xy 108.274866 -261.447534) (xy 108.273342 -261.435596) (xy 108.271818 -261.43077) (xy 108.263766 -261.404642)
			(xy 108.255081 -261.350664) (xy 108.254546 -261.323328) (xy 108.254546 -261.317486) (xy 108.255483 -261.290786)
			(xy 108.264603 -261.238146) (xy 108.281764 -261.187554) (xy 108.306554 -261.14023) (xy 108.338373 -261.097316)
			(xy 108.376454 -261.059848) (xy 108.419878 -261.028729) (xy 108.467598 -261.00471) (xy 108.518462 -260.98837)
			(xy 108.571242 -260.980105) (xy 108.597954 -260.979666) (xy 108.598462 -260.979666) (xy 108.610312 -260.979775)
			(xy 108.633955 -260.981429) (xy 108.645706 -260.982968) (xy 108.649008 -260.983476) (xy 108.66374 -260.983476)
			(xy 108.669444 -260.98248) (xy 108.680215 -260.97824) (xy 108.685076 -260.975094) (xy 108.689394 -260.971792)
			(xy 108.72216 -260.943598) (xy 108.749338 -260.92023) (xy 108.753124 -260.91645) (xy 108.759146 -260.907611)
			(xy 108.761276 -260.902704) (xy 108.7628 -260.899402) (xy 108.76534 -260.886194) (xy 108.76534 -260.221222)
			(xy 108.764972 -260.213187) (xy 108.759919 -260.197928) (xy 108.755434 -260.19125) (xy 108.750862 -260.1849)
			(xy 108.737908 -260.175502) (xy 108.72978 -260.172962) (xy 108.705457 -260.164883) (xy 108.65934 -260.142528)
			(xy 108.61706 -260.113563) (xy 108.579558 -260.078634) (xy 108.547666 -260.038516) (xy 108.522095 -259.994101)
			(xy 108.503412 -259.946378) (xy 108.492033 -259.896408) (xy 108.488212 -259.845301) (xy 108.492033 -259.794194)
			(xy 108.503412 -259.744223) (xy 108.522094 -259.6965) (xy 108.547665 -259.652085) (xy 108.579557 -259.611967)
			(xy 108.61706 -259.577037) (xy 108.659339 -259.548073) (xy 108.705456 -259.525717) (xy 108.72978 -259.517642)
			(xy 108.730034 -259.517642) (xy 108.737632 -259.514912) (xy 108.750707 -259.505455) (xy 108.755688 -259.4991)
			(xy 108.76026 -259.49275) (xy 108.76534 -259.47751) (xy 108.76534 -259.171186) (xy 108.764981 -259.163148)
			(xy 108.759943 -259.147877) (xy 108.755434 -259.141214) (xy 108.750862 -259.134864) (xy 108.737908 -259.125466)
			(xy 108.72978 -259.122926) (xy 108.70546 -259.114847) (xy 108.659348 -259.092493) (xy 108.617074 -259.06353)
			(xy 108.579576 -259.028603) (xy 108.547688 -258.988488) (xy 108.522121 -258.944077) (xy 108.503442 -258.896358)
			(xy 108.492066 -258.846392) (xy 108.488247 -258.79529) (xy 108.492069 -258.744188) (xy 108.503448 -258.694223)
			(xy 108.52213 -258.646505) (xy 108.5477 -258.602096) (xy 108.579589 -258.561983) (xy 108.617089 -258.527057)
			(xy 108.659366 -258.498097) (xy 108.705479 -258.475745) (xy 108.72978 -258.467606) (xy 108.730034 -258.467606)
			(xy 108.73763 -258.464874) (xy 108.7507 -258.455413) (xy 108.755688 -258.449064) (xy 108.76026 -258.442714)
			(xy 108.76534 -258.427474) (xy 108.76534 -258.12115) (xy 108.764976 -258.113114) (xy 108.75993 -258.097849)
			(xy 108.755434 -258.091178) (xy 108.750862 -258.084828) (xy 108.737908 -258.07543) (xy 108.72978 -258.07289)
			(xy 108.703936 -258.064294) (xy 108.65515 -258.04009) (xy 108.610799 -258.008483) (xy 108.571999 -257.970266)
			(xy 108.539722 -257.9264) (xy 108.514781 -257.877986) (xy 108.497801 -257.826239) (xy 108.489209 -257.772461)
			(xy 108.488734 -257.74523) (xy 108.489145 -257.721415) (xy 108.495734 -257.674243) (xy 108.508775 -257.628433)
			(xy 108.52802 -257.584864) (xy 108.553099 -257.544371) (xy 108.567982 -257.525774) (xy 108.57357 -257.51917)
			(xy 108.58246 -257.49504) (xy 108.583984 -257.490753) (xy 108.585654 -257.481809) (xy 108.585762 -257.47726)
			(xy 108.585762 -257.455416) (xy 108.585294 -257.446263) (xy 108.578658 -257.429196) (xy 108.572808 -257.422142)
			(xy 108.571792 -257.420872) (xy 108.57103 -257.42011) (xy 108.348272 -257.197352) (xy 108.345421 -257.194647)
			(xy 108.339041 -257.190055) (xy 108.335572 -257.188208) (xy 108.330146 -257.185623) (xy 108.318466 -257.182795)
			(xy 108.312458 -257.18262) (xy 106.825542 -257.18262) (xy 106.825288 -257.18262) (xy 106.813504 -257.183275)
			(xy 106.79244 -257.19386) (xy 106.784902 -257.20294) (xy 106.775758 -257.21564) (xy 106.736134 -257.27152)
			(xy 106.732682 -257.276628) (xy 106.728066 -257.288055) (xy 106.72699 -257.294126) (xy 106.725466 -257.30581)
			(xy 106.72953 -257.317494) (xy 106.738419 -257.344837) (xy 106.747993 -257.401525) (xy 106.74858 -257.43027)
			(xy 106.7481 -257.455969) (xy 106.740439 -257.506793) (xy 106.72529 -257.555907) (xy 106.702989 -257.602215)
			(xy 106.674036 -257.644682) (xy 106.639076 -257.682359) (xy 106.598892 -257.714405) (xy 106.55438 -257.740104)
			(xy 106.541319 -257.74523) (xy 107.573829 -257.74523) (xy 107.577859 -257.692732) (xy 107.589856 -257.641464)
			(xy 107.609539 -257.592629) (xy 107.636445 -257.54737) (xy 107.669945 -257.506749) (xy 107.709253 -257.471718)
			(xy 107.753448 -257.443098) (xy 107.801493 -257.421559) (xy 107.852264 -257.407607) (xy 107.904569 -257.401569)
			(xy 107.957183 -257.403586) (xy 108.008873 -257.41361) (xy 108.058426 -257.431408) (xy 108.104682 -257.456561)
			(xy 108.146556 -257.48848) (xy 108.183068 -257.526418) (xy 108.21336 -257.569484) (xy 108.236723 -257.616669)
			(xy 108.252609 -257.666868) (xy 108.260646 -257.718904) (xy 108.26115 -257.74523) (xy 108.260646 -257.771556)
			(xy 108.252609 -257.823592) (xy 108.236723 -257.873791) (xy 108.21336 -257.920976) (xy 108.183068 -257.964042)
			(xy 108.146556 -258.00198) (xy 108.104682 -258.033899) (xy 108.058426 -258.059052) (xy 108.008873 -258.07685)
			(xy 107.957183 -258.086874) (xy 107.904569 -258.088891) (xy 107.852264 -258.082853) (xy 107.801493 -258.068901)
			(xy 107.753448 -258.047362) (xy 107.709253 -258.018742) (xy 107.669945 -257.983711) (xy 107.636445 -257.94309)
			(xy 107.609539 -257.897831) (xy 107.589856 -257.848996) (xy 107.577859 -257.797728) (xy 107.573829 -257.74523)
			(xy 106.541319 -257.74523) (xy 106.506535 -257.758881) (xy 106.456426 -257.770319) (xy 106.405172 -257.77416)
			(xy 106.353918 -257.770319) (xy 106.303809 -257.758881) (xy 106.255964 -257.740104) (xy 106.211452 -257.714405)
			(xy 106.171268 -257.682359) (xy 106.136308 -257.644682) (xy 106.107355 -257.602215) (xy 106.085054 -257.555907)
			(xy 106.069905 -257.506793) (xy 106.062244 -257.455969) (xy 106.061764 -257.43027) (xy 106.06235 -257.401525)
			(xy 106.071933 -257.344839) (xy 106.080814 -257.317494) (xy 106.080814 -257.31724) (xy 106.082606 -257.311515)
			(xy 106.083767 -257.299579) (xy 106.0831 -257.293618) (xy 106.081576 -257.28168) (xy 106.034586 -257.21564)
			(xy 106.025442 -257.20294) (xy 106.01789 -257.193873) (xy 105.996838 -257.183276) (xy 105.985056 -257.18262)
			(xy 101.179122 -257.18262) (xy 101.169058 -257.182183) (xy 101.150472 -257.174451) (xy 101.143054 -257.167634)
			(xy 100.919026 -256.943606) (xy 100.908358 -256.935478) (xy 100.90277 -256.932176) (xy 100.895658 -256.930398)
			(xy 100.873109 -256.924189) (xy 100.830081 -256.905859) (xy 100.790352 -256.881182) (xy 100.75485 -256.850736)
			(xy 100.724406 -256.815232) (xy 100.699732 -256.775502) (xy 100.681405 -256.732473) (xy 100.675186 -256.709926)
			(xy 100.673408 -256.702814) (xy 100.670106 -256.697226) (xy 100.661978 -256.686558) (xy 99.96424 -255.98882)
			(xy 99.956599 -255.981903) (xy 99.937461 -255.974308) (xy 99.927156 -255.974088) (xy 99.8474 -255.980438)
			(xy 99.84105 -255.9812) (xy 99.831724 -255.983568) (xy 99.815663 -255.994139) (xy 99.809808 -256.001774)
			(xy 99.795356 -256.021218) (xy 99.761338 -256.05571) (xy 99.722304 -256.084403) (xy 99.679232 -256.106577)
			(xy 99.633201 -256.121679) (xy 99.585364 -256.129329) (xy 99.561142 -256.12979) (xy 99.537147 -256.129347)
			(xy 99.489748 -256.121845) (xy 99.444106 -256.10702) (xy 99.401345 -256.085237) (xy 99.362519 -256.057032)
			(xy 99.328584 -256.023099) (xy 99.300376 -255.984276) (xy 99.278589 -255.941517) (xy 99.26376 -255.895876)
			(xy 99.256255 -255.848477) (xy 99.255834 -255.824482) (xy 99.256299 -255.800261) (xy 99.263947 -255.752425)
			(xy 99.27905 -255.706397) (xy 99.301228 -255.663329) (xy 99.329926 -255.624301) (xy 99.364424 -255.590292)
			(xy 99.38385 -255.575816) (xy 99.391489 -255.569963) (xy 99.402072 -255.553906) (xy 99.404424 -255.544574)
			(xy 99.405186 -255.538224) (xy 99.411536 -255.458468) (xy 99.41132 -255.448164) (xy 99.403716 -255.429029)
			(xy 99.396804 -255.421384) (xy 99.276916 -255.301496) (xy 99.269246 -255.294442) (xy 99.249927 -255.286692)
			(xy 99.22912 -255.287308) (xy 99.219512 -255.291336) (xy 99.199287 -255.300312) (xy 99.156893 -255.31298)
			(xy 99.113111 -255.319381) (xy 99.090988 -255.319784) (xy 99.066996 -255.319337) (xy 99.019604 -255.311829)
			(xy 98.973969 -255.296999) (xy 98.931216 -255.275212) (xy 98.892398 -255.247006) (xy 98.858471 -255.213074)
			(xy 98.830269 -255.174253) (xy 98.808488 -255.131498) (xy 98.793663 -255.085861) (xy 98.78616 -255.038468)
			(xy 98.78568 -255.014476) (xy 98.786093 -254.992354) (xy 98.792509 -254.948577) (xy 98.805161 -254.906179)
			(xy 98.814128 -254.885952) (xy 98.818027 -254.87632) (xy 98.818578 -254.855569) (xy 98.810918 -254.836274)
			(xy 98.803968 -254.828548) (xy 98.156776 -254.181356) (xy 98.149794 -254.174956) (xy 98.132438 -254.167407)
			(xy 98.113525 -254.166697) (xy 98.104452 -254.169418) (xy 98.051366 -254.187706) (xy 98.017838 -254.199136)
			(xy 98.01111 -254.201745) (xy 97.999368 -254.210123) (xy 97.994724 -254.215646) (xy 97.990152 -254.22098)
			(xy 97.985072 -254.23368) (xy 97.984056 -254.241046) (xy 97.980637 -254.265427) (xy 97.966965 -254.312721)
			(xy 97.945883 -254.357209) (xy 97.917937 -254.397739) (xy 97.883851 -254.433261) (xy 97.844509 -254.462854)
			(xy 97.800928 -254.485753) (xy 97.754238 -254.501365) (xy 97.705649 -254.509284) (xy 97.681034 -254.509778)
			(xy 97.65704 -254.509334) (xy 97.609642 -254.501832) (xy 97.564002 -254.487006) (xy 97.521243 -254.465222)
			(xy 97.482419 -254.437016) (xy 97.448486 -254.403084) (xy 97.42028 -254.36426) (xy 97.398496 -254.321502)
			(xy 97.383669 -254.275862) (xy 97.376166 -254.228464) (xy 97.375726 -254.20447) (xy 97.37619 -254.179849)
			(xy 97.384086 -254.131243) (xy 97.399682 -254.084536) (xy 97.422576 -254.040939) (xy 97.452172 -254.001584)
			(xy 97.487704 -253.967491) (xy 97.528248 -253.939545) (xy 97.572753 -253.918472) (xy 97.620065 -253.904817)
			(xy 97.644458 -253.901448) (xy 97.644712 -253.901448) (xy 97.651614 -253.900344) (xy 97.664499 -253.894944)
			(xy 97.670112 -253.89078) (xy 97.6757 -253.886208) (xy 97.683828 -253.874778) (xy 97.697798 -253.834138)
			(xy 97.716086 -253.781052) (xy 97.718802 -253.771981) (xy 97.718064 -253.753074) (xy 97.71054 -253.735712)
			(xy 97.704148 -253.728728) (xy 97.578164 -253.602744) (xy 97.567496 -253.594616) (xy 97.561848 -253.591584)
			(xy 97.549513 -253.588104) (xy 97.543112 -253.587758) (xy 97.468436 -253.588774) (xy 97.463267 -253.588957)
			(xy 97.453155 -253.591128) (xy 97.44837 -253.593092) (xy 97.440242 -253.596648) (xy 97.432876 -253.604268)
			(xy 97.432368 -253.604776) (xy 97.414966 -253.622404) (xy 97.375507 -253.652341) (xy 97.331728 -253.675508)
			(xy 97.284781 -253.691296) (xy 97.235899 -253.69929) (xy 97.211134 -253.699772) (xy 97.18714 -253.699328)
			(xy 97.139743 -253.691826) (xy 97.094103 -253.677) (xy 97.051345 -253.655215) (xy 97.012521 -253.62701)
			(xy 96.978589 -253.593077) (xy 96.950383 -253.554254) (xy 96.9286 -253.511495) (xy 96.913774 -253.465855)
			(xy 96.906272 -253.418458) (xy 96.905826 -253.394464) (xy 96.906311 -253.3697) (xy 96.914315 -253.320822)
			(xy 96.930107 -253.273878) (xy 96.953272 -253.230101) (xy 96.983203 -253.190639) (xy 97.000822 -253.17323)
			(xy 97.00133 -253.172722) (xy 97.00895 -253.165356) (xy 97.012506 -253.157228) (xy 97.014486 -253.152448)
			(xy 97.016657 -253.142334) (xy 97.016824 -253.137162) (xy 97.01784 -253.062486) (xy 97.017527 -253.056079)
			(xy 97.014049 -253.043736) (xy 97.010982 -253.038102) (xy 97.002854 -253.027434) (xy 96.868234 -252.892814)
			(xy 96.863376 -252.88821) (xy 96.851787 -252.881525) (xy 96.845374 -252.879606) (xy 96.83877 -252.877828)
			(xy 96.825562 -252.877828) (xy 96.819212 -252.879606) (xy 96.800069 -252.88436) (xy 96.760956 -252.889451)
			(xy 96.741234 -252.889766) (xy 96.738186 -252.889766) (xy 96.71448 -252.889099) (xy 96.667698 -252.881334)
			(xy 96.622679 -252.866429) (xy 96.580507 -252.844741) (xy 96.542195 -252.816793) (xy 96.508666 -252.783257)
			(xy 96.480726 -252.74494) (xy 96.459047 -252.702763) (xy 96.444151 -252.657741) (xy 96.436396 -252.610958)
			(xy 96.435672 -252.587252) (xy 96.435672 -252.584204) (xy 96.436001 -252.564484) (xy 96.441099 -252.525373)
			(xy 96.445832 -252.506226) (xy 96.44761 -252.499876) (xy 96.44761 -252.486668) (xy 96.445832 -252.480064)
			(xy 96.443877 -252.473668) (xy 96.437191 -252.46209) (xy 96.432624 -252.457204) (xy 95.793052 -251.817632)
			(xy 95.786595 -251.811721) (xy 95.770764 -251.80428) (xy 95.753352 -251.802597) (xy 95.744792 -251.804424)
			(xy 95.659956 -251.826014) (xy 95.653589 -251.827843) (xy 95.642014 -251.834276) (xy 95.637096 -251.838714)
			(xy 95.632524 -251.843286) (xy 95.62592 -251.854208) (xy 95.623888 -251.860812) (xy 95.616488 -251.88419)
			(xy 95.595283 -251.9284) (xy 95.567283 -251.968653) (xy 95.53321 -252.003912) (xy 95.493937 -252.03327)
			(xy 95.450477 -252.055973) (xy 95.403947 -252.071437) (xy 95.355543 -252.079263) (xy 95.331026 -252.07976)
			(xy 95.307033 -252.079316) (xy 95.259637 -252.071812) (xy 95.213999 -252.056985) (xy 95.171243 -252.0352)
			(xy 95.132421 -252.006994) (xy 95.098491 -251.973062) (xy 95.070288 -251.934238) (xy 95.048507 -251.891481)
			(xy 95.033683 -251.845842) (xy 95.026183 -251.798445) (xy 95.025718 -251.774452) (xy 95.026209 -251.749937)
			(xy 95.034051 -251.701539) (xy 95.049524 -251.655016) (xy 95.072232 -251.611562) (xy 95.10159 -251.572295)
			(xy 95.136846 -251.538223) (xy 95.177092 -251.510221) (xy 95.221296 -251.48901) (xy 95.244666 -251.48159)
			(xy 95.24492 -251.48159) (xy 95.251147 -251.479538) (xy 95.262346 -251.472728) (xy 95.267018 -251.468128)
			(xy 95.271336 -251.463556) (xy 95.27794 -251.452126) (xy 95.301054 -251.360686) (xy 95.302854 -251.35212)
			(xy 95.301194 -251.334707) (xy 95.29377 -251.318868) (xy 95.287846 -251.312426) (xy 95.167196 -251.191776)
			(xy 95.159716 -251.184966) (xy 95.140984 -251.177377) (xy 95.130874 -251.177044) (xy 95.100394 -251.177044)
			(xy 95.091102 -251.17755) (xy 95.073783 -251.184321) (xy 95.066612 -251.190252) (xy 95.049661 -251.205135)
			(xy 95.0122 -251.230262) (xy 94.971449 -251.249603) (xy 94.928296 -251.262737) (xy 94.88368 -251.269378)
			(xy 94.861126 -251.269754) (xy 94.837132 -251.269285) (xy 94.789735 -251.261783) (xy 94.744094 -251.246958)
			(xy 94.701335 -251.225177) (xy 94.662509 -251.196975) (xy 94.628572 -251.163046) (xy 94.600361 -251.124227)
			(xy 94.578569 -251.081472) (xy 94.563734 -251.035836) (xy 94.55622 -250.98844) (xy 94.555818 -250.964446)
			(xy 94.556295 -250.94002) (xy 94.564064 -250.891791) (xy 94.579413 -250.845414) (xy 94.601949 -250.802072)
			(xy 94.631097 -250.76287) (xy 94.648274 -250.745498) (xy 94.651576 -250.742196) (xy 94.657471 -250.734722)
			(xy 94.663716 -250.716755) (xy 94.662938 -250.697749) (xy 94.655245 -250.680353) (xy 94.648782 -250.673362)
			(xy 94.449392 -250.473972) (xy 94.445403 -250.470225) (xy 94.436178 -250.464341) (xy 94.431104 -250.462288)
			(xy 94.421706 -250.458732) (xy 94.41053 -250.45924) (xy 94.391226 -250.459748) (xy 94.390718 -250.459748)
			(xy 94.366753 -250.459257) (xy 94.319417 -250.451725) (xy 94.27384 -250.436888) (xy 94.231141 -250.415112)
			(xy 94.192368 -250.386933) (xy 94.158475 -250.353041) (xy 94.130294 -250.314269) (xy 94.108517 -250.271571)
			(xy 94.093678 -250.225994) (xy 94.086144 -250.178659) (xy 94.085664 -250.154694) (xy 94.085664 -250.154186)
			(xy 94.086172 -250.134882) (xy 94.08668 -250.123706) (xy 94.083124 -250.114308) (xy 94.081112 -250.109214)
			(xy 94.075213 -250.09999) (xy 94.07144 -250.09602) (xy 92.762324 -248.786904) (xy 92.75359 -248.779062)
			(xy 92.731346 -248.771654) (xy 92.719652 -248.77268) (xy 92.700602 -248.786904) (xy 92.680019 -248.801707)
			(xy 92.635112 -248.825237) (xy 92.587017 -248.841271) (xy 92.536975 -248.849395) (xy 92.511626 -248.849896)
			(xy 92.511118 -248.849896) (xy 92.485998 -248.849412) (xy 92.436391 -248.84146) (xy 92.388669 -248.825755)
			(xy 92.344036 -248.802691) (xy 92.303617 -248.772852) (xy 92.268433 -248.73699) (xy 92.23937 -248.696009)
			(xy 92.217163 -248.650944) (xy 92.20237 -248.602931) (xy 92.198444 -248.578116) (xy 92.195142 -248.55424)
			(xy 92.188238 -248.546084) (xy 92.169429 -248.535977) (xy 92.15882 -248.534682) (xy 92.154756 -248.534428)
			(xy 91.923616 -248.534428) (xy 91.914513 -248.534806) (xy 91.897466 -248.541193) (xy 91.890342 -248.546874)
			(xy 91.883484 -248.552716) (xy 91.874594 -248.568718) (xy 91.873324 -248.577862) (xy 91.869415 -248.60179)
			(xy 91.855023 -248.648086) (xy 91.833497 -248.691527) (xy 91.805377 -248.73102) (xy 91.77137 -248.765575)
			(xy 91.73233 -248.794321) (xy 91.689238 -248.816538) (xy 91.643177 -248.831667) (xy 91.595305 -248.839327)
			(xy 91.546823 -248.839327) (xy 91.498951 -248.831667) (xy 91.45289 -248.816538) (xy 91.409798 -248.794321)
			(xy 91.370758 -248.765575) (xy 91.336751 -248.73102) (xy 91.308631 -248.691527) (xy 91.287105 -248.648086)
			(xy 91.272713 -248.60179) (xy 91.268804 -248.577862) (xy 91.268804 -248.577608) (xy 91.267108 -248.568759)
			(xy 91.258385 -248.553008) (xy 91.251786 -248.546874) (xy 91.244928 -248.540778) (xy 91.22791 -248.534428)
			(xy 90.992198 -248.534428) (xy 90.984005 -248.534738) (xy 90.968461 -248.539923) (xy 90.961718 -248.544588)
			(xy 90.95613 -248.549414) (xy 90.950796 -248.554748) (xy 90.946224 -248.560082) (xy 90.943684 -248.578116)
			(xy 90.939658 -248.603427) (xy 90.924479 -248.652377) (xy 90.901581 -248.698227) (xy 90.871566 -248.739767)
			(xy 90.835227 -248.775905) (xy 90.79352 -248.805687) (xy 90.747544 -248.82833) (xy 90.69851 -248.843236)
			(xy 90.673174 -248.847102) (xy 90.657172 -248.849134) (xy 90.65133 -248.854214) (xy 90.410284 -249.09526)
			(xy 90.403595 -249.102668) (xy 90.396001 -249.121104) (xy 90.395552 -249.131074) (xy 90.405712 -249.1613)
			(xy 90.41003 -249.167396) (xy 90.423344 -249.186902) (xy 90.444436 -249.229156) (xy 90.45877 -249.274153)
			(xy 90.466006 -249.320821) (xy 90.466418 -249.344434) (xy 90.795106 -249.344434) (xy 90.799066 -249.29538)
			(xy 90.810843 -249.247596) (xy 90.830134 -249.20232) (xy 90.856437 -249.160724) (xy 90.889072 -249.123887)
			(xy 90.927193 -249.092762) (xy 90.969814 -249.068155) (xy 91.01583 -249.050703) (xy 91.064049 -249.040859)
			(xy 91.113224 -249.038878) (xy 91.162079 -249.04481) (xy 91.20935 -249.058502) (xy 91.253812 -249.0796)
			(xy 91.294315 -249.107556) (xy 91.329808 -249.141648) (xy 91.359373 -249.180992) (xy 91.382244 -249.224569)
			(xy 91.397828 -249.27125) (xy 91.405723 -249.319827) (xy 91.406218 -249.344434) (xy 91.724729 -249.344434)
			(xy 91.728824 -249.293706) (xy 91.741003 -249.244292) (xy 91.760951 -249.197472) (xy 91.788152 -249.154458)
			(xy 91.8219 -249.116364) (xy 91.861322 -249.084177) (xy 91.905396 -249.058731) (xy 91.952982 -249.040684)
			(xy 92.002846 -249.030504) (xy 92.053698 -249.028455) (xy 92.104219 -249.034589) (xy 92.153103 -249.048749)
			(xy 92.199082 -249.070566) (xy 92.240966 -249.099476) (xy 92.27767 -249.134731) (xy 92.308243 -249.175417)
			(xy 92.331894 -249.22048) (xy 92.34801 -249.268754) (xy 92.356174 -249.318988) (xy 92.356686 -249.344434)
			(xy 92.356174 -249.36988) (xy 92.34801 -249.420114) (xy 92.331894 -249.468388) (xy 92.308243 -249.513451)
			(xy 92.27767 -249.554137) (xy 92.240966 -249.589392) (xy 92.199082 -249.618302) (xy 92.153103 -249.640119)
			(xy 92.104219 -249.654279) (xy 92.053698 -249.660413) (xy 92.002846 -249.658364) (xy 91.952982 -249.648184)
			(xy 91.905396 -249.630137) (xy 91.861322 -249.604691) (xy 91.8219 -249.572504) (xy 91.788152 -249.53441)
			(xy 91.760951 -249.491396) (xy 91.741003 -249.444576) (xy 91.728824 -249.395162) (xy 91.724729 -249.344434)
			(xy 91.406218 -249.344434) (xy 91.405723 -249.369041) (xy 91.397828 -249.417618) (xy 91.382244 -249.464299)
			(xy 91.359373 -249.507876) (xy 91.329808 -249.54722) (xy 91.294315 -249.581312) (xy 91.253812 -249.609268)
			(xy 91.20935 -249.630366) (xy 91.162079 -249.644058) (xy 91.113224 -249.64999) (xy 91.064049 -249.648009)
			(xy 91.01583 -249.638165) (xy 90.969814 -249.620713) (xy 90.927193 -249.596106) (xy 90.889072 -249.564981)
			(xy 90.856437 -249.528144) (xy 90.830134 -249.486548) (xy 90.810843 -249.441272) (xy 90.799066 -249.393488)
			(xy 90.795106 -249.344434) (xy 90.466418 -249.344434) (xy 90.466418 -249.352816) (xy 90.466164 -249.357388)
			(xy 90.46455 -249.38329) (xy 90.453627 -249.434022) (xy 90.434287 -249.482178) (xy 90.407086 -249.526372)
			(xy 90.372807 -249.565332) (xy 90.332435 -249.597938) (xy 90.287133 -249.623251) (xy 90.238204 -249.640543)
			(xy 90.187057 -249.649316) (xy 90.16111 -249.649742) (xy 90.136186 -249.64925) (xy 90.087001 -249.641157)
			(xy 90.039781 -249.625186) (xy 89.995782 -249.601759) (xy 89.97569 -249.587004) (xy 89.965655 -249.581059)
			(xy 89.942544 -249.578118) (xy 89.920518 -249.585712) (xy 89.911936 -249.593608) (xy 89.791286 -249.714258)
			(xy 89.784682 -249.722386) (xy 89.779812 -249.730652) (xy 89.776047 -249.74945) (xy 89.777316 -249.758962)
			(xy 89.79154 -249.840496) (xy 89.792827 -249.846575) (xy 89.797965 -249.857883) (xy 89.8017 -249.862848)
			(xy 89.8017 -249.863102) (xy 89.805473 -249.867632) (xy 89.814711 -249.874952) (xy 89.819988 -249.87758)
			(xy 89.820242 -249.877834) (xy 89.820496 -249.877834) (xy 89.842677 -249.888766) (xy 89.883478 -249.916702)
			(xy 89.919249 -249.950842) (xy 89.949057 -249.990295) (xy 89.972123 -250.034033) (xy 89.987847 -250.080915)
			(xy 89.995818 -250.129716) (xy 89.996264 -250.15444) (xy 90.325206 -250.15444) (xy 90.329166 -250.105386)
			(xy 90.340943 -250.057602) (xy 90.360234 -250.012326) (xy 90.386537 -249.97073) (xy 90.419172 -249.933893)
			(xy 90.457293 -249.902768) (xy 90.499914 -249.878161) (xy 90.54593 -249.860709) (xy 90.594149 -249.850865)
			(xy 90.643324 -249.848884) (xy 90.692179 -249.854816) (xy 90.73945 -249.868508) (xy 90.783912 -249.889606)
			(xy 90.824415 -249.917562) (xy 90.859908 -249.951654) (xy 90.889473 -249.990998) (xy 90.912344 -250.034575)
			(xy 90.927928 -250.081256) (xy 90.935823 -250.129833) (xy 90.936318 -250.15444) (xy 91.26526 -250.15444)
			(xy 91.26922 -250.105386) (xy 91.280997 -250.057602) (xy 91.300288 -250.012326) (xy 91.326591 -249.97073)
			(xy 91.359226 -249.933893) (xy 91.397347 -249.902768) (xy 91.439968 -249.878161) (xy 91.485984 -249.860709)
			(xy 91.534203 -249.850865) (xy 91.583378 -249.848884) (xy 91.632233 -249.854816) (xy 91.679504 -249.868508)
			(xy 91.723966 -249.889606) (xy 91.764469 -249.917562) (xy 91.799962 -249.951654) (xy 91.829527 -249.990998)
			(xy 91.852398 -250.034575) (xy 91.867982 -250.081256) (xy 91.875877 -250.129833) (xy 91.876372 -250.15444)
			(xy 92.194883 -250.15444) (xy 92.198978 -250.103712) (xy 92.211157 -250.054298) (xy 92.231105 -250.007478)
			(xy 92.258306 -249.964464) (xy 92.292054 -249.92637) (xy 92.331476 -249.894183) (xy 92.37555 -249.868737)
			(xy 92.423136 -249.85069) (xy 92.473 -249.84051) (xy 92.523852 -249.838461) (xy 92.574373 -249.844595)
			(xy 92.623257 -249.858755) (xy 92.669236 -249.880572) (xy 92.71112 -249.909482) (xy 92.747824 -249.944737)
			(xy 92.778397 -249.985423) (xy 92.802048 -250.030486) (xy 92.818164 -250.07876) (xy 92.826328 -250.128994)
			(xy 92.82684 -250.15444) (xy 93.145114 -250.15444) (xy 93.149074 -250.105386) (xy 93.160851 -250.057602)
			(xy 93.180142 -250.012326) (xy 93.206445 -249.97073) (xy 93.23908 -249.933893) (xy 93.277201 -249.902768)
			(xy 93.319822 -249.878161) (xy 93.365838 -249.860709) (xy 93.414057 -249.850865) (xy 93.463232 -249.848884)
			(xy 93.512087 -249.854816) (xy 93.559358 -249.868508) (xy 93.60382 -249.889606) (xy 93.644323 -249.917562)
			(xy 93.679816 -249.951654) (xy 93.709381 -249.990998) (xy 93.732252 -250.034575) (xy 93.747836 -250.081256)
			(xy 93.755731 -250.129833) (xy 93.756226 -250.15444) (xy 93.755731 -250.179047) (xy 93.747836 -250.227624)
			(xy 93.732252 -250.274305) (xy 93.709381 -250.317882) (xy 93.679816 -250.357226) (xy 93.644323 -250.391318)
			(xy 93.60382 -250.419274) (xy 93.559358 -250.440372) (xy 93.512087 -250.454064) (xy 93.463232 -250.459996)
			(xy 93.414057 -250.458015) (xy 93.365838 -250.448171) (xy 93.319822 -250.430719) (xy 93.277201 -250.406112)
			(xy 93.23908 -250.374987) (xy 93.206445 -250.33815) (xy 93.180142 -250.296554) (xy 93.160851 -250.251278)
			(xy 93.149074 -250.203494) (xy 93.145114 -250.15444) (xy 92.82684 -250.15444) (xy 92.826328 -250.179886)
			(xy 92.818164 -250.23012) (xy 92.802048 -250.278394) (xy 92.778397 -250.323457) (xy 92.747824 -250.364143)
			(xy 92.71112 -250.399398) (xy 92.669236 -250.428308) (xy 92.623257 -250.450125) (xy 92.574373 -250.464285)
			(xy 92.523852 -250.470419) (xy 92.473 -250.46837) (xy 92.423136 -250.45819) (xy 92.37555 -250.440143)
			(xy 92.331476 -250.414697) (xy 92.292054 -250.38251) (xy 92.258306 -250.344416) (xy 92.231105 -250.301402)
			(xy 92.211157 -250.254582) (xy 92.198978 -250.205168) (xy 92.194883 -250.15444) (xy 91.876372 -250.15444)
			(xy 91.875877 -250.179047) (xy 91.867982 -250.227624) (xy 91.852398 -250.274305) (xy 91.829527 -250.317882)
			(xy 91.799962 -250.357226) (xy 91.764469 -250.391318) (xy 91.723966 -250.419274) (xy 91.679504 -250.440372)
			(xy 91.632233 -250.454064) (xy 91.583378 -250.459996) (xy 91.534203 -250.458015) (xy 91.485984 -250.448171)
			(xy 91.439968 -250.430719) (xy 91.397347 -250.406112) (xy 91.359226 -250.374987) (xy 91.326591 -250.33815)
			(xy 91.300288 -250.296554) (xy 91.280997 -250.251278) (xy 91.26922 -250.203494) (xy 91.26526 -250.15444)
			(xy 90.936318 -250.15444) (xy 90.935823 -250.179047) (xy 90.927928 -250.227624) (xy 90.912344 -250.274305)
			(xy 90.889473 -250.317882) (xy 90.859908 -250.357226) (xy 90.824415 -250.391318) (xy 90.783912 -250.419274)
			(xy 90.73945 -250.440372) (xy 90.692179 -250.454064) (xy 90.643324 -250.459996) (xy 90.594149 -250.458015)
			(xy 90.54593 -250.448171) (xy 90.499914 -250.430719) (xy 90.457293 -250.406112) (xy 90.419172 -250.374987)
			(xy 90.386537 -250.33815) (xy 90.360234 -250.296554) (xy 90.340943 -250.251278) (xy 90.329166 -250.203494)
			(xy 90.325206 -250.15444) (xy 89.996264 -250.15444) (xy 89.995796 -250.178678) (xy 89.988133 -250.226545)
			(xy 89.973007 -250.272601) (xy 89.950796 -250.31569) (xy 89.922058 -250.35473) (xy 89.887514 -250.388741)
			(xy 89.848033 -250.416869) (xy 89.804605 -250.438408) (xy 89.758319 -250.452818) (xy 89.73439 -250.4567)
			(xy 89.734136 -250.4567) (xy 89.725285 -250.458392) (xy 89.709528 -250.467109) (xy 89.703402 -250.473718)
			(xy 89.697306 -250.480576) (xy 89.690956 -250.497594) (xy 89.690956 -250.658884) (xy 89.691102 -250.664466)
			(xy 89.693537 -250.675361) (xy 89.695782 -250.680474) (xy 89.699592 -250.687078) (xy 89.710168 -250.705728)
			(xy 89.728731 -250.74438) (xy 89.736676 -250.764294) (xy 89.739326 -250.770574) (xy 89.747445 -250.781515)
			(xy 89.752678 -250.785884) (xy 89.763092 -250.794012) (xy 89.775538 -250.795536) (xy 89.865708 -250.806966)
			(xy 89.872587 -250.807564) (xy 89.886236 -250.805505) (xy 89.892632 -250.802902) (xy 89.898474 -250.800362)
			(xy 89.908888 -250.79198) (xy 89.913206 -250.786138) (xy 89.927673 -250.766843) (xy 89.961665 -250.732635)
			(xy 90.000606 -250.704188) (xy 90.04353 -250.682207) (xy 90.089373 -250.667239) (xy 90.136998 -250.659653)
			(xy 90.16111 -250.659138) (xy 90.186361 -250.65966) (xy 90.236174 -250.667974) (xy 90.283939 -250.684373)
			(xy 90.328354 -250.708411) (xy 90.368206 -250.73943) (xy 90.40241 -250.776586) (xy 90.430031 -250.818865)
			(xy 90.450317 -250.865114) (xy 90.462715 -250.91407) (xy 90.466885 -250.9644) (xy 90.466881 -250.964446)
			(xy 90.79536 -250.964446) (xy 90.79932 -250.915392) (xy 90.811097 -250.867608) (xy 90.830388 -250.822332)
			(xy 90.856691 -250.780736) (xy 90.889326 -250.743899) (xy 90.927447 -250.712774) (xy 90.970068 -250.688167)
			(xy 91.016084 -250.670715) (xy 91.064303 -250.660871) (xy 91.113478 -250.65889) (xy 91.162333 -250.664822)
			(xy 91.209604 -250.678514) (xy 91.254066 -250.699612) (xy 91.294569 -250.727568) (xy 91.330062 -250.76166)
			(xy 91.359627 -250.801004) (xy 91.382498 -250.844581) (xy 91.398082 -250.891262) (xy 91.405977 -250.939839)
			(xy 91.406472 -250.964446) (xy 91.724729 -250.964446) (xy 91.728824 -250.913718) (xy 91.741003 -250.864304)
			(xy 91.760951 -250.817484) (xy 91.788152 -250.77447) (xy 91.8219 -250.736376) (xy 91.861322 -250.704189)
			(xy 91.905396 -250.678743) (xy 91.952982 -250.660696) (xy 92.002846 -250.650516) (xy 92.053698 -250.648467)
			(xy 92.104219 -250.654601) (xy 92.153103 -250.668761) (xy 92.199082 -250.690578) (xy 92.240966 -250.719488)
			(xy 92.27767 -250.754743) (xy 92.308243 -250.795429) (xy 92.331894 -250.840492) (xy 92.34801 -250.888766)
			(xy 92.356174 -250.939) (xy 92.356686 -250.964446) (xy 92.675214 -250.964446) (xy 92.679174 -250.915392)
			(xy 92.690951 -250.867608) (xy 92.710242 -250.822332) (xy 92.736545 -250.780736) (xy 92.76918 -250.743899)
			(xy 92.807301 -250.712774) (xy 92.849922 -250.688167) (xy 92.895938 -250.670715) (xy 92.944157 -250.660871)
			(xy 92.993332 -250.65889) (xy 93.042187 -250.664822) (xy 93.089458 -250.678514) (xy 93.13392 -250.699612)
			(xy 93.174423 -250.727568) (xy 93.209916 -250.76166) (xy 93.239481 -250.801004) (xy 93.262352 -250.844581)
			(xy 93.277936 -250.891262) (xy 93.285831 -250.939839) (xy 93.286326 -250.964446) (xy 93.615268 -250.964446)
			(xy 93.619228 -250.915392) (xy 93.631005 -250.867608) (xy 93.650296 -250.822332) (xy 93.676599 -250.780736)
			(xy 93.709234 -250.743899) (xy 93.747355 -250.712774) (xy 93.789976 -250.688167) (xy 93.835992 -250.670715)
			(xy 93.884211 -250.660871) (xy 93.933386 -250.65889) (xy 93.982241 -250.664822) (xy 94.029512 -250.678514)
			(xy 94.073974 -250.699612) (xy 94.114477 -250.727568) (xy 94.14997 -250.76166) (xy 94.179535 -250.801004)
			(xy 94.202406 -250.844581) (xy 94.21799 -250.891262) (xy 94.225885 -250.939839) (xy 94.22638 -250.964446)
			(xy 94.225885 -250.989053) (xy 94.21799 -251.03763) (xy 94.202406 -251.084311) (xy 94.179535 -251.127888)
			(xy 94.14997 -251.167232) (xy 94.114477 -251.201324) (xy 94.073974 -251.22928) (xy 94.029512 -251.250378)
			(xy 93.982241 -251.26407) (xy 93.933386 -251.270002) (xy 93.884211 -251.268021) (xy 93.835992 -251.258177)
			(xy 93.789976 -251.240725) (xy 93.747355 -251.216118) (xy 93.709234 -251.184993) (xy 93.676599 -251.148156)
			(xy 93.650296 -251.10656) (xy 93.631005 -251.061284) (xy 93.619228 -251.0135) (xy 93.615268 -250.964446)
			(xy 93.286326 -250.964446) (xy 93.285831 -250.989053) (xy 93.277936 -251.03763) (xy 93.262352 -251.084311)
			(xy 93.239481 -251.127888) (xy 93.209916 -251.167232) (xy 93.174423 -251.201324) (xy 93.13392 -251.22928)
			(xy 93.089458 -251.250378) (xy 93.042187 -251.26407) (xy 92.993332 -251.270002) (xy 92.944157 -251.268021)
			(xy 92.895938 -251.258177) (xy 92.849922 -251.240725) (xy 92.807301 -251.216118) (xy 92.76918 -251.184993)
			(xy 92.736545 -251.148156) (xy 92.710242 -251.10656) (xy 92.690951 -251.061284) (xy 92.679174 -251.0135)
			(xy 92.675214 -250.964446) (xy 92.356686 -250.964446) (xy 92.356174 -250.989892) (xy 92.34801 -251.040126)
			(xy 92.331894 -251.0884) (xy 92.308243 -251.133463) (xy 92.27767 -251.174149) (xy 92.240966 -251.209404)
			(xy 92.199082 -251.238314) (xy 92.153103 -251.260131) (xy 92.104219 -251.274291) (xy 92.053698 -251.280425)
			(xy 92.002846 -251.278376) (xy 91.952982 -251.268196) (xy 91.905396 -251.250149) (xy 91.861322 -251.224703)
			(xy 91.8219 -251.192516) (xy 91.788152 -251.154422) (xy 91.760951 -251.111408) (xy 91.741003 -251.064588)
			(xy 91.728824 -251.015174) (xy 91.724729 -250.964446) (xy 91.406472 -250.964446) (xy 91.405977 -250.989053)
			(xy 91.398082 -251.03763) (xy 91.382498 -251.084311) (xy 91.359627 -251.127888) (xy 91.330062 -251.167232)
			(xy 91.294569 -251.201324) (xy 91.254066 -251.22928) (xy 91.209604 -251.250378) (xy 91.162333 -251.26407)
			(xy 91.113478 -251.270002) (xy 91.064303 -251.268021) (xy 91.016084 -251.258177) (xy 90.970068 -251.240725)
			(xy 90.927447 -251.216118) (xy 90.889326 -251.184993) (xy 90.856691 -251.148156) (xy 90.830388 -251.10656)
			(xy 90.811097 -251.061284) (xy 90.79932 -251.0135) (xy 90.79536 -250.964446) (xy 90.466881 -250.964446)
			(xy 90.462715 -251.01473) (xy 90.450317 -251.063686) (xy 90.430031 -251.109935) (xy 90.40241 -251.152214)
			(xy 90.368206 -251.18937) (xy 90.328354 -251.220389) (xy 90.283939 -251.244427) (xy 90.236174 -251.260826)
			(xy 90.186361 -251.26914) (xy 90.16111 -251.269754) (xy 90.148347 -251.269618) (xy 90.122912 -251.267459)
			(xy 90.11031 -251.265436) (xy 90.11031 -251.26569) (xy 90.086857 -251.261262) (xy 90.041605 -251.246099)
			(xy 89.999256 -251.224093) (xy 89.960837 -251.195778) (xy 89.927281 -251.161842) (xy 89.912952 -251.142754)
			(xy 89.908888 -251.136912) (xy 89.89822 -251.128276) (xy 89.892378 -251.125736) (xy 89.886095 -251.123214)
			(xy 89.872701 -251.121276) (xy 89.865962 -251.121926) (xy 89.777316 -251.133102) (xy 89.770419 -251.134217)
			(xy 89.757548 -251.139635) (xy 89.751916 -251.14377) (xy 89.741502 -251.152152) (xy 89.731811 -251.177968)
			(xy 89.708014 -251.227715) (xy 89.694004 -251.251466) (xy 89.690956 -251.262896) (xy 89.690956 -251.4219)
			(xy 89.691335 -251.431003) (xy 89.69772 -251.448052) (xy 89.703402 -251.455174) (xy 89.709244 -251.462032)
			(xy 89.725246 -251.470922) (xy 89.73439 -251.472192) (xy 89.758324 -251.476097) (xy 89.804634 -251.490486)
			(xy 89.848088 -251.512012) (xy 89.887594 -251.540134) (xy 89.922159 -251.574145) (xy 89.950916 -251.613192)
			(xy 89.973141 -251.656292) (xy 89.988276 -251.702363) (xy 89.99594 -251.750247) (xy 89.99594 -251.774452)
			(xy 90.314775 -251.774452) (xy 90.31887 -251.723724) (xy 90.331049 -251.67431) (xy 90.350997 -251.62749)
			(xy 90.378198 -251.584476) (xy 90.411946 -251.546382) (xy 90.451368 -251.514195) (xy 90.495442 -251.488749)
			(xy 90.543028 -251.470702) (xy 90.592892 -251.460522) (xy 90.643744 -251.458473) (xy 90.694265 -251.464607)
			(xy 90.743149 -251.478767) (xy 90.789128 -251.500584) (xy 90.831012 -251.529494) (xy 90.867716 -251.564749)
			(xy 90.898289 -251.605435) (xy 90.92194 -251.650498) (xy 90.938056 -251.698772) (xy 90.94622 -251.749006)
			(xy 90.946732 -251.774452) (xy 91.26526 -251.774452) (xy 91.26922 -251.725398) (xy 91.280997 -251.677614)
			(xy 91.300288 -251.632338) (xy 91.326591 -251.590742) (xy 91.359226 -251.553905) (xy 91.397347 -251.52278)
			(xy 91.439968 -251.498173) (xy 91.485984 -251.480721) (xy 91.534203 -251.470877) (xy 91.583378 -251.468896)
			(xy 91.632233 -251.474828) (xy 91.679504 -251.48852) (xy 91.723966 -251.509618) (xy 91.764469 -251.537574)
			(xy 91.799962 -251.571666) (xy 91.829527 -251.61101) (xy 91.852398 -251.654587) (xy 91.867982 -251.701268)
			(xy 91.875877 -251.749845) (xy 91.876372 -251.774452) (xy 92.205314 -251.774452) (xy 92.209274 -251.725398)
			(xy 92.221051 -251.677614) (xy 92.240342 -251.632338) (xy 92.266645 -251.590742) (xy 92.29928 -251.553905)
			(xy 92.337401 -251.52278) (xy 92.380022 -251.498173) (xy 92.426038 -251.480721) (xy 92.474257 -251.470877)
			(xy 92.523432 -251.468896) (xy 92.572287 -251.474828) (xy 92.619558 -251.48852) (xy 92.66402 -251.509618)
			(xy 92.704523 -251.537574) (xy 92.740016 -251.571666) (xy 92.769581 -251.61101) (xy 92.792452 -251.654587)
			(xy 92.808036 -251.701268) (xy 92.815931 -251.749845) (xy 92.816426 -251.774452) (xy 94.074737 -251.774452)
			(xy 94.078832 -251.723724) (xy 94.091011 -251.67431) (xy 94.110959 -251.62749) (xy 94.13816 -251.584476)
			(xy 94.171908 -251.546382) (xy 94.21133 -251.514195) (xy 94.255404 -251.488749) (xy 94.30299 -251.470702)
			(xy 94.352854 -251.460522) (xy 94.403706 -251.458473) (xy 94.454227 -251.464607) (xy 94.503111 -251.478767)
			(xy 94.54909 -251.500584) (xy 94.590974 -251.529494) (xy 94.627678 -251.564749) (xy 94.658251 -251.605435)
			(xy 94.681902 -251.650498) (xy 94.698018 -251.698772) (xy 94.706182 -251.749006) (xy 94.706694 -251.774452)
			(xy 94.706182 -251.799898) (xy 94.698018 -251.850132) (xy 94.681902 -251.898406) (xy 94.658251 -251.943469)
			(xy 94.627678 -251.984155) (xy 94.590974 -252.01941) (xy 94.54909 -252.04832) (xy 94.503111 -252.070137)
			(xy 94.454227 -252.084297) (xy 94.403706 -252.090431) (xy 94.352854 -252.088382) (xy 94.30299 -252.078202)
			(xy 94.255404 -252.060155) (xy 94.21133 -252.034709) (xy 94.171908 -252.002522) (xy 94.13816 -251.964428)
			(xy 94.110959 -251.921414) (xy 94.091011 -251.874594) (xy 94.078832 -251.82518) (xy 94.074737 -251.774452)
			(xy 92.816426 -251.774452) (xy 92.815931 -251.799059) (xy 92.808036 -251.847636) (xy 92.792452 -251.894317)
			(xy 92.769581 -251.937894) (xy 92.740016 -251.977238) (xy 92.704523 -252.01133) (xy 92.66402 -252.039286)
			(xy 92.619558 -252.060384) (xy 92.572287 -252.074076) (xy 92.523432 -252.080008) (xy 92.474257 -252.078027)
			(xy 92.426038 -252.068183) (xy 92.380022 -252.050731) (xy 92.337401 -252.026124) (xy 92.29928 -251.994999)
			(xy 92.266645 -251.958162) (xy 92.240342 -251.916566) (xy 92.221051 -251.87129) (xy 92.209274 -251.823506)
			(xy 92.205314 -251.774452) (xy 91.876372 -251.774452) (xy 91.875877 -251.799059) (xy 91.867982 -251.847636)
			(xy 91.852398 -251.894317) (xy 91.829527 -251.937894) (xy 91.799962 -251.977238) (xy 91.764469 -252.01133)
			(xy 91.723966 -252.039286) (xy 91.679504 -252.060384) (xy 91.632233 -252.074076) (xy 91.583378 -252.080008)
			(xy 91.534203 -252.078027) (xy 91.485984 -252.068183) (xy 91.439968 -252.050731) (xy 91.397347 -252.026124)
			(xy 91.359226 -251.994999) (xy 91.326591 -251.958162) (xy 91.300288 -251.916566) (xy 91.280997 -251.87129)
			(xy 91.26922 -251.823506) (xy 91.26526 -251.774452) (xy 90.946732 -251.774452) (xy 90.94622 -251.799898)
			(xy 90.938056 -251.850132) (xy 90.92194 -251.898406) (xy 90.898289 -251.943469) (xy 90.867716 -251.984155)
			(xy 90.831012 -252.01941) (xy 90.789128 -252.04832) (xy 90.743149 -252.070137) (xy 90.694265 -252.084297)
			(xy 90.643744 -252.090431) (xy 90.592892 -252.088382) (xy 90.543028 -252.078202) (xy 90.495442 -252.060155)
			(xy 90.451368 -252.034709) (xy 90.411946 -252.002522) (xy 90.378198 -251.964428) (xy 90.350997 -251.921414)
			(xy 90.331049 -251.874594) (xy 90.31887 -251.82518) (xy 90.314775 -251.774452) (xy 89.99594 -251.774452)
			(xy 89.995941 -251.79874) (xy 89.988279 -251.846624) (xy 89.973146 -251.892695) (xy 89.950923 -251.935796)
			(xy 89.922168 -251.974844) (xy 89.887604 -252.008858) (xy 89.848099 -252.036981) (xy 89.804647 -252.058509)
			(xy 89.758338 -252.072899) (xy 89.73439 -252.076712) (xy 89.734136 -252.076712) (xy 89.725285 -252.078405)
			(xy 89.70953 -252.087123) (xy 89.703402 -252.09373) (xy 89.697306 -252.100588) (xy 89.690956 -252.117606)
			(xy 89.690956 -252.278896) (xy 89.691103 -252.284478) (xy 89.69354 -252.295372) (xy 89.695782 -252.300486)
			(xy 89.699592 -252.30709) (xy 89.710168 -252.32574) (xy 89.72873 -252.364393) (xy 89.736676 -252.384306)
			(xy 89.739298 -252.390603) (xy 89.747409 -252.401565) (xy 89.752678 -252.405896) (xy 89.763092 -252.414024)
			(xy 89.775538 -252.415548) (xy 89.865708 -252.426978) (xy 89.872587 -252.427576) (xy 89.886236 -252.425517)
			(xy 89.892632 -252.422914) (xy 89.898474 -252.420374) (xy 89.908888 -252.411992) (xy 89.913206 -252.40615)
			(xy 89.927673 -252.386854) (xy 89.961664 -252.352645) (xy 90.000605 -252.324197) (xy 90.043529 -252.302215)
			(xy 90.089373 -252.287246) (xy 90.136998 -252.27966) (xy 90.16111 -252.27915) (xy 90.186368 -252.279672)
			(xy 90.236196 -252.287989) (xy 90.283975 -252.304393) (xy 90.328402 -252.328437) (xy 90.368266 -252.359465)
			(xy 90.402479 -252.396632) (xy 90.430109 -252.438923) (xy 90.450401 -252.485185) (xy 90.462801 -252.534156)
			(xy 90.46697 -252.584458) (xy 90.784675 -252.584458) (xy 90.78877 -252.53373) (xy 90.800949 -252.484316)
			(xy 90.820897 -252.437496) (xy 90.848098 -252.394482) (xy 90.881846 -252.356388) (xy 90.921268 -252.324201)
			(xy 90.965342 -252.298755) (xy 91.012928 -252.280708) (xy 91.062792 -252.270528) (xy 91.113644 -252.268479)
			(xy 91.164165 -252.274613) (xy 91.213049 -252.288773) (xy 91.259028 -252.31059) (xy 91.300912 -252.3395)
			(xy 91.337616 -252.374755) (xy 91.368189 -252.415441) (xy 91.39184 -252.460504) (xy 91.407956 -252.508778)
			(xy 91.41612 -252.559012) (xy 91.416632 -252.584458) (xy 91.724729 -252.584458) (xy 91.728824 -252.53373)
			(xy 91.741003 -252.484316) (xy 91.760951 -252.437496) (xy 91.788152 -252.394482) (xy 91.8219 -252.356388)
			(xy 91.861322 -252.324201) (xy 91.905396 -252.298755) (xy 91.952982 -252.280708) (xy 92.002846 -252.270528)
			(xy 92.053698 -252.268479) (xy 92.104219 -252.274613) (xy 92.153103 -252.288773) (xy 92.199082 -252.31059)
			(xy 92.240966 -252.3395) (xy 92.27767 -252.374755) (xy 92.308243 -252.415441) (xy 92.331894 -252.460504)
			(xy 92.34801 -252.508778) (xy 92.356174 -252.559012) (xy 92.356686 -252.584458) (xy 92.675214 -252.584458)
			(xy 92.679174 -252.535404) (xy 92.690951 -252.48762) (xy 92.710242 -252.442344) (xy 92.736545 -252.400748)
			(xy 92.76918 -252.363911) (xy 92.807301 -252.332786) (xy 92.849922 -252.308179) (xy 92.895938 -252.290727)
			(xy 92.944157 -252.280883) (xy 92.993332 -252.278902) (xy 93.042187 -252.284834) (xy 93.089458 -252.298526)
			(xy 93.13392 -252.319624) (xy 93.174423 -252.34758) (xy 93.209916 -252.381672) (xy 93.239481 -252.421016)
			(xy 93.262352 -252.464593) (xy 93.277936 -252.511274) (xy 93.285831 -252.559851) (xy 93.286326 -252.584458)
			(xy 93.604837 -252.584458) (xy 93.608932 -252.53373) (xy 93.621111 -252.484316) (xy 93.641059 -252.437496)
			(xy 93.66826 -252.394482) (xy 93.702008 -252.356388) (xy 93.74143 -252.324201) (xy 93.785504 -252.298755)
			(xy 93.83309 -252.280708) (xy 93.882954 -252.270528) (xy 93.933806 -252.268479) (xy 93.984327 -252.274613)
			(xy 94.033211 -252.288773) (xy 94.07919 -252.31059) (xy 94.121074 -252.3395) (xy 94.157778 -252.374755)
			(xy 94.188351 -252.415441) (xy 94.212002 -252.460504) (xy 94.228118 -252.508778) (xy 94.236282 -252.559012)
			(xy 94.236794 -252.584458) (xy 94.555322 -252.584458) (xy 94.559282 -252.535404) (xy 94.571059 -252.48762)
			(xy 94.59035 -252.442344) (xy 94.616653 -252.400748) (xy 94.649288 -252.363911) (xy 94.687409 -252.332786)
			(xy 94.73003 -252.308179) (xy 94.776046 -252.290727) (xy 94.824265 -252.280883) (xy 94.87344 -252.278902)
			(xy 94.922295 -252.284834) (xy 94.969566 -252.298526) (xy 95.014028 -252.319624) (xy 95.054531 -252.34758)
			(xy 95.090024 -252.381672) (xy 95.119589 -252.421016) (xy 95.14246 -252.464593) (xy 95.158044 -252.511274)
			(xy 95.165939 -252.559851) (xy 95.166434 -252.584458) (xy 95.484691 -252.584458) (xy 95.488786 -252.53373)
			(xy 95.500965 -252.484316) (xy 95.520913 -252.437496) (xy 95.548114 -252.394482) (xy 95.581862 -252.356388)
			(xy 95.621284 -252.324201) (xy 95.665358 -252.298755) (xy 95.712944 -252.280708) (xy 95.762808 -252.270528)
			(xy 95.81366 -252.268479) (xy 95.864181 -252.274613) (xy 95.913065 -252.288773) (xy 95.959044 -252.31059)
			(xy 96.000928 -252.3395) (xy 96.037632 -252.374755) (xy 96.068205 -252.415441) (xy 96.091856 -252.460504)
			(xy 96.107972 -252.508778) (xy 96.116136 -252.559012) (xy 96.116648 -252.584458) (xy 96.116136 -252.609904)
			(xy 96.107972 -252.660138) (xy 96.091856 -252.708412) (xy 96.068205 -252.753475) (xy 96.037632 -252.794161)
			(xy 96.000928 -252.829416) (xy 95.959044 -252.858326) (xy 95.913065 -252.880143) (xy 95.864181 -252.894303)
			(xy 95.81366 -252.900437) (xy 95.762808 -252.898388) (xy 95.712944 -252.888208) (xy 95.665358 -252.870161)
			(xy 95.621284 -252.844715) (xy 95.581862 -252.812528) (xy 95.548114 -252.774434) (xy 95.520913 -252.73142)
			(xy 95.500965 -252.6846) (xy 95.488786 -252.635186) (xy 95.484691 -252.584458) (xy 95.166434 -252.584458)
			(xy 95.165939 -252.609065) (xy 95.158044 -252.657642) (xy 95.14246 -252.704323) (xy 95.119589 -252.7479)
			(xy 95.090024 -252.787244) (xy 95.054531 -252.821336) (xy 95.014028 -252.849292) (xy 94.969566 -252.87039)
			(xy 94.922295 -252.884082) (xy 94.87344 -252.890014) (xy 94.824265 -252.888033) (xy 94.776046 -252.878189)
			(xy 94.73003 -252.860737) (xy 94.687409 -252.83613) (xy 94.649288 -252.805005) (xy 94.616653 -252.768168)
			(xy 94.59035 -252.726572) (xy 94.571059 -252.681296) (xy 94.559282 -252.633512) (xy 94.555322 -252.584458)
			(xy 94.236794 -252.584458) (xy 94.236282 -252.609904) (xy 94.228118 -252.660138) (xy 94.212002 -252.708412)
			(xy 94.188351 -252.753475) (xy 94.157778 -252.794161) (xy 94.121074 -252.829416) (xy 94.07919 -252.858326)
			(xy 94.033211 -252.880143) (xy 93.984327 -252.894303) (xy 93.933806 -252.900437) (xy 93.882954 -252.898388)
			(xy 93.83309 -252.888208) (xy 93.785504 -252.870161) (xy 93.74143 -252.844715) (xy 93.702008 -252.812528)
			(xy 93.66826 -252.774434) (xy 93.641059 -252.73142) (xy 93.621111 -252.6846) (xy 93.608932 -252.635186)
			(xy 93.604837 -252.584458) (xy 93.286326 -252.584458) (xy 93.285831 -252.609065) (xy 93.277936 -252.657642)
			(xy 93.262352 -252.704323) (xy 93.239481 -252.7479) (xy 93.209916 -252.787244) (xy 93.174423 -252.821336)
			(xy 93.13392 -252.849292) (xy 93.089458 -252.87039) (xy 93.042187 -252.884082) (xy 92.993332 -252.890014)
			(xy 92.944157 -252.888033) (xy 92.895938 -252.878189) (xy 92.849922 -252.860737) (xy 92.807301 -252.83613)
			(xy 92.76918 -252.805005) (xy 92.736545 -252.768168) (xy 92.710242 -252.726572) (xy 92.690951 -252.681296)
			(xy 92.679174 -252.633512) (xy 92.675214 -252.584458) (xy 92.356686 -252.584458) (xy 92.356174 -252.609904)
			(xy 92.34801 -252.660138) (xy 92.331894 -252.708412) (xy 92.308243 -252.753475) (xy 92.27767 -252.794161)
			(xy 92.240966 -252.829416) (xy 92.199082 -252.858326) (xy 92.153103 -252.880143) (xy 92.104219 -252.894303)
			(xy 92.053698 -252.900437) (xy 92.002846 -252.898388) (xy 91.952982 -252.888208) (xy 91.905396 -252.870161)
			(xy 91.861322 -252.844715) (xy 91.8219 -252.812528) (xy 91.788152 -252.774434) (xy 91.760951 -252.73142)
			(xy 91.741003 -252.6846) (xy 91.728824 -252.635186) (xy 91.724729 -252.584458) (xy 91.416632 -252.584458)
			(xy 91.41612 -252.609904) (xy 91.407956 -252.660138) (xy 91.39184 -252.708412) (xy 91.368189 -252.753475)
			(xy 91.337616 -252.794161) (xy 91.300912 -252.829416) (xy 91.259028 -252.858326) (xy 91.213049 -252.880143)
			(xy 91.164165 -252.894303) (xy 91.113644 -252.900437) (xy 91.062792 -252.898388) (xy 91.012928 -252.888208)
			(xy 90.965342 -252.870161) (xy 90.921268 -252.844715) (xy 90.881846 -252.812528) (xy 90.848098 -252.774434)
			(xy 90.820897 -252.73142) (xy 90.800949 -252.6846) (xy 90.78877 -252.635186) (xy 90.784675 -252.584458)
			(xy 90.46697 -252.584458) (xy 90.466973 -252.5845) (xy 90.462801 -252.634844) (xy 90.450401 -252.683815)
			(xy 90.430109 -252.730077) (xy 90.402479 -252.772368) (xy 90.368266 -252.809535) (xy 90.328402 -252.840563)
			(xy 90.283975 -252.864607) (xy 90.236196 -252.881011) (xy 90.186368 -252.889328) (xy 90.16111 -252.889766)
			(xy 90.148347 -252.88963) (xy 90.122912 -252.887471) (xy 90.11031 -252.885448) (xy 90.11031 -252.885702)
			(xy 90.086857 -252.881274) (xy 90.041604 -252.866111) (xy 89.999255 -252.844106) (xy 89.960835 -252.815792)
			(xy 89.927277 -252.781856) (xy 89.912952 -252.762766) (xy 89.908888 -252.756924) (xy 89.89822 -252.748288)
			(xy 89.892378 -252.745748) (xy 89.886095 -252.743225) (xy 89.872701 -252.741287) (xy 89.865962 -252.741938)
			(xy 89.777316 -252.753114) (xy 89.770418 -252.754226) (xy 89.757541 -252.759637) (xy 89.751916 -252.763782)
			(xy 89.741502 -252.772164) (xy 89.731815 -252.797982) (xy 89.708024 -252.847733) (xy 89.694004 -252.871478)
			(xy 89.690956 -252.882908) (xy 89.690956 -253.041912) (xy 89.691337 -253.051014) (xy 89.697725 -253.06806)
			(xy 89.703402 -253.075186) (xy 89.709244 -253.082044) (xy 89.725246 -253.090934) (xy 89.73439 -253.092204)
			(xy 89.758324 -253.096109) (xy 89.804631 -253.110498) (xy 89.848083 -253.132023) (xy 89.887587 -253.160144)
			(xy 89.922152 -253.194154) (xy 89.950907 -253.2332) (xy 89.973131 -253.276298) (xy 89.988265 -253.322367)
			(xy 89.995928 -253.370249) (xy 89.995928 -253.394464) (xy 90.314775 -253.394464) (xy 90.31887 -253.343736)
			(xy 90.331049 -253.294322) (xy 90.350997 -253.247502) (xy 90.378198 -253.204488) (xy 90.411946 -253.166394)
			(xy 90.451368 -253.134207) (xy 90.495442 -253.108761) (xy 90.543028 -253.090714) (xy 90.592892 -253.080534)
			(xy 90.643744 -253.078485) (xy 90.694265 -253.084619) (xy 90.743149 -253.098779) (xy 90.789128 -253.120596)
			(xy 90.831012 -253.149506) (xy 90.867716 -253.184761) (xy 90.898289 -253.225447) (xy 90.92194 -253.27051)
			(xy 90.938056 -253.318784) (xy 90.94622 -253.369018) (xy 90.946732 -253.394464) (xy 91.26526 -253.394464)
			(xy 91.26922 -253.34541) (xy 91.280997 -253.297626) (xy 91.300288 -253.25235) (xy 91.326591 -253.210754)
			(xy 91.359226 -253.173917) (xy 91.397347 -253.142792) (xy 91.439968 -253.118185) (xy 91.485984 -253.100733)
			(xy 91.534203 -253.090889) (xy 91.583378 -253.088908) (xy 91.632233 -253.09484) (xy 91.679504 -253.108532)
			(xy 91.723966 -253.12963) (xy 91.764469 -253.157586) (xy 91.799962 -253.191678) (xy 91.829527 -253.231022)
			(xy 91.852398 -253.274599) (xy 91.867982 -253.32128) (xy 91.875877 -253.369857) (xy 91.876372 -253.394464)
			(xy 92.194883 -253.394464) (xy 92.198978 -253.343736) (xy 92.211157 -253.294322) (xy 92.231105 -253.247502)
			(xy 92.258306 -253.204488) (xy 92.292054 -253.166394) (xy 92.331476 -253.134207) (xy 92.37555 -253.108761)
			(xy 92.423136 -253.090714) (xy 92.473 -253.080534) (xy 92.523852 -253.078485) (xy 92.574373 -253.084619)
			(xy 92.623257 -253.098779) (xy 92.669236 -253.120596) (xy 92.71112 -253.149506) (xy 92.747824 -253.184761)
			(xy 92.778397 -253.225447) (xy 92.802048 -253.27051) (xy 92.818164 -253.318784) (xy 92.826328 -253.369018)
			(xy 92.82684 -253.394464) (xy 93.145114 -253.394464) (xy 93.149074 -253.34541) (xy 93.160851 -253.297626)
			(xy 93.180142 -253.25235) (xy 93.206445 -253.210754) (xy 93.23908 -253.173917) (xy 93.277201 -253.142792)
			(xy 93.319822 -253.118185) (xy 93.365838 -253.100733) (xy 93.414057 -253.090889) (xy 93.463232 -253.088908)
			(xy 93.512087 -253.09484) (xy 93.559358 -253.108532) (xy 93.60382 -253.12963) (xy 93.644323 -253.157586)
			(xy 93.679816 -253.191678) (xy 93.709381 -253.231022) (xy 93.732252 -253.274599) (xy 93.747836 -253.32128)
			(xy 93.755731 -253.369857) (xy 93.756226 -253.394464) (xy 94.074737 -253.394464) (xy 94.078832 -253.343736)
			(xy 94.091011 -253.294322) (xy 94.110959 -253.247502) (xy 94.13816 -253.204488) (xy 94.171908 -253.166394)
			(xy 94.21133 -253.134207) (xy 94.255404 -253.108761) (xy 94.30299 -253.090714) (xy 94.352854 -253.080534)
			(xy 94.403706 -253.078485) (xy 94.454227 -253.084619) (xy 94.503111 -253.098779) (xy 94.54909 -253.120596)
			(xy 94.590974 -253.149506) (xy 94.627678 -253.184761) (xy 94.658251 -253.225447) (xy 94.681902 -253.27051)
			(xy 94.698018 -253.318784) (xy 94.706182 -253.369018) (xy 94.706694 -253.394464) (xy 95.014791 -253.394464)
			(xy 95.018886 -253.343736) (xy 95.031065 -253.294322) (xy 95.051013 -253.247502) (xy 95.078214 -253.204488)
			(xy 95.111962 -253.166394) (xy 95.151384 -253.134207) (xy 95.195458 -253.108761) (xy 95.243044 -253.090714)
			(xy 95.292908 -253.080534) (xy 95.34376 -253.078485) (xy 95.394281 -253.084619) (xy 95.443165 -253.098779)
			(xy 95.489144 -253.120596) (xy 95.531028 -253.149506) (xy 95.567732 -253.184761) (xy 95.598305 -253.225447)
			(xy 95.621956 -253.27051) (xy 95.638072 -253.318784) (xy 95.646236 -253.369018) (xy 95.646748 -253.394464)
			(xy 95.965276 -253.394464) (xy 95.969236 -253.34541) (xy 95.981013 -253.297626) (xy 96.000304 -253.25235)
			(xy 96.026607 -253.210754) (xy 96.059242 -253.173917) (xy 96.097363 -253.142792) (xy 96.139984 -253.118185)
			(xy 96.186 -253.100733) (xy 96.234219 -253.090889) (xy 96.283394 -253.088908) (xy 96.332249 -253.09484)
			(xy 96.37952 -253.108532) (xy 96.423982 -253.12963) (xy 96.464485 -253.157586) (xy 96.499978 -253.191678)
			(xy 96.529543 -253.231022) (xy 96.552414 -253.274599) (xy 96.567998 -253.32128) (xy 96.575893 -253.369857)
			(xy 96.576388 -253.394464) (xy 96.575893 -253.419071) (xy 96.567998 -253.467648) (xy 96.552414 -253.514329)
			(xy 96.529543 -253.557906) (xy 96.499978 -253.59725) (xy 96.464485 -253.631342) (xy 96.423982 -253.659298)
			(xy 96.37952 -253.680396) (xy 96.332249 -253.694088) (xy 96.283394 -253.70002) (xy 96.234219 -253.698039)
			(xy 96.186 -253.688195) (xy 96.139984 -253.670743) (xy 96.097363 -253.646136) (xy 96.059242 -253.615011)
			(xy 96.026607 -253.578174) (xy 96.000304 -253.536578) (xy 95.981013 -253.491302) (xy 95.969236 -253.443518)
			(xy 95.965276 -253.394464) (xy 95.646748 -253.394464) (xy 95.646236 -253.41991) (xy 95.638072 -253.470144)
			(xy 95.621956 -253.518418) (xy 95.598305 -253.563481) (xy 95.567732 -253.604167) (xy 95.531028 -253.639422)
			(xy 95.489144 -253.668332) (xy 95.443165 -253.690149) (xy 95.394281 -253.704309) (xy 95.34376 -253.710443)
			(xy 95.292908 -253.708394) (xy 95.243044 -253.698214) (xy 95.195458 -253.680167) (xy 95.151384 -253.654721)
			(xy 95.111962 -253.622534) (xy 95.078214 -253.58444) (xy 95.051013 -253.541426) (xy 95.031065 -253.494606)
			(xy 95.018886 -253.445192) (xy 95.014791 -253.394464) (xy 94.706694 -253.394464) (xy 94.706182 -253.41991)
			(xy 94.698018 -253.470144) (xy 94.681902 -253.518418) (xy 94.658251 -253.563481) (xy 94.627678 -253.604167)
			(xy 94.590974 -253.639422) (xy 94.54909 -253.668332) (xy 94.503111 -253.690149) (xy 94.454227 -253.704309)
			(xy 94.403706 -253.710443) (xy 94.352854 -253.708394) (xy 94.30299 -253.698214) (xy 94.255404 -253.680167)
			(xy 94.21133 -253.654721) (xy 94.171908 -253.622534) (xy 94.13816 -253.58444) (xy 94.110959 -253.541426)
			(xy 94.091011 -253.494606) (xy 94.078832 -253.445192) (xy 94.074737 -253.394464) (xy 93.756226 -253.394464)
			(xy 93.755731 -253.419071) (xy 93.747836 -253.467648) (xy 93.732252 -253.514329) (xy 93.709381 -253.557906)
			(xy 93.679816 -253.59725) (xy 93.644323 -253.631342) (xy 93.60382 -253.659298) (xy 93.559358 -253.680396)
			(xy 93.512087 -253.694088) (xy 93.463232 -253.70002) (xy 93.414057 -253.698039) (xy 93.365838 -253.688195)
			(xy 93.319822 -253.670743) (xy 93.277201 -253.646136) (xy 93.23908 -253.615011) (xy 93.206445 -253.578174)
			(xy 93.180142 -253.536578) (xy 93.160851 -253.491302) (xy 93.149074 -253.443518) (xy 93.145114 -253.394464)
			(xy 92.82684 -253.394464) (xy 92.826328 -253.41991) (xy 92.818164 -253.470144) (xy 92.802048 -253.518418)
			(xy 92.778397 -253.563481) (xy 92.747824 -253.604167) (xy 92.71112 -253.639422) (xy 92.669236 -253.668332)
			(xy 92.623257 -253.690149) (xy 92.574373 -253.704309) (xy 92.523852 -253.710443) (xy 92.473 -253.708394)
			(xy 92.423136 -253.698214) (xy 92.37555 -253.680167) (xy 92.331476 -253.654721) (xy 92.292054 -253.622534)
			(xy 92.258306 -253.58444) (xy 92.231105 -253.541426) (xy 92.211157 -253.494606) (xy 92.198978 -253.445192)
			(xy 92.194883 -253.394464) (xy 91.876372 -253.394464) (xy 91.875877 -253.419071) (xy 91.867982 -253.467648)
			(xy 91.852398 -253.514329) (xy 91.829527 -253.557906) (xy 91.799962 -253.59725) (xy 91.764469 -253.631342)
			(xy 91.723966 -253.659298) (xy 91.679504 -253.680396) (xy 91.632233 -253.694088) (xy 91.583378 -253.70002)
			(xy 91.534203 -253.698039) (xy 91.485984 -253.688195) (xy 91.439968 -253.670743) (xy 91.397347 -253.646136)
			(xy 91.359226 -253.615011) (xy 91.326591 -253.578174) (xy 91.300288 -253.536578) (xy 91.280997 -253.491302)
			(xy 91.26922 -253.443518) (xy 91.26526 -253.394464) (xy 90.946732 -253.394464) (xy 90.94622 -253.41991)
			(xy 90.938056 -253.470144) (xy 90.92194 -253.518418) (xy 90.898289 -253.563481) (xy 90.867716 -253.604167)
			(xy 90.831012 -253.639422) (xy 90.789128 -253.668332) (xy 90.743149 -253.690149) (xy 90.694265 -253.704309)
			(xy 90.643744 -253.710443) (xy 90.592892 -253.708394) (xy 90.543028 -253.698214) (xy 90.495442 -253.680167)
			(xy 90.451368 -253.654721) (xy 90.411946 -253.622534) (xy 90.378198 -253.58444) (xy 90.350997 -253.541426)
			(xy 90.331049 -253.494606) (xy 90.31887 -253.445192) (xy 90.314775 -253.394464) (xy 89.995928 -253.394464)
			(xy 89.995929 -253.418741) (xy 89.988267 -253.466623) (xy 89.973135 -253.512692) (xy 89.950912 -253.555792)
			(xy 89.922158 -253.594838) (xy 89.887595 -253.62885) (xy 89.848092 -253.656972) (xy 89.804641 -253.678499)
			(xy 89.758334 -253.692888) (xy 89.73439 -253.696724) (xy 89.734136 -253.696724) (xy 89.725285 -253.698417)
			(xy 89.709532 -253.707137) (xy 89.703402 -253.713742) (xy 89.697306 -253.7206) (xy 89.690956 -253.737618)
			(xy 89.690956 -253.898908) (xy 89.691104 -253.904489) (xy 89.693544 -253.915382) (xy 89.695782 -253.920498)
			(xy 89.699592 -253.927102) (xy 89.710168 -253.945752) (xy 89.728729 -253.984405) (xy 89.736676 -254.004318)
			(xy 89.739299 -254.010614) (xy 89.747412 -254.021574) (xy 89.752678 -254.025908) (xy 89.763092 -254.034036)
			(xy 89.775538 -254.03556) (xy 89.865708 -254.04699) (xy 89.872587 -254.047588) (xy 89.886236 -254.045529)
			(xy 89.892632 -254.042926) (xy 89.898474 -254.040386) (xy 89.908888 -254.032004) (xy 89.913206 -254.026162)
			(xy 89.927673 -254.006866) (xy 89.961664 -253.972655) (xy 90.000604 -253.944206) (xy 90.043528 -253.922224)
			(xy 90.089372 -253.907254) (xy 90.136997 -253.899668) (xy 90.16111 -253.899162) (xy 90.186367 -253.899684)
			(xy 90.236193 -253.908) (xy 90.28397 -253.924404) (xy 90.328395 -253.948447) (xy 90.368258 -253.979474)
			(xy 90.40247 -254.01664) (xy 90.430098 -254.058929) (xy 90.450389 -254.105189) (xy 90.46279 -254.154158)
			(xy 90.466959 -254.20447) (xy 90.784675 -254.20447) (xy 90.78877 -254.153742) (xy 90.800949 -254.104328)
			(xy 90.820897 -254.057508) (xy 90.848098 -254.014494) (xy 90.881846 -253.9764) (xy 90.921268 -253.944213)
			(xy 90.965342 -253.918767) (xy 91.012928 -253.90072) (xy 91.062792 -253.89054) (xy 91.113644 -253.888491)
			(xy 91.164165 -253.894625) (xy 91.213049 -253.908785) (xy 91.259028 -253.930602) (xy 91.300912 -253.959512)
			(xy 91.337616 -253.994767) (xy 91.368189 -254.035453) (xy 91.39184 -254.080516) (xy 91.407956 -254.12879)
			(xy 91.41612 -254.179024) (xy 91.416632 -254.20447) (xy 91.724729 -254.20447) (xy 91.728824 -254.153742)
			(xy 91.741003 -254.104328) (xy 91.760951 -254.057508) (xy 91.788152 -254.014494) (xy 91.8219 -253.9764)
			(xy 91.861322 -253.944213) (xy 91.905396 -253.918767) (xy 91.952982 -253.90072) (xy 92.002846 -253.89054)
			(xy 92.053698 -253.888491) (xy 92.104219 -253.894625) (xy 92.153103 -253.908785) (xy 92.199082 -253.930602)
			(xy 92.240966 -253.959512) (xy 92.27767 -253.994767) (xy 92.308243 -254.035453) (xy 92.331894 -254.080516)
			(xy 92.34801 -254.12879) (xy 92.356174 -254.179024) (xy 92.356686 -254.20447) (xy 93.604837 -254.20447)
			(xy 93.608932 -254.153742) (xy 93.621111 -254.104328) (xy 93.641059 -254.057508) (xy 93.66826 -254.014494)
			(xy 93.702008 -253.9764) (xy 93.74143 -253.944213) (xy 93.785504 -253.918767) (xy 93.83309 -253.90072)
			(xy 93.882954 -253.89054) (xy 93.933806 -253.888491) (xy 93.984327 -253.894625) (xy 94.033211 -253.908785)
			(xy 94.07919 -253.930602) (xy 94.121074 -253.959512) (xy 94.157778 -253.994767) (xy 94.188351 -254.035453)
			(xy 94.212002 -254.080516) (xy 94.228118 -254.12879) (xy 94.236282 -254.179024) (xy 94.236794 -254.20447)
			(xy 94.555322 -254.20447) (xy 94.559282 -254.155416) (xy 94.571059 -254.107632) (xy 94.59035 -254.062356)
			(xy 94.616653 -254.02076) (xy 94.649288 -253.983923) (xy 94.687409 -253.952798) (xy 94.73003 -253.928191)
			(xy 94.776046 -253.910739) (xy 94.824265 -253.900895) (xy 94.87344 -253.898914) (xy 94.922295 -253.904846)
			(xy 94.969566 -253.918538) (xy 95.014028 -253.939636) (xy 95.054531 -253.967592) (xy 95.090024 -254.001684)
			(xy 95.119589 -254.041028) (xy 95.14246 -254.084605) (xy 95.158044 -254.131286) (xy 95.165939 -254.179863)
			(xy 95.166434 -254.20447) (xy 95.484691 -254.20447) (xy 95.488786 -254.153742) (xy 95.500965 -254.104328)
			(xy 95.520913 -254.057508) (xy 95.548114 -254.014494) (xy 95.581862 -253.9764) (xy 95.621284 -253.944213)
			(xy 95.665358 -253.918767) (xy 95.712944 -253.90072) (xy 95.762808 -253.89054) (xy 95.81366 -253.888491)
			(xy 95.864181 -253.894625) (xy 95.913065 -253.908785) (xy 95.959044 -253.930602) (xy 96.000928 -253.959512)
			(xy 96.037632 -253.994767) (xy 96.068205 -254.035453) (xy 96.091856 -254.080516) (xy 96.107972 -254.12879)
			(xy 96.116136 -254.179024) (xy 96.116648 -254.20447) (xy 96.435176 -254.20447) (xy 96.439136 -254.155416)
			(xy 96.450913 -254.107632) (xy 96.470204 -254.062356) (xy 96.496507 -254.02076) (xy 96.529142 -253.983923)
			(xy 96.567263 -253.952798) (xy 96.609884 -253.928191) (xy 96.6559 -253.910739) (xy 96.704119 -253.900895)
			(xy 96.753294 -253.898914) (xy 96.802149 -253.904846) (xy 96.84942 -253.918538) (xy 96.893882 -253.939636)
			(xy 96.934385 -253.967592) (xy 96.969878 -254.001684) (xy 96.999443 -254.041028) (xy 97.022314 -254.084605)
			(xy 97.037898 -254.131286) (xy 97.045793 -254.179863) (xy 97.046288 -254.20447) (xy 97.045793 -254.229077)
			(xy 97.037898 -254.277654) (xy 97.022314 -254.324335) (xy 96.999443 -254.367912) (xy 96.969878 -254.407256)
			(xy 96.934385 -254.441348) (xy 96.893882 -254.469304) (xy 96.84942 -254.490402) (xy 96.802149 -254.504094)
			(xy 96.753294 -254.510026) (xy 96.704119 -254.508045) (xy 96.6559 -254.498201) (xy 96.609884 -254.480749)
			(xy 96.567263 -254.456142) (xy 96.529142 -254.425017) (xy 96.496507 -254.38818) (xy 96.470204 -254.346584)
			(xy 96.450913 -254.301308) (xy 96.439136 -254.253524) (xy 96.435176 -254.20447) (xy 96.116648 -254.20447)
			(xy 96.116136 -254.229916) (xy 96.107972 -254.28015) (xy 96.091856 -254.328424) (xy 96.068205 -254.373487)
			(xy 96.037632 -254.414173) (xy 96.000928 -254.449428) (xy 95.959044 -254.478338) (xy 95.913065 -254.500155)
			(xy 95.864181 -254.514315) (xy 95.81366 -254.520449) (xy 95.762808 -254.5184) (xy 95.712944 -254.50822)
			(xy 95.665358 -254.490173) (xy 95.621284 -254.464727) (xy 95.581862 -254.43254) (xy 95.548114 -254.394446)
			(xy 95.520913 -254.351432) (xy 95.500965 -254.304612) (xy 95.488786 -254.255198) (xy 95.484691 -254.20447)
			(xy 95.166434 -254.20447) (xy 95.165939 -254.229077) (xy 95.158044 -254.277654) (xy 95.14246 -254.324335)
			(xy 95.119589 -254.367912) (xy 95.090024 -254.407256) (xy 95.054531 -254.441348) (xy 95.014028 -254.469304)
			(xy 94.969566 -254.490402) (xy 94.922295 -254.504094) (xy 94.87344 -254.510026) (xy 94.824265 -254.508045)
			(xy 94.776046 -254.498201) (xy 94.73003 -254.480749) (xy 94.687409 -254.456142) (xy 94.649288 -254.425017)
			(xy 94.616653 -254.38818) (xy 94.59035 -254.346584) (xy 94.571059 -254.301308) (xy 94.559282 -254.253524)
			(xy 94.555322 -254.20447) (xy 94.236794 -254.20447) (xy 94.236282 -254.229916) (xy 94.228118 -254.28015)
			(xy 94.212002 -254.328424) (xy 94.188351 -254.373487) (xy 94.157778 -254.414173) (xy 94.121074 -254.449428)
			(xy 94.07919 -254.478338) (xy 94.033211 -254.500155) (xy 93.984327 -254.514315) (xy 93.933806 -254.520449)
			(xy 93.882954 -254.5184) (xy 93.83309 -254.50822) (xy 93.785504 -254.490173) (xy 93.74143 -254.464727)
			(xy 93.702008 -254.43254) (xy 93.66826 -254.394446) (xy 93.641059 -254.351432) (xy 93.621111 -254.304612)
			(xy 93.608932 -254.255198) (xy 93.604837 -254.20447) (xy 92.356686 -254.20447) (xy 92.356174 -254.229916)
			(xy 92.34801 -254.28015) (xy 92.331894 -254.328424) (xy 92.308243 -254.373487) (xy 92.27767 -254.414173)
			(xy 92.240966 -254.449428) (xy 92.199082 -254.478338) (xy 92.153103 -254.500155) (xy 92.104219 -254.514315)
			(xy 92.053698 -254.520449) (xy 92.002846 -254.5184) (xy 91.952982 -254.50822) (xy 91.905396 -254.490173)
			(xy 91.861322 -254.464727) (xy 91.8219 -254.43254) (xy 91.788152 -254.394446) (xy 91.760951 -254.351432)
			(xy 91.741003 -254.304612) (xy 91.728824 -254.255198) (xy 91.724729 -254.20447) (xy 91.416632 -254.20447)
			(xy 91.41612 -254.229916) (xy 91.407956 -254.28015) (xy 91.39184 -254.328424) (xy 91.368189 -254.373487)
			(xy 91.337616 -254.414173) (xy 91.300912 -254.449428) (xy 91.259028 -254.478338) (xy 91.213049 -254.500155)
			(xy 91.164165 -254.514315) (xy 91.113644 -254.520449) (xy 91.062792 -254.5184) (xy 91.012928 -254.50822)
			(xy 90.965342 -254.490173) (xy 90.921268 -254.464727) (xy 90.881846 -254.43254) (xy 90.848098 -254.394446)
			(xy 90.820897 -254.351432) (xy 90.800949 -254.304612) (xy 90.78877 -254.255198) (xy 90.784675 -254.20447)
			(xy 90.466959 -254.20447) (xy 90.466961 -254.2045) (xy 90.46279 -254.254842) (xy 90.450389 -254.303811)
			(xy 90.430098 -254.350071) (xy 90.40247 -254.39236) (xy 90.368258 -254.429526) (xy 90.328395 -254.460553)
			(xy 90.28397 -254.484596) (xy 90.236193 -254.501) (xy 90.186367 -254.509316) (xy 90.16111 -254.509778)
			(xy 90.148347 -254.509642) (xy 90.122912 -254.507483) (xy 90.11031 -254.50546) (xy 90.11031 -254.505714)
			(xy 90.086857 -254.501286) (xy 90.041604 -254.486124) (xy 89.999253 -254.464119) (xy 89.960833 -254.435806)
			(xy 89.927274 -254.401871) (xy 89.912952 -254.382778) (xy 89.908888 -254.376936) (xy 89.89822 -254.3683)
			(xy 89.892378 -254.36576) (xy 89.886095 -254.363237) (xy 89.872701 -254.361298) (xy 89.865962 -254.36195)
			(xy 89.777316 -254.373126) (xy 89.770418 -254.374238) (xy 89.757542 -254.37965) (xy 89.751916 -254.383794)
			(xy 89.741502 -254.392176) (xy 89.731814 -254.417994) (xy 89.708023 -254.467744) (xy 89.694004 -254.49149)
			(xy 89.690956 -254.50292) (xy 89.690956 -254.661924) (xy 89.691322 -254.671032) (xy 89.697687 -254.688098)
			(xy 89.703402 -254.695198) (xy 89.709244 -254.702056) (xy 89.725246 -254.710946) (xy 89.73439 -254.712216)
			(xy 89.758322 -254.716122) (xy 89.804628 -254.73051) (xy 89.848078 -254.752034) (xy 89.887581 -254.780154)
			(xy 89.922143 -254.814164) (xy 89.950897 -254.853208) (xy 89.97312 -254.896305) (xy 89.988253 -254.942372)
			(xy 89.995916 -254.990252) (xy 89.995916 -255.014476) (xy 90.314775 -255.014476) (xy 90.31887 -254.963748)
			(xy 90.331049 -254.914334) (xy 90.350997 -254.867514) (xy 90.378198 -254.8245) (xy 90.411946 -254.786406)
			(xy 90.451368 -254.754219) (xy 90.495442 -254.728773) (xy 90.543028 -254.710726) (xy 90.592892 -254.700546)
			(xy 90.643744 -254.698497) (xy 90.694265 -254.704631) (xy 90.743149 -254.718791) (xy 90.789128 -254.740608)
			(xy 90.831012 -254.769518) (xy 90.867716 -254.804773) (xy 90.898289 -254.845459) (xy 90.92194 -254.890522)
			(xy 90.938056 -254.938796) (xy 90.94622 -254.98903) (xy 90.946732 -255.014476) (xy 91.26526 -255.014476)
			(xy 91.26922 -254.965422) (xy 91.280997 -254.917638) (xy 91.300288 -254.872362) (xy 91.326591 -254.830766)
			(xy 91.359226 -254.793929) (xy 91.397347 -254.762804) (xy 91.439968 -254.738197) (xy 91.485984 -254.720745)
			(xy 91.534203 -254.710901) (xy 91.583378 -254.70892) (xy 91.632233 -254.714852) (xy 91.679504 -254.728544)
			(xy 91.723966 -254.749642) (xy 91.764469 -254.777598) (xy 91.799962 -254.81169) (xy 91.829527 -254.851034)
			(xy 91.852398 -254.894611) (xy 91.867982 -254.941292) (xy 91.875877 -254.989869) (xy 91.876372 -255.014476)
			(xy 92.194883 -255.014476) (xy 92.198978 -254.963748) (xy 92.211157 -254.914334) (xy 92.231105 -254.867514)
			(xy 92.258306 -254.8245) (xy 92.292054 -254.786406) (xy 92.331476 -254.754219) (xy 92.37555 -254.728773)
			(xy 92.423136 -254.710726) (xy 92.473 -254.700546) (xy 92.523852 -254.698497) (xy 92.574373 -254.704631)
			(xy 92.623257 -254.718791) (xy 92.669236 -254.740608) (xy 92.71112 -254.769518) (xy 92.747824 -254.804773)
			(xy 92.778397 -254.845459) (xy 92.802048 -254.890522) (xy 92.818164 -254.938796) (xy 92.826328 -254.98903)
			(xy 92.82684 -255.014476) (xy 93.145114 -255.014476) (xy 93.149074 -254.965422) (xy 93.160851 -254.917638)
			(xy 93.180142 -254.872362) (xy 93.206445 -254.830766) (xy 93.23908 -254.793929) (xy 93.277201 -254.762804)
			(xy 93.319822 -254.738197) (xy 93.365838 -254.720745) (xy 93.414057 -254.710901) (xy 93.463232 -254.70892)
			(xy 93.512087 -254.714852) (xy 93.559358 -254.728544) (xy 93.60382 -254.749642) (xy 93.644323 -254.777598)
			(xy 93.679816 -254.81169) (xy 93.709381 -254.851034) (xy 93.732252 -254.894611) (xy 93.747836 -254.941292)
			(xy 93.755731 -254.989869) (xy 93.756226 -255.014476) (xy 94.074737 -255.014476) (xy 94.078832 -254.963748)
			(xy 94.091011 -254.914334) (xy 94.110959 -254.867514) (xy 94.13816 -254.8245) (xy 94.171908 -254.786406)
			(xy 94.21133 -254.754219) (xy 94.255404 -254.728773) (xy 94.30299 -254.710726) (xy 94.352854 -254.700546)
			(xy 94.403706 -254.698497) (xy 94.454227 -254.704631) (xy 94.503111 -254.718791) (xy 94.54909 -254.740608)
			(xy 94.590974 -254.769518) (xy 94.627678 -254.804773) (xy 94.658251 -254.845459) (xy 94.681902 -254.890522)
			(xy 94.698018 -254.938796) (xy 94.706182 -254.98903) (xy 94.706694 -255.014476) (xy 95.014791 -255.014476)
			(xy 95.018886 -254.963748) (xy 95.031065 -254.914334) (xy 95.051013 -254.867514) (xy 95.078214 -254.8245)
			(xy 95.111962 -254.786406) (xy 95.151384 -254.754219) (xy 95.195458 -254.728773) (xy 95.243044 -254.710726)
			(xy 95.292908 -254.700546) (xy 95.34376 -254.698497) (xy 95.394281 -254.704631) (xy 95.443165 -254.718791)
			(xy 95.489144 -254.740608) (xy 95.531028 -254.769518) (xy 95.567732 -254.804773) (xy 95.598305 -254.845459)
			(xy 95.621956 -254.890522) (xy 95.638072 -254.938796) (xy 95.646236 -254.98903) (xy 95.646748 -255.014476)
			(xy 95.965276 -255.014476) (xy 95.969236 -254.965422) (xy 95.981013 -254.917638) (xy 96.000304 -254.872362)
			(xy 96.026607 -254.830766) (xy 96.059242 -254.793929) (xy 96.097363 -254.762804) (xy 96.139984 -254.738197)
			(xy 96.186 -254.720745) (xy 96.234219 -254.710901) (xy 96.283394 -254.70892) (xy 96.332249 -254.714852)
			(xy 96.37952 -254.728544) (xy 96.423982 -254.749642) (xy 96.464485 -254.777598) (xy 96.499978 -254.81169)
			(xy 96.529543 -254.851034) (xy 96.552414 -254.894611) (xy 96.567998 -254.941292) (xy 96.575893 -254.989869)
			(xy 96.576388 -255.014476) (xy 96.90533 -255.014476) (xy 96.90929 -254.965422) (xy 96.921067 -254.917638)
			(xy 96.940358 -254.872362) (xy 96.966661 -254.830766) (xy 96.999296 -254.793929) (xy 97.037417 -254.762804)
			(xy 97.080038 -254.738197) (xy 97.126054 -254.720745) (xy 97.174273 -254.710901) (xy 97.223448 -254.70892)
			(xy 97.272303 -254.714852) (xy 97.319574 -254.728544) (xy 97.364036 -254.749642) (xy 97.404539 -254.777598)
			(xy 97.440032 -254.81169) (xy 97.469597 -254.851034) (xy 97.492468 -254.894611) (xy 97.508052 -254.941292)
			(xy 97.515947 -254.989869) (xy 97.516442 -255.014476) (xy 97.84513 -255.014476) (xy 97.84909 -254.965422)
			(xy 97.860867 -254.917638) (xy 97.880158 -254.872362) (xy 97.906461 -254.830766) (xy 97.939096 -254.793929)
			(xy 97.977217 -254.762804) (xy 98.019838 -254.738197) (xy 98.065854 -254.720745) (xy 98.114073 -254.710901)
			(xy 98.163248 -254.70892) (xy 98.212103 -254.714852) (xy 98.259374 -254.728544) (xy 98.303836 -254.749642)
			(xy 98.344339 -254.777598) (xy 98.379832 -254.81169) (xy 98.409397 -254.851034) (xy 98.432268 -254.894611)
			(xy 98.447852 -254.941292) (xy 98.455747 -254.989869) (xy 98.456242 -255.014476) (xy 98.455747 -255.039083)
			(xy 98.447852 -255.08766) (xy 98.432268 -255.134341) (xy 98.409397 -255.177918) (xy 98.379832 -255.217262)
			(xy 98.344339 -255.251354) (xy 98.303836 -255.27931) (xy 98.259374 -255.300408) (xy 98.212103 -255.3141)
			(xy 98.163248 -255.320032) (xy 98.114073 -255.318051) (xy 98.065854 -255.308207) (xy 98.019838 -255.290755)
			(xy 97.977217 -255.266148) (xy 97.939096 -255.235023) (xy 97.906461 -255.198186) (xy 97.880158 -255.15659)
			(xy 97.860867 -255.111314) (xy 97.84909 -255.06353) (xy 97.84513 -255.014476) (xy 97.516442 -255.014476)
			(xy 97.515947 -255.039083) (xy 97.508052 -255.08766) (xy 97.492468 -255.134341) (xy 97.469597 -255.177918)
			(xy 97.440032 -255.217262) (xy 97.404539 -255.251354) (xy 97.364036 -255.27931) (xy 97.319574 -255.300408)
			(xy 97.272303 -255.3141) (xy 97.223448 -255.320032) (xy 97.174273 -255.318051) (xy 97.126054 -255.308207)
			(xy 97.080038 -255.290755) (xy 97.037417 -255.266148) (xy 96.999296 -255.235023) (xy 96.966661 -255.198186)
			(xy 96.940358 -255.15659) (xy 96.921067 -255.111314) (xy 96.90929 -255.06353) (xy 96.90533 -255.014476)
			(xy 96.576388 -255.014476) (xy 96.575893 -255.039083) (xy 96.567998 -255.08766) (xy 96.552414 -255.134341)
			(xy 96.529543 -255.177918) (xy 96.499978 -255.217262) (xy 96.464485 -255.251354) (xy 96.423982 -255.27931)
			(xy 96.37952 -255.300408) (xy 96.332249 -255.3141) (xy 96.283394 -255.320032) (xy 96.234219 -255.318051)
			(xy 96.186 -255.308207) (xy 96.139984 -255.290755) (xy 96.097363 -255.266148) (xy 96.059242 -255.235023)
			(xy 96.026607 -255.198186) (xy 96.000304 -255.15659) (xy 95.981013 -255.111314) (xy 95.969236 -255.06353)
			(xy 95.965276 -255.014476) (xy 95.646748 -255.014476) (xy 95.646236 -255.039922) (xy 95.638072 -255.090156)
			(xy 95.621956 -255.13843) (xy 95.598305 -255.183493) (xy 95.567732 -255.224179) (xy 95.531028 -255.259434)
			(xy 95.489144 -255.288344) (xy 95.443165 -255.310161) (xy 95.394281 -255.324321) (xy 95.34376 -255.330455)
			(xy 95.292908 -255.328406) (xy 95.243044 -255.318226) (xy 95.195458 -255.300179) (xy 95.151384 -255.274733)
			(xy 95.111962 -255.242546) (xy 95.078214 -255.204452) (xy 95.051013 -255.161438) (xy 95.031065 -255.114618)
			(xy 95.018886 -255.065204) (xy 95.014791 -255.014476) (xy 94.706694 -255.014476) (xy 94.706182 -255.039922)
			(xy 94.698018 -255.090156) (xy 94.681902 -255.13843) (xy 94.658251 -255.183493) (xy 94.627678 -255.224179)
			(xy 94.590974 -255.259434) (xy 94.54909 -255.288344) (xy 94.503111 -255.310161) (xy 94.454227 -255.324321)
			(xy 94.403706 -255.330455) (xy 94.352854 -255.328406) (xy 94.30299 -255.318226) (xy 94.255404 -255.300179)
			(xy 94.21133 -255.274733) (xy 94.171908 -255.242546) (xy 94.13816 -255.204452) (xy 94.110959 -255.161438)
			(xy 94.091011 -255.114618) (xy 94.078832 -255.065204) (xy 94.074737 -255.014476) (xy 93.756226 -255.014476)
			(xy 93.755731 -255.039083) (xy 93.747836 -255.08766) (xy 93.732252 -255.134341) (xy 93.709381 -255.177918)
			(xy 93.679816 -255.217262) (xy 93.644323 -255.251354) (xy 93.60382 -255.27931) (xy 93.559358 -255.300408)
			(xy 93.512087 -255.3141) (xy 93.463232 -255.320032) (xy 93.414057 -255.318051) (xy 93.365838 -255.308207)
			(xy 93.319822 -255.290755) (xy 93.277201 -255.266148) (xy 93.23908 -255.235023) (xy 93.206445 -255.198186)
			(xy 93.180142 -255.15659) (xy 93.160851 -255.111314) (xy 93.149074 -255.06353) (xy 93.145114 -255.014476)
			(xy 92.82684 -255.014476) (xy 92.826328 -255.039922) (xy 92.818164 -255.090156) (xy 92.802048 -255.13843)
			(xy 92.778397 -255.183493) (xy 92.747824 -255.224179) (xy 92.71112 -255.259434) (xy 92.669236 -255.288344)
			(xy 92.623257 -255.310161) (xy 92.574373 -255.324321) (xy 92.523852 -255.330455) (xy 92.473 -255.328406)
			(xy 92.423136 -255.318226) (xy 92.37555 -255.300179) (xy 92.331476 -255.274733) (xy 92.292054 -255.242546)
			(xy 92.258306 -255.204452) (xy 92.231105 -255.161438) (xy 92.211157 -255.114618) (xy 92.198978 -255.065204)
			(xy 92.194883 -255.014476) (xy 91.876372 -255.014476) (xy 91.875877 -255.039083) (xy 91.867982 -255.08766)
			(xy 91.852398 -255.134341) (xy 91.829527 -255.177918) (xy 91.799962 -255.217262) (xy 91.764469 -255.251354)
			(xy 91.723966 -255.27931) (xy 91.679504 -255.300408) (xy 91.632233 -255.3141) (xy 91.583378 -255.320032)
			(xy 91.534203 -255.318051) (xy 91.485984 -255.308207) (xy 91.439968 -255.290755) (xy 91.397347 -255.266148)
			(xy 91.359226 -255.235023) (xy 91.326591 -255.198186) (xy 91.300288 -255.15659) (xy 91.280997 -255.111314)
			(xy 91.26922 -255.06353) (xy 91.26526 -255.014476) (xy 90.946732 -255.014476) (xy 90.94622 -255.039922)
			(xy 90.938056 -255.090156) (xy 90.92194 -255.13843) (xy 90.898289 -255.183493) (xy 90.867716 -255.224179)
			(xy 90.831012 -255.259434) (xy 90.789128 -255.288344) (xy 90.743149 -255.310161) (xy 90.694265 -255.324321)
			(xy 90.643744 -255.330455) (xy 90.592892 -255.328406) (xy 90.543028 -255.318226) (xy 90.495442 -255.300179)
			(xy 90.451368 -255.274733) (xy 90.411946 -255.242546) (xy 90.378198 -255.204452) (xy 90.350997 -255.161438)
			(xy 90.331049 -255.114618) (xy 90.31887 -255.065204) (xy 90.314775 -255.014476) (xy 89.995916 -255.014476)
			(xy 89.995917 -255.038741) (xy 89.988255 -255.086621) (xy 89.973123 -255.132689) (xy 89.950901 -255.175787)
			(xy 89.922148 -255.214831) (xy 89.887586 -255.248841) (xy 89.848084 -255.276962) (xy 89.804634 -255.298488)
			(xy 89.758329 -255.312877) (xy 89.73439 -255.316736) (xy 89.734136 -255.316736) (xy 89.725286 -255.318429)
			(xy 89.709533 -255.327151) (xy 89.703402 -255.333754) (xy 89.697306 -255.340612) (xy 89.690956 -255.35763)
			(xy 89.690956 -255.51892) (xy 89.691106 -255.524501) (xy 89.693548 -255.535393) (xy 89.695782 -255.54051)
			(xy 89.699592 -255.547114) (xy 89.710167 -255.565765) (xy 89.728728 -255.604418) (xy 89.736676 -255.62433)
			(xy 89.7393 -255.630625) (xy 89.747415 -255.641583) (xy 89.752678 -255.64592) (xy 89.763092 -255.654048)
			(xy 89.775538 -255.655572) (xy 89.865708 -255.667002) (xy 89.872587 -255.6676) (xy 89.886236 -255.665542)
			(xy 89.892632 -255.662938) (xy 89.898474 -255.660398) (xy 89.908888 -255.652016) (xy 89.913206 -255.646174)
			(xy 89.927673 -255.626877) (xy 89.961663 -255.592665) (xy 90.000603 -255.564215) (xy 90.043527 -255.542232)
			(xy 90.089371 -255.527261) (xy 90.136997 -255.519675) (xy 90.16111 -255.519174) (xy 90.186366 -255.519696)
			(xy 90.23619 -255.528012) (xy 90.283965 -255.544415) (xy 90.328389 -255.568457) (xy 90.36825 -255.599483)
			(xy 90.40246 -255.636647) (xy 90.430088 -255.678935) (xy 90.450378 -255.725193) (xy 90.462778 -255.77416)
			(xy 90.466948 -255.824482) (xy 90.784675 -255.824482) (xy 90.78877 -255.773754) (xy 90.800949 -255.72434)
			(xy 90.820897 -255.67752) (xy 90.848098 -255.634506) (xy 90.881846 -255.596412) (xy 90.921268 -255.564225)
			(xy 90.965342 -255.538779) (xy 91.012928 -255.520732) (xy 91.062792 -255.510552) (xy 91.113644 -255.508503)
			(xy 91.164165 -255.514637) (xy 91.213049 -255.528797) (xy 91.259028 -255.550614) (xy 91.300912 -255.579524)
			(xy 91.337616 -255.614779) (xy 91.368189 -255.655465) (xy 91.39184 -255.700528) (xy 91.407956 -255.748802)
			(xy 91.41612 -255.799036) (xy 91.416632 -255.824482) (xy 91.724729 -255.824482) (xy 91.728824 -255.773754)
			(xy 91.741003 -255.72434) (xy 91.760951 -255.67752) (xy 91.788152 -255.634506) (xy 91.8219 -255.596412)
			(xy 91.861322 -255.564225) (xy 91.905396 -255.538779) (xy 91.952982 -255.520732) (xy 92.002846 -255.510552)
			(xy 92.053698 -255.508503) (xy 92.104219 -255.514637) (xy 92.153103 -255.528797) (xy 92.199082 -255.550614)
			(xy 92.240966 -255.579524) (xy 92.27767 -255.614779) (xy 92.308243 -255.655465) (xy 92.331894 -255.700528)
			(xy 92.34801 -255.748802) (xy 92.356174 -255.799036) (xy 92.356686 -255.824482) (xy 92.675214 -255.824482)
			(xy 92.679174 -255.775428) (xy 92.690951 -255.727644) (xy 92.710242 -255.682368) (xy 92.736545 -255.640772)
			(xy 92.76918 -255.603935) (xy 92.807301 -255.57281) (xy 92.849922 -255.548203) (xy 92.895938 -255.530751)
			(xy 92.944157 -255.520907) (xy 92.993332 -255.518926) (xy 93.042187 -255.524858) (xy 93.089458 -255.53855)
			(xy 93.13392 -255.559648) (xy 93.174423 -255.587604) (xy 93.209916 -255.621696) (xy 93.239481 -255.66104)
			(xy 93.262352 -255.704617) (xy 93.277936 -255.751298) (xy 93.285831 -255.799875) (xy 93.286326 -255.824482)
			(xy 93.604837 -255.824482) (xy 93.608932 -255.773754) (xy 93.621111 -255.72434) (xy 93.641059 -255.67752)
			(xy 93.66826 -255.634506) (xy 93.702008 -255.596412) (xy 93.74143 -255.564225) (xy 93.785504 -255.538779)
			(xy 93.83309 -255.520732) (xy 93.882954 -255.510552) (xy 93.933806 -255.508503) (xy 93.984327 -255.514637)
			(xy 94.033211 -255.528797) (xy 94.07919 -255.550614) (xy 94.121074 -255.579524) (xy 94.157778 -255.614779)
			(xy 94.188351 -255.655465) (xy 94.212002 -255.700528) (xy 94.228118 -255.748802) (xy 94.236282 -255.799036)
			(xy 94.236794 -255.824482) (xy 94.555322 -255.824482) (xy 94.559282 -255.775428) (xy 94.571059 -255.727644)
			(xy 94.59035 -255.682368) (xy 94.616653 -255.640772) (xy 94.649288 -255.603935) (xy 94.687409 -255.57281)
			(xy 94.73003 -255.548203) (xy 94.776046 -255.530751) (xy 94.824265 -255.520907) (xy 94.87344 -255.518926)
			(xy 94.922295 -255.524858) (xy 94.969566 -255.53855) (xy 95.014028 -255.559648) (xy 95.054531 -255.587604)
			(xy 95.090024 -255.621696) (xy 95.119589 -255.66104) (xy 95.14246 -255.704617) (xy 95.158044 -255.751298)
			(xy 95.165939 -255.799875) (xy 95.166434 -255.824482) (xy 95.484691 -255.824482) (xy 95.488786 -255.773754)
			(xy 95.500965 -255.72434) (xy 95.520913 -255.67752) (xy 95.548114 -255.634506) (xy 95.581862 -255.596412)
			(xy 95.621284 -255.564225) (xy 95.665358 -255.538779) (xy 95.712944 -255.520732) (xy 95.762808 -255.510552)
			(xy 95.81366 -255.508503) (xy 95.864181 -255.514637) (xy 95.913065 -255.528797) (xy 95.959044 -255.550614)
			(xy 96.000928 -255.579524) (xy 96.037632 -255.614779) (xy 96.068205 -255.655465) (xy 96.091856 -255.700528)
			(xy 96.107972 -255.748802) (xy 96.116136 -255.799036) (xy 96.116648 -255.824482) (xy 96.435176 -255.824482)
			(xy 96.439136 -255.775428) (xy 96.450913 -255.727644) (xy 96.470204 -255.682368) (xy 96.496507 -255.640772)
			(xy 96.529142 -255.603935) (xy 96.567263 -255.57281) (xy 96.609884 -255.548203) (xy 96.6559 -255.530751)
			(xy 96.704119 -255.520907) (xy 96.753294 -255.518926) (xy 96.802149 -255.524858) (xy 96.84942 -255.53855)
			(xy 96.893882 -255.559648) (xy 96.934385 -255.587604) (xy 96.969878 -255.621696) (xy 96.999443 -255.66104)
			(xy 97.022314 -255.704617) (xy 97.037898 -255.751298) (xy 97.045793 -255.799875) (xy 97.046288 -255.824482)
			(xy 97.37523 -255.824482) (xy 97.37919 -255.775428) (xy 97.390967 -255.727644) (xy 97.410258 -255.682368)
			(xy 97.436561 -255.640772) (xy 97.469196 -255.603935) (xy 97.507317 -255.57281) (xy 97.549938 -255.548203)
			(xy 97.595954 -255.530751) (xy 97.644173 -255.520907) (xy 97.693348 -255.518926) (xy 97.742203 -255.524858)
			(xy 97.789474 -255.53855) (xy 97.833936 -255.559648) (xy 97.874439 -255.587604) (xy 97.909932 -255.621696)
			(xy 97.939497 -255.66104) (xy 97.962368 -255.704617) (xy 97.977952 -255.751298) (xy 97.985847 -255.799875)
			(xy 97.986342 -255.824482) (xy 98.315284 -255.824482) (xy 98.319244 -255.775428) (xy 98.331021 -255.727644)
			(xy 98.350312 -255.682368) (xy 98.376615 -255.640772) (xy 98.40925 -255.603935) (xy 98.447371 -255.57281)
			(xy 98.489992 -255.548203) (xy 98.536008 -255.530751) (xy 98.584227 -255.520907) (xy 98.633402 -255.518926)
			(xy 98.682257 -255.524858) (xy 98.729528 -255.53855) (xy 98.77399 -255.559648) (xy 98.814493 -255.587604)
			(xy 98.849986 -255.621696) (xy 98.879551 -255.66104) (xy 98.902422 -255.704617) (xy 98.918006 -255.751298)
			(xy 98.925901 -255.799875) (xy 98.926396 -255.824482) (xy 98.925901 -255.849089) (xy 98.918006 -255.897666)
			(xy 98.902422 -255.944347) (xy 98.879551 -255.987924) (xy 98.849986 -256.027268) (xy 98.814493 -256.06136)
			(xy 98.77399 -256.089316) (xy 98.729528 -256.110414) (xy 98.682257 -256.124106) (xy 98.633402 -256.130038)
			(xy 98.584227 -256.128057) (xy 98.536008 -256.118213) (xy 98.489992 -256.100761) (xy 98.447371 -256.076154)
			(xy 98.40925 -256.045029) (xy 98.376615 -256.008192) (xy 98.350312 -255.966596) (xy 98.331021 -255.92132)
			(xy 98.319244 -255.873536) (xy 98.315284 -255.824482) (xy 97.986342 -255.824482) (xy 97.985847 -255.849089)
			(xy 97.977952 -255.897666) (xy 97.962368 -255.944347) (xy 97.939497 -255.987924) (xy 97.909932 -256.027268)
			(xy 97.874439 -256.06136) (xy 97.833936 -256.089316) (xy 97.789474 -256.110414) (xy 97.742203 -256.124106)
			(xy 97.693348 -256.130038) (xy 97.644173 -256.128057) (xy 97.595954 -256.118213) (xy 97.549938 -256.100761)
			(xy 97.507317 -256.076154) (xy 97.469196 -256.045029) (xy 97.436561 -256.008192) (xy 97.410258 -255.966596)
			(xy 97.390967 -255.92132) (xy 97.37919 -255.873536) (xy 97.37523 -255.824482) (xy 97.046288 -255.824482)
			(xy 97.045793 -255.849089) (xy 97.037898 -255.897666) (xy 97.022314 -255.944347) (xy 96.999443 -255.987924)
			(xy 96.969878 -256.027268) (xy 96.934385 -256.06136) (xy 96.893882 -256.089316) (xy 96.84942 -256.110414)
			(xy 96.802149 -256.124106) (xy 96.753294 -256.130038) (xy 96.704119 -256.128057) (xy 96.6559 -256.118213)
			(xy 96.609884 -256.100761) (xy 96.567263 -256.076154) (xy 96.529142 -256.045029) (xy 96.496507 -256.008192)
			(xy 96.470204 -255.966596) (xy 96.450913 -255.92132) (xy 96.439136 -255.873536) (xy 96.435176 -255.824482)
			(xy 96.116648 -255.824482) (xy 96.116136 -255.849928) (xy 96.107972 -255.900162) (xy 96.091856 -255.948436)
			(xy 96.068205 -255.993499) (xy 96.037632 -256.034185) (xy 96.000928 -256.06944) (xy 95.959044 -256.09835)
			(xy 95.913065 -256.120167) (xy 95.864181 -256.134327) (xy 95.81366 -256.140461) (xy 95.762808 -256.138412)
			(xy 95.712944 -256.128232) (xy 95.665358 -256.110185) (xy 95.621284 -256.084739) (xy 95.581862 -256.052552)
			(xy 95.548114 -256.014458) (xy 95.520913 -255.971444) (xy 95.500965 -255.924624) (xy 95.488786 -255.87521)
			(xy 95.484691 -255.824482) (xy 95.166434 -255.824482) (xy 95.165939 -255.849089) (xy 95.158044 -255.897666)
			(xy 95.14246 -255.944347) (xy 95.119589 -255.987924) (xy 95.090024 -256.027268) (xy 95.054531 -256.06136)
			(xy 95.014028 -256.089316) (xy 94.969566 -256.110414) (xy 94.922295 -256.124106) (xy 94.87344 -256.130038)
			(xy 94.824265 -256.128057) (xy 94.776046 -256.118213) (xy 94.73003 -256.100761) (xy 94.687409 -256.076154)
			(xy 94.649288 -256.045029) (xy 94.616653 -256.008192) (xy 94.59035 -255.966596) (xy 94.571059 -255.92132)
			(xy 94.559282 -255.873536) (xy 94.555322 -255.824482) (xy 94.236794 -255.824482) (xy 94.236282 -255.849928)
			(xy 94.228118 -255.900162) (xy 94.212002 -255.948436) (xy 94.188351 -255.993499) (xy 94.157778 -256.034185)
			(xy 94.121074 -256.06944) (xy 94.07919 -256.09835) (xy 94.033211 -256.120167) (xy 93.984327 -256.134327)
			(xy 93.933806 -256.140461) (xy 93.882954 -256.138412) (xy 93.83309 -256.128232) (xy 93.785504 -256.110185)
			(xy 93.74143 -256.084739) (xy 93.702008 -256.052552) (xy 93.66826 -256.014458) (xy 93.641059 -255.971444)
			(xy 93.621111 -255.924624) (xy 93.608932 -255.87521) (xy 93.604837 -255.824482) (xy 93.286326 -255.824482)
			(xy 93.285831 -255.849089) (xy 93.277936 -255.897666) (xy 93.262352 -255.944347) (xy 93.239481 -255.987924)
			(xy 93.209916 -256.027268) (xy 93.174423 -256.06136) (xy 93.13392 -256.089316) (xy 93.089458 -256.110414)
			(xy 93.042187 -256.124106) (xy 92.993332 -256.130038) (xy 92.944157 -256.128057) (xy 92.895938 -256.118213)
			(xy 92.849922 -256.100761) (xy 92.807301 -256.076154) (xy 92.76918 -256.045029) (xy 92.736545 -256.008192)
			(xy 92.710242 -255.966596) (xy 92.690951 -255.92132) (xy 92.679174 -255.873536) (xy 92.675214 -255.824482)
			(xy 92.356686 -255.824482) (xy 92.356174 -255.849928) (xy 92.34801 -255.900162) (xy 92.331894 -255.948436)
			(xy 92.308243 -255.993499) (xy 92.27767 -256.034185) (xy 92.240966 -256.06944) (xy 92.199082 -256.09835)
			(xy 92.153103 -256.120167) (xy 92.104219 -256.134327) (xy 92.053698 -256.140461) (xy 92.002846 -256.138412)
			(xy 91.952982 -256.128232) (xy 91.905396 -256.110185) (xy 91.861322 -256.084739) (xy 91.8219 -256.052552)
			(xy 91.788152 -256.014458) (xy 91.760951 -255.971444) (xy 91.741003 -255.924624) (xy 91.728824 -255.87521)
			(xy 91.724729 -255.824482) (xy 91.416632 -255.824482) (xy 91.41612 -255.849928) (xy 91.407956 -255.900162)
			(xy 91.39184 -255.948436) (xy 91.368189 -255.993499) (xy 91.337616 -256.034185) (xy 91.300912 -256.06944)
			(xy 91.259028 -256.09835) (xy 91.213049 -256.120167) (xy 91.164165 -256.134327) (xy 91.113644 -256.140461)
			(xy 91.062792 -256.138412) (xy 91.012928 -256.128232) (xy 90.965342 -256.110185) (xy 90.921268 -256.084739)
			(xy 90.881846 -256.052552) (xy 90.848098 -256.014458) (xy 90.820897 -255.971444) (xy 90.800949 -255.924624)
			(xy 90.78877 -255.87521) (xy 90.784675 -255.824482) (xy 90.466948 -255.824482) (xy 90.466949 -255.8245)
			(xy 90.462778 -255.87484) (xy 90.450378 -255.923807) (xy 90.430088 -255.970065) (xy 90.40246 -256.012353)
			(xy 90.36825 -256.049517) (xy 90.328389 -256.080543) (xy 90.283965 -256.104585) (xy 90.23619 -256.120988)
			(xy 90.186366 -256.129304) (xy 90.16111 -256.12979) (xy 90.148347 -256.129654) (xy 90.122912 -256.127496)
			(xy 90.11031 -256.125472) (xy 90.11031 -256.125726) (xy 90.086857 -256.121299) (xy 90.041603 -256.106136)
			(xy 89.999252 -256.084132) (xy 89.960831 -256.05582) (xy 89.927271 -256.021885) (xy 89.912952 -256.00279)
			(xy 89.908888 -255.996948) (xy 89.89822 -255.988312) (xy 89.892378 -255.985772) (xy 89.886095 -255.983248)
			(xy 89.872701 -255.981309) (xy 89.865962 -255.981962) (xy 89.777316 -255.993138) (xy 89.770418 -255.994251)
			(xy 89.757543 -255.999663) (xy 89.751916 -256.003806) (xy 89.741502 -256.012188) (xy 89.731814 -256.038005)
			(xy 89.708021 -256.087755) (xy 89.694004 -256.111502) (xy 89.690956 -256.122932) (xy 89.690956 -256.281936)
			(xy 89.691324 -256.291043) (xy 89.697693 -256.308107) (xy 89.703402 -256.31521) (xy 89.709244 -256.322068)
			(xy 89.725246 -256.330958) (xy 89.73439 -256.332228) (xy 89.758322 -256.336134) (xy 89.804625 -256.350521)
			(xy 89.848073 -256.372045) (xy 89.887574 -256.400165) (xy 89.922135 -256.434173) (xy 89.950888 -256.473215)
			(xy 89.97311 -256.516311) (xy 89.988242 -256.562377) (xy 89.995904 -256.610255) (xy 89.995904 -256.634488)
			(xy 90.314775 -256.634488) (xy 90.31887 -256.58376) (xy 90.331049 -256.534346) (xy 90.350997 -256.487526)
			(xy 90.378198 -256.444512) (xy 90.411946 -256.406418) (xy 90.451368 -256.374231) (xy 90.495442 -256.348785)
			(xy 90.543028 -256.330738) (xy 90.592892 -256.320558) (xy 90.643744 -256.318509) (xy 90.694265 -256.324643)
			(xy 90.743149 -256.338803) (xy 90.789128 -256.36062) (xy 90.831012 -256.38953) (xy 90.867716 -256.424785)
			(xy 90.898289 -256.465471) (xy 90.92194 -256.510534) (xy 90.938056 -256.558808) (xy 90.94622 -256.609042)
			(xy 90.946732 -256.634488) (xy 91.26526 -256.634488) (xy 91.26922 -256.585434) (xy 91.280997 -256.53765)
			(xy 91.300288 -256.492374) (xy 91.326591 -256.450778) (xy 91.359226 -256.413941) (xy 91.397347 -256.382816)
			(xy 91.439968 -256.358209) (xy 91.485984 -256.340757) (xy 91.534203 -256.330913) (xy 91.583378 -256.328932)
			(xy 91.632233 -256.334864) (xy 91.679504 -256.348556) (xy 91.723966 -256.369654) (xy 91.764469 -256.39761)
			(xy 91.799962 -256.431702) (xy 91.829527 -256.471046) (xy 91.852398 -256.514623) (xy 91.867982 -256.561304)
			(xy 91.875877 -256.609881) (xy 91.876372 -256.634488) (xy 92.205314 -256.634488) (xy 92.209274 -256.585434)
			(xy 92.221051 -256.53765) (xy 92.240342 -256.492374) (xy 92.266645 -256.450778) (xy 92.29928 -256.413941)
			(xy 92.337401 -256.382816) (xy 92.380022 -256.358209) (xy 92.426038 -256.340757) (xy 92.474257 -256.330913)
			(xy 92.523432 -256.328932) (xy 92.572287 -256.334864) (xy 92.619558 -256.348556) (xy 92.66402 -256.369654)
			(xy 92.704523 -256.39761) (xy 92.740016 -256.431702) (xy 92.769581 -256.471046) (xy 92.792452 -256.514623)
			(xy 92.808036 -256.561304) (xy 92.815931 -256.609881) (xy 92.816426 -256.634488) (xy 93.145114 -256.634488)
			(xy 93.149074 -256.585434) (xy 93.160851 -256.53765) (xy 93.180142 -256.492374) (xy 93.206445 -256.450778)
			(xy 93.23908 -256.413941) (xy 93.277201 -256.382816) (xy 93.319822 -256.358209) (xy 93.365838 -256.340757)
			(xy 93.414057 -256.330913) (xy 93.463232 -256.328932) (xy 93.512087 -256.334864) (xy 93.559358 -256.348556)
			(xy 93.60382 -256.369654) (xy 93.644323 -256.39761) (xy 93.679816 -256.431702) (xy 93.709381 -256.471046)
			(xy 93.732252 -256.514623) (xy 93.747836 -256.561304) (xy 93.755731 -256.609881) (xy 93.756226 -256.634488)
			(xy 94.074737 -256.634488) (xy 94.078832 -256.58376) (xy 94.091011 -256.534346) (xy 94.110959 -256.487526)
			(xy 94.13816 -256.444512) (xy 94.171908 -256.406418) (xy 94.21133 -256.374231) (xy 94.255404 -256.348785)
			(xy 94.30299 -256.330738) (xy 94.352854 -256.320558) (xy 94.403706 -256.318509) (xy 94.454227 -256.324643)
			(xy 94.503111 -256.338803) (xy 94.54909 -256.36062) (xy 94.590974 -256.38953) (xy 94.627678 -256.424785)
			(xy 94.658251 -256.465471) (xy 94.681902 -256.510534) (xy 94.698018 -256.558808) (xy 94.706182 -256.609042)
			(xy 94.706694 -256.634488) (xy 95.025222 -256.634488) (xy 95.029182 -256.585434) (xy 95.040959 -256.53765)
			(xy 95.06025 -256.492374) (xy 95.086553 -256.450778) (xy 95.119188 -256.413941) (xy 95.157309 -256.382816)
			(xy 95.19993 -256.358209) (xy 95.245946 -256.340757) (xy 95.294165 -256.330913) (xy 95.34334 -256.328932)
			(xy 95.392195 -256.334864) (xy 95.439466 -256.348556) (xy 95.483928 -256.369654) (xy 95.524431 -256.39761)
			(xy 95.559924 -256.431702) (xy 95.589489 -256.471046) (xy 95.61236 -256.514623) (xy 95.627944 -256.561304)
			(xy 95.635839 -256.609881) (xy 95.636334 -256.634488) (xy 96.90533 -256.634488) (xy 96.90929 -256.585434)
			(xy 96.921067 -256.53765) (xy 96.940358 -256.492374) (xy 96.966661 -256.450778) (xy 96.999296 -256.413941)
			(xy 97.037417 -256.382816) (xy 97.080038 -256.358209) (xy 97.126054 -256.340757) (xy 97.174273 -256.330913)
			(xy 97.223448 -256.328932) (xy 97.272303 -256.334864) (xy 97.319574 -256.348556) (xy 97.364036 -256.369654)
			(xy 97.404539 -256.39761) (xy 97.440032 -256.431702) (xy 97.469597 -256.471046) (xy 97.492468 -256.514623)
			(xy 97.508052 -256.561304) (xy 97.515947 -256.609881) (xy 97.516442 -256.634488) (xy 98.785184 -256.634488)
			(xy 98.789144 -256.585434) (xy 98.800921 -256.53765) (xy 98.820212 -256.492374) (xy 98.846515 -256.450778)
			(xy 98.87915 -256.413941) (xy 98.917271 -256.382816) (xy 98.959892 -256.358209) (xy 99.005908 -256.340757)
			(xy 99.054127 -256.330913) (xy 99.103302 -256.328932) (xy 99.152157 -256.334864) (xy 99.199428 -256.348556)
			(xy 99.24389 -256.369654) (xy 99.284393 -256.39761) (xy 99.319886 -256.431702) (xy 99.349451 -256.471046)
			(xy 99.372322 -256.514623) (xy 99.387906 -256.561304) (xy 99.395801 -256.609881) (xy 99.396296 -256.634488)
			(xy 99.395801 -256.659095) (xy 99.387906 -256.707672) (xy 99.372322 -256.754353) (xy 99.349451 -256.79793)
			(xy 99.319886 -256.837274) (xy 99.284393 -256.871366) (xy 99.24389 -256.899322) (xy 99.199428 -256.92042)
			(xy 99.152157 -256.934112) (xy 99.103302 -256.940044) (xy 99.054127 -256.938063) (xy 99.005908 -256.928219)
			(xy 98.959892 -256.910767) (xy 98.917271 -256.88616) (xy 98.87915 -256.855035) (xy 98.846515 -256.818198)
			(xy 98.820212 -256.776602) (xy 98.800921 -256.731326) (xy 98.789144 -256.683542) (xy 98.785184 -256.634488)
			(xy 97.516442 -256.634488) (xy 97.515947 -256.659095) (xy 97.508052 -256.707672) (xy 97.492468 -256.754353)
			(xy 97.469597 -256.79793) (xy 97.440032 -256.837274) (xy 97.404539 -256.871366) (xy 97.364036 -256.899322)
			(xy 97.319574 -256.92042) (xy 97.272303 -256.934112) (xy 97.223448 -256.940044) (xy 97.174273 -256.938063)
			(xy 97.126054 -256.928219) (xy 97.080038 -256.910767) (xy 97.037417 -256.88616) (xy 96.999296 -256.855035)
			(xy 96.966661 -256.818198) (xy 96.940358 -256.776602) (xy 96.921067 -256.731326) (xy 96.90929 -256.683542)
			(xy 96.90533 -256.634488) (xy 95.636334 -256.634488) (xy 95.635839 -256.659095) (xy 95.627944 -256.707672)
			(xy 95.61236 -256.754353) (xy 95.589489 -256.79793) (xy 95.559924 -256.837274) (xy 95.524431 -256.871366)
			(xy 95.483928 -256.899322) (xy 95.439466 -256.92042) (xy 95.392195 -256.934112) (xy 95.34334 -256.940044)
			(xy 95.294165 -256.938063) (xy 95.245946 -256.928219) (xy 95.19993 -256.910767) (xy 95.157309 -256.88616)
			(xy 95.119188 -256.855035) (xy 95.086553 -256.818198) (xy 95.06025 -256.776602) (xy 95.040959 -256.731326)
			(xy 95.029182 -256.683542) (xy 95.025222 -256.634488) (xy 94.706694 -256.634488) (xy 94.706182 -256.659934)
			(xy 94.698018 -256.710168) (xy 94.681902 -256.758442) (xy 94.658251 -256.803505) (xy 94.627678 -256.844191)
			(xy 94.590974 -256.879446) (xy 94.54909 -256.908356) (xy 94.503111 -256.930173) (xy 94.454227 -256.944333)
			(xy 94.403706 -256.950467) (xy 94.352854 -256.948418) (xy 94.30299 -256.938238) (xy 94.255404 -256.920191)
			(xy 94.21133 -256.894745) (xy 94.171908 -256.862558) (xy 94.13816 -256.824464) (xy 94.110959 -256.78145)
			(xy 94.091011 -256.73463) (xy 94.078832 -256.685216) (xy 94.074737 -256.634488) (xy 93.756226 -256.634488)
			(xy 93.755731 -256.659095) (xy 93.747836 -256.707672) (xy 93.732252 -256.754353) (xy 93.709381 -256.79793)
			(xy 93.679816 -256.837274) (xy 93.644323 -256.871366) (xy 93.60382 -256.899322) (xy 93.559358 -256.92042)
			(xy 93.512087 -256.934112) (xy 93.463232 -256.940044) (xy 93.414057 -256.938063) (xy 93.365838 -256.928219)
			(xy 93.319822 -256.910767) (xy 93.277201 -256.88616) (xy 93.23908 -256.855035) (xy 93.206445 -256.818198)
			(xy 93.180142 -256.776602) (xy 93.160851 -256.731326) (xy 93.149074 -256.683542) (xy 93.145114 -256.634488)
			(xy 92.816426 -256.634488) (xy 92.815931 -256.659095) (xy 92.808036 -256.707672) (xy 92.792452 -256.754353)
			(xy 92.769581 -256.79793) (xy 92.740016 -256.837274) (xy 92.704523 -256.871366) (xy 92.66402 -256.899322)
			(xy 92.619558 -256.92042) (xy 92.572287 -256.934112) (xy 92.523432 -256.940044) (xy 92.474257 -256.938063)
			(xy 92.426038 -256.928219) (xy 92.380022 -256.910767) (xy 92.337401 -256.88616) (xy 92.29928 -256.855035)
			(xy 92.266645 -256.818198) (xy 92.240342 -256.776602) (xy 92.221051 -256.731326) (xy 92.209274 -256.683542)
			(xy 92.205314 -256.634488) (xy 91.876372 -256.634488) (xy 91.875877 -256.659095) (xy 91.867982 -256.707672)
			(xy 91.852398 -256.754353) (xy 91.829527 -256.79793) (xy 91.799962 -256.837274) (xy 91.764469 -256.871366)
			(xy 91.723966 -256.899322) (xy 91.679504 -256.92042) (xy 91.632233 -256.934112) (xy 91.583378 -256.940044)
			(xy 91.534203 -256.938063) (xy 91.485984 -256.928219) (xy 91.439968 -256.910767) (xy 91.397347 -256.88616)
			(xy 91.359226 -256.855035) (xy 91.326591 -256.818198) (xy 91.300288 -256.776602) (xy 91.280997 -256.731326)
			(xy 91.26922 -256.683542) (xy 91.26526 -256.634488) (xy 90.946732 -256.634488) (xy 90.94622 -256.659934)
			(xy 90.938056 -256.710168) (xy 90.92194 -256.758442) (xy 90.898289 -256.803505) (xy 90.867716 -256.844191)
			(xy 90.831012 -256.879446) (xy 90.789128 -256.908356) (xy 90.743149 -256.930173) (xy 90.694265 -256.944333)
			(xy 90.643744 -256.950467) (xy 90.592892 -256.948418) (xy 90.543028 -256.938238) (xy 90.495442 -256.920191)
			(xy 90.451368 -256.894745) (xy 90.411946 -256.862558) (xy 90.378198 -256.824464) (xy 90.350997 -256.78145)
			(xy 90.331049 -256.73463) (xy 90.31887 -256.685216) (xy 90.314775 -256.634488) (xy 89.995904 -256.634488)
			(xy 89.995905 -256.658742) (xy 89.988243 -256.70662) (xy 89.973111 -256.752686) (xy 89.95089 -256.795782)
			(xy 89.922138 -256.834825) (xy 89.887577 -256.868833) (xy 89.848076 -256.896953) (xy 89.804628 -256.918477)
			(xy 89.758325 -256.932865) (xy 89.73439 -256.936748) (xy 89.734136 -256.936748) (xy 89.725286 -256.938442)
			(xy 89.709535 -256.947165) (xy 89.703402 -256.953766) (xy 89.697306 -256.960624) (xy 89.690956 -256.977642)
			(xy 89.690956 -257.930396) (xy 98.711261 -257.930396) (xy 98.715291 -257.877898) (xy 98.727288 -257.82663)
			(xy 98.746971 -257.777795) (xy 98.773877 -257.732536) (xy 98.807377 -257.691915) (xy 98.846685 -257.656884)
			(xy 98.89088 -257.628264) (xy 98.938925 -257.606725) (xy 98.989696 -257.592773) (xy 99.042001 -257.586735)
			(xy 99.094615 -257.588752) (xy 99.146305 -257.598776) (xy 99.195858 -257.616574) (xy 99.242114 -257.641727)
			(xy 99.283988 -257.673646) (xy 99.3205 -257.711584) (xy 99.350792 -257.75465) (xy 99.374155 -257.801835)
			(xy 99.390041 -257.852034) (xy 99.398078 -257.90407) (xy 99.398582 -257.930396) (xy 100.611181 -257.930396)
			(xy 100.615211 -257.877898) (xy 100.627208 -257.82663) (xy 100.646891 -257.777795) (xy 100.673797 -257.732536)
			(xy 100.707297 -257.691915) (xy 100.746605 -257.656884) (xy 100.7908 -257.628264) (xy 100.838845 -257.606725)
			(xy 100.889616 -257.592773) (xy 100.941921 -257.586735) (xy 100.994535 -257.588752) (xy 101.046225 -257.598776)
			(xy 101.095778 -257.616574) (xy 101.142034 -257.641727) (xy 101.183908 -257.673646) (xy 101.22042 -257.711584)
			(xy 101.250712 -257.75465) (xy 101.274075 -257.801835) (xy 101.289961 -257.852034) (xy 101.297998 -257.90407)
			(xy 101.298502 -257.930396) (xy 102.511101 -257.930396) (xy 102.515131 -257.877898) (xy 102.527128 -257.82663)
			(xy 102.546811 -257.777795) (xy 102.573717 -257.732536) (xy 102.607217 -257.691915) (xy 102.646525 -257.656884)
			(xy 102.69072 -257.628264) (xy 102.738765 -257.606725) (xy 102.789536 -257.592773) (xy 102.841841 -257.586735)
			(xy 102.894455 -257.588752) (xy 102.946145 -257.598776) (xy 102.995698 -257.616574) (xy 103.041954 -257.641727)
			(xy 103.083828 -257.673646) (xy 103.12034 -257.711584) (xy 103.150632 -257.75465) (xy 103.173995 -257.801835)
			(xy 103.189881 -257.852034) (xy 103.197918 -257.90407) (xy 103.198422 -257.930396) (xy 103.197918 -257.956722)
			(xy 103.189881 -258.008758) (xy 103.173995 -258.058957) (xy 103.150632 -258.106142) (xy 103.12034 -258.149208)
			(xy 103.083828 -258.187146) (xy 103.041954 -258.219065) (xy 102.995698 -258.244218) (xy 102.946145 -258.262016)
			(xy 102.894455 -258.27204) (xy 102.841841 -258.274057) (xy 102.789536 -258.268019) (xy 102.738765 -258.254067)
			(xy 102.69072 -258.232528) (xy 102.646525 -258.203908) (xy 102.607217 -258.168877) (xy 102.573717 -258.128256)
			(xy 102.546811 -258.082997) (xy 102.527128 -258.034162) (xy 102.515131 -257.982894) (xy 102.511101 -257.930396)
			(xy 101.298502 -257.930396) (xy 101.297998 -257.956722) (xy 101.289961 -258.008758) (xy 101.274075 -258.058957)
			(xy 101.250712 -258.106142) (xy 101.22042 -258.149208) (xy 101.183908 -258.187146) (xy 101.142034 -258.219065)
			(xy 101.095778 -258.244218) (xy 101.046225 -258.262016) (xy 100.994535 -258.27204) (xy 100.941921 -258.274057)
			(xy 100.889616 -258.268019) (xy 100.838845 -258.254067) (xy 100.7908 -258.232528) (xy 100.746605 -258.203908)
			(xy 100.707297 -258.168877) (xy 100.673797 -258.128256) (xy 100.646891 -258.082997) (xy 100.627208 -258.034162)
			(xy 100.615211 -257.982894) (xy 100.611181 -257.930396) (xy 99.398582 -257.930396) (xy 99.398078 -257.956722)
			(xy 99.390041 -258.008758) (xy 99.374155 -258.058957) (xy 99.350792 -258.106142) (xy 99.3205 -258.149208)
			(xy 99.283988 -258.187146) (xy 99.242114 -258.219065) (xy 99.195858 -258.244218) (xy 99.146305 -258.262016)
			(xy 99.094615 -258.27204) (xy 99.042001 -258.274057) (xy 98.989696 -258.268019) (xy 98.938925 -258.254067)
			(xy 98.89088 -258.232528) (xy 98.846685 -258.203908) (xy 98.807377 -258.168877) (xy 98.773877 -258.128256)
			(xy 98.746971 -258.082997) (xy 98.727288 -258.034162) (xy 98.715291 -257.982894) (xy 98.711261 -257.930396)
			(xy 89.690956 -257.930396) (xy 89.690956 -258.38023) (xy 106.061259 -258.38023) (xy 106.065289 -258.327732)
			(xy 106.077286 -258.276464) (xy 106.096969 -258.227629) (xy 106.123875 -258.18237) (xy 106.157375 -258.141749)
			(xy 106.196683 -258.106718) (xy 106.240878 -258.078098) (xy 106.288923 -258.056559) (xy 106.339694 -258.042607)
			(xy 106.391999 -258.036569) (xy 106.444613 -258.038586) (xy 106.496303 -258.04861) (xy 106.545856 -258.066408)
			(xy 106.592112 -258.091561) (xy 106.633986 -258.12348) (xy 106.670498 -258.161418) (xy 106.70079 -258.204484)
			(xy 106.724153 -258.251669) (xy 106.740039 -258.301868) (xy 106.748076 -258.353904) (xy 106.74858 -258.38023)
			(xy 106.748076 -258.406556) (xy 106.740039 -258.458592) (xy 106.724153 -258.508791) (xy 106.70079 -258.555976)
			(xy 106.670498 -258.599042) (xy 106.633986 -258.63698) (xy 106.592112 -258.668899) (xy 106.545856 -258.694052)
			(xy 106.496303 -258.71185) (xy 106.444613 -258.721874) (xy 106.391999 -258.723891) (xy 106.339694 -258.717853)
			(xy 106.288923 -258.703901) (xy 106.240878 -258.682362) (xy 106.196683 -258.653742) (xy 106.157375 -258.618711)
			(xy 106.123875 -258.57809) (xy 106.096969 -258.532831) (xy 106.077286 -258.483996) (xy 106.065289 -258.432728)
			(xy 106.061259 -258.38023) (xy 89.690956 -258.38023) (xy 89.690956 -258.830318) (xy 98.711261 -258.830318)
			(xy 98.715291 -258.77782) (xy 98.727288 -258.726552) (xy 98.746971 -258.677717) (xy 98.773877 -258.632458)
			(xy 98.807377 -258.591837) (xy 98.846685 -258.556806) (xy 98.89088 -258.528186) (xy 98.938925 -258.506647)
			(xy 98.989696 -258.492695) (xy 99.042001 -258.486657) (xy 99.094615 -258.488674) (xy 99.146305 -258.498698)
			(xy 99.195858 -258.516496) (xy 99.242114 -258.541649) (xy 99.283988 -258.573568) (xy 99.3205 -258.611506)
			(xy 99.350792 -258.654572) (xy 99.374155 -258.701757) (xy 99.390041 -258.751956) (xy 99.398078 -258.803992)
			(xy 99.398582 -258.830318) (xy 100.611181 -258.830318) (xy 100.615211 -258.77782) (xy 100.627208 -258.726552)
			(xy 100.646891 -258.677717) (xy 100.673797 -258.632458) (xy 100.707297 -258.591837) (xy 100.746605 -258.556806)
			(xy 100.7908 -258.528186) (xy 100.838845 -258.506647) (xy 100.889616 -258.492695) (xy 100.941921 -258.486657)
			(xy 100.994535 -258.488674) (xy 101.046225 -258.498698) (xy 101.095778 -258.516496) (xy 101.142034 -258.541649)
			(xy 101.183908 -258.573568) (xy 101.22042 -258.611506) (xy 101.250712 -258.654572) (xy 101.274075 -258.701757)
			(xy 101.289961 -258.751956) (xy 101.297998 -258.803992) (xy 101.298502 -258.830318) (xy 102.511101 -258.830318)
			(xy 102.515131 -258.77782) (xy 102.527128 -258.726552) (xy 102.546811 -258.677717) (xy 102.573717 -258.632458)
			(xy 102.607217 -258.591837) (xy 102.646525 -258.556806) (xy 102.69072 -258.528186) (xy 102.738765 -258.506647)
			(xy 102.789536 -258.492695) (xy 102.841841 -258.486657) (xy 102.894455 -258.488674) (xy 102.946145 -258.498698)
			(xy 102.995698 -258.516496) (xy 103.041954 -258.541649) (xy 103.083828 -258.573568) (xy 103.12034 -258.611506)
			(xy 103.150632 -258.654572) (xy 103.173995 -258.701757) (xy 103.189881 -258.751956) (xy 103.197918 -258.803992)
			(xy 103.198422 -258.830318) (xy 103.197918 -258.856644) (xy 103.189881 -258.90868) (xy 103.173995 -258.958879)
			(xy 103.150632 -259.006064) (xy 103.12034 -259.04913) (xy 103.083828 -259.087068) (xy 103.041954 -259.118987)
			(xy 102.995698 -259.14414) (xy 102.946145 -259.161938) (xy 102.894455 -259.171962) (xy 102.841841 -259.173979)
			(xy 102.789536 -259.167941) (xy 102.738765 -259.153989) (xy 102.69072 -259.13245) (xy 102.646525 -259.10383)
			(xy 102.607217 -259.068799) (xy 102.573717 -259.028178) (xy 102.546811 -258.982919) (xy 102.527128 -258.934084)
			(xy 102.515131 -258.882816) (xy 102.511101 -258.830318) (xy 101.298502 -258.830318) (xy 101.297998 -258.856644)
			(xy 101.289961 -258.90868) (xy 101.274075 -258.958879) (xy 101.250712 -259.006064) (xy 101.22042 -259.04913)
			(xy 101.183908 -259.087068) (xy 101.142034 -259.118987) (xy 101.095778 -259.14414) (xy 101.046225 -259.161938)
			(xy 100.994535 -259.171962) (xy 100.941921 -259.173979) (xy 100.889616 -259.167941) (xy 100.838845 -259.153989)
			(xy 100.7908 -259.13245) (xy 100.746605 -259.10383) (xy 100.707297 -259.068799) (xy 100.673797 -259.028178)
			(xy 100.646891 -258.982919) (xy 100.627208 -258.934084) (xy 100.615211 -258.882816) (xy 100.611181 -258.830318)
			(xy 99.398582 -258.830318) (xy 99.398078 -258.856644) (xy 99.390041 -258.90868) (xy 99.374155 -258.958879)
			(xy 99.350792 -259.006064) (xy 99.3205 -259.04913) (xy 99.283988 -259.087068) (xy 99.242114 -259.118987)
			(xy 99.195858 -259.14414) (xy 99.146305 -259.161938) (xy 99.094615 -259.171962) (xy 99.042001 -259.173979)
			(xy 98.989696 -259.167941) (xy 98.938925 -259.153989) (xy 98.89088 -259.13245) (xy 98.846685 -259.10383)
			(xy 98.807377 -259.068799) (xy 98.773877 -259.028178) (xy 98.746971 -258.982919) (xy 98.727288 -258.934084)
			(xy 98.715291 -258.882816) (xy 98.711261 -258.830318) (xy 89.690956 -258.830318) (xy 89.690956 -259.330444)
			(xy 106.061259 -259.330444) (xy 106.065289 -259.277946) (xy 106.077286 -259.226678) (xy 106.096969 -259.177843)
			(xy 106.123875 -259.132584) (xy 106.157375 -259.091963) (xy 106.196683 -259.056932) (xy 106.240878 -259.028312)
			(xy 106.288923 -259.006773) (xy 106.339694 -258.992821) (xy 106.391999 -258.986783) (xy 106.444613 -258.9888)
			(xy 106.496303 -258.998824) (xy 106.545856 -259.016622) (xy 106.592112 -259.041775) (xy 106.633986 -259.073694)
			(xy 106.670498 -259.111632) (xy 106.70079 -259.154698) (xy 106.724153 -259.201883) (xy 106.740039 -259.252082)
			(xy 106.748076 -259.304118) (xy 106.74858 -259.330444) (xy 106.748076 -259.35677) (xy 106.740039 -259.408806)
			(xy 106.724153 -259.459005) (xy 106.70079 -259.50619) (xy 106.670498 -259.549256) (xy 106.633986 -259.587194)
			(xy 106.592112 -259.619113) (xy 106.545856 -259.644266) (xy 106.496303 -259.662064) (xy 106.444613 -259.672088)
			(xy 106.391999 -259.674105) (xy 106.339694 -259.668067) (xy 106.288923 -259.654115) (xy 106.240878 -259.632576)
			(xy 106.196683 -259.603956) (xy 106.157375 -259.568925) (xy 106.123875 -259.528304) (xy 106.096969 -259.483045)
			(xy 106.077286 -259.43421) (xy 106.065289 -259.382942) (xy 106.061259 -259.330444) (xy 89.690956 -259.330444)
			(xy 89.690956 -259.73024) (xy 98.711261 -259.73024) (xy 98.715291 -259.677742) (xy 98.727288 -259.626474)
			(xy 98.746971 -259.577639) (xy 98.773877 -259.53238) (xy 98.807377 -259.491759) (xy 98.846685 -259.456728)
			(xy 98.89088 -259.428108) (xy 98.938925 -259.406569) (xy 98.989696 -259.392617) (xy 99.042001 -259.386579)
			(xy 99.094615 -259.388596) (xy 99.146305 -259.39862) (xy 99.195858 -259.416418) (xy 99.242114 -259.441571)
			(xy 99.283988 -259.47349) (xy 99.3205 -259.511428) (xy 99.350792 -259.554494) (xy 99.374155 -259.601679)
			(xy 99.390041 -259.651878) (xy 99.398078 -259.703914) (xy 99.398582 -259.73024) (xy 100.611181 -259.73024)
			(xy 100.615211 -259.677742) (xy 100.627208 -259.626474) (xy 100.646891 -259.577639) (xy 100.673797 -259.53238)
			(xy 100.707297 -259.491759) (xy 100.746605 -259.456728) (xy 100.7908 -259.428108) (xy 100.838845 -259.406569)
			(xy 100.889616 -259.392617) (xy 100.941921 -259.386579) (xy 100.994535 -259.388596) (xy 101.046225 -259.39862)
			(xy 101.095778 -259.416418) (xy 101.142034 -259.441571) (xy 101.183908 -259.47349) (xy 101.22042 -259.511428)
			(xy 101.250712 -259.554494) (xy 101.274075 -259.601679) (xy 101.289961 -259.651878) (xy 101.297998 -259.703914)
			(xy 101.298502 -259.73024) (xy 102.511101 -259.73024) (xy 102.515131 -259.677742) (xy 102.527128 -259.626474)
			(xy 102.546811 -259.577639) (xy 102.573717 -259.53238) (xy 102.607217 -259.491759) (xy 102.646525 -259.456728)
			(xy 102.69072 -259.428108) (xy 102.738765 -259.406569) (xy 102.789536 -259.392617) (xy 102.841841 -259.386579)
			(xy 102.894455 -259.388596) (xy 102.946145 -259.39862) (xy 102.995698 -259.416418) (xy 103.041954 -259.441571)
			(xy 103.083828 -259.47349) (xy 103.12034 -259.511428) (xy 103.150632 -259.554494) (xy 103.173995 -259.601679)
			(xy 103.189881 -259.651878) (xy 103.197918 -259.703914) (xy 103.198422 -259.73024) (xy 103.197918 -259.756566)
			(xy 103.189881 -259.808602) (xy 103.173995 -259.858801) (xy 103.150632 -259.905986) (xy 103.12034 -259.949052)
			(xy 103.083828 -259.98699) (xy 103.041954 -260.018909) (xy 102.995698 -260.044062) (xy 102.946145 -260.06186)
			(xy 102.894455 -260.071884) (xy 102.841841 -260.073901) (xy 102.789536 -260.067863) (xy 102.738765 -260.053911)
			(xy 102.69072 -260.032372) (xy 102.646525 -260.003752) (xy 102.607217 -259.968721) (xy 102.573717 -259.9281)
			(xy 102.546811 -259.882841) (xy 102.527128 -259.834006) (xy 102.515131 -259.782738) (xy 102.511101 -259.73024)
			(xy 101.298502 -259.73024) (xy 101.297998 -259.756566) (xy 101.289961 -259.808602) (xy 101.274075 -259.858801)
			(xy 101.250712 -259.905986) (xy 101.22042 -259.949052) (xy 101.183908 -259.98699) (xy 101.142034 -260.018909)
			(xy 101.095778 -260.044062) (xy 101.046225 -260.06186) (xy 100.994535 -260.071884) (xy 100.941921 -260.073901)
			(xy 100.889616 -260.067863) (xy 100.838845 -260.053911) (xy 100.7908 -260.032372) (xy 100.746605 -260.003752)
			(xy 100.707297 -259.968721) (xy 100.673797 -259.9281) (xy 100.646891 -259.882841) (xy 100.627208 -259.834006)
			(xy 100.615211 -259.782738) (xy 100.611181 -259.73024) (xy 99.398582 -259.73024) (xy 99.398078 -259.756566)
			(xy 99.390041 -259.808602) (xy 99.374155 -259.858801) (xy 99.350792 -259.905986) (xy 99.3205 -259.949052)
			(xy 99.283988 -259.98699) (xy 99.242114 -260.018909) (xy 99.195858 -260.044062) (xy 99.146305 -260.06186)
			(xy 99.094615 -260.071884) (xy 99.042001 -260.073901) (xy 98.989696 -260.067863) (xy 98.938925 -260.053911)
			(xy 98.89088 -260.032372) (xy 98.846685 -260.003752) (xy 98.807377 -259.968721) (xy 98.773877 -259.9281)
			(xy 98.746971 -259.882841) (xy 98.727288 -259.834006) (xy 98.715291 -259.782738) (xy 98.711261 -259.73024)
			(xy 89.690956 -259.73024) (xy 89.690956 -260.280404) (xy 106.061259 -260.280404) (xy 106.065289 -260.227906)
			(xy 106.077286 -260.176638) (xy 106.096969 -260.127803) (xy 106.123875 -260.082544) (xy 106.157375 -260.041923)
			(xy 106.196683 -260.006892) (xy 106.240878 -259.978272) (xy 106.288923 -259.956733) (xy 106.339694 -259.942781)
			(xy 106.391999 -259.936743) (xy 106.444613 -259.93876) (xy 106.496303 -259.948784) (xy 106.545856 -259.966582)
			(xy 106.592112 -259.991735) (xy 106.633986 -260.023654) (xy 106.670498 -260.061592) (xy 106.70079 -260.104658)
			(xy 106.724153 -260.151843) (xy 106.740039 -260.202042) (xy 106.748076 -260.254078) (xy 106.74858 -260.280404)
			(xy 106.748076 -260.30673) (xy 106.740039 -260.358766) (xy 106.724153 -260.408965) (xy 106.70079 -260.45615)
			(xy 106.670498 -260.499216) (xy 106.633986 -260.537154) (xy 106.592112 -260.569073) (xy 106.545856 -260.594226)
			(xy 106.496303 -260.612024) (xy 106.444613 -260.622048) (xy 106.391999 -260.624065) (xy 106.339694 -260.618027)
			(xy 106.288923 -260.604075) (xy 106.240878 -260.582536) (xy 106.196683 -260.553916) (xy 106.157375 -260.518885)
			(xy 106.123875 -260.478264) (xy 106.096969 -260.433005) (xy 106.077286 -260.38417) (xy 106.065289 -260.332902)
			(xy 106.061259 -260.280404) (xy 89.690956 -260.280404) (xy 89.690956 -260.771132) (xy 89.691377 -260.779941)
			(xy 89.697422 -260.796494) (xy 89.70869 -260.810044) (xy 89.716102 -260.81482) (xy 89.754456 -260.837426)
			(xy 89.79408 -260.86054) (xy 89.805431 -260.865721) (xy 89.830353 -260.865475) (xy 89.841578 -260.860032)
			(xy 89.842086 -260.859778) (xy 89.864973 -260.847563) (xy 89.913871 -260.830245) (xy 89.964993 -260.821445)
			(xy 89.99093 -260.820916) (xy 90.014919 -260.821389) (xy 90.062306 -260.828899) (xy 90.107934 -260.843729)
			(xy 90.150681 -260.865515) (xy 90.189493 -260.893719) (xy 90.223416 -260.927648) (xy 90.251614 -260.966465)
			(xy 90.273391 -261.009216) (xy 90.288214 -261.054847) (xy 90.295715 -261.102235) (xy 90.296238 -261.126224)
			(xy 90.62518 -261.126224) (xy 90.62914 -261.07717) (xy 90.640917 -261.029386) (xy 90.660208 -260.98411)
			(xy 90.686511 -260.942514) (xy 90.719146 -260.905677) (xy 90.757267 -260.874552) (xy 90.799888 -260.849945)
			(xy 90.845904 -260.832493) (xy 90.894123 -260.822649) (xy 90.943298 -260.820668) (xy 90.992153 -260.8266)
			(xy 91.039424 -260.840292) (xy 91.083886 -260.86139) (xy 91.124389 -260.889346) (xy 91.159882 -260.923438)
			(xy 91.189447 -260.962782) (xy 91.212318 -261.006359) (xy 91.227902 -261.05304) (xy 91.235797 -261.101617)
			(xy 91.236292 -261.126224) (xy 91.565234 -261.126224) (xy 91.569194 -261.07717) (xy 91.580971 -261.029386)
			(xy 91.600262 -260.98411) (xy 91.626565 -260.942514) (xy 91.6592 -260.905677) (xy 91.697321 -260.874552)
			(xy 91.739942 -260.849945) (xy 91.785958 -260.832493) (xy 91.834177 -260.822649) (xy 91.883352 -260.820668)
			(xy 91.932207 -260.8266) (xy 91.979478 -260.840292) (xy 92.02394 -260.86139) (xy 92.064443 -260.889346)
			(xy 92.099936 -260.923438) (xy 92.129501 -260.962782) (xy 92.152372 -261.006359) (xy 92.167956 -261.05304)
			(xy 92.175851 -261.101617) (xy 92.176346 -261.126224) (xy 92.505288 -261.126224) (xy 92.509248 -261.07717)
			(xy 92.521025 -261.029386) (xy 92.540316 -260.98411) (xy 92.566619 -260.942514) (xy 92.599254 -260.905677)
			(xy 92.637375 -260.874552) (xy 92.679996 -260.849945) (xy 92.726012 -260.832493) (xy 92.774231 -260.822649)
			(xy 92.823406 -260.820668) (xy 92.872261 -260.8266) (xy 92.919532 -260.840292) (xy 92.963994 -260.86139)
			(xy 93.004497 -260.889346) (xy 93.03999 -260.923438) (xy 93.069555 -260.962782) (xy 93.092426 -261.006359)
			(xy 93.10801 -261.05304) (xy 93.115905 -261.101617) (xy 93.1164 -261.126224) (xy 94.385142 -261.126224)
			(xy 94.389102 -261.07717) (xy 94.400879 -261.029386) (xy 94.42017 -260.98411) (xy 94.446473 -260.942514)
			(xy 94.479108 -260.905677) (xy 94.517229 -260.874552) (xy 94.55985 -260.849945) (xy 94.605866 -260.832493)
			(xy 94.654085 -260.822649) (xy 94.70326 -260.820668) (xy 94.752115 -260.8266) (xy 94.799386 -260.840292)
			(xy 94.843848 -260.86139) (xy 94.884351 -260.889346) (xy 94.919844 -260.923438) (xy 94.949409 -260.962782)
			(xy 94.97228 -261.006359) (xy 94.987864 -261.05304) (xy 94.995759 -261.101617) (xy 94.996254 -261.126224)
			(xy 95.325196 -261.126224) (xy 95.329156 -261.07717) (xy 95.340933 -261.029386) (xy 95.360224 -260.98411)
			(xy 95.386527 -260.942514) (xy 95.419162 -260.905677) (xy 95.457283 -260.874552) (xy 95.499904 -260.849945)
			(xy 95.54592 -260.832493) (xy 95.594139 -260.822649) (xy 95.643314 -260.820668) (xy 95.692169 -260.8266)
			(xy 95.73944 -260.840292) (xy 95.783902 -260.86139) (xy 95.824405 -260.889346) (xy 95.859898 -260.923438)
			(xy 95.889463 -260.962782) (xy 95.912334 -261.006359) (xy 95.927918 -261.05304) (xy 95.935813 -261.101617)
			(xy 95.936308 -261.126224) (xy 96.26525 -261.126224) (xy 96.26921 -261.07717) (xy 96.280987 -261.029386)
			(xy 96.300278 -260.98411) (xy 96.326581 -260.942514) (xy 96.359216 -260.905677) (xy 96.397337 -260.874552)
			(xy 96.439958 -260.849945) (xy 96.485974 -260.832493) (xy 96.534193 -260.822649) (xy 96.583368 -260.820668)
			(xy 96.632223 -260.8266) (xy 96.679494 -260.840292) (xy 96.723956 -260.86139) (xy 96.764459 -260.889346)
			(xy 96.799952 -260.923438) (xy 96.829517 -260.962782) (xy 96.852388 -261.006359) (xy 96.867972 -261.05304)
			(xy 96.875867 -261.101617) (xy 96.876362 -261.126224) (xy 98.145358 -261.126224) (xy 98.149318 -261.07717)
			(xy 98.161095 -261.029386) (xy 98.180386 -260.98411) (xy 98.206689 -260.942514) (xy 98.239324 -260.905677)
			(xy 98.277445 -260.874552) (xy 98.320066 -260.849945) (xy 98.366082 -260.832493) (xy 98.414301 -260.822649)
			(xy 98.463476 -260.820668) (xy 98.512331 -260.8266) (xy 98.559602 -260.840292) (xy 98.604064 -260.86139)
			(xy 98.644567 -260.889346) (xy 98.68006 -260.923438) (xy 98.709625 -260.962782) (xy 98.732496 -261.006359)
			(xy 98.74808 -261.05304) (xy 98.755975 -261.101617) (xy 98.75647 -261.126224) (xy 100.025212 -261.126224)
			(xy 100.029172 -261.07717) (xy 100.040949 -261.029386) (xy 100.06024 -260.98411) (xy 100.086543 -260.942514)
			(xy 100.119178 -260.905677) (xy 100.157299 -260.874552) (xy 100.19992 -260.849945) (xy 100.245936 -260.832493)
			(xy 100.294155 -260.822649) (xy 100.34333 -260.820668) (xy 100.392185 -260.8266) (xy 100.439456 -260.840292)
			(xy 100.483918 -260.86139) (xy 100.524421 -260.889346) (xy 100.559914 -260.923438) (xy 100.589479 -260.962782)
			(xy 100.61235 -261.006359) (xy 100.627934 -261.05304) (xy 100.635829 -261.101617) (xy 100.636324 -261.126224)
			(xy 100.965266 -261.126224) (xy 100.969226 -261.07717) (xy 100.981003 -261.029386) (xy 101.000294 -260.98411)
			(xy 101.026597 -260.942514) (xy 101.059232 -260.905677) (xy 101.097353 -260.874552) (xy 101.139974 -260.849945)
			(xy 101.18599 -260.832493) (xy 101.234209 -260.822649) (xy 101.283384 -260.820668) (xy 101.332239 -260.8266)
			(xy 101.37951 -260.840292) (xy 101.423972 -260.86139) (xy 101.464475 -260.889346) (xy 101.499968 -260.923438)
			(xy 101.529533 -260.962782) (xy 101.552404 -261.006359) (xy 101.567988 -261.05304) (xy 101.575883 -261.101617)
			(xy 101.576378 -261.126224) (xy 101.90532 -261.126224) (xy 101.90928 -261.07717) (xy 101.921057 -261.029386)
			(xy 101.940348 -260.98411) (xy 101.966651 -260.942514) (xy 101.999286 -260.905677) (xy 102.037407 -260.874552)
			(xy 102.080028 -260.849945) (xy 102.126044 -260.832493) (xy 102.174263 -260.822649) (xy 102.223438 -260.820668)
			(xy 102.272293 -260.8266) (xy 102.319564 -260.840292) (xy 102.364026 -260.86139) (xy 102.404529 -260.889346)
			(xy 102.440022 -260.923438) (xy 102.469587 -260.962782) (xy 102.492458 -261.006359) (xy 102.508042 -261.05304)
			(xy 102.515937 -261.101617) (xy 102.516432 -261.126224) (xy 102.516391 -261.128256) (xy 102.842072 -261.128256)
			(xy 102.846032 -261.079202) (xy 102.857809 -261.031418) (xy 102.8771 -260.986142) (xy 102.903403 -260.944546)
			(xy 102.936038 -260.907709) (xy 102.974159 -260.876584) (xy 103.01678 -260.851977) (xy 103.062796 -260.834525)
			(xy 103.111015 -260.824681) (xy 103.16019 -260.8227) (xy 103.209045 -260.828632) (xy 103.256316 -260.842324)
			(xy 103.300778 -260.863422) (xy 103.341281 -260.891378) (xy 103.376774 -260.92547) (xy 103.406339 -260.964814)
			(xy 103.42921 -261.008391) (xy 103.444794 -261.055072) (xy 103.452689 -261.103649) (xy 103.453184 -261.128256)
			(xy 103.782126 -261.128256) (xy 103.786086 -261.079202) (xy 103.797863 -261.031418) (xy 103.817154 -260.986142)
			(xy 103.843457 -260.944546) (xy 103.876092 -260.907709) (xy 103.914213 -260.876584) (xy 103.956834 -260.851977)
			(xy 104.00285 -260.834525) (xy 104.051069 -260.824681) (xy 104.100244 -260.8227) (xy 104.149099 -260.828632)
			(xy 104.19637 -260.842324) (xy 104.240832 -260.863422) (xy 104.281335 -260.891378) (xy 104.316828 -260.92547)
			(xy 104.346393 -260.964814) (xy 104.369264 -261.008391) (xy 104.384848 -261.055072) (xy 104.392743 -261.103649)
			(xy 104.393238 -261.128256) (xy 104.392743 -261.152863) (xy 104.384848 -261.20144) (xy 104.369264 -261.248121)
			(xy 104.346393 -261.291698) (xy 104.316828 -261.331042) (xy 104.281335 -261.365134) (xy 104.240832 -261.39309)
			(xy 104.19637 -261.414188) (xy 104.149099 -261.42788) (xy 104.100244 -261.433812) (xy 104.051069 -261.431831)
			(xy 104.00285 -261.421987) (xy 103.956834 -261.404535) (xy 103.914213 -261.379928) (xy 103.876092 -261.348803)
			(xy 103.843457 -261.311966) (xy 103.817154 -261.27037) (xy 103.797863 -261.225094) (xy 103.786086 -261.17731)
			(xy 103.782126 -261.128256) (xy 103.453184 -261.128256) (xy 103.452689 -261.152863) (xy 103.444794 -261.20144)
			(xy 103.42921 -261.248121) (xy 103.406339 -261.291698) (xy 103.376774 -261.331042) (xy 103.341281 -261.365134)
			(xy 103.300778 -261.39309) (xy 103.256316 -261.414188) (xy 103.209045 -261.42788) (xy 103.16019 -261.433812)
			(xy 103.111015 -261.431831) (xy 103.062796 -261.421987) (xy 103.01678 -261.404535) (xy 102.974159 -261.379928)
			(xy 102.936038 -261.348803) (xy 102.903403 -261.311966) (xy 102.8771 -261.27037) (xy 102.857809 -261.225094)
			(xy 102.846032 -261.17731) (xy 102.842072 -261.128256) (xy 102.516391 -261.128256) (xy 102.515937 -261.150831)
			(xy 102.508042 -261.199408) (xy 102.492458 -261.246089) (xy 102.469587 -261.289666) (xy 102.440022 -261.32901)
			(xy 102.404529 -261.363102) (xy 102.364026 -261.391058) (xy 102.319564 -261.412156) (xy 102.272293 -261.425848)
			(xy 102.223438 -261.43178) (xy 102.174263 -261.429799) (xy 102.126044 -261.419955) (xy 102.080028 -261.402503)
			(xy 102.037407 -261.377896) (xy 101.999286 -261.346771) (xy 101.966651 -261.309934) (xy 101.940348 -261.268338)
			(xy 101.921057 -261.223062) (xy 101.90928 -261.175278) (xy 101.90532 -261.126224) (xy 101.576378 -261.126224)
			(xy 101.575883 -261.150831) (xy 101.567988 -261.199408) (xy 101.552404 -261.246089) (xy 101.529533 -261.289666)
			(xy 101.499968 -261.32901) (xy 101.464475 -261.363102) (xy 101.423972 -261.391058) (xy 101.37951 -261.412156)
			(xy 101.332239 -261.425848) (xy 101.283384 -261.43178) (xy 101.234209 -261.429799) (xy 101.18599 -261.419955)
			(xy 101.139974 -261.402503) (xy 101.097353 -261.377896) (xy 101.059232 -261.346771) (xy 101.026597 -261.309934)
			(xy 101.000294 -261.268338) (xy 100.981003 -261.223062) (xy 100.969226 -261.175278) (xy 100.965266 -261.126224)
			(xy 100.636324 -261.126224) (xy 100.635829 -261.150831) (xy 100.627934 -261.199408) (xy 100.61235 -261.246089)
			(xy 100.589479 -261.289666) (xy 100.559914 -261.32901) (xy 100.524421 -261.363102) (xy 100.483918 -261.391058)
			(xy 100.439456 -261.412156) (xy 100.392185 -261.425848) (xy 100.34333 -261.43178) (xy 100.294155 -261.429799)
			(xy 100.245936 -261.419955) (xy 100.19992 -261.402503) (xy 100.157299 -261.377896) (xy 100.119178 -261.346771)
			(xy 100.086543 -261.309934) (xy 100.06024 -261.268338) (xy 100.040949 -261.223062) (xy 100.029172 -261.175278)
			(xy 100.025212 -261.126224) (xy 98.75647 -261.126224) (xy 98.755975 -261.150831) (xy 98.74808 -261.199408)
			(xy 98.732496 -261.246089) (xy 98.709625 -261.289666) (xy 98.68006 -261.32901) (xy 98.644567 -261.363102)
			(xy 98.604064 -261.391058) (xy 98.559602 -261.412156) (xy 98.512331 -261.425848) (xy 98.463476 -261.43178)
			(xy 98.414301 -261.429799) (xy 98.366082 -261.419955) (xy 98.320066 -261.402503) (xy 98.277445 -261.377896)
			(xy 98.239324 -261.346771) (xy 98.206689 -261.309934) (xy 98.180386 -261.268338) (xy 98.161095 -261.223062)
			(xy 98.149318 -261.175278) (xy 98.145358 -261.126224) (xy 96.876362 -261.126224) (xy 96.875867 -261.150831)
			(xy 96.867972 -261.199408) (xy 96.852388 -261.246089) (xy 96.829517 -261.289666) (xy 96.799952 -261.32901)
			(xy 96.764459 -261.363102) (xy 96.723956 -261.391058) (xy 96.679494 -261.412156) (xy 96.632223 -261.425848)
			(xy 96.583368 -261.43178) (xy 96.534193 -261.429799) (xy 96.485974 -261.419955) (xy 96.439958 -261.402503)
			(xy 96.397337 -261.377896) (xy 96.359216 -261.346771) (xy 96.326581 -261.309934) (xy 96.300278 -261.268338)
			(xy 96.280987 -261.223062) (xy 96.26921 -261.175278) (xy 96.26525 -261.126224) (xy 95.936308 -261.126224)
			(xy 95.935813 -261.150831) (xy 95.927918 -261.199408) (xy 95.912334 -261.246089) (xy 95.889463 -261.289666)
			(xy 95.859898 -261.32901) (xy 95.824405 -261.363102) (xy 95.783902 -261.391058) (xy 95.73944 -261.412156)
			(xy 95.692169 -261.425848) (xy 95.643314 -261.43178) (xy 95.594139 -261.429799) (xy 95.54592 -261.419955)
			(xy 95.499904 -261.402503) (xy 95.457283 -261.377896) (xy 95.419162 -261.346771) (xy 95.386527 -261.309934)
			(xy 95.360224 -261.268338) (xy 95.340933 -261.223062) (xy 95.329156 -261.175278) (xy 95.325196 -261.126224)
			(xy 94.996254 -261.126224) (xy 94.995759 -261.150831) (xy 94.987864 -261.199408) (xy 94.97228 -261.246089)
			(xy 94.949409 -261.289666) (xy 94.919844 -261.32901) (xy 94.884351 -261.363102) (xy 94.843848 -261.391058)
			(xy 94.799386 -261.412156) (xy 94.752115 -261.425848) (xy 94.70326 -261.43178) (xy 94.654085 -261.429799)
			(xy 94.605866 -261.419955) (xy 94.55985 -261.402503) (xy 94.517229 -261.377896) (xy 94.479108 -261.346771)
			(xy 94.446473 -261.309934) (xy 94.42017 -261.268338) (xy 94.400879 -261.223062) (xy 94.389102 -261.175278)
			(xy 94.385142 -261.126224) (xy 93.1164 -261.126224) (xy 93.115905 -261.150831) (xy 93.10801 -261.199408)
			(xy 93.092426 -261.246089) (xy 93.069555 -261.289666) (xy 93.03999 -261.32901) (xy 93.004497 -261.363102)
			(xy 92.963994 -261.391058) (xy 92.919532 -261.412156) (xy 92.872261 -261.425848) (xy 92.823406 -261.43178)
			(xy 92.774231 -261.429799) (xy 92.726012 -261.419955) (xy 92.679996 -261.402503) (xy 92.637375 -261.377896)
			(xy 92.599254 -261.346771) (xy 92.566619 -261.309934) (xy 92.540316 -261.268338) (xy 92.521025 -261.223062)
			(xy 92.509248 -261.175278) (xy 92.505288 -261.126224) (xy 92.176346 -261.126224) (xy 92.175851 -261.150831)
			(xy 92.167956 -261.199408) (xy 92.152372 -261.246089) (xy 92.129501 -261.289666) (xy 92.099936 -261.32901)
			(xy 92.064443 -261.363102) (xy 92.02394 -261.391058) (xy 91.979478 -261.412156) (xy 91.932207 -261.425848)
			(xy 91.883352 -261.43178) (xy 91.834177 -261.429799) (xy 91.785958 -261.419955) (xy 91.739942 -261.402503)
			(xy 91.697321 -261.377896) (xy 91.6592 -261.346771) (xy 91.626565 -261.309934) (xy 91.600262 -261.268338)
			(xy 91.580971 -261.223062) (xy 91.569194 -261.175278) (xy 91.565234 -261.126224) (xy 91.236292 -261.126224)
			(xy 91.235797 -261.150831) (xy 91.227902 -261.199408) (xy 91.212318 -261.246089) (xy 91.189447 -261.289666)
			(xy 91.159882 -261.32901) (xy 91.124389 -261.363102) (xy 91.083886 -261.391058) (xy 91.039424 -261.412156)
			(xy 90.992153 -261.425848) (xy 90.943298 -261.43178) (xy 90.894123 -261.429799) (xy 90.845904 -261.419955)
			(xy 90.799888 -261.402503) (xy 90.757267 -261.377896) (xy 90.719146 -261.346771) (xy 90.686511 -261.309934)
			(xy 90.660208 -261.268338) (xy 90.640917 -261.223062) (xy 90.62914 -261.175278) (xy 90.62518 -261.126224)
			(xy 90.296238 -261.126224) (xy 90.29575 -261.151044) (xy 90.287717 -261.200029) (xy 90.271865 -261.24707)
			(xy 90.248613 -261.290927) (xy 90.218572 -261.330446) (xy 90.182535 -261.364584) (xy 90.14145 -261.392444)
			(xy 90.0964 -261.41329) (xy 90.04857 -261.426575) (xy 90.02395 -261.429754) (xy 90.023696 -261.429754)
			(xy 90.01699 -261.430672) (xy 90.004371 -261.435557) (xy 89.998804 -261.439406) (xy 89.993724 -261.44347)
			(xy 89.985342 -261.453884) (xy 89.948004 -261.54253) (xy 89.945525 -261.548957) (xy 89.943712 -261.562606)
			(xy 89.944448 -261.569454) (xy 89.946226 -261.582662) (xy 89.954862 -261.593584) (xy 89.979731 -261.62628)
			(xy 90.020544 -261.697568) (xy 90.036142 -261.73557) (xy 90.036142 -261.735824) (xy 90.038775 -261.742009)
			(xy 90.046758 -261.752818) (xy 90.05189 -261.75716) (xy 90.063066 -261.765796) (xy 90.075512 -261.76732)
			(xy 90.165682 -261.77875) (xy 90.172562 -261.779352) (xy 90.186213 -261.777298) (xy 90.192606 -261.774686)
			(xy 90.198448 -261.772146) (xy 90.208862 -261.763764) (xy 90.21318 -261.757922) (xy 90.227644 -261.738621)
			(xy 90.261631 -261.704401) (xy 90.30057 -261.675943) (xy 90.343495 -261.653953) (xy 90.389341 -261.638976)
			(xy 90.436969 -261.631384) (xy 90.461084 -261.630922) (xy 90.48634 -261.631413) (xy 90.536164 -261.639725)
			(xy 90.58394 -261.656124) (xy 90.628365 -261.680164) (xy 90.668227 -261.711188) (xy 90.702439 -261.74835)
			(xy 90.730067 -261.790637) (xy 90.750358 -261.836894) (xy 90.762759 -261.88586) (xy 90.76693 -261.9362)
			(xy 90.766928 -261.93623) (xy 91.095334 -261.93623) (xy 91.099294 -261.887176) (xy 91.111071 -261.839392)
			(xy 91.130362 -261.794116) (xy 91.156665 -261.75252) (xy 91.1893 -261.715683) (xy 91.227421 -261.684558)
			(xy 91.270042 -261.659951) (xy 91.316058 -261.642499) (xy 91.364277 -261.632655) (xy 91.413452 -261.630674)
			(xy 91.462307 -261.636606) (xy 91.509578 -261.650298) (xy 91.55404 -261.671396) (xy 91.594543 -261.699352)
			(xy 91.630036 -261.733444) (xy 91.659601 -261.772788) (xy 91.682472 -261.816365) (xy 91.698056 -261.863046)
			(xy 91.705951 -261.911623) (xy 91.706446 -261.93623) (xy 92.024703 -261.93623) (xy 92.028798 -261.885502)
			(xy 92.040977 -261.836088) (xy 92.060925 -261.789268) (xy 92.088126 -261.746254) (xy 92.121874 -261.70816)
			(xy 92.161296 -261.675973) (xy 92.20537 -261.650527) (xy 92.252956 -261.63248) (xy 92.30282 -261.6223)
			(xy 92.353672 -261.620251) (xy 92.404193 -261.626385) (xy 92.453077 -261.640545) (xy 92.499056 -261.662362)
			(xy 92.54094 -261.691272) (xy 92.577644 -261.726527) (xy 92.608217 -261.767213) (xy 92.631868 -261.812276)
			(xy 92.647984 -261.86055) (xy 92.656148 -261.910784) (xy 92.65666 -261.93623) (xy 92.975188 -261.93623)
			(xy 92.979148 -261.887176) (xy 92.990925 -261.839392) (xy 93.010216 -261.794116) (xy 93.036519 -261.75252)
			(xy 93.069154 -261.715683) (xy 93.107275 -261.684558) (xy 93.149896 -261.659951) (xy 93.195912 -261.642499)
			(xy 93.244131 -261.632655) (xy 93.293306 -261.630674) (xy 93.342161 -261.636606) (xy 93.389432 -261.650298)
			(xy 93.433894 -261.671396) (xy 93.474397 -261.699352) (xy 93.50989 -261.733444) (xy 93.539455 -261.772788)
			(xy 93.562326 -261.816365) (xy 93.57791 -261.863046) (xy 93.585805 -261.911623) (xy 93.5863 -261.93623)
			(xy 93.915242 -261.93623) (xy 93.919202 -261.887176) (xy 93.930979 -261.839392) (xy 93.95027 -261.794116)
			(xy 93.976573 -261.75252) (xy 94.009208 -261.715683) (xy 94.047329 -261.684558) (xy 94.08995 -261.659951)
			(xy 94.135966 -261.642499) (xy 94.184185 -261.632655) (xy 94.23336 -261.630674) (xy 94.282215 -261.636606)
			(xy 94.329486 -261.650298) (xy 94.373948 -261.671396) (xy 94.414451 -261.699352) (xy 94.449944 -261.733444)
			(xy 94.479509 -261.772788) (xy 94.50238 -261.816365) (xy 94.517964 -261.863046) (xy 94.525859 -261.911623)
			(xy 94.526354 -261.93623) (xy 94.855296 -261.93623) (xy 94.859256 -261.887176) (xy 94.871033 -261.839392)
			(xy 94.890324 -261.794116) (xy 94.916627 -261.75252) (xy 94.949262 -261.715683) (xy 94.987383 -261.684558)
			(xy 95.030004 -261.659951) (xy 95.07602 -261.642499) (xy 95.124239 -261.632655) (xy 95.173414 -261.630674)
			(xy 95.222269 -261.636606) (xy 95.26954 -261.650298) (xy 95.314002 -261.671396) (xy 95.354505 -261.699352)
			(xy 95.389998 -261.733444) (xy 95.419563 -261.772788) (xy 95.442434 -261.816365) (xy 95.458018 -261.863046)
			(xy 95.465913 -261.911623) (xy 95.466408 -261.93623) (xy 95.784919 -261.93623) (xy 95.789014 -261.885502)
			(xy 95.801193 -261.836088) (xy 95.821141 -261.789268) (xy 95.848342 -261.746254) (xy 95.88209 -261.70816)
			(xy 95.921512 -261.675973) (xy 95.965586 -261.650527) (xy 96.013172 -261.63248) (xy 96.063036 -261.6223)
			(xy 96.113888 -261.620251) (xy 96.164409 -261.626385) (xy 96.213293 -261.640545) (xy 96.259272 -261.662362)
			(xy 96.301156 -261.691272) (xy 96.33786 -261.726527) (xy 96.368433 -261.767213) (xy 96.392084 -261.812276)
			(xy 96.4082 -261.86055) (xy 96.416364 -261.910784) (xy 96.416876 -261.93623) (xy 97.675204 -261.93623)
			(xy 97.679164 -261.887176) (xy 97.690941 -261.839392) (xy 97.710232 -261.794116) (xy 97.736535 -261.75252)
			(xy 97.76917 -261.715683) (xy 97.807291 -261.684558) (xy 97.849912 -261.659951) (xy 97.895928 -261.642499)
			(xy 97.944147 -261.632655) (xy 97.993322 -261.630674) (xy 98.042177 -261.636606) (xy 98.089448 -261.650298)
			(xy 98.13391 -261.671396) (xy 98.174413 -261.699352) (xy 98.209906 -261.733444) (xy 98.239471 -261.772788)
			(xy 98.262342 -261.816365) (xy 98.277926 -261.863046) (xy 98.285821 -261.911623) (xy 98.286316 -261.93623)
			(xy 99.555312 -261.93623) (xy 99.559272 -261.887176) (xy 99.571049 -261.839392) (xy 99.59034 -261.794116)
			(xy 99.616643 -261.75252) (xy 99.649278 -261.715683) (xy 99.687399 -261.684558) (xy 99.73002 -261.659951)
			(xy 99.776036 -261.642499) (xy 99.824255 -261.632655) (xy 99.87343 -261.630674) (xy 99.922285 -261.636606)
			(xy 99.969556 -261.650298) (xy 100.014018 -261.671396) (xy 100.054521 -261.699352) (xy 100.090014 -261.733444)
			(xy 100.119579 -261.772788) (xy 100.14245 -261.816365) (xy 100.158034 -261.863046) (xy 100.165929 -261.911623)
			(xy 100.166424 -261.93623) (xy 101.435166 -261.93623) (xy 101.439126 -261.887176) (xy 101.450903 -261.839392)
			(xy 101.470194 -261.794116) (xy 101.496497 -261.75252) (xy 101.529132 -261.715683) (xy 101.567253 -261.684558)
			(xy 101.609874 -261.659951) (xy 101.65589 -261.642499) (xy 101.704109 -261.632655) (xy 101.753284 -261.630674)
			(xy 101.802139 -261.636606) (xy 101.84941 -261.650298) (xy 101.893872 -261.671396) (xy 101.934375 -261.699352)
			(xy 101.969868 -261.733444) (xy 101.999433 -261.772788) (xy 102.022304 -261.816365) (xy 102.037888 -261.863046)
			(xy 102.045783 -261.911623) (xy 102.046278 -261.93623) (xy 102.37522 -261.93623) (xy 102.37918 -261.887176)
			(xy 102.390957 -261.839392) (xy 102.410248 -261.794116) (xy 102.436551 -261.75252) (xy 102.469186 -261.715683)
			(xy 102.507307 -261.684558) (xy 102.549928 -261.659951) (xy 102.595944 -261.642499) (xy 102.644163 -261.632655)
			(xy 102.693338 -261.630674) (xy 102.742193 -261.636606) (xy 102.789464 -261.650298) (xy 102.833926 -261.671396)
			(xy 102.874429 -261.699352) (xy 102.909922 -261.733444) (xy 102.939487 -261.772788) (xy 102.962358 -261.816365)
			(xy 102.977942 -261.863046) (xy 102.985837 -261.911623) (xy 102.986332 -261.93623) (xy 102.985837 -261.960837)
			(xy 102.977942 -262.009414) (xy 102.962358 -262.056095) (xy 102.939487 -262.099672) (xy 102.909922 -262.139016)
			(xy 102.874429 -262.173108) (xy 102.833926 -262.201064) (xy 102.789464 -262.222162) (xy 102.742193 -262.235854)
			(xy 102.693338 -262.241786) (xy 102.644163 -262.239805) (xy 102.595944 -262.229961) (xy 102.549928 -262.212509)
			(xy 102.507307 -262.187902) (xy 102.469186 -262.156777) (xy 102.436551 -262.11994) (xy 102.410248 -262.078344)
			(xy 102.390957 -262.033068) (xy 102.37918 -261.985284) (xy 102.37522 -261.93623) (xy 102.046278 -261.93623)
			(xy 102.045783 -261.960837) (xy 102.037888 -262.009414) (xy 102.022304 -262.056095) (xy 101.999433 -262.099672)
			(xy 101.969868 -262.139016) (xy 101.934375 -262.173108) (xy 101.893872 -262.201064) (xy 101.84941 -262.222162)
			(xy 101.802139 -262.235854) (xy 101.753284 -262.241786) (xy 101.704109 -262.239805) (xy 101.65589 -262.229961)
			(xy 101.609874 -262.212509) (xy 101.567253 -262.187902) (xy 101.529132 -262.156777) (xy 101.496497 -262.11994)
			(xy 101.470194 -262.078344) (xy 101.450903 -262.033068) (xy 101.439126 -261.985284) (xy 101.435166 -261.93623)
			(xy 100.166424 -261.93623) (xy 100.165929 -261.960837) (xy 100.158034 -262.009414) (xy 100.14245 -262.056095)
			(xy 100.119579 -262.099672) (xy 100.090014 -262.139016) (xy 100.054521 -262.173108) (xy 100.014018 -262.201064)
			(xy 99.969556 -262.222162) (xy 99.922285 -262.235854) (xy 99.87343 -262.241786) (xy 99.824255 -262.239805)
			(xy 99.776036 -262.229961) (xy 99.73002 -262.212509) (xy 99.687399 -262.187902) (xy 99.649278 -262.156777)
			(xy 99.616643 -262.11994) (xy 99.59034 -262.078344) (xy 99.571049 -262.033068) (xy 99.559272 -261.985284)
			(xy 99.555312 -261.93623) (xy 98.286316 -261.93623) (xy 98.285821 -261.960837) (xy 98.277926 -262.009414)
			(xy 98.262342 -262.056095) (xy 98.239471 -262.099672) (xy 98.209906 -262.139016) (xy 98.174413 -262.173108)
			(xy 98.13391 -262.201064) (xy 98.089448 -262.222162) (xy 98.042177 -262.235854) (xy 97.993322 -262.241786)
			(xy 97.944147 -262.239805) (xy 97.895928 -262.229961) (xy 97.849912 -262.212509) (xy 97.807291 -262.187902)
			(xy 97.76917 -262.156777) (xy 97.736535 -262.11994) (xy 97.710232 -262.078344) (xy 97.690941 -262.033068)
			(xy 97.679164 -261.985284) (xy 97.675204 -261.93623) (xy 96.416876 -261.93623) (xy 96.416364 -261.961676)
			(xy 96.4082 -262.01191) (xy 96.392084 -262.060184) (xy 96.368433 -262.105247) (xy 96.33786 -262.145933)
			(xy 96.301156 -262.181188) (xy 96.259272 -262.210098) (xy 96.213293 -262.231915) (xy 96.164409 -262.246075)
			(xy 96.113888 -262.252209) (xy 96.063036 -262.25016) (xy 96.013172 -262.23998) (xy 95.965586 -262.221933)
			(xy 95.921512 -262.196487) (xy 95.88209 -262.1643) (xy 95.848342 -262.126206) (xy 95.821141 -262.083192)
			(xy 95.801193 -262.036372) (xy 95.789014 -261.986958) (xy 95.784919 -261.93623) (xy 95.466408 -261.93623)
			(xy 95.465913 -261.960837) (xy 95.458018 -262.009414) (xy 95.442434 -262.056095) (xy 95.419563 -262.099672)
			(xy 95.389998 -262.139016) (xy 95.354505 -262.173108) (xy 95.314002 -262.201064) (xy 95.26954 -262.222162)
			(xy 95.222269 -262.235854) (xy 95.173414 -262.241786) (xy 95.124239 -262.239805) (xy 95.07602 -262.229961)
			(xy 95.030004 -262.212509) (xy 94.987383 -262.187902) (xy 94.949262 -262.156777) (xy 94.916627 -262.11994)
			(xy 94.890324 -262.078344) (xy 94.871033 -262.033068) (xy 94.859256 -261.985284) (xy 94.855296 -261.93623)
			(xy 94.526354 -261.93623) (xy 94.525859 -261.960837) (xy 94.517964 -262.009414) (xy 94.50238 -262.056095)
			(xy 94.479509 -262.099672) (xy 94.449944 -262.139016) (xy 94.414451 -262.173108) (xy 94.373948 -262.201064)
			(xy 94.329486 -262.222162) (xy 94.282215 -262.235854) (xy 94.23336 -262.241786) (xy 94.184185 -262.239805)
			(xy 94.135966 -262.229961) (xy 94.08995 -262.212509) (xy 94.047329 -262.187902) (xy 94.009208 -262.156777)
			(xy 93.976573 -262.11994) (xy 93.95027 -262.078344) (xy 93.930979 -262.033068) (xy 93.919202 -261.985284)
			(xy 93.915242 -261.93623) (xy 93.5863 -261.93623) (xy 93.585805 -261.960837) (xy 93.57791 -262.009414)
			(xy 93.562326 -262.056095) (xy 93.539455 -262.099672) (xy 93.50989 -262.139016) (xy 93.474397 -262.173108)
			(xy 93.433894 -262.201064) (xy 93.389432 -262.222162) (xy 93.342161 -262.235854) (xy 93.293306 -262.241786)
			(xy 93.244131 -262.239805) (xy 93.195912 -262.229961) (xy 93.149896 -262.212509) (xy 93.107275 -262.187902)
			(xy 93.069154 -262.156777) (xy 93.036519 -262.11994) (xy 93.010216 -262.078344) (xy 92.990925 -262.033068)
			(xy 92.979148 -261.985284) (xy 92.975188 -261.93623) (xy 92.65666 -261.93623) (xy 92.656148 -261.961676)
			(xy 92.647984 -262.01191) (xy 92.631868 -262.060184) (xy 92.608217 -262.105247) (xy 92.577644 -262.145933)
			(xy 92.54094 -262.181188) (xy 92.499056 -262.210098) (xy 92.453077 -262.231915) (xy 92.404193 -262.246075)
			(xy 92.353672 -262.252209) (xy 92.30282 -262.25016) (xy 92.252956 -262.23998) (xy 92.20537 -262.221933)
			(xy 92.161296 -262.196487) (xy 92.121874 -262.1643) (xy 92.088126 -262.126206) (xy 92.060925 -262.083192)
			(xy 92.040977 -262.036372) (xy 92.028798 -261.986958) (xy 92.024703 -261.93623) (xy 91.706446 -261.93623)
			(xy 91.705951 -261.960837) (xy 91.698056 -262.009414) (xy 91.682472 -262.056095) (xy 91.659601 -262.099672)
			(xy 91.630036 -262.139016) (xy 91.594543 -262.173108) (xy 91.55404 -262.201064) (xy 91.509578 -262.222162)
			(xy 91.462307 -262.235854) (xy 91.413452 -262.241786) (xy 91.364277 -262.239805) (xy 91.316058 -262.229961)
			(xy 91.270042 -262.212509) (xy 91.227421 -262.187902) (xy 91.1893 -262.156777) (xy 91.156665 -262.11994)
			(xy 91.130362 -262.078344) (xy 91.111071 -262.033068) (xy 91.099294 -261.985284) (xy 91.095334 -261.93623)
			(xy 90.766928 -261.93623) (xy 90.762759 -261.98654) (xy 90.750358 -262.035506) (xy 90.730067 -262.081763)
			(xy 90.702439 -262.12405) (xy 90.668227 -262.161212) (xy 90.628365 -262.192236) (xy 90.58394 -262.216276)
			(xy 90.536164 -262.232675) (xy 90.48634 -262.240987) (xy 90.461084 -262.241538) (xy 90.448321 -262.2414)
			(xy 90.422887 -262.23924) (xy 90.410284 -262.23722) (xy 90.410284 -262.237474) (xy 90.386831 -262.233045)
			(xy 90.341578 -262.217882) (xy 90.299227 -262.195878) (xy 90.260806 -262.167566) (xy 90.227244 -262.133634)
			(xy 90.212926 -262.114538) (xy 90.208862 -262.108696) (xy 90.198194 -262.10006) (xy 90.192352 -262.09752)
			(xy 90.186068 -262.095002) (xy 90.172675 -262.093072) (xy 90.165936 -262.09371) (xy 90.075512 -262.10514)
			(xy 90.063066 -262.106664) (xy 90.05189 -262.1153) (xy 90.046764 -262.119646) (xy 90.038791 -262.130459)
			(xy 90.036142 -262.136636) (xy 90.036142 -262.13689) (xy 90.028246 -262.15667) (xy 90.009812 -262.195068)
			(xy 89.999312 -262.213598) (xy 89.9541 -262.291576) (xy 89.94837 -262.302816) (xy 89.94757 -262.328001)
			(xy 89.952576 -262.339582) (xy 89.981024 -262.396986) (xy 89.989914 -262.415274) (xy 89.992912 -262.420912)
			(xy 90.001265 -262.430563) (xy 90.006424 -262.434324) (xy 90.01633 -262.441436) (xy 90.02649 -262.44296)
			(xy 90.029284 -262.443214) (xy 90.053547 -262.4468) (xy 90.100581 -262.460697) (xy 90.144793 -262.481925)
			(xy 90.185047 -262.509942) (xy 90.220311 -262.544026) (xy 90.24968 -262.583305) (xy 90.272399 -262.626769)
			(xy 90.287886 -262.673304) (xy 90.295744 -262.721714) (xy 90.296238 -262.746236) (xy 90.614749 -262.746236)
			(xy 90.618844 -262.695508) (xy 90.631023 -262.646094) (xy 90.650971 -262.599274) (xy 90.678172 -262.55626)
			(xy 90.71192 -262.518166) (xy 90.751342 -262.485979) (xy 90.795416 -262.460533) (xy 90.843002 -262.442486)
			(xy 90.892866 -262.432306) (xy 90.943718 -262.430257) (xy 90.994239 -262.436391) (xy 91.043123 -262.450551)
			(xy 91.089102 -262.472368) (xy 91.130986 -262.501278) (xy 91.16769 -262.536533) (xy 91.198263 -262.577219)
			(xy 91.221914 -262.622282) (xy 91.23803 -262.670556) (xy 91.246194 -262.72079) (xy 91.246706 -262.746236)
			(xy 91.565234 -262.746236) (xy 91.569194 -262.697182) (xy 91.580971 -262.649398) (xy 91.600262 -262.604122)
			(xy 91.626565 -262.562526) (xy 91.6592 -262.525689) (xy 91.697321 -262.494564) (xy 91.739942 -262.469957)
			(xy 91.785958 -262.452505) (xy 91.834177 -262.442661) (xy 91.883352 -262.44068) (xy 91.932207 -262.446612)
			(xy 91.979478 -262.460304) (xy 92.02394 -262.481402) (xy 92.064443 -262.509358) (xy 92.099936 -262.54345)
			(xy 92.129501 -262.582794) (xy 92.152372 -262.626371) (xy 92.167956 -262.673052) (xy 92.175851 -262.721629)
			(xy 92.176346 -262.746236) (xy 92.494857 -262.746236) (xy 92.498952 -262.695508) (xy 92.511131 -262.646094)
			(xy 92.531079 -262.599274) (xy 92.55828 -262.55626) (xy 92.592028 -262.518166) (xy 92.63145 -262.485979)
			(xy 92.675524 -262.460533) (xy 92.72311 -262.442486) (xy 92.772974 -262.432306) (xy 92.823826 -262.430257)
			(xy 92.874347 -262.436391) (xy 92.923231 -262.450551) (xy 92.96921 -262.472368) (xy 93.011094 -262.501278)
			(xy 93.047798 -262.536533) (xy 93.078371 -262.577219) (xy 93.102022 -262.622282) (xy 93.118138 -262.670556)
			(xy 93.126302 -262.72079) (xy 93.126814 -262.746236) (xy 93.445342 -262.746236) (xy 93.449302 -262.697182)
			(xy 93.461079 -262.649398) (xy 93.48037 -262.604122) (xy 93.506673 -262.562526) (xy 93.539308 -262.525689)
			(xy 93.577429 -262.494564) (xy 93.62005 -262.469957) (xy 93.666066 -262.452505) (xy 93.714285 -262.442661)
			(xy 93.76346 -262.44068) (xy 93.812315 -262.446612) (xy 93.859586 -262.460304) (xy 93.904048 -262.481402)
			(xy 93.944551 -262.509358) (xy 93.980044 -262.54345) (xy 94.009609 -262.582794) (xy 94.03248 -262.626371)
			(xy 94.048064 -262.673052) (xy 94.055959 -262.721629) (xy 94.056454 -262.746236) (xy 94.374711 -262.746236)
			(xy 94.378806 -262.695508) (xy 94.390985 -262.646094) (xy 94.410933 -262.599274) (xy 94.438134 -262.55626)
			(xy 94.471882 -262.518166) (xy 94.511304 -262.485979) (xy 94.555378 -262.460533) (xy 94.602964 -262.442486)
			(xy 94.652828 -262.432306) (xy 94.70368 -262.430257) (xy 94.754201 -262.436391) (xy 94.803085 -262.450551)
			(xy 94.849064 -262.472368) (xy 94.890948 -262.501278) (xy 94.927652 -262.536533) (xy 94.958225 -262.577219)
			(xy 94.981876 -262.622282) (xy 94.997992 -262.670556) (xy 95.006156 -262.72079) (xy 95.006668 -262.746236)
			(xy 95.314765 -262.746236) (xy 95.31886 -262.695508) (xy 95.331039 -262.646094) (xy 95.350987 -262.599274)
			(xy 95.378188 -262.55626) (xy 95.411936 -262.518166) (xy 95.451358 -262.485979) (xy 95.495432 -262.460533)
			(xy 95.543018 -262.442486) (xy 95.592882 -262.432306) (xy 95.643734 -262.430257) (xy 95.694255 -262.436391)
			(xy 95.743139 -262.450551) (xy 95.789118 -262.472368) (xy 95.831002 -262.501278) (xy 95.867706 -262.536533)
			(xy 95.898279 -262.577219) (xy 95.92193 -262.622282) (xy 95.938046 -262.670556) (xy 95.94621 -262.72079)
			(xy 95.946722 -262.746236) (xy 96.26525 -262.746236) (xy 96.26921 -262.697182) (xy 96.280987 -262.649398)
			(xy 96.300278 -262.604122) (xy 96.326581 -262.562526) (xy 96.359216 -262.525689) (xy 96.397337 -262.494564)
			(xy 96.439958 -262.469957) (xy 96.485974 -262.452505) (xy 96.534193 -262.442661) (xy 96.583368 -262.44068)
			(xy 96.632223 -262.446612) (xy 96.679494 -262.460304) (xy 96.723956 -262.481402) (xy 96.764459 -262.509358)
			(xy 96.799952 -262.54345) (xy 96.829517 -262.582794) (xy 96.852388 -262.626371) (xy 96.867972 -262.673052)
			(xy 96.875867 -262.721629) (xy 96.876362 -262.746236) (xy 98.145358 -262.746236) (xy 98.149318 -262.697182)
			(xy 98.161095 -262.649398) (xy 98.180386 -262.604122) (xy 98.206689 -262.562526) (xy 98.239324 -262.525689)
			(xy 98.277445 -262.494564) (xy 98.320066 -262.469957) (xy 98.366082 -262.452505) (xy 98.414301 -262.442661)
			(xy 98.463476 -262.44068) (xy 98.512331 -262.446612) (xy 98.559602 -262.460304) (xy 98.604064 -262.481402)
			(xy 98.644567 -262.509358) (xy 98.68006 -262.54345) (xy 98.709625 -262.582794) (xy 98.732496 -262.626371)
			(xy 98.74808 -262.673052) (xy 98.755975 -262.721629) (xy 98.75647 -262.746236) (xy 100.025212 -262.746236)
			(xy 100.029172 -262.697182) (xy 100.040949 -262.649398) (xy 100.06024 -262.604122) (xy 100.086543 -262.562526)
			(xy 100.119178 -262.525689) (xy 100.157299 -262.494564) (xy 100.19992 -262.469957) (xy 100.245936 -262.452505)
			(xy 100.294155 -262.442661) (xy 100.34333 -262.44068) (xy 100.392185 -262.446612) (xy 100.439456 -262.460304)
			(xy 100.483918 -262.481402) (xy 100.524421 -262.509358) (xy 100.559914 -262.54345) (xy 100.589479 -262.582794)
			(xy 100.61235 -262.626371) (xy 100.627934 -262.673052) (xy 100.635829 -262.721629) (xy 100.636324 -262.746236)
			(xy 100.965266 -262.746236) (xy 100.969226 -262.697182) (xy 100.981003 -262.649398) (xy 101.000294 -262.604122)
			(xy 101.026597 -262.562526) (xy 101.059232 -262.525689) (xy 101.097353 -262.494564) (xy 101.139974 -262.469957)
			(xy 101.18599 -262.452505) (xy 101.234209 -262.442661) (xy 101.283384 -262.44068) (xy 101.332239 -262.446612)
			(xy 101.37951 -262.460304) (xy 101.423972 -262.481402) (xy 101.464475 -262.509358) (xy 101.499968 -262.54345)
			(xy 101.529533 -262.582794) (xy 101.552404 -262.626371) (xy 101.567988 -262.673052) (xy 101.575883 -262.721629)
			(xy 101.576378 -262.746236) (xy 101.90532 -262.746236) (xy 101.90928 -262.697182) (xy 101.921057 -262.649398)
			(xy 101.940348 -262.604122) (xy 101.966651 -262.562526) (xy 101.999286 -262.525689) (xy 102.037407 -262.494564)
			(xy 102.080028 -262.469957) (xy 102.126044 -262.452505) (xy 102.174263 -262.442661) (xy 102.223438 -262.44068)
			(xy 102.272293 -262.446612) (xy 102.319564 -262.460304) (xy 102.364026 -262.481402) (xy 102.404529 -262.509358)
			(xy 102.440022 -262.54345) (xy 102.469587 -262.582794) (xy 102.492458 -262.626371) (xy 102.508042 -262.673052)
			(xy 102.515937 -262.721629) (xy 102.516432 -262.746236) (xy 102.515937 -262.770843) (xy 102.508042 -262.81942)
			(xy 102.492458 -262.866101) (xy 102.469587 -262.909678) (xy 102.440022 -262.949022) (xy 102.404529 -262.983114)
			(xy 102.364026 -263.01107) (xy 102.319564 -263.032168) (xy 102.272293 -263.04586) (xy 102.223438 -263.051792)
			(xy 102.174263 -263.049811) (xy 102.126044 -263.039967) (xy 102.080028 -263.022515) (xy 102.037407 -262.997908)
			(xy 101.999286 -262.966783) (xy 101.966651 -262.929946) (xy 101.940348 -262.88835) (xy 101.921057 -262.843074)
			(xy 101.90928 -262.79529) (xy 101.90532 -262.746236) (xy 101.576378 -262.746236) (xy 101.575883 -262.770843)
			(xy 101.567988 -262.81942) (xy 101.552404 -262.866101) (xy 101.529533 -262.909678) (xy 101.499968 -262.949022)
			(xy 101.464475 -262.983114) (xy 101.423972 -263.01107) (xy 101.37951 -263.032168) (xy 101.332239 -263.04586)
			(xy 101.283384 -263.051792) (xy 101.234209 -263.049811) (xy 101.18599 -263.039967) (xy 101.139974 -263.022515)
			(xy 101.097353 -262.997908) (xy 101.059232 -262.966783) (xy 101.026597 -262.929946) (xy 101.000294 -262.88835)
			(xy 100.981003 -262.843074) (xy 100.969226 -262.79529) (xy 100.965266 -262.746236) (xy 100.636324 -262.746236)
			(xy 100.635829 -262.770843) (xy 100.627934 -262.81942) (xy 100.61235 -262.866101) (xy 100.589479 -262.909678)
			(xy 100.559914 -262.949022) (xy 100.524421 -262.983114) (xy 100.483918 -263.01107) (xy 100.439456 -263.032168)
			(xy 100.392185 -263.04586) (xy 100.34333 -263.051792) (xy 100.294155 -263.049811) (xy 100.245936 -263.039967)
			(xy 100.19992 -263.022515) (xy 100.157299 -262.997908) (xy 100.119178 -262.966783) (xy 100.086543 -262.929946)
			(xy 100.06024 -262.88835) (xy 100.040949 -262.843074) (xy 100.029172 -262.79529) (xy 100.025212 -262.746236)
			(xy 98.75647 -262.746236) (xy 98.755975 -262.770843) (xy 98.74808 -262.81942) (xy 98.732496 -262.866101)
			(xy 98.709625 -262.909678) (xy 98.68006 -262.949022) (xy 98.644567 -262.983114) (xy 98.604064 -263.01107)
			(xy 98.559602 -263.032168) (xy 98.512331 -263.04586) (xy 98.463476 -263.051792) (xy 98.414301 -263.049811)
			(xy 98.366082 -263.039967) (xy 98.320066 -263.022515) (xy 98.277445 -262.997908) (xy 98.239324 -262.966783)
			(xy 98.206689 -262.929946) (xy 98.180386 -262.88835) (xy 98.161095 -262.843074) (xy 98.149318 -262.79529)
			(xy 98.145358 -262.746236) (xy 96.876362 -262.746236) (xy 96.875867 -262.770843) (xy 96.867972 -262.81942)
			(xy 96.852388 -262.866101) (xy 96.829517 -262.909678) (xy 96.799952 -262.949022) (xy 96.764459 -262.983114)
			(xy 96.723956 -263.01107) (xy 96.679494 -263.032168) (xy 96.632223 -263.04586) (xy 96.583368 -263.051792)
			(xy 96.534193 -263.049811) (xy 96.485974 -263.039967) (xy 96.439958 -263.022515) (xy 96.397337 -262.997908)
			(xy 96.359216 -262.966783) (xy 96.326581 -262.929946) (xy 96.300278 -262.88835) (xy 96.280987 -262.843074)
			(xy 96.26921 -262.79529) (xy 96.26525 -262.746236) (xy 95.946722 -262.746236) (xy 95.94621 -262.771682)
			(xy 95.938046 -262.821916) (xy 95.92193 -262.87019) (xy 95.898279 -262.915253) (xy 95.867706 -262.955939)
			(xy 95.831002 -262.991194) (xy 95.789118 -263.020104) (xy 95.743139 -263.041921) (xy 95.694255 -263.056081)
			(xy 95.643734 -263.062215) (xy 95.592882 -263.060166) (xy 95.543018 -263.049986) (xy 95.495432 -263.031939)
			(xy 95.451358 -263.006493) (xy 95.411936 -262.974306) (xy 95.378188 -262.936212) (xy 95.350987 -262.893198)
			(xy 95.331039 -262.846378) (xy 95.31886 -262.796964) (xy 95.314765 -262.746236) (xy 95.006668 -262.746236)
			(xy 95.006156 -262.771682) (xy 94.997992 -262.821916) (xy 94.981876 -262.87019) (xy 94.958225 -262.915253)
			(xy 94.927652 -262.955939) (xy 94.890948 -262.991194) (xy 94.849064 -263.020104) (xy 94.803085 -263.041921)
			(xy 94.754201 -263.056081) (xy 94.70368 -263.062215) (xy 94.652828 -263.060166) (xy 94.602964 -263.049986)
			(xy 94.555378 -263.031939) (xy 94.511304 -263.006493) (xy 94.471882 -262.974306) (xy 94.438134 -262.936212)
			(xy 94.410933 -262.893198) (xy 94.390985 -262.846378) (xy 94.378806 -262.796964) (xy 94.374711 -262.746236)
			(xy 94.056454 -262.746236) (xy 94.055959 -262.770843) (xy 94.048064 -262.81942) (xy 94.03248 -262.866101)
			(xy 94.009609 -262.909678) (xy 93.980044 -262.949022) (xy 93.944551 -262.983114) (xy 93.904048 -263.01107)
			(xy 93.859586 -263.032168) (xy 93.812315 -263.04586) (xy 93.76346 -263.051792) (xy 93.714285 -263.049811)
			(xy 93.666066 -263.039967) (xy 93.62005 -263.022515) (xy 93.577429 -262.997908) (xy 93.539308 -262.966783)
			(xy 93.506673 -262.929946) (xy 93.48037 -262.88835) (xy 93.461079 -262.843074) (xy 93.449302 -262.79529)
			(xy 93.445342 -262.746236) (xy 93.126814 -262.746236) (xy 93.126302 -262.771682) (xy 93.118138 -262.821916)
			(xy 93.102022 -262.87019) (xy 93.078371 -262.915253) (xy 93.047798 -262.955939) (xy 93.011094 -262.991194)
			(xy 92.96921 -263.020104) (xy 92.923231 -263.041921) (xy 92.874347 -263.056081) (xy 92.823826 -263.062215)
			(xy 92.772974 -263.060166) (xy 92.72311 -263.049986) (xy 92.675524 -263.031939) (xy 92.63145 -263.006493)
			(xy 92.592028 -262.974306) (xy 92.55828 -262.936212) (xy 92.531079 -262.893198) (xy 92.511131 -262.846378)
			(xy 92.498952 -262.796964) (xy 92.494857 -262.746236) (xy 92.176346 -262.746236) (xy 92.175851 -262.770843)
			(xy 92.167956 -262.81942) (xy 92.152372 -262.866101) (xy 92.129501 -262.909678) (xy 92.099936 -262.949022)
			(xy 92.064443 -262.983114) (xy 92.02394 -263.01107) (xy 91.979478 -263.032168) (xy 91.932207 -263.04586)
			(xy 91.883352 -263.051792) (xy 91.834177 -263.049811) (xy 91.785958 -263.039967) (xy 91.739942 -263.022515)
			(xy 91.697321 -262.997908) (xy 91.6592 -262.966783) (xy 91.626565 -262.929946) (xy 91.600262 -262.88835)
			(xy 91.580971 -262.843074) (xy 91.569194 -262.79529) (xy 91.565234 -262.746236) (xy 91.246706 -262.746236)
			(xy 91.246194 -262.771682) (xy 91.23803 -262.821916) (xy 91.221914 -262.87019) (xy 91.198263 -262.915253)
			(xy 91.16769 -262.955939) (xy 91.130986 -262.991194) (xy 91.089102 -263.020104) (xy 91.043123 -263.041921)
			(xy 90.994239 -263.056081) (xy 90.943718 -263.062215) (xy 90.892866 -263.060166) (xy 90.843002 -263.049986)
			(xy 90.795416 -263.031939) (xy 90.751342 -263.006493) (xy 90.71192 -262.974306) (xy 90.678172 -262.936212)
			(xy 90.650971 -262.893198) (xy 90.631023 -262.846378) (xy 90.618844 -262.796964) (xy 90.614749 -262.746236)
			(xy 90.296238 -262.746236) (xy 90.295749 -262.771055) (xy 90.287714 -262.820039) (xy 90.271861 -262.867079)
			(xy 90.248608 -262.910934) (xy 90.218568 -262.950451) (xy 90.182531 -262.984588) (xy 90.141446 -263.012446)
			(xy 90.096397 -263.033291) (xy 90.048569 -263.046575) (xy 90.02395 -263.049766) (xy 90.023696 -263.049766)
			(xy 90.01699 -263.050684) (xy 90.004372 -263.05557) (xy 89.998804 -263.059418) (xy 89.993724 -263.063482)
			(xy 89.985342 -263.073896) (xy 89.948004 -263.162542) (xy 89.945527 -263.168969) (xy 89.943717 -263.182618)
			(xy 89.944448 -263.189466) (xy 89.946226 -263.202674) (xy 89.954862 -263.213596) (xy 89.979731 -263.246292)
			(xy 90.020542 -263.317581) (xy 90.036142 -263.355582) (xy 90.036142 -263.355836) (xy 90.038776 -263.36202)
			(xy 90.046761 -263.372827) (xy 90.05189 -263.377172) (xy 90.063066 -263.385808) (xy 90.075512 -263.387332)
			(xy 90.165682 -263.398762) (xy 90.172562 -263.399364) (xy 90.186213 -263.39731) (xy 90.192606 -263.394698)
			(xy 90.198448 -263.392158) (xy 90.208862 -263.383776) (xy 90.21318 -263.377934) (xy 90.227647 -263.358638)
			(xy 90.261638 -263.324427) (xy 90.300579 -263.295977) (xy 90.343503 -263.273993) (xy 90.389346 -263.259021)
			(xy 90.436971 -263.251432) (xy 90.461084 -263.250934) (xy 90.486339 -263.251425) (xy 90.536161 -263.259737)
			(xy 90.583935 -263.276135) (xy 90.628358 -263.300174) (xy 90.668219 -263.331197) (xy 90.702429 -263.368357)
			(xy 90.730056 -263.410642) (xy 90.750347 -263.456898) (xy 90.762747 -263.505862) (xy 90.766918 -263.5562)
			(xy 90.766915 -263.556242) (xy 91.084903 -263.556242) (xy 91.088998 -263.505514) (xy 91.101177 -263.4561)
			(xy 91.121125 -263.40928) (xy 91.148326 -263.366266) (xy 91.182074 -263.328172) (xy 91.221496 -263.295985)
			(xy 91.26557 -263.270539) (xy 91.313156 -263.252492) (xy 91.36302 -263.242312) (xy 91.413872 -263.240263)
			(xy 91.464393 -263.246397) (xy 91.513277 -263.260557) (xy 91.559256 -263.282374) (xy 91.60114 -263.311284)
			(xy 91.637844 -263.346539) (xy 91.668417 -263.387225) (xy 91.692068 -263.432288) (xy 91.708184 -263.480562)
			(xy 91.716348 -263.530796) (xy 91.71686 -263.556242) (xy 92.024703 -263.556242) (xy 92.028798 -263.505514)
			(xy 92.040977 -263.4561) (xy 92.060925 -263.40928) (xy 92.088126 -263.366266) (xy 92.121874 -263.328172)
			(xy 92.161296 -263.295985) (xy 92.20537 -263.270539) (xy 92.252956 -263.252492) (xy 92.30282 -263.242312)
			(xy 92.353672 -263.240263) (xy 92.404193 -263.246397) (xy 92.453077 -263.260557) (xy 92.499056 -263.282374)
			(xy 92.54094 -263.311284) (xy 92.577644 -263.346539) (xy 92.608217 -263.387225) (xy 92.631868 -263.432288)
			(xy 92.647984 -263.480562) (xy 92.656148 -263.530796) (xy 92.65666 -263.556242) (xy 93.904811 -263.556242)
			(xy 93.908906 -263.505514) (xy 93.921085 -263.4561) (xy 93.941033 -263.40928) (xy 93.968234 -263.366266)
			(xy 94.001982 -263.328172) (xy 94.041404 -263.295985) (xy 94.085478 -263.270539) (xy 94.133064 -263.252492)
			(xy 94.182928 -263.242312) (xy 94.23378 -263.240263) (xy 94.284301 -263.246397) (xy 94.333185 -263.260557)
			(xy 94.379164 -263.282374) (xy 94.421048 -263.311284) (xy 94.457752 -263.346539) (xy 94.488325 -263.387225)
			(xy 94.511976 -263.432288) (xy 94.528092 -263.480562) (xy 94.536256 -263.530796) (xy 94.536768 -263.556242)
			(xy 94.855296 -263.556242) (xy 94.859256 -263.507188) (xy 94.871033 -263.459404) (xy 94.890324 -263.414128)
			(xy 94.916627 -263.372532) (xy 94.949262 -263.335695) (xy 94.987383 -263.30457) (xy 95.030004 -263.279963)
			(xy 95.07602 -263.262511) (xy 95.124239 -263.252667) (xy 95.173414 -263.250686) (xy 95.222269 -263.256618)
			(xy 95.26954 -263.27031) (xy 95.314002 -263.291408) (xy 95.354505 -263.319364) (xy 95.389998 -263.353456)
			(xy 95.419563 -263.3928) (xy 95.442434 -263.436377) (xy 95.458018 -263.483058) (xy 95.465913 -263.531635)
			(xy 95.466408 -263.556242) (xy 95.784919 -263.556242) (xy 95.789014 -263.505514) (xy 95.801193 -263.4561)
			(xy 95.821141 -263.40928) (xy 95.848342 -263.366266) (xy 95.88209 -263.328172) (xy 95.921512 -263.295985)
			(xy 95.965586 -263.270539) (xy 96.013172 -263.252492) (xy 96.063036 -263.242312) (xy 96.113888 -263.240263)
			(xy 96.164409 -263.246397) (xy 96.213293 -263.260557) (xy 96.259272 -263.282374) (xy 96.301156 -263.311284)
			(xy 96.33786 -263.346539) (xy 96.368433 -263.387225) (xy 96.392084 -263.432288) (xy 96.4082 -263.480562)
			(xy 96.416364 -263.530796) (xy 96.416876 -263.556242) (xy 97.675204 -263.556242) (xy 97.679164 -263.507188)
			(xy 97.690941 -263.459404) (xy 97.710232 -263.414128) (xy 97.736535 -263.372532) (xy 97.76917 -263.335695)
			(xy 97.807291 -263.30457) (xy 97.849912 -263.279963) (xy 97.895928 -263.262511) (xy 97.944147 -263.252667)
			(xy 97.993322 -263.250686) (xy 98.042177 -263.256618) (xy 98.089448 -263.27031) (xy 98.13391 -263.291408)
			(xy 98.174413 -263.319364) (xy 98.209906 -263.353456) (xy 98.239471 -263.3928) (xy 98.262342 -263.436377)
			(xy 98.277926 -263.483058) (xy 98.285821 -263.531635) (xy 98.286316 -263.556242) (xy 99.555312 -263.556242)
			(xy 99.559272 -263.507188) (xy 99.571049 -263.459404) (xy 99.59034 -263.414128) (xy 99.616643 -263.372532)
			(xy 99.649278 -263.335695) (xy 99.687399 -263.30457) (xy 99.73002 -263.279963) (xy 99.776036 -263.262511)
			(xy 99.824255 -263.252667) (xy 99.87343 -263.250686) (xy 99.922285 -263.256618) (xy 99.969556 -263.27031)
			(xy 100.014018 -263.291408) (xy 100.054521 -263.319364) (xy 100.090014 -263.353456) (xy 100.119579 -263.3928)
			(xy 100.14245 -263.436377) (xy 100.158034 -263.483058) (xy 100.165929 -263.531635) (xy 100.166424 -263.556242)
			(xy 101.435166 -263.556242) (xy 101.439126 -263.507188) (xy 101.450903 -263.459404) (xy 101.470194 -263.414128)
			(xy 101.496497 -263.372532) (xy 101.529132 -263.335695) (xy 101.567253 -263.30457) (xy 101.609874 -263.279963)
			(xy 101.65589 -263.262511) (xy 101.704109 -263.252667) (xy 101.753284 -263.250686) (xy 101.802139 -263.256618)
			(xy 101.84941 -263.27031) (xy 101.893872 -263.291408) (xy 101.934375 -263.319364) (xy 101.969868 -263.353456)
			(xy 101.999433 -263.3928) (xy 102.022304 -263.436377) (xy 102.037888 -263.483058) (xy 102.045783 -263.531635)
			(xy 102.046278 -263.556242) (xy 102.045783 -263.580849) (xy 102.037888 -263.629426) (xy 102.022304 -263.676107)
			(xy 101.999433 -263.719684) (xy 101.969868 -263.759028) (xy 101.934375 -263.79312) (xy 101.893872 -263.821076)
			(xy 101.84941 -263.842174) (xy 101.802139 -263.855866) (xy 101.753284 -263.861798) (xy 101.704109 -263.859817)
			(xy 101.65589 -263.849973) (xy 101.609874 -263.832521) (xy 101.567253 -263.807914) (xy 101.529132 -263.776789)
			(xy 101.496497 -263.739952) (xy 101.470194 -263.698356) (xy 101.450903 -263.65308) (xy 101.439126 -263.605296)
			(xy 101.435166 -263.556242) (xy 100.166424 -263.556242) (xy 100.165929 -263.580849) (xy 100.158034 -263.629426)
			(xy 100.14245 -263.676107) (xy 100.119579 -263.719684) (xy 100.090014 -263.759028) (xy 100.054521 -263.79312)
			(xy 100.014018 -263.821076) (xy 99.969556 -263.842174) (xy 99.922285 -263.855866) (xy 99.87343 -263.861798)
			(xy 99.824255 -263.859817) (xy 99.776036 -263.849973) (xy 99.73002 -263.832521) (xy 99.687399 -263.807914)
			(xy 99.649278 -263.776789) (xy 99.616643 -263.739952) (xy 99.59034 -263.698356) (xy 99.571049 -263.65308)
			(xy 99.559272 -263.605296) (xy 99.555312 -263.556242) (xy 98.286316 -263.556242) (xy 98.285821 -263.580849)
			(xy 98.277926 -263.629426) (xy 98.262342 -263.676107) (xy 98.239471 -263.719684) (xy 98.209906 -263.759028)
			(xy 98.174413 -263.79312) (xy 98.13391 -263.821076) (xy 98.089448 -263.842174) (xy 98.042177 -263.855866)
			(xy 97.993322 -263.861798) (xy 97.944147 -263.859817) (xy 97.895928 -263.849973) (xy 97.849912 -263.832521)
			(xy 97.807291 -263.807914) (xy 97.76917 -263.776789) (xy 97.736535 -263.739952) (xy 97.710232 -263.698356)
			(xy 97.690941 -263.65308) (xy 97.679164 -263.605296) (xy 97.675204 -263.556242) (xy 96.416876 -263.556242)
			(xy 96.416364 -263.581688) (xy 96.4082 -263.631922) (xy 96.392084 -263.680196) (xy 96.368433 -263.725259)
			(xy 96.33786 -263.765945) (xy 96.301156 -263.8012) (xy 96.259272 -263.83011) (xy 96.213293 -263.851927)
			(xy 96.164409 -263.866087) (xy 96.113888 -263.872221) (xy 96.063036 -263.870172) (xy 96.013172 -263.859992)
			(xy 95.965586 -263.841945) (xy 95.921512 -263.816499) (xy 95.88209 -263.784312) (xy 95.848342 -263.746218)
			(xy 95.821141 -263.703204) (xy 95.801193 -263.656384) (xy 95.789014 -263.60697) (xy 95.784919 -263.556242)
			(xy 95.466408 -263.556242) (xy 95.465913 -263.580849) (xy 95.458018 -263.629426) (xy 95.442434 -263.676107)
			(xy 95.419563 -263.719684) (xy 95.389998 -263.759028) (xy 95.354505 -263.79312) (xy 95.314002 -263.821076)
			(xy 95.26954 -263.842174) (xy 95.222269 -263.855866) (xy 95.173414 -263.861798) (xy 95.124239 -263.859817)
			(xy 95.07602 -263.849973) (xy 95.030004 -263.832521) (xy 94.987383 -263.807914) (xy 94.949262 -263.776789)
			(xy 94.916627 -263.739952) (xy 94.890324 -263.698356) (xy 94.871033 -263.65308) (xy 94.859256 -263.605296)
			(xy 94.855296 -263.556242) (xy 94.536768 -263.556242) (xy 94.536256 -263.581688) (xy 94.528092 -263.631922)
			(xy 94.511976 -263.680196) (xy 94.488325 -263.725259) (xy 94.457752 -263.765945) (xy 94.421048 -263.8012)
			(xy 94.379164 -263.83011) (xy 94.333185 -263.851927) (xy 94.284301 -263.866087) (xy 94.23378 -263.872221)
			(xy 94.182928 -263.870172) (xy 94.133064 -263.859992) (xy 94.085478 -263.841945) (xy 94.041404 -263.816499)
			(xy 94.001982 -263.784312) (xy 93.968234 -263.746218) (xy 93.941033 -263.703204) (xy 93.921085 -263.656384)
			(xy 93.908906 -263.60697) (xy 93.904811 -263.556242) (xy 92.65666 -263.556242) (xy 92.656148 -263.581688)
			(xy 92.647984 -263.631922) (xy 92.631868 -263.680196) (xy 92.608217 -263.725259) (xy 92.577644 -263.765945)
			(xy 92.54094 -263.8012) (xy 92.499056 -263.83011) (xy 92.453077 -263.851927) (xy 92.404193 -263.866087)
			(xy 92.353672 -263.872221) (xy 92.30282 -263.870172) (xy 92.252956 -263.859992) (xy 92.20537 -263.841945)
			(xy 92.161296 -263.816499) (xy 92.121874 -263.784312) (xy 92.088126 -263.746218) (xy 92.060925 -263.703204)
			(xy 92.040977 -263.656384) (xy 92.028798 -263.60697) (xy 92.024703 -263.556242) (xy 91.71686 -263.556242)
			(xy 91.716348 -263.581688) (xy 91.708184 -263.631922) (xy 91.692068 -263.680196) (xy 91.668417 -263.725259)
			(xy 91.637844 -263.765945) (xy 91.60114 -263.8012) (xy 91.559256 -263.83011) (xy 91.513277 -263.851927)
			(xy 91.464393 -263.866087) (xy 91.413872 -263.872221) (xy 91.36302 -263.870172) (xy 91.313156 -263.859992)
			(xy 91.26557 -263.841945) (xy 91.221496 -263.816499) (xy 91.182074 -263.784312) (xy 91.148326 -263.746218)
			(xy 91.121125 -263.703204) (xy 91.101177 -263.656384) (xy 91.088998 -263.60697) (xy 91.084903 -263.556242)
			(xy 90.766915 -263.556242) (xy 90.762747 -263.606538) (xy 90.750347 -263.655502) (xy 90.730056 -263.701758)
			(xy 90.702429 -263.744043) (xy 90.668219 -263.781203) (xy 90.628358 -263.812226) (xy 90.583935 -263.836265)
			(xy 90.536161 -263.852663) (xy 90.486339 -263.860975) (xy 90.461084 -263.86155) (xy 90.448321 -263.861412)
			(xy 90.422887 -263.859252) (xy 90.410284 -263.857232) (xy 90.410284 -263.857486) (xy 90.386832 -263.853056)
			(xy 90.341583 -263.83789) (xy 90.299237 -263.815881) (xy 90.260821 -263.787565) (xy 90.227268 -263.753627)
			(xy 90.212926 -263.73455) (xy 90.208862 -263.728708) (xy 90.198194 -263.720072) (xy 90.192352 -263.717532)
			(xy 90.186068 -263.715014) (xy 90.172675 -263.713083) (xy 90.165936 -263.713722) (xy 90.075512 -263.725152)
			(xy 90.063066 -263.726676) (xy 90.05189 -263.735312) (xy 90.046765 -263.739658) (xy 90.038794 -263.750473)
			(xy 90.036142 -263.756648) (xy 90.036142 -263.756902) (xy 90.028245 -263.776682) (xy 90.009811 -263.81508)
			(xy 89.999312 -263.83361) (xy 89.9541 -263.911588) (xy 89.948373 -263.922828) (xy 89.947579 -263.94801)
			(xy 89.952576 -263.959594) (xy 89.981024 -264.016998) (xy 89.989914 -264.035286) (xy 89.992913 -264.040923)
			(xy 90.001267 -264.050572) (xy 90.006424 -264.054336) (xy 90.01633 -264.061448) (xy 90.02649 -264.062972)
			(xy 90.029284 -264.063226) (xy 90.053547 -264.066813) (xy 90.10058 -264.080709) (xy 90.144791 -264.101938)
			(xy 90.185044 -264.129954) (xy 90.220307 -264.164039) (xy 90.249674 -264.203318) (xy 90.272392 -264.246782)
			(xy 90.287877 -264.293317) (xy 90.295733 -264.341727) (xy 90.296238 -264.366248) (xy 90.614749 -264.366248)
			(xy 90.618844 -264.31552) (xy 90.631023 -264.266106) (xy 90.650971 -264.219286) (xy 90.678172 -264.176272)
			(xy 90.71192 -264.138178) (xy 90.751342 -264.105991) (xy 90.795416 -264.080545) (xy 90.843002 -264.062498)
			(xy 90.892866 -264.052318) (xy 90.943718 -264.050269) (xy 90.994239 -264.056403) (xy 91.043123 -264.070563)
			(xy 91.089102 -264.09238) (xy 91.130986 -264.12129) (xy 91.16769 -264.156545) (xy 91.198263 -264.197231)
			(xy 91.221914 -264.242294) (xy 91.23803 -264.290568) (xy 91.246194 -264.340802) (xy 91.246706 -264.366248)
			(xy 91.565234 -264.366248) (xy 91.569194 -264.317194) (xy 91.580971 -264.26941) (xy 91.600262 -264.224134)
			(xy 91.626565 -264.182538) (xy 91.6592 -264.145701) (xy 91.697321 -264.114576) (xy 91.739942 -264.089969)
			(xy 91.785958 -264.072517) (xy 91.834177 -264.062673) (xy 91.883352 -264.060692) (xy 91.932207 -264.066624)
			(xy 91.979478 -264.080316) (xy 92.02394 -264.101414) (xy 92.064443 -264.12937) (xy 92.099936 -264.163462)
			(xy 92.129501 -264.202806) (xy 92.152372 -264.246383) (xy 92.167956 -264.293064) (xy 92.175851 -264.341641)
			(xy 92.176346 -264.366248) (xy 92.494857 -264.366248) (xy 92.498952 -264.31552) (xy 92.511131 -264.266106)
			(xy 92.531079 -264.219286) (xy 92.55828 -264.176272) (xy 92.592028 -264.138178) (xy 92.63145 -264.105991)
			(xy 92.675524 -264.080545) (xy 92.72311 -264.062498) (xy 92.772974 -264.052318) (xy 92.823826 -264.050269)
			(xy 92.874347 -264.056403) (xy 92.923231 -264.070563) (xy 92.96921 -264.09238) (xy 93.011094 -264.12129)
			(xy 93.047798 -264.156545) (xy 93.078371 -264.197231) (xy 93.102022 -264.242294) (xy 93.118138 -264.290568)
			(xy 93.126302 -264.340802) (xy 93.126814 -264.366248) (xy 93.445342 -264.366248) (xy 93.449302 -264.317194)
			(xy 93.461079 -264.26941) (xy 93.48037 -264.224134) (xy 93.506673 -264.182538) (xy 93.539308 -264.145701)
			(xy 93.577429 -264.114576) (xy 93.62005 -264.089969) (xy 93.666066 -264.072517) (xy 93.714285 -264.062673)
			(xy 93.76346 -264.060692) (xy 93.812315 -264.066624) (xy 93.859586 -264.080316) (xy 93.904048 -264.101414)
			(xy 93.944551 -264.12937) (xy 93.980044 -264.163462) (xy 94.009609 -264.202806) (xy 94.03248 -264.246383)
			(xy 94.048064 -264.293064) (xy 94.055959 -264.341641) (xy 94.056454 -264.366248) (xy 94.374711 -264.366248)
			(xy 94.378806 -264.31552) (xy 94.390985 -264.266106) (xy 94.410933 -264.219286) (xy 94.438134 -264.176272)
			(xy 94.471882 -264.138178) (xy 94.511304 -264.105991) (xy 94.555378 -264.080545) (xy 94.602964 -264.062498)
			(xy 94.652828 -264.052318) (xy 94.70368 -264.050269) (xy 94.754201 -264.056403) (xy 94.803085 -264.070563)
			(xy 94.849064 -264.09238) (xy 94.890948 -264.12129) (xy 94.927652 -264.156545) (xy 94.958225 -264.197231)
			(xy 94.981876 -264.242294) (xy 94.997992 -264.290568) (xy 95.006156 -264.340802) (xy 95.006668 -264.366248)
			(xy 95.314765 -264.366248) (xy 95.31886 -264.31552) (xy 95.331039 -264.266106) (xy 95.350987 -264.219286)
			(xy 95.378188 -264.176272) (xy 95.411936 -264.138178) (xy 95.451358 -264.105991) (xy 95.495432 -264.080545)
			(xy 95.543018 -264.062498) (xy 95.592882 -264.052318) (xy 95.643734 -264.050269) (xy 95.694255 -264.056403)
			(xy 95.743139 -264.070563) (xy 95.789118 -264.09238) (xy 95.831002 -264.12129) (xy 95.867706 -264.156545)
			(xy 95.898279 -264.197231) (xy 95.92193 -264.242294) (xy 95.938046 -264.290568) (xy 95.94621 -264.340802)
			(xy 95.946722 -264.366248) (xy 96.26525 -264.366248) (xy 96.26921 -264.317194) (xy 96.280987 -264.26941)
			(xy 96.300278 -264.224134) (xy 96.326581 -264.182538) (xy 96.359216 -264.145701) (xy 96.397337 -264.114576)
			(xy 96.439958 -264.089969) (xy 96.485974 -264.072517) (xy 96.534193 -264.062673) (xy 96.583368 -264.060692)
			(xy 96.632223 -264.066624) (xy 96.679494 -264.080316) (xy 96.723956 -264.101414) (xy 96.764459 -264.12937)
			(xy 96.799952 -264.163462) (xy 96.829517 -264.202806) (xy 96.852388 -264.246383) (xy 96.867972 -264.293064)
			(xy 96.875867 -264.341641) (xy 96.876362 -264.366248) (xy 98.145358 -264.366248) (xy 98.149318 -264.317194)
			(xy 98.161095 -264.26941) (xy 98.180386 -264.224134) (xy 98.206689 -264.182538) (xy 98.239324 -264.145701)
			(xy 98.277445 -264.114576) (xy 98.320066 -264.089969) (xy 98.366082 -264.072517) (xy 98.414301 -264.062673)
			(xy 98.463476 -264.060692) (xy 98.512331 -264.066624) (xy 98.559602 -264.080316) (xy 98.604064 -264.101414)
			(xy 98.644567 -264.12937) (xy 98.68006 -264.163462) (xy 98.709625 -264.202806) (xy 98.732496 -264.246383)
			(xy 98.74808 -264.293064) (xy 98.755975 -264.341641) (xy 98.75647 -264.366248) (xy 100.025212 -264.366248)
			(xy 100.029172 -264.317194) (xy 100.040949 -264.26941) (xy 100.06024 -264.224134) (xy 100.086543 -264.182538)
			(xy 100.119178 -264.145701) (xy 100.157299 -264.114576) (xy 100.19992 -264.089969) (xy 100.245936 -264.072517)
			(xy 100.294155 -264.062673) (xy 100.34333 -264.060692) (xy 100.392185 -264.066624) (xy 100.439456 -264.080316)
			(xy 100.483918 -264.101414) (xy 100.524421 -264.12937) (xy 100.559914 -264.163462) (xy 100.589479 -264.202806)
			(xy 100.61235 -264.246383) (xy 100.627934 -264.293064) (xy 100.635829 -264.341641) (xy 100.636324 -264.366248)
			(xy 100.965266 -264.366248) (xy 100.969226 -264.317194) (xy 100.981003 -264.26941) (xy 101.000294 -264.224134)
			(xy 101.026597 -264.182538) (xy 101.059232 -264.145701) (xy 101.097353 -264.114576) (xy 101.139974 -264.089969)
			(xy 101.18599 -264.072517) (xy 101.234209 -264.062673) (xy 101.283384 -264.060692) (xy 101.332239 -264.066624)
			(xy 101.37951 -264.080316) (xy 101.423972 -264.101414) (xy 101.464475 -264.12937) (xy 101.499968 -264.163462)
			(xy 101.529533 -264.202806) (xy 101.552404 -264.246383) (xy 101.567988 -264.293064) (xy 101.575883 -264.341641)
			(xy 101.576378 -264.366248) (xy 101.575883 -264.390855) (xy 101.567988 -264.439432) (xy 101.552404 -264.486113)
			(xy 101.529533 -264.52969) (xy 101.499968 -264.569034) (xy 101.464475 -264.603126) (xy 101.423972 -264.631082)
			(xy 101.37951 -264.65218) (xy 101.332239 -264.665872) (xy 101.283384 -264.671804) (xy 101.234209 -264.669823)
			(xy 101.18599 -264.659979) (xy 101.139974 -264.642527) (xy 101.097353 -264.61792) (xy 101.059232 -264.586795)
			(xy 101.026597 -264.549958) (xy 101.000294 -264.508362) (xy 100.981003 -264.463086) (xy 100.969226 -264.415302)
			(xy 100.965266 -264.366248) (xy 100.636324 -264.366248) (xy 100.635829 -264.390855) (xy 100.627934 -264.439432)
			(xy 100.61235 -264.486113) (xy 100.589479 -264.52969) (xy 100.559914 -264.569034) (xy 100.524421 -264.603126)
			(xy 100.483918 -264.631082) (xy 100.439456 -264.65218) (xy 100.392185 -264.665872) (xy 100.34333 -264.671804)
			(xy 100.294155 -264.669823) (xy 100.245936 -264.659979) (xy 100.19992 -264.642527) (xy 100.157299 -264.61792)
			(xy 100.119178 -264.586795) (xy 100.086543 -264.549958) (xy 100.06024 -264.508362) (xy 100.040949 -264.463086)
			(xy 100.029172 -264.415302) (xy 100.025212 -264.366248) (xy 98.75647 -264.366248) (xy 98.755975 -264.390855)
			(xy 98.74808 -264.439432) (xy 98.732496 -264.486113) (xy 98.709625 -264.52969) (xy 98.68006 -264.569034)
			(xy 98.644567 -264.603126) (xy 98.604064 -264.631082) (xy 98.559602 -264.65218) (xy 98.512331 -264.665872)
			(xy 98.463476 -264.671804) (xy 98.414301 -264.669823) (xy 98.366082 -264.659979) (xy 98.320066 -264.642527)
			(xy 98.277445 -264.61792) (xy 98.239324 -264.586795) (xy 98.206689 -264.549958) (xy 98.180386 -264.508362)
			(xy 98.161095 -264.463086) (xy 98.149318 -264.415302) (xy 98.145358 -264.366248) (xy 96.876362 -264.366248)
			(xy 96.875867 -264.390855) (xy 96.867972 -264.439432) (xy 96.852388 -264.486113) (xy 96.829517 -264.52969)
			(xy 96.799952 -264.569034) (xy 96.764459 -264.603126) (xy 96.723956 -264.631082) (xy 96.679494 -264.65218)
			(xy 96.632223 -264.665872) (xy 96.583368 -264.671804) (xy 96.534193 -264.669823) (xy 96.485974 -264.659979)
			(xy 96.439958 -264.642527) (xy 96.397337 -264.61792) (xy 96.359216 -264.586795) (xy 96.326581 -264.549958)
			(xy 96.300278 -264.508362) (xy 96.280987 -264.463086) (xy 96.26921 -264.415302) (xy 96.26525 -264.366248)
			(xy 95.946722 -264.366248) (xy 95.94621 -264.391694) (xy 95.938046 -264.441928) (xy 95.92193 -264.490202)
			(xy 95.898279 -264.535265) (xy 95.867706 -264.575951) (xy 95.831002 -264.611206) (xy 95.789118 -264.640116)
			(xy 95.743139 -264.661933) (xy 95.694255 -264.676093) (xy 95.643734 -264.682227) (xy 95.592882 -264.680178)
			(xy 95.543018 -264.669998) (xy 95.495432 -264.651951) (xy 95.451358 -264.626505) (xy 95.411936 -264.594318)
			(xy 95.378188 -264.556224) (xy 95.350987 -264.51321) (xy 95.331039 -264.46639) (xy 95.31886 -264.416976)
			(xy 95.314765 -264.366248) (xy 95.006668 -264.366248) (xy 95.006156 -264.391694) (xy 94.997992 -264.441928)
			(xy 94.981876 -264.490202) (xy 94.958225 -264.535265) (xy 94.927652 -264.575951) (xy 94.890948 -264.611206)
			(xy 94.849064 -264.640116) (xy 94.803085 -264.661933) (xy 94.754201 -264.676093) (xy 94.70368 -264.682227)
			(xy 94.652828 -264.680178) (xy 94.602964 -264.669998) (xy 94.555378 -264.651951) (xy 94.511304 -264.626505)
			(xy 94.471882 -264.594318) (xy 94.438134 -264.556224) (xy 94.410933 -264.51321) (xy 94.390985 -264.46639)
			(xy 94.378806 -264.416976) (xy 94.374711 -264.366248) (xy 94.056454 -264.366248) (xy 94.055959 -264.390855)
			(xy 94.048064 -264.439432) (xy 94.03248 -264.486113) (xy 94.009609 -264.52969) (xy 93.980044 -264.569034)
			(xy 93.944551 -264.603126) (xy 93.904048 -264.631082) (xy 93.859586 -264.65218) (xy 93.812315 -264.665872)
			(xy 93.76346 -264.671804) (xy 93.714285 -264.669823) (xy 93.666066 -264.659979) (xy 93.62005 -264.642527)
			(xy 93.577429 -264.61792) (xy 93.539308 -264.586795) (xy 93.506673 -264.549958) (xy 93.48037 -264.508362)
			(xy 93.461079 -264.463086) (xy 93.449302 -264.415302) (xy 93.445342 -264.366248) (xy 93.126814 -264.366248)
			(xy 93.126302 -264.391694) (xy 93.118138 -264.441928) (xy 93.102022 -264.490202) (xy 93.078371 -264.535265)
			(xy 93.047798 -264.575951) (xy 93.011094 -264.611206) (xy 92.96921 -264.640116) (xy 92.923231 -264.661933)
			(xy 92.874347 -264.676093) (xy 92.823826 -264.682227) (xy 92.772974 -264.680178) (xy 92.72311 -264.669998)
			(xy 92.675524 -264.651951) (xy 92.63145 -264.626505) (xy 92.592028 -264.594318) (xy 92.55828 -264.556224)
			(xy 92.531079 -264.51321) (xy 92.511131 -264.46639) (xy 92.498952 -264.416976) (xy 92.494857 -264.366248)
			(xy 92.176346 -264.366248) (xy 92.175851 -264.390855) (xy 92.167956 -264.439432) (xy 92.152372 -264.486113)
			(xy 92.129501 -264.52969) (xy 92.099936 -264.569034) (xy 92.064443 -264.603126) (xy 92.02394 -264.631082)
			(xy 91.979478 -264.65218) (xy 91.932207 -264.665872) (xy 91.883352 -264.671804) (xy 91.834177 -264.669823)
			(xy 91.785958 -264.659979) (xy 91.739942 -264.642527) (xy 91.697321 -264.61792) (xy 91.6592 -264.586795)
			(xy 91.626565 -264.549958) (xy 91.600262 -264.508362) (xy 91.580971 -264.463086) (xy 91.569194 -264.415302)
			(xy 91.565234 -264.366248) (xy 91.246706 -264.366248) (xy 91.246194 -264.391694) (xy 91.23803 -264.441928)
			(xy 91.221914 -264.490202) (xy 91.198263 -264.535265) (xy 91.16769 -264.575951) (xy 91.130986 -264.611206)
			(xy 91.089102 -264.640116) (xy 91.043123 -264.661933) (xy 90.994239 -264.676093) (xy 90.943718 -264.682227)
			(xy 90.892866 -264.680178) (xy 90.843002 -264.669998) (xy 90.795416 -264.651951) (xy 90.751342 -264.626505)
			(xy 90.71192 -264.594318) (xy 90.678172 -264.556224) (xy 90.650971 -264.51321) (xy 90.631023 -264.46639)
			(xy 90.618844 -264.416976) (xy 90.614749 -264.366248) (xy 90.296238 -264.366248) (xy 90.295764 -264.390238)
			(xy 90.288252 -264.437625) (xy 90.273421 -264.483255) (xy 90.251635 -264.526003) (xy 90.223431 -264.564818)
			(xy 90.189504 -264.598743) (xy 90.150688 -264.626944) (xy 90.107938 -264.648728) (xy 90.062308 -264.663556)
			(xy 90.01492 -264.671065) (xy 89.99093 -264.671556) (xy 89.966926 -264.671089) (xy 89.919506 -264.66359)
			(xy 89.873841 -264.648772) (xy 89.852246 -264.638282) (xy 89.846819 -264.635701) (xy 89.835139 -264.632881)
			(xy 89.829132 -264.632694) (xy 89.806272 -264.632694) (xy 89.799526 -264.632935) (xy 89.786522 -264.636535)
			(xy 89.780618 -264.639806) (xy 89.716102 -264.677652) (xy 89.708663 -264.682409) (xy 89.697338 -264.695939)
			(xy 89.691304 -264.712519) (xy 89.690956 -264.72134) (xy 89.690956 -264.884916) (xy 89.6911 -264.890642)
			(xy 89.693656 -264.901805) (xy 89.696036 -264.907014) (xy 89.705434 -264.926318) (xy 89.707841 -264.930984)
			(xy 89.714246 -264.939299) (xy 89.718134 -264.942828) (xy 89.718388 -264.943082) (xy 89.736504 -264.959027)
			(xy 89.767965 -264.99562) (xy 89.793285 -265.036701) (xy 89.811835 -265.081251) (xy 89.823155 -265.128163)
			(xy 89.826962 -265.176254) (xy 90.15528 -265.176254) (xy 90.15924 -265.1272) (xy 90.171017 -265.079416)
			(xy 90.190308 -265.03414) (xy 90.216611 -264.992544) (xy 90.249246 -264.955707) (xy 90.287367 -264.924582)
			(xy 90.329988 -264.899975) (xy 90.376004 -264.882523) (xy 90.424223 -264.872679) (xy 90.473398 -264.870698)
			(xy 90.522253 -264.87663) (xy 90.569524 -264.890322) (xy 90.613986 -264.91142) (xy 90.654489 -264.939376)
			(xy 90.689982 -264.973468) (xy 90.719547 -265.012812) (xy 90.742418 -265.056389) (xy 90.758002 -265.10307)
			(xy 90.765897 -265.151647) (xy 90.766392 -265.176254) (xy 91.084903 -265.176254) (xy 91.088998 -265.125526)
			(xy 91.101177 -265.076112) (xy 91.121125 -265.029292) (xy 91.148326 -264.986278) (xy 91.182074 -264.948184)
			(xy 91.221496 -264.915997) (xy 91.26557 -264.890551) (xy 91.313156 -264.872504) (xy 91.36302 -264.862324)
			(xy 91.413872 -264.860275) (xy 91.464393 -264.866409) (xy 91.513277 -264.880569) (xy 91.559256 -264.902386)
			(xy 91.60114 -264.931296) (xy 91.637844 -264.966551) (xy 91.668417 -265.007237) (xy 91.692068 -265.0523)
			(xy 91.708184 -265.100574) (xy 91.716348 -265.150808) (xy 91.71686 -265.176254) (xy 92.035134 -265.176254)
			(xy 92.039094 -265.1272) (xy 92.050871 -265.079416) (xy 92.070162 -265.03414) (xy 92.096465 -264.992544)
			(xy 92.1291 -264.955707) (xy 92.167221 -264.924582) (xy 92.209842 -264.899975) (xy 92.255858 -264.882523)
			(xy 92.304077 -264.872679) (xy 92.353252 -264.870698) (xy 92.402107 -264.87663) (xy 92.449378 -264.890322)
			(xy 92.49384 -264.91142) (xy 92.534343 -264.939376) (xy 92.569836 -264.973468) (xy 92.599401 -265.012812)
			(xy 92.622272 -265.056389) (xy 92.637856 -265.10307) (xy 92.645751 -265.151647) (xy 92.646246 -265.176254)
			(xy 92.975188 -265.176254) (xy 92.979148 -265.1272) (xy 92.990925 -265.079416) (xy 93.010216 -265.03414)
			(xy 93.036519 -264.992544) (xy 93.069154 -264.955707) (xy 93.107275 -264.924582) (xy 93.149896 -264.899975)
			(xy 93.195912 -264.882523) (xy 93.244131 -264.872679) (xy 93.293306 -264.870698) (xy 93.342161 -264.87663)
			(xy 93.389432 -264.890322) (xy 93.433894 -264.91142) (xy 93.474397 -264.939376) (xy 93.50989 -264.973468)
			(xy 93.539455 -265.012812) (xy 93.562326 -265.056389) (xy 93.57791 -265.10307) (xy 93.585805 -265.151647)
			(xy 93.5863 -265.176254) (xy 93.904811 -265.176254) (xy 93.908906 -265.125526) (xy 93.921085 -265.076112)
			(xy 93.941033 -265.029292) (xy 93.968234 -264.986278) (xy 94.001982 -264.948184) (xy 94.041404 -264.915997)
			(xy 94.085478 -264.890551) (xy 94.133064 -264.872504) (xy 94.182928 -264.862324) (xy 94.23378 -264.860275)
			(xy 94.284301 -264.866409) (xy 94.333185 -264.880569) (xy 94.379164 -264.902386) (xy 94.421048 -264.931296)
			(xy 94.457752 -264.966551) (xy 94.488325 -265.007237) (xy 94.511976 -265.0523) (xy 94.528092 -265.100574)
			(xy 94.536256 -265.150808) (xy 94.536768 -265.176254) (xy 94.855296 -265.176254) (xy 94.859256 -265.1272)
			(xy 94.871033 -265.079416) (xy 94.890324 -265.03414) (xy 94.916627 -264.992544) (xy 94.949262 -264.955707)
			(xy 94.987383 -264.924582) (xy 95.030004 -264.899975) (xy 95.07602 -264.882523) (xy 95.124239 -264.872679)
			(xy 95.173414 -264.870698) (xy 95.222269 -264.87663) (xy 95.26954 -264.890322) (xy 95.314002 -264.91142)
			(xy 95.354505 -264.939376) (xy 95.389998 -264.973468) (xy 95.419563 -265.012812) (xy 95.442434 -265.056389)
			(xy 95.458018 -265.10307) (xy 95.465913 -265.151647) (xy 95.466408 -265.176254) (xy 95.79535 -265.176254)
			(xy 95.79931 -265.1272) (xy 95.811087 -265.079416) (xy 95.830378 -265.03414) (xy 95.856681 -264.992544)
			(xy 95.889316 -264.955707) (xy 95.927437 -264.924582) (xy 95.970058 -264.899975) (xy 96.016074 -264.882523)
			(xy 96.064293 -264.872679) (xy 96.113468 -264.870698) (xy 96.162323 -264.87663) (xy 96.209594 -264.890322)
			(xy 96.254056 -264.91142) (xy 96.294559 -264.939376) (xy 96.330052 -264.973468) (xy 96.359617 -265.012812)
			(xy 96.382488 -265.056389) (xy 96.398072 -265.10307) (xy 96.405967 -265.151647) (xy 96.406462 -265.176254)
			(xy 97.675204 -265.176254) (xy 97.679164 -265.1272) (xy 97.690941 -265.079416) (xy 97.710232 -265.03414)
			(xy 97.736535 -264.992544) (xy 97.76917 -264.955707) (xy 97.807291 -264.924582) (xy 97.849912 -264.899975)
			(xy 97.895928 -264.882523) (xy 97.944147 -264.872679) (xy 97.993322 -264.870698) (xy 98.042177 -264.87663)
			(xy 98.089448 -264.890322) (xy 98.13391 -264.91142) (xy 98.174413 -264.939376) (xy 98.209906 -264.973468)
			(xy 98.239471 -265.012812) (xy 98.262342 -265.056389) (xy 98.277926 -265.10307) (xy 98.285821 -265.151647)
			(xy 98.286316 -265.176254) (xy 99.555312 -265.176254) (xy 99.559272 -265.1272) (xy 99.571049 -265.079416)
			(xy 99.59034 -265.03414) (xy 99.616643 -264.992544) (xy 99.649278 -264.955707) (xy 99.687399 -264.924582)
			(xy 99.73002 -264.899975) (xy 99.776036 -264.882523) (xy 99.824255 -264.872679) (xy 99.87343 -264.870698)
			(xy 99.922285 -264.87663) (xy 99.969556 -264.890322) (xy 100.014018 -264.91142) (xy 100.054521 -264.939376)
			(xy 100.090014 -264.973468) (xy 100.119579 -265.012812) (xy 100.14245 -265.056389) (xy 100.158034 -265.10307)
			(xy 100.165929 -265.151647) (xy 100.166424 -265.176254) (xy 100.165929 -265.200861) (xy 100.158034 -265.249438)
			(xy 100.14245 -265.296119) (xy 100.119579 -265.339696) (xy 100.090014 -265.37904) (xy 100.054521 -265.413132)
			(xy 100.014018 -265.441088) (xy 99.969556 -265.462186) (xy 99.922285 -265.475878) (xy 99.87343 -265.48181)
			(xy 99.824255 -265.479829) (xy 99.776036 -265.469985) (xy 99.73002 -265.452533) (xy 99.687399 -265.427926)
			(xy 99.649278 -265.396801) (xy 99.616643 -265.359964) (xy 99.59034 -265.318368) (xy 99.571049 -265.273092)
			(xy 99.559272 -265.225308) (xy 99.555312 -265.176254) (xy 98.286316 -265.176254) (xy 98.285821 -265.200861)
			(xy 98.277926 -265.249438) (xy 98.262342 -265.296119) (xy 98.239471 -265.339696) (xy 98.209906 -265.37904)
			(xy 98.174413 -265.413132) (xy 98.13391 -265.441088) (xy 98.089448 -265.462186) (xy 98.042177 -265.475878)
			(xy 97.993322 -265.48181) (xy 97.944147 -265.479829) (xy 97.895928 -265.469985) (xy 97.849912 -265.452533)
			(xy 97.807291 -265.427926) (xy 97.76917 -265.396801) (xy 97.736535 -265.359964) (xy 97.710232 -265.318368)
			(xy 97.690941 -265.273092) (xy 97.679164 -265.225308) (xy 97.675204 -265.176254) (xy 96.406462 -265.176254)
			(xy 96.405967 -265.200861) (xy 96.398072 -265.249438) (xy 96.382488 -265.296119) (xy 96.359617 -265.339696)
			(xy 96.330052 -265.37904) (xy 96.294559 -265.413132) (xy 96.254056 -265.441088) (xy 96.209594 -265.462186)
			(xy 96.162323 -265.475878) (xy 96.113468 -265.48181) (xy 96.064293 -265.479829) (xy 96.016074 -265.469985)
			(xy 95.970058 -265.452533) (xy 95.927437 -265.427926) (xy 95.889316 -265.396801) (xy 95.856681 -265.359964)
			(xy 95.830378 -265.318368) (xy 95.811087 -265.273092) (xy 95.79931 -265.225308) (xy 95.79535 -265.176254)
			(xy 95.466408 -265.176254) (xy 95.465913 -265.200861) (xy 95.458018 -265.249438) (xy 95.442434 -265.296119)
			(xy 95.419563 -265.339696) (xy 95.389998 -265.37904) (xy 95.354505 -265.413132) (xy 95.314002 -265.441088)
			(xy 95.26954 -265.462186) (xy 95.222269 -265.475878) (xy 95.173414 -265.48181) (xy 95.124239 -265.479829)
			(xy 95.07602 -265.469985) (xy 95.030004 -265.452533) (xy 94.987383 -265.427926) (xy 94.949262 -265.396801)
			(xy 94.916627 -265.359964) (xy 94.890324 -265.318368) (xy 94.871033 -265.273092) (xy 94.859256 -265.225308)
			(xy 94.855296 -265.176254) (xy 94.536768 -265.176254) (xy 94.536256 -265.2017) (xy 94.528092 -265.251934)
			(xy 94.511976 -265.300208) (xy 94.488325 -265.345271) (xy 94.457752 -265.385957) (xy 94.421048 -265.421212)
			(xy 94.379164 -265.450122) (xy 94.333185 -265.471939) (xy 94.284301 -265.486099) (xy 94.23378 -265.492233)
			(xy 94.182928 -265.490184) (xy 94.133064 -265.480004) (xy 94.085478 -265.461957) (xy 94.041404 -265.436511)
			(xy 94.001982 -265.404324) (xy 93.968234 -265.36623) (xy 93.941033 -265.323216) (xy 93.921085 -265.276396)
			(xy 93.908906 -265.226982) (xy 93.904811 -265.176254) (xy 93.5863 -265.176254) (xy 93.585805 -265.200861)
			(xy 93.57791 -265.249438) (xy 93.562326 -265.296119) (xy 93.539455 -265.339696) (xy 93.50989 -265.37904)
			(xy 93.474397 -265.413132) (xy 93.433894 -265.441088) (xy 93.389432 -265.462186) (xy 93.342161 -265.475878)
			(xy 93.293306 -265.48181) (xy 93.244131 -265.479829) (xy 93.195912 -265.469985) (xy 93.149896 -265.452533)
			(xy 93.107275 -265.427926) (xy 93.069154 -265.396801) (xy 93.036519 -265.359964) (xy 93.010216 -265.318368)
			(xy 92.990925 -265.273092) (xy 92.979148 -265.225308) (xy 92.975188 -265.176254) (xy 92.646246 -265.176254)
			(xy 92.645751 -265.200861) (xy 92.637856 -265.249438) (xy 92.622272 -265.296119) (xy 92.599401 -265.339696)
			(xy 92.569836 -265.37904) (xy 92.534343 -265.413132) (xy 92.49384 -265.441088) (xy 92.449378 -265.462186)
			(xy 92.402107 -265.475878) (xy 92.353252 -265.48181) (xy 92.304077 -265.479829) (xy 92.255858 -265.469985)
			(xy 92.209842 -265.452533) (xy 92.167221 -265.427926) (xy 92.1291 -265.396801) (xy 92.096465 -265.359964)
			(xy 92.070162 -265.318368) (xy 92.050871 -265.273092) (xy 92.039094 -265.225308) (xy 92.035134 -265.176254)
			(xy 91.71686 -265.176254) (xy 91.716348 -265.2017) (xy 91.708184 -265.251934) (xy 91.692068 -265.300208)
			(xy 91.668417 -265.345271) (xy 91.637844 -265.385957) (xy 91.60114 -265.421212) (xy 91.559256 -265.450122)
			(xy 91.513277 -265.471939) (xy 91.464393 -265.486099) (xy 91.413872 -265.492233) (xy 91.36302 -265.490184)
			(xy 91.313156 -265.480004) (xy 91.26557 -265.461957) (xy 91.221496 -265.436511) (xy 91.182074 -265.404324)
			(xy 91.148326 -265.36623) (xy 91.121125 -265.323216) (xy 91.101177 -265.276396) (xy 91.088998 -265.226982)
			(xy 91.084903 -265.176254) (xy 90.766392 -265.176254) (xy 90.765897 -265.200861) (xy 90.758002 -265.249438)
			(xy 90.742418 -265.296119) (xy 90.719547 -265.339696) (xy 90.689982 -265.37904) (xy 90.654489 -265.413132)
			(xy 90.613986 -265.441088) (xy 90.569524 -265.462186) (xy 90.522253 -265.475878) (xy 90.473398 -265.48181)
			(xy 90.424223 -265.479829) (xy 90.376004 -265.469985) (xy 90.329988 -265.452533) (xy 90.287367 -265.427926)
			(xy 90.249246 -265.396801) (xy 90.216611 -265.359964) (xy 90.190308 -265.318368) (xy 90.171017 -265.273092)
			(xy 90.15924 -265.225308) (xy 90.15528 -265.176254) (xy 89.826962 -265.176254) (xy 89.826963 -265.17627)
			(xy 89.823164 -265.224378) (xy 89.811854 -265.271292) (xy 89.793312 -265.315846) (xy 89.768 -265.356932)
			(xy 89.736546 -265.393531) (xy 89.718388 -265.409426) (xy 89.718134 -265.40968) (xy 89.714232 -265.413194)
			(xy 89.707836 -265.42152) (xy 89.705434 -265.42619) (xy 89.696036 -265.445494) (xy 89.693694 -265.450717)
			(xy 89.691133 -265.46187) (xy 89.690956 -265.467592) (xy 89.690956 -265.631168) (xy 89.691383 -265.639974)
			(xy 89.697435 -265.656518) (xy 89.708706 -265.670058) (xy 89.716102 -265.674856) (xy 89.754456 -265.697462)
			(xy 89.79408 -265.720576) (xy 89.80543 -265.725761) (xy 89.830353 -265.725515) (xy 89.841578 -265.720068)
			(xy 89.842086 -265.719814) (xy 89.864972 -265.707598) (xy 89.91387 -265.690278) (xy 89.964993 -265.681477)
			(xy 89.99093 -265.680952) (xy 90.014921 -265.681425) (xy 90.062311 -265.688934) (xy 90.107944 -265.703764)
			(xy 90.150695 -265.725548) (xy 90.189513 -265.753752) (xy 90.223442 -265.787679) (xy 90.251646 -265.826496)
			(xy 90.273432 -265.869247) (xy 90.288263 -265.914879) (xy 90.295774 -265.962269) (xy 90.296238 -265.98626)
			(xy 90.62518 -265.98626) (xy 90.62914 -265.937206) (xy 90.640917 -265.889422) (xy 90.660208 -265.844146)
			(xy 90.686511 -265.80255) (xy 90.719146 -265.765713) (xy 90.757267 -265.734588) (xy 90.799888 -265.709981)
			(xy 90.845904 -265.692529) (xy 90.894123 -265.682685) (xy 90.943298 -265.680704) (xy 90.992153 -265.686636)
			(xy 91.039424 -265.700328) (xy 91.083886 -265.721426) (xy 91.124389 -265.749382) (xy 91.159882 -265.783474)
			(xy 91.189447 -265.822818) (xy 91.212318 -265.866395) (xy 91.227902 -265.913076) (xy 91.235797 -265.961653)
			(xy 91.236292 -265.98626) (xy 91.565234 -265.98626) (xy 91.569194 -265.937206) (xy 91.580971 -265.889422)
			(xy 91.600262 -265.844146) (xy 91.626565 -265.80255) (xy 91.6592 -265.765713) (xy 91.697321 -265.734588)
			(xy 91.739942 -265.709981) (xy 91.785958 -265.692529) (xy 91.834177 -265.682685) (xy 91.883352 -265.680704)
			(xy 91.932207 -265.686636) (xy 91.979478 -265.700328) (xy 92.02394 -265.721426) (xy 92.064443 -265.749382)
			(xy 92.099936 -265.783474) (xy 92.129501 -265.822818) (xy 92.152372 -265.866395) (xy 92.167956 -265.913076)
			(xy 92.175851 -265.961653) (xy 92.176346 -265.98626) (xy 92.494857 -265.98626) (xy 92.498952 -265.935532)
			(xy 92.511131 -265.886118) (xy 92.531079 -265.839298) (xy 92.55828 -265.796284) (xy 92.592028 -265.75819)
			(xy 92.63145 -265.726003) (xy 92.675524 -265.700557) (xy 92.72311 -265.68251) (xy 92.772974 -265.67233)
			(xy 92.823826 -265.670281) (xy 92.874347 -265.676415) (xy 92.923231 -265.690575) (xy 92.96921 -265.712392)
			(xy 93.011094 -265.741302) (xy 93.047798 -265.776557) (xy 93.078371 -265.817243) (xy 93.102022 -265.862306)
			(xy 93.118138 -265.91058) (xy 93.126302 -265.960814) (xy 93.126814 -265.98626) (xy 94.385142 -265.98626)
			(xy 94.389102 -265.937206) (xy 94.400879 -265.889422) (xy 94.42017 -265.844146) (xy 94.446473 -265.80255)
			(xy 94.479108 -265.765713) (xy 94.517229 -265.734588) (xy 94.55985 -265.709981) (xy 94.605866 -265.692529)
			(xy 94.654085 -265.682685) (xy 94.70326 -265.680704) (xy 94.752115 -265.686636) (xy 94.799386 -265.700328)
			(xy 94.843848 -265.721426) (xy 94.884351 -265.749382) (xy 94.919844 -265.783474) (xy 94.949409 -265.822818)
			(xy 94.97228 -265.866395) (xy 94.987864 -265.913076) (xy 94.995759 -265.961653) (xy 94.996254 -265.98626)
			(xy 95.314765 -265.98626) (xy 95.31886 -265.935532) (xy 95.331039 -265.886118) (xy 95.350987 -265.839298)
			(xy 95.378188 -265.796284) (xy 95.411936 -265.75819) (xy 95.451358 -265.726003) (xy 95.495432 -265.700557)
			(xy 95.543018 -265.68251) (xy 95.592882 -265.67233) (xy 95.643734 -265.670281) (xy 95.694255 -265.676415)
			(xy 95.743139 -265.690575) (xy 95.789118 -265.712392) (xy 95.831002 -265.741302) (xy 95.867706 -265.776557)
			(xy 95.898279 -265.817243) (xy 95.92193 -265.862306) (xy 95.938046 -265.91058) (xy 95.94621 -265.960814)
			(xy 95.946722 -265.98626) (xy 96.26525 -265.98626) (xy 96.26921 -265.937206) (xy 96.280987 -265.889422)
			(xy 96.300278 -265.844146) (xy 96.326581 -265.80255) (xy 96.359216 -265.765713) (xy 96.397337 -265.734588)
			(xy 96.439958 -265.709981) (xy 96.485974 -265.692529) (xy 96.534193 -265.682685) (xy 96.583368 -265.680704)
			(xy 96.632223 -265.686636) (xy 96.679494 -265.700328) (xy 96.723956 -265.721426) (xy 96.764459 -265.749382)
			(xy 96.799952 -265.783474) (xy 96.829517 -265.822818) (xy 96.852388 -265.866395) (xy 96.867972 -265.913076)
			(xy 96.875867 -265.961653) (xy 96.876362 -265.98626) (xy 98.145358 -265.98626) (xy 98.149318 -265.937206)
			(xy 98.161095 -265.889422) (xy 98.180386 -265.844146) (xy 98.206689 -265.80255) (xy 98.239324 -265.765713)
			(xy 98.277445 -265.734588) (xy 98.320066 -265.709981) (xy 98.366082 -265.692529) (xy 98.414301 -265.682685)
			(xy 98.463476 -265.680704) (xy 98.512331 -265.686636) (xy 98.559602 -265.700328) (xy 98.604064 -265.721426)
			(xy 98.644567 -265.749382) (xy 98.68006 -265.783474) (xy 98.709625 -265.822818) (xy 98.732496 -265.866395)
			(xy 98.74808 -265.913076) (xy 98.755975 -265.961653) (xy 98.75647 -265.98626) (xy 98.755975 -266.010867)
			(xy 98.74808 -266.059444) (xy 98.732496 -266.106125) (xy 98.709625 -266.149702) (xy 98.68006 -266.189046)
			(xy 98.644567 -266.223138) (xy 98.604064 -266.251094) (xy 98.559602 -266.272192) (xy 98.512331 -266.285884)
			(xy 98.463476 -266.291816) (xy 98.414301 -266.289835) (xy 98.366082 -266.279991) (xy 98.320066 -266.262539)
			(xy 98.277445 -266.237932) (xy 98.239324 -266.206807) (xy 98.206689 -266.16997) (xy 98.180386 -266.128374)
			(xy 98.161095 -266.083098) (xy 98.149318 -266.035314) (xy 98.145358 -265.98626) (xy 96.876362 -265.98626)
			(xy 96.875867 -266.010867) (xy 96.867972 -266.059444) (xy 96.852388 -266.106125) (xy 96.829517 -266.149702)
			(xy 96.799952 -266.189046) (xy 96.764459 -266.223138) (xy 96.723956 -266.251094) (xy 96.679494 -266.272192)
			(xy 96.632223 -266.285884) (xy 96.583368 -266.291816) (xy 96.534193 -266.289835) (xy 96.485974 -266.279991)
			(xy 96.439958 -266.262539) (xy 96.397337 -266.237932) (xy 96.359216 -266.206807) (xy 96.326581 -266.16997)
			(xy 96.300278 -266.128374) (xy 96.280987 -266.083098) (xy 96.26921 -266.035314) (xy 96.26525 -265.98626)
			(xy 95.946722 -265.98626) (xy 95.94621 -266.011706) (xy 95.938046 -266.06194) (xy 95.92193 -266.110214)
			(xy 95.898279 -266.155277) (xy 95.867706 -266.195963) (xy 95.831002 -266.231218) (xy 95.789118 -266.260128)
			(xy 95.743139 -266.281945) (xy 95.694255 -266.296105) (xy 95.643734 -266.302239) (xy 95.592882 -266.30019)
			(xy 95.543018 -266.29001) (xy 95.495432 -266.271963) (xy 95.451358 -266.246517) (xy 95.411936 -266.21433)
			(xy 95.378188 -266.176236) (xy 95.350987 -266.133222) (xy 95.331039 -266.086402) (xy 95.31886 -266.036988)
			(xy 95.314765 -265.98626) (xy 94.996254 -265.98626) (xy 94.995759 -266.010867) (xy 94.987864 -266.059444)
			(xy 94.97228 -266.106125) (xy 94.949409 -266.149702) (xy 94.919844 -266.189046) (xy 94.884351 -266.223138)
			(xy 94.843848 -266.251094) (xy 94.799386 -266.272192) (xy 94.752115 -266.285884) (xy 94.70326 -266.291816)
			(xy 94.654085 -266.289835) (xy 94.605866 -266.279991) (xy 94.55985 -266.262539) (xy 94.517229 -266.237932)
			(xy 94.479108 -266.206807) (xy 94.446473 -266.16997) (xy 94.42017 -266.128374) (xy 94.400879 -266.083098)
			(xy 94.389102 -266.035314) (xy 94.385142 -265.98626) (xy 93.126814 -265.98626) (xy 93.126302 -266.011706)
			(xy 93.118138 -266.06194) (xy 93.102022 -266.110214) (xy 93.078371 -266.155277) (xy 93.047798 -266.195963)
			(xy 93.011094 -266.231218) (xy 92.96921 -266.260128) (xy 92.923231 -266.281945) (xy 92.874347 -266.296105)
			(xy 92.823826 -266.302239) (xy 92.772974 -266.30019) (xy 92.72311 -266.29001) (xy 92.675524 -266.271963)
			(xy 92.63145 -266.246517) (xy 92.592028 -266.21433) (xy 92.55828 -266.176236) (xy 92.531079 -266.133222)
			(xy 92.511131 -266.086402) (xy 92.498952 -266.036988) (xy 92.494857 -265.98626) (xy 92.176346 -265.98626)
			(xy 92.175851 -266.010867) (xy 92.167956 -266.059444) (xy 92.152372 -266.106125) (xy 92.129501 -266.149702)
			(xy 92.099936 -266.189046) (xy 92.064443 -266.223138) (xy 92.02394 -266.251094) (xy 91.979478 -266.272192)
			(xy 91.932207 -266.285884) (xy 91.883352 -266.291816) (xy 91.834177 -266.289835) (xy 91.785958 -266.279991)
			(xy 91.739942 -266.262539) (xy 91.697321 -266.237932) (xy 91.6592 -266.206807) (xy 91.626565 -266.16997)
			(xy 91.600262 -266.128374) (xy 91.580971 -266.083098) (xy 91.569194 -266.035314) (xy 91.565234 -265.98626)
			(xy 91.236292 -265.98626) (xy 91.235797 -266.010867) (xy 91.227902 -266.059444) (xy 91.212318 -266.106125)
			(xy 91.189447 -266.149702) (xy 91.159882 -266.189046) (xy 91.124389 -266.223138) (xy 91.083886 -266.251094)
			(xy 91.039424 -266.272192) (xy 90.992153 -266.285884) (xy 90.943298 -266.291816) (xy 90.894123 -266.289835)
			(xy 90.845904 -266.279991) (xy 90.799888 -266.262539) (xy 90.757267 -266.237932) (xy 90.719146 -266.206807)
			(xy 90.686511 -266.16997) (xy 90.660208 -266.128374) (xy 90.640917 -266.083098) (xy 90.62914 -266.035314)
			(xy 90.62518 -265.98626) (xy 90.296238 -265.98626) (xy 90.295755 -266.011083) (xy 90.28773 -266.060076)
			(xy 90.271884 -266.107126) (xy 90.248635 -266.150992) (xy 90.218596 -266.190519) (xy 90.182558 -266.224666)
			(xy 90.14147 -266.252532) (xy 90.096415 -266.273384) (xy 90.04858 -266.286673) (xy 90.02395 -266.28979)
			(xy 90.023696 -266.28979) (xy 90.01699 -266.290709) (xy 90.004374 -266.295597) (xy 89.998804 -266.299442)
			(xy 89.993724 -266.303506) (xy 89.985342 -266.31392) (xy 89.948004 -266.402566) (xy 89.94553 -266.408993)
			(xy 89.943726 -266.422641) (xy 89.944448 -266.42949) (xy 89.946226 -266.442698) (xy 89.954862 -266.45362)
			(xy 89.966914 -266.469172) (xy 89.989032 -266.501715) (xy 89.999058 -266.518644) (xy 90.037158 -266.584176)
			(xy 90.049096 -266.604496) (xy 90.055837 -266.613781) (xy 90.075361 -266.625774) (xy 90.086688 -266.62761)
			(xy 90.113866 -266.629388) (xy 90.173302 -266.633198) (xy 90.179716 -266.633375) (xy 90.192305 -266.630922)
			(xy 90.198194 -266.628372) (xy 90.203528 -266.625832) (xy 90.21318 -266.617958) (xy 90.21699 -266.612878)
			(xy 90.231508 -266.594287) (xy 90.265304 -266.561383) (xy 90.303759 -266.534068) (xy 90.345956 -266.512991)
			(xy 90.390893 -266.498655) (xy 90.4375 -266.491399) (xy 90.461084 -266.490958) (xy 90.486345 -266.49145)
			(xy 90.536179 -266.499763) (xy 90.583965 -266.516166) (xy 90.6284 -266.54021) (xy 90.66827 -266.571241)
			(xy 90.702489 -266.608411) (xy 90.730123 -266.650706) (xy 90.750419 -266.696973) (xy 90.762822 -266.74595)
			(xy 90.766991 -266.796266) (xy 91.084903 -266.796266) (xy 91.088998 -266.745538) (xy 91.101177 -266.696124)
			(xy 91.121125 -266.649304) (xy 91.148326 -266.60629) (xy 91.182074 -266.568196) (xy 91.221496 -266.536009)
			(xy 91.26557 -266.510563) (xy 91.313156 -266.492516) (xy 91.36302 -266.482336) (xy 91.413872 -266.480287)
			(xy 91.464393 -266.486421) (xy 91.513277 -266.500581) (xy 91.559256 -266.522398) (xy 91.60114 -266.551308)
			(xy 91.637844 -266.586563) (xy 91.668417 -266.627249) (xy 91.692068 -266.672312) (xy 91.708184 -266.720586)
			(xy 91.716348 -266.77082) (xy 91.71686 -266.796266) (xy 92.024703 -266.796266) (xy 92.028798 -266.745538)
			(xy 92.040977 -266.696124) (xy 92.060925 -266.649304) (xy 92.088126 -266.60629) (xy 92.121874 -266.568196)
			(xy 92.161296 -266.536009) (xy 92.20537 -266.510563) (xy 92.252956 -266.492516) (xy 92.30282 -266.482336)
			(xy 92.353672 -266.480287) (xy 92.404193 -266.486421) (xy 92.453077 -266.500581) (xy 92.499056 -266.522398)
			(xy 92.54094 -266.551308) (xy 92.577644 -266.586563) (xy 92.608217 -266.627249) (xy 92.631868 -266.672312)
			(xy 92.647984 -266.720586) (xy 92.656148 -266.77082) (xy 92.65666 -266.796266) (xy 92.975188 -266.796266)
			(xy 92.979148 -266.747212) (xy 92.990925 -266.699428) (xy 93.010216 -266.654152) (xy 93.036519 -266.612556)
			(xy 93.069154 -266.575719) (xy 93.107275 -266.544594) (xy 93.149896 -266.519987) (xy 93.195912 -266.502535)
			(xy 93.244131 -266.492691) (xy 93.293306 -266.49071) (xy 93.342161 -266.496642) (xy 93.389432 -266.510334)
			(xy 93.433894 -266.531432) (xy 93.474397 -266.559388) (xy 93.50989 -266.59348) (xy 93.539455 -266.632824)
			(xy 93.562326 -266.676401) (xy 93.57791 -266.723082) (xy 93.585805 -266.771659) (xy 93.5863 -266.796266)
			(xy 93.904811 -266.796266) (xy 93.908906 -266.745538) (xy 93.921085 -266.696124) (xy 93.941033 -266.649304)
			(xy 93.968234 -266.60629) (xy 94.001982 -266.568196) (xy 94.041404 -266.536009) (xy 94.085478 -266.510563)
			(xy 94.133064 -266.492516) (xy 94.182928 -266.482336) (xy 94.23378 -266.480287) (xy 94.284301 -266.486421)
			(xy 94.333185 -266.500581) (xy 94.379164 -266.522398) (xy 94.421048 -266.551308) (xy 94.457752 -266.586563)
			(xy 94.488325 -266.627249) (xy 94.511976 -266.672312) (xy 94.528092 -266.720586) (xy 94.536256 -266.77082)
			(xy 94.536768 -266.796266) (xy 94.855296 -266.796266) (xy 94.859256 -266.747212) (xy 94.871033 -266.699428)
			(xy 94.890324 -266.654152) (xy 94.916627 -266.612556) (xy 94.949262 -266.575719) (xy 94.987383 -266.544594)
			(xy 95.030004 -266.519987) (xy 95.07602 -266.502535) (xy 95.124239 -266.492691) (xy 95.173414 -266.49071)
			(xy 95.222269 -266.496642) (xy 95.26954 -266.510334) (xy 95.314002 -266.531432) (xy 95.354505 -266.559388)
			(xy 95.389998 -266.59348) (xy 95.419563 -266.632824) (xy 95.442434 -266.676401) (xy 95.458018 -266.723082)
			(xy 95.465913 -266.771659) (xy 95.466408 -266.796266) (xy 95.784919 -266.796266) (xy 95.789014 -266.745538)
			(xy 95.801193 -266.696124) (xy 95.821141 -266.649304) (xy 95.848342 -266.60629) (xy 95.88209 -266.568196)
			(xy 95.921512 -266.536009) (xy 95.965586 -266.510563) (xy 96.013172 -266.492516) (xy 96.063036 -266.482336)
			(xy 96.113888 -266.480287) (xy 96.164409 -266.486421) (xy 96.213293 -266.500581) (xy 96.259272 -266.522398)
			(xy 96.301156 -266.551308) (xy 96.33786 -266.586563) (xy 96.368433 -266.627249) (xy 96.392084 -266.672312)
			(xy 96.4082 -266.720586) (xy 96.416364 -266.77082) (xy 96.416876 -266.796266) (xy 97.675204 -266.796266)
			(xy 97.679164 -266.747212) (xy 97.690941 -266.699428) (xy 97.710232 -266.654152) (xy 97.736535 -266.612556)
			(xy 97.76917 -266.575719) (xy 97.807291 -266.544594) (xy 97.849912 -266.519987) (xy 97.895928 -266.502535)
			(xy 97.944147 -266.492691) (xy 97.993322 -266.49071) (xy 98.042177 -266.496642) (xy 98.089448 -266.510334)
			(xy 98.13391 -266.531432) (xy 98.174413 -266.559388) (xy 98.209906 -266.59348) (xy 98.239471 -266.632824)
			(xy 98.262342 -266.676401) (xy 98.277926 -266.723082) (xy 98.285821 -266.771659) (xy 98.286316 -266.796266)
			(xy 98.285821 -266.820873) (xy 98.277926 -266.86945) (xy 98.262342 -266.916131) (xy 98.239471 -266.959708)
			(xy 98.209906 -266.999052) (xy 98.174413 -267.033144) (xy 98.13391 -267.0611) (xy 98.089448 -267.082198)
			(xy 98.042177 -267.09589) (xy 97.993322 -267.101822) (xy 97.944147 -267.099841) (xy 97.895928 -267.089997)
			(xy 97.849912 -267.072545) (xy 97.807291 -267.047938) (xy 97.76917 -267.016813) (xy 97.736535 -266.979976)
			(xy 97.710232 -266.93838) (xy 97.690941 -266.893104) (xy 97.679164 -266.84532) (xy 97.675204 -266.796266)
			(xy 96.416876 -266.796266) (xy 96.416364 -266.821712) (xy 96.4082 -266.871946) (xy 96.392084 -266.92022)
			(xy 96.368433 -266.965283) (xy 96.33786 -267.005969) (xy 96.301156 -267.041224) (xy 96.259272 -267.070134)
			(xy 96.213293 -267.091951) (xy 96.164409 -267.106111) (xy 96.113888 -267.112245) (xy 96.063036 -267.110196)
			(xy 96.013172 -267.100016) (xy 95.965586 -267.081969) (xy 95.921512 -267.056523) (xy 95.88209 -267.024336)
			(xy 95.848342 -266.986242) (xy 95.821141 -266.943228) (xy 95.801193 -266.896408) (xy 95.789014 -266.846994)
			(xy 95.784919 -266.796266) (xy 95.466408 -266.796266) (xy 95.465913 -266.820873) (xy 95.458018 -266.86945)
			(xy 95.442434 -266.916131) (xy 95.419563 -266.959708) (xy 95.389998 -266.999052) (xy 95.354505 -267.033144)
			(xy 95.314002 -267.0611) (xy 95.26954 -267.082198) (xy 95.222269 -267.09589) (xy 95.173414 -267.101822)
			(xy 95.124239 -267.099841) (xy 95.07602 -267.089997) (xy 95.030004 -267.072545) (xy 94.987383 -267.047938)
			(xy 94.949262 -267.016813) (xy 94.916627 -266.979976) (xy 94.890324 -266.93838) (xy 94.871033 -266.893104)
			(xy 94.859256 -266.84532) (xy 94.855296 -266.796266) (xy 94.536768 -266.796266) (xy 94.536256 -266.821712)
			(xy 94.528092 -266.871946) (xy 94.511976 -266.92022) (xy 94.488325 -266.965283) (xy 94.457752 -267.005969)
			(xy 94.421048 -267.041224) (xy 94.379164 -267.070134) (xy 94.333185 -267.091951) (xy 94.284301 -267.106111)
			(xy 94.23378 -267.112245) (xy 94.182928 -267.110196) (xy 94.133064 -267.100016) (xy 94.085478 -267.081969)
			(xy 94.041404 -267.056523) (xy 94.001982 -267.024336) (xy 93.968234 -266.986242) (xy 93.941033 -266.943228)
			(xy 93.921085 -266.896408) (xy 93.908906 -266.846994) (xy 93.904811 -266.796266) (xy 93.5863 -266.796266)
			(xy 93.585805 -266.820873) (xy 93.57791 -266.86945) (xy 93.562326 -266.916131) (xy 93.539455 -266.959708)
			(xy 93.50989 -266.999052) (xy 93.474397 -267.033144) (xy 93.433894 -267.0611) (xy 93.389432 -267.082198)
			(xy 93.342161 -267.09589) (xy 93.293306 -267.101822) (xy 93.244131 -267.099841) (xy 93.195912 -267.089997)
			(xy 93.149896 -267.072545) (xy 93.107275 -267.047938) (xy 93.069154 -267.016813) (xy 93.036519 -266.979976)
			(xy 93.010216 -266.93838) (xy 92.990925 -266.893104) (xy 92.979148 -266.84532) (xy 92.975188 -266.796266)
			(xy 92.65666 -266.796266) (xy 92.656148 -266.821712) (xy 92.647984 -266.871946) (xy 92.631868 -266.92022)
			(xy 92.608217 -266.965283) (xy 92.577644 -267.005969) (xy 92.54094 -267.041224) (xy 92.499056 -267.070134)
			(xy 92.453077 -267.091951) (xy 92.404193 -267.106111) (xy 92.353672 -267.112245) (xy 92.30282 -267.110196)
			(xy 92.252956 -267.100016) (xy 92.20537 -267.081969) (xy 92.161296 -267.056523) (xy 92.121874 -267.024336)
			(xy 92.088126 -266.986242) (xy 92.060925 -266.943228) (xy 92.040977 -266.896408) (xy 92.028798 -266.846994)
			(xy 92.024703 -266.796266) (xy 91.71686 -266.796266) (xy 91.716348 -266.821712) (xy 91.708184 -266.871946)
			(xy 91.692068 -266.92022) (xy 91.668417 -266.965283) (xy 91.637844 -267.005969) (xy 91.60114 -267.041224)
			(xy 91.559256 -267.070134) (xy 91.513277 -267.091951) (xy 91.464393 -267.106111) (xy 91.413872 -267.112245)
			(xy 91.36302 -267.110196) (xy 91.313156 -267.100016) (xy 91.26557 -267.081969) (xy 91.221496 -267.056523)
			(xy 91.182074 -267.024336) (xy 91.148326 -266.986242) (xy 91.121125 -266.943228) (xy 91.101177 -266.896408)
			(xy 91.088998 -266.846994) (xy 91.084903 -266.796266) (xy 90.766991 -266.796266) (xy 90.766994 -266.7963)
			(xy 90.762822 -266.84665) (xy 90.750419 -266.895627) (xy 90.730123 -266.941894) (xy 90.702489 -266.984189)
			(xy 90.66827 -267.021359) (xy 90.6284 -267.05239) (xy 90.583965 -267.076434) (xy 90.536179 -267.092837)
			(xy 90.486345 -267.10115) (xy 90.461084 -267.101574) (xy 90.432525 -267.100933) (xy 90.376399 -267.090324)
			(xy 90.349578 -267.080492) (xy 90.339676 -267.077138) (xy 90.318809 -267.077918) (xy 90.309192 -267.082016)
			(xy 90.236802 -267.122148) (xy 90.228277 -267.127718) (xy 90.216214 -267.144102) (xy 90.213434 -267.153898)
			(xy 90.212926 -267.156184) (xy 90.21191 -267.161264) (xy 90.21191 -267.16228) (xy 90.204036 -267.194284)
			(xy 90.204036 -267.194792) (xy 90.180668 -267.282422) (xy 90.17 -267.318236) (xy 90.167711 -267.327511)
			(xy 90.169411 -267.346527) (xy 90.177905 -267.363625) (xy 90.184732 -267.370306) (xy 90.205221 -267.387878)
			(xy 90.240258 -267.428931) (xy 90.26753 -267.475505) (xy 90.286188 -267.52615) (xy 90.295648 -267.579286)
			(xy 90.296238 -267.606272) (xy 90.614749 -267.606272) (xy 90.618844 -267.555544) (xy 90.631023 -267.50613)
			(xy 90.650971 -267.45931) (xy 90.678172 -267.416296) (xy 90.71192 -267.378202) (xy 90.751342 -267.346015)
			(xy 90.795416 -267.320569) (xy 90.843002 -267.302522) (xy 90.892866 -267.292342) (xy 90.943718 -267.290293)
			(xy 90.994239 -267.296427) (xy 91.043123 -267.310587) (xy 91.089102 -267.332404) (xy 91.130986 -267.361314)
			(xy 91.16769 -267.396569) (xy 91.198263 -267.437255) (xy 91.221914 -267.482318) (xy 91.23803 -267.530592)
			(xy 91.246194 -267.580826) (xy 91.246706 -267.606272) (xy 91.565234 -267.606272) (xy 91.569194 -267.557218)
			(xy 91.580971 -267.509434) (xy 91.600262 -267.464158) (xy 91.626565 -267.422562) (xy 91.6592 -267.385725)
			(xy 91.697321 -267.3546) (xy 91.739942 -267.329993) (xy 91.785958 -267.312541) (xy 91.834177 -267.302697)
			(xy 91.883352 -267.300716) (xy 91.932207 -267.306648) (xy 91.979478 -267.32034) (xy 92.02394 -267.341438)
			(xy 92.064443 -267.369394) (xy 92.099936 -267.403486) (xy 92.129501 -267.44283) (xy 92.152372 -267.486407)
			(xy 92.167956 -267.533088) (xy 92.175851 -267.581665) (xy 92.176346 -267.606272) (xy 92.505288 -267.606272)
			(xy 92.509248 -267.557218) (xy 92.521025 -267.509434) (xy 92.540316 -267.464158) (xy 92.566619 -267.422562)
			(xy 92.599254 -267.385725) (xy 92.637375 -267.3546) (xy 92.679996 -267.329993) (xy 92.726012 -267.312541)
			(xy 92.774231 -267.302697) (xy 92.823406 -267.300716) (xy 92.872261 -267.306648) (xy 92.919532 -267.32034)
			(xy 92.963994 -267.341438) (xy 93.004497 -267.369394) (xy 93.03999 -267.403486) (xy 93.069555 -267.44283)
			(xy 93.092426 -267.486407) (xy 93.10801 -267.533088) (xy 93.115905 -267.581665) (xy 93.1164 -267.606272)
			(xy 93.445342 -267.606272) (xy 93.449302 -267.557218) (xy 93.461079 -267.509434) (xy 93.48037 -267.464158)
			(xy 93.506673 -267.422562) (xy 93.539308 -267.385725) (xy 93.577429 -267.3546) (xy 93.62005 -267.329993)
			(xy 93.666066 -267.312541) (xy 93.714285 -267.302697) (xy 93.76346 -267.300716) (xy 93.812315 -267.306648)
			(xy 93.859586 -267.32034) (xy 93.904048 -267.341438) (xy 93.944551 -267.369394) (xy 93.980044 -267.403486)
			(xy 94.009609 -267.44283) (xy 94.03248 -267.486407) (xy 94.048064 -267.533088) (xy 94.055959 -267.581665)
			(xy 94.056454 -267.606272) (xy 94.374711 -267.606272) (xy 94.378806 -267.555544) (xy 94.390985 -267.50613)
			(xy 94.410933 -267.45931) (xy 94.438134 -267.416296) (xy 94.471882 -267.378202) (xy 94.511304 -267.346015)
			(xy 94.555378 -267.320569) (xy 94.602964 -267.302522) (xy 94.652828 -267.292342) (xy 94.70368 -267.290293)
			(xy 94.754201 -267.296427) (xy 94.803085 -267.310587) (xy 94.849064 -267.332404) (xy 94.890948 -267.361314)
			(xy 94.927652 -267.396569) (xy 94.958225 -267.437255) (xy 94.981876 -267.482318) (xy 94.997992 -267.530592)
			(xy 95.006156 -267.580826) (xy 95.006668 -267.606272) (xy 95.325196 -267.606272) (xy 95.329156 -267.557218)
			(xy 95.340933 -267.509434) (xy 95.360224 -267.464158) (xy 95.386527 -267.422562) (xy 95.419162 -267.385725)
			(xy 95.457283 -267.3546) (xy 95.499904 -267.329993) (xy 95.54592 -267.312541) (xy 95.594139 -267.302697)
			(xy 95.643314 -267.300716) (xy 95.692169 -267.306648) (xy 95.73944 -267.32034) (xy 95.783902 -267.341438)
			(xy 95.824405 -267.369394) (xy 95.859898 -267.403486) (xy 95.889463 -267.44283) (xy 95.912334 -267.486407)
			(xy 95.927918 -267.533088) (xy 95.935813 -267.581665) (xy 95.936308 -267.606272) (xy 96.26525 -267.606272)
			(xy 96.26921 -267.557218) (xy 96.280987 -267.509434) (xy 96.300278 -267.464158) (xy 96.326581 -267.422562)
			(xy 96.359216 -267.385725) (xy 96.397337 -267.3546) (xy 96.439958 -267.329993) (xy 96.485974 -267.312541)
			(xy 96.534193 -267.302697) (xy 96.583368 -267.300716) (xy 96.632223 -267.306648) (xy 96.679494 -267.32034)
			(xy 96.723956 -267.341438) (xy 96.764459 -267.369394) (xy 96.799952 -267.403486) (xy 96.829517 -267.44283)
			(xy 96.852388 -267.486407) (xy 96.867972 -267.533088) (xy 96.875867 -267.581665) (xy 96.876362 -267.606272)
			(xy 97.205304 -267.606272) (xy 97.209264 -267.557218) (xy 97.221041 -267.509434) (xy 97.240332 -267.464158)
			(xy 97.266635 -267.422562) (xy 97.29927 -267.385725) (xy 97.337391 -267.3546) (xy 97.380012 -267.329993)
			(xy 97.426028 -267.312541) (xy 97.474247 -267.302697) (xy 97.523422 -267.300716) (xy 97.572277 -267.306648)
			(xy 97.619548 -267.32034) (xy 97.66401 -267.341438) (xy 97.704513 -267.369394) (xy 97.740006 -267.403486)
			(xy 97.769571 -267.44283) (xy 97.792442 -267.486407) (xy 97.808026 -267.533088) (xy 97.815921 -267.581665)
			(xy 97.816416 -267.606272) (xy 97.815921 -267.630879) (xy 97.808026 -267.679456) (xy 97.792442 -267.726137)
			(xy 97.769571 -267.769714) (xy 97.740006 -267.809058) (xy 97.704513 -267.84315) (xy 97.66401 -267.871106)
			(xy 97.619548 -267.892204) (xy 97.572277 -267.905896) (xy 97.523422 -267.911828) (xy 97.474247 -267.909847)
			(xy 97.426028 -267.900003) (xy 97.380012 -267.882551) (xy 97.337391 -267.857944) (xy 97.29927 -267.826819)
			(xy 97.266635 -267.789982) (xy 97.240332 -267.748386) (xy 97.221041 -267.70311) (xy 97.209264 -267.655326)
			(xy 97.205304 -267.606272) (xy 96.876362 -267.606272) (xy 96.875867 -267.630879) (xy 96.867972 -267.679456)
			(xy 96.852388 -267.726137) (xy 96.829517 -267.769714) (xy 96.799952 -267.809058) (xy 96.764459 -267.84315)
			(xy 96.723956 -267.871106) (xy 96.679494 -267.892204) (xy 96.632223 -267.905896) (xy 96.583368 -267.911828)
			(xy 96.534193 -267.909847) (xy 96.485974 -267.900003) (xy 96.439958 -267.882551) (xy 96.397337 -267.857944)
			(xy 96.359216 -267.826819) (xy 96.326581 -267.789982) (xy 96.300278 -267.748386) (xy 96.280987 -267.70311)
			(xy 96.26921 -267.655326) (xy 96.26525 -267.606272) (xy 95.936308 -267.606272) (xy 95.935813 -267.630879)
			(xy 95.927918 -267.679456) (xy 95.912334 -267.726137) (xy 95.889463 -267.769714) (xy 95.859898 -267.809058)
			(xy 95.824405 -267.84315) (xy 95.783902 -267.871106) (xy 95.73944 -267.892204) (xy 95.692169 -267.905896)
			(xy 95.643314 -267.911828) (xy 95.594139 -267.909847) (xy 95.54592 -267.900003) (xy 95.499904 -267.882551)
			(xy 95.457283 -267.857944) (xy 95.419162 -267.826819) (xy 95.386527 -267.789982) (xy 95.360224 -267.748386)
			(xy 95.340933 -267.70311) (xy 95.329156 -267.655326) (xy 95.325196 -267.606272) (xy 95.006668 -267.606272)
			(xy 95.006156 -267.631718) (xy 94.997992 -267.681952) (xy 94.981876 -267.730226) (xy 94.958225 -267.775289)
			(xy 94.927652 -267.815975) (xy 94.890948 -267.85123) (xy 94.849064 -267.88014) (xy 94.803085 -267.901957)
			(xy 94.754201 -267.916117) (xy 94.70368 -267.922251) (xy 94.652828 -267.920202) (xy 94.602964 -267.910022)
			(xy 94.555378 -267.891975) (xy 94.511304 -267.866529) (xy 94.471882 -267.834342) (xy 94.438134 -267.796248)
			(xy 94.410933 -267.753234) (xy 94.390985 -267.706414) (xy 94.378806 -267.657) (xy 94.374711 -267.606272)
			(xy 94.056454 -267.606272) (xy 94.055959 -267.630879) (xy 94.048064 -267.679456) (xy 94.03248 -267.726137)
			(xy 94.009609 -267.769714) (xy 93.980044 -267.809058) (xy 93.944551 -267.84315) (xy 93.904048 -267.871106)
			(xy 93.859586 -267.892204) (xy 93.812315 -267.905896) (xy 93.76346 -267.911828) (xy 93.714285 -267.909847)
			(xy 93.666066 -267.900003) (xy 93.62005 -267.882551) (xy 93.577429 -267.857944) (xy 93.539308 -267.826819)
			(xy 93.506673 -267.789982) (xy 93.48037 -267.748386) (xy 93.461079 -267.70311) (xy 93.449302 -267.655326)
			(xy 93.445342 -267.606272) (xy 93.1164 -267.606272) (xy 93.115905 -267.630879) (xy 93.10801 -267.679456)
			(xy 93.092426 -267.726137) (xy 93.069555 -267.769714) (xy 93.03999 -267.809058) (xy 93.004497 -267.84315)
			(xy 92.963994 -267.871106) (xy 92.919532 -267.892204) (xy 92.872261 -267.905896) (xy 92.823406 -267.911828)
			(xy 92.774231 -267.909847) (xy 92.726012 -267.900003) (xy 92.679996 -267.882551) (xy 92.637375 -267.857944)
			(xy 92.599254 -267.826819) (xy 92.566619 -267.789982) (xy 92.540316 -267.748386) (xy 92.521025 -267.70311)
			(xy 92.509248 -267.655326) (xy 92.505288 -267.606272) (xy 92.176346 -267.606272) (xy 92.175851 -267.630879)
			(xy 92.167956 -267.679456) (xy 92.152372 -267.726137) (xy 92.129501 -267.769714) (xy 92.099936 -267.809058)
			(xy 92.064443 -267.84315) (xy 92.02394 -267.871106) (xy 91.979478 -267.892204) (xy 91.932207 -267.905896)
			(xy 91.883352 -267.911828) (xy 91.834177 -267.909847) (xy 91.785958 -267.900003) (xy 91.739942 -267.882551)
			(xy 91.697321 -267.857944) (xy 91.6592 -267.826819) (xy 91.626565 -267.789982) (xy 91.600262 -267.748386)
			(xy 91.580971 -267.70311) (xy 91.569194 -267.655326) (xy 91.565234 -267.606272) (xy 91.246706 -267.606272)
			(xy 91.246194 -267.631718) (xy 91.23803 -267.681952) (xy 91.221914 -267.730226) (xy 91.198263 -267.775289)
			(xy 91.16769 -267.815975) (xy 91.130986 -267.85123) (xy 91.089102 -267.88014) (xy 91.043123 -267.901957)
			(xy 90.994239 -267.916117) (xy 90.943718 -267.922251) (xy 90.892866 -267.920202) (xy 90.843002 -267.910022)
			(xy 90.795416 -267.891975) (xy 90.751342 -267.866529) (xy 90.71192 -267.834342) (xy 90.678172 -267.796248)
			(xy 90.650971 -267.753234) (xy 90.631023 -267.706414) (xy 90.618844 -267.657) (xy 90.614749 -267.606272)
			(xy 90.296238 -267.606272) (xy 90.295769 -267.630266) (xy 90.288267 -267.677662) (xy 90.273443 -267.723302)
			(xy 90.251661 -267.766061) (xy 90.223459 -267.804886) (xy 90.18953 -267.838821) (xy 90.15071 -267.867031)
			(xy 90.107956 -267.88882) (xy 90.062319 -267.903654) (xy 90.014923 -267.911165) (xy 89.99093 -267.91158)
			(xy 89.966926 -267.911113) (xy 89.919506 -267.903615) (xy 89.87384 -267.888798) (xy 89.852246 -267.878306)
			(xy 89.846819 -267.875724) (xy 89.835139 -267.872902) (xy 89.829132 -267.872718) (xy 89.806272 -267.872718)
			(xy 89.799527 -267.872959) (xy 89.786523 -267.876562) (xy 89.780618 -267.87983) (xy 89.716102 -267.917676)
			(xy 89.708666 -267.922434) (xy 89.697347 -267.935965) (xy 89.69132 -267.952544) (xy 89.690956 -267.961364)
			(xy 89.690956 -268.12494) (xy 89.691103 -268.130665) (xy 89.693663 -268.141826) (xy 89.696036 -268.147038)
			(xy 89.705434 -268.166342) (xy 89.707835 -268.171012) (xy 89.714233 -268.179337) (xy 89.718134 -268.182852)
			(xy 89.718388 -268.183106) (xy 89.736502 -268.199051) (xy 89.767959 -268.235643) (xy 89.793276 -268.276724)
			(xy 89.811823 -268.321272) (xy 89.823139 -268.368181) (xy 89.826944 -268.416278) (xy 90.15528 -268.416278)
			(xy 90.15924 -268.367224) (xy 90.171017 -268.31944) (xy 90.190308 -268.274164) (xy 90.216611 -268.232568)
			(xy 90.249246 -268.195731) (xy 90.287367 -268.164606) (xy 90.329988 -268.139999) (xy 90.376004 -268.122547)
			(xy 90.424223 -268.112703) (xy 90.473398 -268.110722) (xy 90.522253 -268.116654) (xy 90.569524 -268.130346)
			(xy 90.613986 -268.151444) (xy 90.654489 -268.1794) (xy 90.689982 -268.213492) (xy 90.719547 -268.252836)
			(xy 90.742418 -268.296413) (xy 90.758002 -268.343094) (xy 90.765897 -268.391671) (xy 90.766392 -268.416278)
			(xy 91.095334 -268.416278) (xy 91.099294 -268.367224) (xy 91.111071 -268.31944) (xy 91.130362 -268.274164)
			(xy 91.156665 -268.232568) (xy 91.1893 -268.195731) (xy 91.227421 -268.164606) (xy 91.270042 -268.139999)
			(xy 91.316058 -268.122547) (xy 91.364277 -268.112703) (xy 91.413452 -268.110722) (xy 91.462307 -268.116654)
			(xy 91.509578 -268.130346) (xy 91.55404 -268.151444) (xy 91.594543 -268.1794) (xy 91.630036 -268.213492)
			(xy 91.659601 -268.252836) (xy 91.682472 -268.296413) (xy 91.698056 -268.343094) (xy 91.705951 -268.391671)
			(xy 91.706446 -268.416278) (xy 92.035134 -268.416278) (xy 92.039094 -268.367224) (xy 92.050871 -268.31944)
			(xy 92.070162 -268.274164) (xy 92.096465 -268.232568) (xy 92.1291 -268.195731) (xy 92.167221 -268.164606)
			(xy 92.209842 -268.139999) (xy 92.255858 -268.122547) (xy 92.304077 -268.112703) (xy 92.353252 -268.110722)
			(xy 92.402107 -268.116654) (xy 92.449378 -268.130346) (xy 92.49384 -268.151444) (xy 92.534343 -268.1794)
			(xy 92.569836 -268.213492) (xy 92.599401 -268.252836) (xy 92.622272 -268.296413) (xy 92.637856 -268.343094)
			(xy 92.645751 -268.391671) (xy 92.646246 -268.416278) (xy 93.915242 -268.416278) (xy 93.919202 -268.367224)
			(xy 93.930979 -268.31944) (xy 93.95027 -268.274164) (xy 93.976573 -268.232568) (xy 94.009208 -268.195731)
			(xy 94.047329 -268.164606) (xy 94.08995 -268.139999) (xy 94.135966 -268.122547) (xy 94.184185 -268.112703)
			(xy 94.23336 -268.110722) (xy 94.282215 -268.116654) (xy 94.329486 -268.130346) (xy 94.373948 -268.151444)
			(xy 94.414451 -268.1794) (xy 94.449944 -268.213492) (xy 94.479509 -268.252836) (xy 94.50238 -268.296413)
			(xy 94.517964 -268.343094) (xy 94.525859 -268.391671) (xy 94.526354 -268.416278) (xy 94.855296 -268.416278)
			(xy 94.859256 -268.367224) (xy 94.871033 -268.31944) (xy 94.890324 -268.274164) (xy 94.916627 -268.232568)
			(xy 94.949262 -268.195731) (xy 94.987383 -268.164606) (xy 95.030004 -268.139999) (xy 95.07602 -268.122547)
			(xy 95.124239 -268.112703) (xy 95.173414 -268.110722) (xy 95.222269 -268.116654) (xy 95.26954 -268.130346)
			(xy 95.314002 -268.151444) (xy 95.354505 -268.1794) (xy 95.389998 -268.213492) (xy 95.419563 -268.252836)
			(xy 95.442434 -268.296413) (xy 95.458018 -268.343094) (xy 95.465913 -268.391671) (xy 95.466408 -268.416278)
			(xy 95.79535 -268.416278) (xy 95.79931 -268.367224) (xy 95.811087 -268.31944) (xy 95.830378 -268.274164)
			(xy 95.856681 -268.232568) (xy 95.889316 -268.195731) (xy 95.927437 -268.164606) (xy 95.970058 -268.139999)
			(xy 96.016074 -268.122547) (xy 96.064293 -268.112703) (xy 96.113468 -268.110722) (xy 96.162323 -268.116654)
			(xy 96.209594 -268.130346) (xy 96.254056 -268.151444) (xy 96.294559 -268.1794) (xy 96.330052 -268.213492)
			(xy 96.359617 -268.252836) (xy 96.382488 -268.296413) (xy 96.398072 -268.343094) (xy 96.405967 -268.391671)
			(xy 96.406462 -268.416278) (xy 96.405967 -268.440885) (xy 96.398072 -268.489462) (xy 96.382488 -268.536143)
			(xy 96.359617 -268.57972) (xy 96.330052 -268.619064) (xy 96.294559 -268.653156) (xy 96.254056 -268.681112)
			(xy 96.209594 -268.70221) (xy 96.162323 -268.715902) (xy 96.113468 -268.721834) (xy 96.064293 -268.719853)
			(xy 96.016074 -268.710009) (xy 95.970058 -268.692557) (xy 95.927437 -268.66795) (xy 95.889316 -268.636825)
			(xy 95.856681 -268.599988) (xy 95.830378 -268.558392) (xy 95.811087 -268.513116) (xy 95.79931 -268.465332)
			(xy 95.79535 -268.416278) (xy 95.466408 -268.416278) (xy 95.465913 -268.440885) (xy 95.458018 -268.489462)
			(xy 95.442434 -268.536143) (xy 95.419563 -268.57972) (xy 95.389998 -268.619064) (xy 95.354505 -268.653156)
			(xy 95.314002 -268.681112) (xy 95.26954 -268.70221) (xy 95.222269 -268.715902) (xy 95.173414 -268.721834)
			(xy 95.124239 -268.719853) (xy 95.07602 -268.710009) (xy 95.030004 -268.692557) (xy 94.987383 -268.66795)
			(xy 94.949262 -268.636825) (xy 94.916627 -268.599988) (xy 94.890324 -268.558392) (xy 94.871033 -268.513116)
			(xy 94.859256 -268.465332) (xy 94.855296 -268.416278) (xy 94.526354 -268.416278) (xy 94.525859 -268.440885)
			(xy 94.517964 -268.489462) (xy 94.50238 -268.536143) (xy 94.479509 -268.57972) (xy 94.449944 -268.619064)
			(xy 94.414451 -268.653156) (xy 94.373948 -268.681112) (xy 94.329486 -268.70221) (xy 94.282215 -268.715902)
			(xy 94.23336 -268.721834) (xy 94.184185 -268.719853) (xy 94.135966 -268.710009) (xy 94.08995 -268.692557)
			(xy 94.047329 -268.66795) (xy 94.009208 -268.636825) (xy 93.976573 -268.599988) (xy 93.95027 -268.558392)
			(xy 93.930979 -268.513116) (xy 93.919202 -268.465332) (xy 93.915242 -268.416278) (xy 92.646246 -268.416278)
			(xy 92.645751 -268.440885) (xy 92.637856 -268.489462) (xy 92.622272 -268.536143) (xy 92.599401 -268.57972)
			(xy 92.569836 -268.619064) (xy 92.534343 -268.653156) (xy 92.49384 -268.681112) (xy 92.449378 -268.70221)
			(xy 92.402107 -268.715902) (xy 92.353252 -268.721834) (xy 92.304077 -268.719853) (xy 92.255858 -268.710009)
			(xy 92.209842 -268.692557) (xy 92.167221 -268.66795) (xy 92.1291 -268.636825) (xy 92.096465 -268.599988)
			(xy 92.070162 -268.558392) (xy 92.050871 -268.513116) (xy 92.039094 -268.465332) (xy 92.035134 -268.416278)
			(xy 91.706446 -268.416278) (xy 91.705951 -268.440885) (xy 91.698056 -268.489462) (xy 91.682472 -268.536143)
			(xy 91.659601 -268.57972) (xy 91.630036 -268.619064) (xy 91.594543 -268.653156) (xy 91.55404 -268.681112)
			(xy 91.509578 -268.70221) (xy 91.462307 -268.715902) (xy 91.413452 -268.721834) (xy 91.364277 -268.719853)
			(xy 91.316058 -268.710009) (xy 91.270042 -268.692557) (xy 91.227421 -268.66795) (xy 91.1893 -268.636825)
			(xy 91.156665 -268.599988) (xy 91.130362 -268.558392) (xy 91.111071 -268.513116) (xy 91.099294 -268.465332)
			(xy 91.095334 -268.416278) (xy 90.766392 -268.416278) (xy 90.765897 -268.440885) (xy 90.758002 -268.489462)
			(xy 90.742418 -268.536143) (xy 90.719547 -268.57972) (xy 90.689982 -268.619064) (xy 90.654489 -268.653156)
			(xy 90.613986 -268.681112) (xy 90.569524 -268.70221) (xy 90.522253 -268.715902) (xy 90.473398 -268.721834)
			(xy 90.424223 -268.719853) (xy 90.376004 -268.710009) (xy 90.329988 -268.692557) (xy 90.287367 -268.66795)
			(xy 90.249246 -268.636825) (xy 90.216611 -268.599988) (xy 90.190308 -268.558392) (xy 90.171017 -268.513116)
			(xy 90.15924 -268.465332) (xy 90.15528 -268.416278) (xy 89.826944 -268.416278) (xy 89.826945 -268.416286)
			(xy 89.823144 -268.464391) (xy 89.811831 -268.511301) (xy 89.793289 -268.555851) (xy 89.767976 -268.596934)
			(xy 89.736522 -268.633529) (xy 89.718388 -268.64945) (xy 89.718134 -268.649704) (xy 89.714227 -268.653215)
			(xy 89.707821 -268.661535) (xy 89.705434 -268.666214) (xy 89.696036 -268.685518) (xy 89.693696 -268.690741)
			(xy 89.691141 -268.701895) (xy 89.690956 -268.707616) (xy 89.690956 -268.871192) (xy 89.691371 -268.880004)
			(xy 89.697407 -268.896568) (xy 89.708672 -268.910128) (xy 89.716102 -268.91488) (xy 89.754456 -268.937486)
			(xy 89.79408 -268.9606) (xy 89.805431 -268.965784) (xy 89.830353 -268.965538) (xy 89.841578 -268.960092)
			(xy 89.842086 -268.959838) (xy 89.864972 -268.947621) (xy 89.91387 -268.9303) (xy 89.964993 -268.921498)
			(xy 89.99093 -268.920976) (xy 90.01492 -268.921449) (xy 90.062309 -268.928959) (xy 90.10794 -268.943788)
			(xy 90.15069 -268.965573) (xy 90.189506 -268.993777) (xy 90.223432 -269.027705) (xy 90.251634 -269.066522)
			(xy 90.273417 -269.109273) (xy 90.288245 -269.154904) (xy 90.295752 -269.202294) (xy 90.296238 -269.226284)
			(xy 90.614749 -269.226284) (xy 90.618844 -269.175556) (xy 90.631023 -269.126142) (xy 90.650971 -269.079322)
			(xy 90.678172 -269.036308) (xy 90.71192 -268.998214) (xy 90.751342 -268.966027) (xy 90.795416 -268.940581)
			(xy 90.843002 -268.922534) (xy 90.892866 -268.912354) (xy 90.943718 -268.910305) (xy 90.994239 -268.916439)
			(xy 91.043123 -268.930599) (xy 91.089102 -268.952416) (xy 91.130986 -268.981326) (xy 91.16769 -269.016581)
			(xy 91.198263 -269.057267) (xy 91.221914 -269.10233) (xy 91.23803 -269.150604) (xy 91.246194 -269.200838)
			(xy 91.246706 -269.226284) (xy 91.565234 -269.226284) (xy 91.569194 -269.17723) (xy 91.580971 -269.129446)
			(xy 91.600262 -269.08417) (xy 91.626565 -269.042574) (xy 91.6592 -269.005737) (xy 91.697321 -268.974612)
			(xy 91.739942 -268.950005) (xy 91.785958 -268.932553) (xy 91.834177 -268.922709) (xy 91.883352 -268.920728)
			(xy 91.932207 -268.92666) (xy 91.979478 -268.940352) (xy 92.02394 -268.96145) (xy 92.064443 -268.989406)
			(xy 92.099936 -269.023498) (xy 92.129501 -269.062842) (xy 92.152372 -269.106419) (xy 92.167956 -269.1531)
			(xy 92.175851 -269.201677) (xy 92.176346 -269.226284) (xy 92.505288 -269.226284) (xy 92.509248 -269.17723)
			(xy 92.521025 -269.129446) (xy 92.540316 -269.08417) (xy 92.566619 -269.042574) (xy 92.599254 -269.005737)
			(xy 92.637375 -268.974612) (xy 92.679996 -268.950005) (xy 92.726012 -268.932553) (xy 92.774231 -268.922709)
			(xy 92.823406 -268.920728) (xy 92.872261 -268.92666) (xy 92.919532 -268.940352) (xy 92.963994 -268.96145)
			(xy 93.004497 -268.989406) (xy 93.03999 -269.023498) (xy 93.069555 -269.062842) (xy 93.092426 -269.106419)
			(xy 93.10801 -269.1531) (xy 93.115905 -269.201677) (xy 93.1164 -269.226284) (xy 93.445342 -269.226284)
			(xy 93.449302 -269.17723) (xy 93.461079 -269.129446) (xy 93.48037 -269.08417) (xy 93.506673 -269.042574)
			(xy 93.539308 -269.005737) (xy 93.577429 -268.974612) (xy 93.62005 -268.950005) (xy 93.666066 -268.932553)
			(xy 93.714285 -268.922709) (xy 93.76346 -268.920728) (xy 93.812315 -268.92666) (xy 93.859586 -268.940352)
			(xy 93.904048 -268.96145) (xy 93.944551 -268.989406) (xy 93.980044 -269.023498) (xy 94.009609 -269.062842)
			(xy 94.03248 -269.106419) (xy 94.048064 -269.1531) (xy 94.055959 -269.201677) (xy 94.056454 -269.226284)
			(xy 94.374711 -269.226284) (xy 94.378806 -269.175556) (xy 94.390985 -269.126142) (xy 94.410933 -269.079322)
			(xy 94.438134 -269.036308) (xy 94.471882 -268.998214) (xy 94.511304 -268.966027) (xy 94.555378 -268.940581)
			(xy 94.602964 -268.922534) (xy 94.652828 -268.912354) (xy 94.70368 -268.910305) (xy 94.754201 -268.916439)
			(xy 94.803085 -268.930599) (xy 94.849064 -268.952416) (xy 94.890948 -268.981326) (xy 94.927652 -269.016581)
			(xy 94.958225 -269.057267) (xy 94.981876 -269.10233) (xy 94.997992 -269.150604) (xy 95.006156 -269.200838)
			(xy 95.006668 -269.226284) (xy 95.325196 -269.226284) (xy 95.329156 -269.17723) (xy 95.340933 -269.129446)
			(xy 95.360224 -269.08417) (xy 95.386527 -269.042574) (xy 95.419162 -269.005737) (xy 95.457283 -268.974612)
			(xy 95.499904 -268.950005) (xy 95.54592 -268.932553) (xy 95.594139 -268.922709) (xy 95.643314 -268.920728)
			(xy 95.692169 -268.92666) (xy 95.73944 -268.940352) (xy 95.783902 -268.96145) (xy 95.824405 -268.989406)
			(xy 95.859898 -269.023498) (xy 95.889463 -269.062842) (xy 95.912334 -269.106419) (xy 95.927918 -269.1531)
			(xy 95.935813 -269.201677) (xy 95.936308 -269.226284) (xy 96.26525 -269.226284) (xy 96.26921 -269.17723)
			(xy 96.280987 -269.129446) (xy 96.300278 -269.08417) (xy 96.326581 -269.042574) (xy 96.359216 -269.005737)
			(xy 96.397337 -268.974612) (xy 96.439958 -268.950005) (xy 96.485974 -268.932553) (xy 96.534193 -268.922709)
			(xy 96.583368 -268.920728) (xy 96.632223 -268.92666) (xy 96.679494 -268.940352) (xy 96.723956 -268.96145)
			(xy 96.764459 -268.989406) (xy 96.799952 -269.023498) (xy 96.829517 -269.062842) (xy 96.852388 -269.106419)
			(xy 96.867972 -269.1531) (xy 96.875867 -269.201677) (xy 96.876362 -269.226284) (xy 96.875867 -269.250891)
			(xy 96.867972 -269.299468) (xy 96.852388 -269.346149) (xy 96.829517 -269.389726) (xy 96.799952 -269.42907)
			(xy 96.764459 -269.463162) (xy 96.723956 -269.491118) (xy 96.679494 -269.512216) (xy 96.632223 -269.525908)
			(xy 96.583368 -269.53184) (xy 96.534193 -269.529859) (xy 96.485974 -269.520015) (xy 96.439958 -269.502563)
			(xy 96.397337 -269.477956) (xy 96.359216 -269.446831) (xy 96.326581 -269.409994) (xy 96.300278 -269.368398)
			(xy 96.280987 -269.323122) (xy 96.26921 -269.275338) (xy 96.26525 -269.226284) (xy 95.936308 -269.226284)
			(xy 95.935813 -269.250891) (xy 95.927918 -269.299468) (xy 95.912334 -269.346149) (xy 95.889463 -269.389726)
			(xy 95.859898 -269.42907) (xy 95.824405 -269.463162) (xy 95.783902 -269.491118) (xy 95.73944 -269.512216)
			(xy 95.692169 -269.525908) (xy 95.643314 -269.53184) (xy 95.594139 -269.529859) (xy 95.54592 -269.520015)
			(xy 95.499904 -269.502563) (xy 95.457283 -269.477956) (xy 95.419162 -269.446831) (xy 95.386527 -269.409994)
			(xy 95.360224 -269.368398) (xy 95.340933 -269.323122) (xy 95.329156 -269.275338) (xy 95.325196 -269.226284)
			(xy 95.006668 -269.226284) (xy 95.006156 -269.25173) (xy 94.997992 -269.301964) (xy 94.981876 -269.350238)
			(xy 94.958225 -269.395301) (xy 94.927652 -269.435987) (xy 94.890948 -269.471242) (xy 94.849064 -269.500152)
			(xy 94.803085 -269.521969) (xy 94.754201 -269.536129) (xy 94.70368 -269.542263) (xy 94.652828 -269.540214)
			(xy 94.602964 -269.530034) (xy 94.555378 -269.511987) (xy 94.511304 -269.486541) (xy 94.471882 -269.454354)
			(xy 94.438134 -269.41626) (xy 94.410933 -269.373246) (xy 94.390985 -269.326426) (xy 94.378806 -269.277012)
			(xy 94.374711 -269.226284) (xy 94.056454 -269.226284) (xy 94.055959 -269.250891) (xy 94.048064 -269.299468)
			(xy 94.03248 -269.346149) (xy 94.009609 -269.389726) (xy 93.980044 -269.42907) (xy 93.944551 -269.463162)
			(xy 93.904048 -269.491118) (xy 93.859586 -269.512216) (xy 93.812315 -269.525908) (xy 93.76346 -269.53184)
			(xy 93.714285 -269.529859) (xy 93.666066 -269.520015) (xy 93.62005 -269.502563) (xy 93.577429 -269.477956)
			(xy 93.539308 -269.446831) (xy 93.506673 -269.409994) (xy 93.48037 -269.368398) (xy 93.461079 -269.323122)
			(xy 93.449302 -269.275338) (xy 93.445342 -269.226284) (xy 93.1164 -269.226284) (xy 93.115905 -269.250891)
			(xy 93.10801 -269.299468) (xy 93.092426 -269.346149) (xy 93.069555 -269.389726) (xy 93.03999 -269.42907)
			(xy 93.004497 -269.463162) (xy 92.963994 -269.491118) (xy 92.919532 -269.512216) (xy 92.872261 -269.525908)
			(xy 92.823406 -269.53184) (xy 92.774231 -269.529859) (xy 92.726012 -269.520015) (xy 92.679996 -269.502563)
			(xy 92.637375 -269.477956) (xy 92.599254 -269.446831) (xy 92.566619 -269.409994) (xy 92.540316 -269.368398)
			(xy 92.521025 -269.323122) (xy 92.509248 -269.275338) (xy 92.505288 -269.226284) (xy 92.176346 -269.226284)
			(xy 92.175851 -269.250891) (xy 92.167956 -269.299468) (xy 92.152372 -269.346149) (xy 92.129501 -269.389726)
			(xy 92.099936 -269.42907) (xy 92.064443 -269.463162) (xy 92.02394 -269.491118) (xy 91.979478 -269.512216)
			(xy 91.932207 -269.525908) (xy 91.883352 -269.53184) (xy 91.834177 -269.529859) (xy 91.785958 -269.520015)
			(xy 91.739942 -269.502563) (xy 91.697321 -269.477956) (xy 91.6592 -269.446831) (xy 91.626565 -269.409994)
			(xy 91.600262 -269.368398) (xy 91.580971 -269.323122) (xy 91.569194 -269.275338) (xy 91.565234 -269.226284)
			(xy 91.246706 -269.226284) (xy 91.246194 -269.25173) (xy 91.23803 -269.301964) (xy 91.221914 -269.350238)
			(xy 91.198263 -269.395301) (xy 91.16769 -269.435987) (xy 91.130986 -269.471242) (xy 91.089102 -269.500152)
			(xy 91.043123 -269.521969) (xy 90.994239 -269.536129) (xy 90.943718 -269.542263) (xy 90.892866 -269.540214)
			(xy 90.843002 -269.530034) (xy 90.795416 -269.511987) (xy 90.751342 -269.486541) (xy 90.71192 -269.454354)
			(xy 90.678172 -269.41626) (xy 90.650971 -269.373246) (xy 90.631023 -269.326426) (xy 90.618844 -269.277012)
			(xy 90.614749 -269.226284) (xy 90.296238 -269.226284) (xy 90.295753 -269.251106) (xy 90.287725 -269.300096)
			(xy 90.271877 -269.347143) (xy 90.248627 -269.391005) (xy 90.218587 -269.430529) (xy 90.182549 -269.464673)
			(xy 90.141463 -269.492537) (xy 90.096409 -269.513387) (xy 90.048577 -269.526674) (xy 90.02395 -269.529814)
			(xy 90.023696 -269.529814) (xy 90.016991 -269.530734) (xy 90.004375 -269.535623) (xy 89.998804 -269.539466)
			(xy 89.993724 -269.54353) (xy 89.985342 -269.553944) (xy 89.948004 -269.64259) (xy 89.945533 -269.649017)
			(xy 89.943736 -269.662665) (xy 89.944448 -269.669514) (xy 89.946226 -269.682722) (xy 89.954862 -269.693644)
			(xy 89.979728 -269.726341) (xy 90.020533 -269.797632) (xy 90.036142 -269.83563) (xy 90.036142 -269.835884)
			(xy 90.038781 -269.842065) (xy 90.046772 -269.852863) (xy 90.05189 -269.85722) (xy 90.063066 -269.865856)
			(xy 90.075512 -269.86738) (xy 90.165682 -269.87881) (xy 90.172562 -269.879412) (xy 90.186214 -269.87736)
			(xy 90.192606 -269.874746) (xy 90.198448 -269.872206) (xy 90.208862 -269.863824) (xy 90.21318 -269.857982)
			(xy 90.227645 -269.838683) (xy 90.261634 -269.804467) (xy 90.300574 -269.776013) (xy 90.343499 -269.754026)
			(xy 90.389343 -269.739051) (xy 90.43697 -269.73146) (xy 90.461084 -269.730982) (xy 90.486343 -269.731473)
			(xy 90.536174 -269.739786) (xy 90.583956 -269.756188) (xy 90.628387 -269.78023) (xy 90.668254 -269.811258)
			(xy 90.70247 -269.848425) (xy 90.730102 -269.890718) (xy 90.750396 -269.936981) (xy 90.762798 -269.985954)
			(xy 90.766969 -270.03629) (xy 91.084903 -270.03629) (xy 91.088998 -269.985562) (xy 91.101177 -269.936148)
			(xy 91.121125 -269.889328) (xy 91.148326 -269.846314) (xy 91.182074 -269.80822) (xy 91.221496 -269.776033)
			(xy 91.26557 -269.750587) (xy 91.313156 -269.73254) (xy 91.36302 -269.72236) (xy 91.413872 -269.720311)
			(xy 91.464393 -269.726445) (xy 91.513277 -269.740605) (xy 91.559256 -269.762422) (xy 91.60114 -269.791332)
			(xy 91.637844 -269.826587) (xy 91.668417 -269.867273) (xy 91.692068 -269.912336) (xy 91.708184 -269.96061)
			(xy 91.716348 -270.010844) (xy 91.71686 -270.03629) (xy 92.024703 -270.03629) (xy 92.028798 -269.985562)
			(xy 92.040977 -269.936148) (xy 92.060925 -269.889328) (xy 92.088126 -269.846314) (xy 92.121874 -269.80822)
			(xy 92.161296 -269.776033) (xy 92.20537 -269.750587) (xy 92.252956 -269.73254) (xy 92.30282 -269.72236)
			(xy 92.353672 -269.720311) (xy 92.404193 -269.726445) (xy 92.453077 -269.740605) (xy 92.499056 -269.762422)
			(xy 92.54094 -269.791332) (xy 92.577644 -269.826587) (xy 92.608217 -269.867273) (xy 92.631868 -269.912336)
			(xy 92.647984 -269.96061) (xy 92.656148 -270.010844) (xy 92.65666 -270.03629) (xy 92.975188 -270.03629)
			(xy 92.979148 -269.987236) (xy 92.990925 -269.939452) (xy 93.010216 -269.894176) (xy 93.036519 -269.85258)
			(xy 93.069154 -269.815743) (xy 93.107275 -269.784618) (xy 93.149896 -269.760011) (xy 93.195912 -269.742559)
			(xy 93.244131 -269.732715) (xy 93.293306 -269.730734) (xy 93.342161 -269.736666) (xy 93.389432 -269.750358)
			(xy 93.433894 -269.771456) (xy 93.474397 -269.799412) (xy 93.50989 -269.833504) (xy 93.539455 -269.872848)
			(xy 93.562326 -269.916425) (xy 93.57791 -269.963106) (xy 93.585805 -270.011683) (xy 93.5863 -270.03629)
			(xy 93.904811 -270.03629) (xy 93.908906 -269.985562) (xy 93.921085 -269.936148) (xy 93.941033 -269.889328)
			(xy 93.968234 -269.846314) (xy 94.001982 -269.80822) (xy 94.041404 -269.776033) (xy 94.085478 -269.750587)
			(xy 94.133064 -269.73254) (xy 94.182928 -269.72236) (xy 94.23378 -269.720311) (xy 94.284301 -269.726445)
			(xy 94.333185 -269.740605) (xy 94.379164 -269.762422) (xy 94.421048 -269.791332) (xy 94.457752 -269.826587)
			(xy 94.488325 -269.867273) (xy 94.511976 -269.912336) (xy 94.528092 -269.96061) (xy 94.536256 -270.010844)
			(xy 94.536768 -270.03629) (xy 94.855296 -270.03629) (xy 94.859256 -269.987236) (xy 94.871033 -269.939452)
			(xy 94.890324 -269.894176) (xy 94.916627 -269.85258) (xy 94.949262 -269.815743) (xy 94.987383 -269.784618)
			(xy 95.030004 -269.760011) (xy 95.07602 -269.742559) (xy 95.124239 -269.732715) (xy 95.173414 -269.730734)
			(xy 95.222269 -269.736666) (xy 95.26954 -269.750358) (xy 95.314002 -269.771456) (xy 95.354505 -269.799412)
			(xy 95.389998 -269.833504) (xy 95.419563 -269.872848) (xy 95.442434 -269.916425) (xy 95.458018 -269.963106)
			(xy 95.465913 -270.011683) (xy 95.466408 -270.03629) (xy 95.784919 -270.03629) (xy 95.789014 -269.985562)
			(xy 95.801193 -269.936148) (xy 95.821141 -269.889328) (xy 95.848342 -269.846314) (xy 95.88209 -269.80822)
			(xy 95.921512 -269.776033) (xy 95.965586 -269.750587) (xy 96.013172 -269.73254) (xy 96.063036 -269.72236)
			(xy 96.113888 -269.720311) (xy 96.164409 -269.726445) (xy 96.213293 -269.740605) (xy 96.259272 -269.762422)
			(xy 96.301156 -269.791332) (xy 96.33786 -269.826587) (xy 96.368433 -269.867273) (xy 96.392084 -269.912336)
			(xy 96.4082 -269.96061) (xy 96.416364 -270.010844) (xy 96.416876 -270.03629) (xy 96.416364 -270.061736)
			(xy 96.4082 -270.11197) (xy 96.392084 -270.160244) (xy 96.368433 -270.205307) (xy 96.33786 -270.245993)
			(xy 96.301156 -270.281248) (xy 96.259272 -270.310158) (xy 96.213293 -270.331975) (xy 96.164409 -270.346135)
			(xy 96.113888 -270.352269) (xy 96.063036 -270.35022) (xy 96.013172 -270.34004) (xy 95.965586 -270.321993)
			(xy 95.921512 -270.296547) (xy 95.88209 -270.26436) (xy 95.848342 -270.226266) (xy 95.821141 -270.183252)
			(xy 95.801193 -270.136432) (xy 95.789014 -270.087018) (xy 95.784919 -270.03629) (xy 95.466408 -270.03629)
			(xy 95.465913 -270.060897) (xy 95.458018 -270.109474) (xy 95.442434 -270.156155) (xy 95.419563 -270.199732)
			(xy 95.389998 -270.239076) (xy 95.354505 -270.273168) (xy 95.314002 -270.301124) (xy 95.26954 -270.322222)
			(xy 95.222269 -270.335914) (xy 95.173414 -270.341846) (xy 95.124239 -270.339865) (xy 95.07602 -270.330021)
			(xy 95.030004 -270.312569) (xy 94.987383 -270.287962) (xy 94.949262 -270.256837) (xy 94.916627 -270.22)
			(xy 94.890324 -270.178404) (xy 94.871033 -270.133128) (xy 94.859256 -270.085344) (xy 94.855296 -270.03629)
			(xy 94.536768 -270.03629) (xy 94.536256 -270.061736) (xy 94.528092 -270.11197) (xy 94.511976 -270.160244)
			(xy 94.488325 -270.205307) (xy 94.457752 -270.245993) (xy 94.421048 -270.281248) (xy 94.379164 -270.310158)
			(xy 94.333185 -270.331975) (xy 94.284301 -270.346135) (xy 94.23378 -270.352269) (xy 94.182928 -270.35022)
			(xy 94.133064 -270.34004) (xy 94.085478 -270.321993) (xy 94.041404 -270.296547) (xy 94.001982 -270.26436)
			(xy 93.968234 -270.226266) (xy 93.941033 -270.183252) (xy 93.921085 -270.136432) (xy 93.908906 -270.087018)
			(xy 93.904811 -270.03629) (xy 93.5863 -270.03629) (xy 93.585805 -270.060897) (xy 93.57791 -270.109474)
			(xy 93.562326 -270.156155) (xy 93.539455 -270.199732) (xy 93.50989 -270.239076) (xy 93.474397 -270.273168)
			(xy 93.433894 -270.301124) (xy 93.389432 -270.322222) (xy 93.342161 -270.335914) (xy 93.293306 -270.341846)
			(xy 93.244131 -270.339865) (xy 93.195912 -270.330021) (xy 93.149896 -270.312569) (xy 93.107275 -270.287962)
			(xy 93.069154 -270.256837) (xy 93.036519 -270.22) (xy 93.010216 -270.178404) (xy 92.990925 -270.133128)
			(xy 92.979148 -270.085344) (xy 92.975188 -270.03629) (xy 92.65666 -270.03629) (xy 92.656148 -270.061736)
			(xy 92.647984 -270.11197) (xy 92.631868 -270.160244) (xy 92.608217 -270.205307) (xy 92.577644 -270.245993)
			(xy 92.54094 -270.281248) (xy 92.499056 -270.310158) (xy 92.453077 -270.331975) (xy 92.404193 -270.346135)
			(xy 92.353672 -270.352269) (xy 92.30282 -270.35022) (xy 92.252956 -270.34004) (xy 92.20537 -270.321993)
			(xy 92.161296 -270.296547) (xy 92.121874 -270.26436) (xy 92.088126 -270.226266) (xy 92.060925 -270.183252)
			(xy 92.040977 -270.136432) (xy 92.028798 -270.087018) (xy 92.024703 -270.03629) (xy 91.71686 -270.03629)
			(xy 91.716348 -270.061736) (xy 91.708184 -270.11197) (xy 91.692068 -270.160244) (xy 91.668417 -270.205307)
			(xy 91.637844 -270.245993) (xy 91.60114 -270.281248) (xy 91.559256 -270.310158) (xy 91.513277 -270.331975)
			(xy 91.464393 -270.346135) (xy 91.413872 -270.352269) (xy 91.36302 -270.35022) (xy 91.313156 -270.34004)
			(xy 91.26557 -270.321993) (xy 91.221496 -270.296547) (xy 91.182074 -270.26436) (xy 91.148326 -270.226266)
			(xy 91.121125 -270.183252) (xy 91.101177 -270.136432) (xy 91.088998 -270.087018) (xy 91.084903 -270.03629)
			(xy 90.766969 -270.03629) (xy 90.76697 -270.0363) (xy 90.762798 -270.086646) (xy 90.750396 -270.135619)
			(xy 90.730102 -270.181882) (xy 90.70247 -270.224175) (xy 90.668254 -270.261342) (xy 90.628387 -270.29237)
			(xy 90.583956 -270.316412) (xy 90.536174 -270.332814) (xy 90.486343 -270.341127) (xy 90.461084 -270.341598)
			(xy 90.448321 -270.34146) (xy 90.422887 -270.3393) (xy 90.410284 -270.33728) (xy 90.410284 -270.337534)
			(xy 90.386832 -270.333105) (xy 90.34158 -270.31794) (xy 90.299232 -270.295934) (xy 90.260813 -270.26762)
			(xy 90.227255 -270.233685) (xy 90.212926 -270.214598) (xy 90.208862 -270.208756) (xy 90.198194 -270.20012)
			(xy 90.192352 -270.19758) (xy 90.186069 -270.195059) (xy 90.172675 -270.193127) (xy 90.165936 -270.19377)
			(xy 90.075512 -270.2052) (xy 90.063066 -270.206724) (xy 90.05189 -270.21536) (xy 90.046761 -270.219704)
			(xy 90.03878 -270.230514) (xy 90.036142 -270.236696) (xy 90.036142 -270.23695) (xy 90.028244 -270.256729)
			(xy 90.009807 -270.295125) (xy 89.999312 -270.313658) (xy 89.9541 -270.391636) (xy 89.94836 -270.402876)
			(xy 89.947543 -270.42807) (xy 89.952576 -270.439642) (xy 89.981024 -270.497046) (xy 89.989914 -270.515334)
			(xy 89.992917 -270.520967) (xy 90.001276 -270.530609) (xy 90.006424 -270.534384) (xy 90.01633 -270.541496)
			(xy 90.02649 -270.54302) (xy 90.029284 -270.543274) (xy 90.053549 -270.54686) (xy 90.100585 -270.560756)
			(xy 90.1448 -270.581984) (xy 90.185058 -270.609999) (xy 90.220326 -270.644083) (xy 90.249699 -270.683361)
			(xy 90.272424 -270.726826) (xy 90.287917 -270.773361) (xy 90.29578 -270.821773) (xy 90.296238 -270.846296)
			(xy 90.614749 -270.846296) (xy 90.618844 -270.795568) (xy 90.631023 -270.746154) (xy 90.650971 -270.699334)
			(xy 90.678172 -270.65632) (xy 90.71192 -270.618226) (xy 90.751342 -270.586039) (xy 90.795416 -270.560593)
			(xy 90.843002 -270.542546) (xy 90.892866 -270.532366) (xy 90.943718 -270.530317) (xy 90.994239 -270.536451)
			(xy 91.043123 -270.550611) (xy 91.089102 -270.572428) (xy 91.130986 -270.601338) (xy 91.16769 -270.636593)
			(xy 91.198263 -270.677279) (xy 91.221914 -270.722342) (xy 91.23803 -270.770616) (xy 91.246194 -270.82085)
			(xy 91.246706 -270.846296) (xy 91.565234 -270.846296) (xy 91.569194 -270.797242) (xy 91.580971 -270.749458)
			(xy 91.600262 -270.704182) (xy 91.626565 -270.662586) (xy 91.6592 -270.625749) (xy 91.697321 -270.594624)
			(xy 91.739942 -270.570017) (xy 91.785958 -270.552565) (xy 91.834177 -270.542721) (xy 91.883352 -270.54074)
			(xy 91.932207 -270.546672) (xy 91.979478 -270.560364) (xy 92.02394 -270.581462) (xy 92.064443 -270.609418)
			(xy 92.099936 -270.64351) (xy 92.129501 -270.682854) (xy 92.152372 -270.726431) (xy 92.167956 -270.773112)
			(xy 92.175851 -270.821689) (xy 92.176346 -270.846296) (xy 92.494857 -270.846296) (xy 92.498952 -270.795568)
			(xy 92.511131 -270.746154) (xy 92.531079 -270.699334) (xy 92.55828 -270.65632) (xy 92.592028 -270.618226)
			(xy 92.63145 -270.586039) (xy 92.675524 -270.560593) (xy 92.72311 -270.542546) (xy 92.772974 -270.532366)
			(xy 92.823826 -270.530317) (xy 92.874347 -270.536451) (xy 92.923231 -270.550611) (xy 92.96921 -270.572428)
			(xy 93.011094 -270.601338) (xy 93.047798 -270.636593) (xy 93.078371 -270.677279) (xy 93.102022 -270.722342)
			(xy 93.118138 -270.770616) (xy 93.126302 -270.82085) (xy 93.126814 -270.846296) (xy 94.374711 -270.846296)
			(xy 94.378806 -270.795568) (xy 94.390985 -270.746154) (xy 94.410933 -270.699334) (xy 94.438134 -270.65632)
			(xy 94.471882 -270.618226) (xy 94.511304 -270.586039) (xy 94.555378 -270.560593) (xy 94.602964 -270.542546)
			(xy 94.652828 -270.532366) (xy 94.70368 -270.530317) (xy 94.754201 -270.536451) (xy 94.803085 -270.550611)
			(xy 94.849064 -270.572428) (xy 94.890948 -270.601338) (xy 94.927652 -270.636593) (xy 94.958225 -270.677279)
			(xy 94.981876 -270.722342) (xy 94.997992 -270.770616) (xy 95.006156 -270.82085) (xy 95.006668 -270.846296)
			(xy 95.314765 -270.846296) (xy 95.31886 -270.795568) (xy 95.331039 -270.746154) (xy 95.350987 -270.699334)
			(xy 95.378188 -270.65632) (xy 95.411936 -270.618226) (xy 95.451358 -270.586039) (xy 95.495432 -270.560593)
			(xy 95.543018 -270.542546) (xy 95.592882 -270.532366) (xy 95.643734 -270.530317) (xy 95.694255 -270.536451)
			(xy 95.743139 -270.550611) (xy 95.789118 -270.572428) (xy 95.831002 -270.601338) (xy 95.867706 -270.636593)
			(xy 95.898279 -270.677279) (xy 95.92193 -270.722342) (xy 95.938046 -270.770616) (xy 95.94621 -270.82085)
			(xy 95.946722 -270.846296) (xy 95.94621 -270.871742) (xy 95.938046 -270.921976) (xy 95.92193 -270.97025)
			(xy 95.898279 -271.015313) (xy 95.867706 -271.055999) (xy 95.831002 -271.091254) (xy 95.789118 -271.120164)
			(xy 95.743139 -271.141981) (xy 95.694255 -271.156141) (xy 95.643734 -271.162275) (xy 95.592882 -271.160226)
			(xy 95.543018 -271.150046) (xy 95.495432 -271.131999) (xy 95.451358 -271.106553) (xy 95.411936 -271.074366)
			(xy 95.378188 -271.036272) (xy 95.350987 -270.993258) (xy 95.331039 -270.946438) (xy 95.31886 -270.897024)
			(xy 95.314765 -270.846296) (xy 95.006668 -270.846296) (xy 95.006156 -270.871742) (xy 94.997992 -270.921976)
			(xy 94.981876 -270.97025) (xy 94.958225 -271.015313) (xy 94.927652 -271.055999) (xy 94.890948 -271.091254)
			(xy 94.849064 -271.120164) (xy 94.803085 -271.141981) (xy 94.754201 -271.156141) (xy 94.70368 -271.162275)
			(xy 94.652828 -271.160226) (xy 94.602964 -271.150046) (xy 94.555378 -271.131999) (xy 94.511304 -271.106553)
			(xy 94.471882 -271.074366) (xy 94.438134 -271.036272) (xy 94.410933 -270.993258) (xy 94.390985 -270.946438)
			(xy 94.378806 -270.897024) (xy 94.374711 -270.846296) (xy 93.126814 -270.846296) (xy 93.126302 -270.871742)
			(xy 93.118138 -270.921976) (xy 93.102022 -270.97025) (xy 93.078371 -271.015313) (xy 93.047798 -271.055999)
			(xy 93.011094 -271.091254) (xy 92.96921 -271.120164) (xy 92.923231 -271.141981) (xy 92.874347 -271.156141)
			(xy 92.823826 -271.162275) (xy 92.772974 -271.160226) (xy 92.72311 -271.150046) (xy 92.675524 -271.131999)
			(xy 92.63145 -271.106553) (xy 92.592028 -271.074366) (xy 92.55828 -271.036272) (xy 92.531079 -270.993258)
			(xy 92.511131 -270.946438) (xy 92.498952 -270.897024) (xy 92.494857 -270.846296) (xy 92.176346 -270.846296)
			(xy 92.175851 -270.870903) (xy 92.167956 -270.91948) (xy 92.152372 -270.966161) (xy 92.129501 -271.009738)
			(xy 92.099936 -271.049082) (xy 92.064443 -271.083174) (xy 92.02394 -271.11113) (xy 91.979478 -271.132228)
			(xy 91.932207 -271.14592) (xy 91.883352 -271.151852) (xy 91.834177 -271.149871) (xy 91.785958 -271.140027)
			(xy 91.739942 -271.122575) (xy 91.697321 -271.097968) (xy 91.6592 -271.066843) (xy 91.626565 -271.030006)
			(xy 91.600262 -270.98841) (xy 91.580971 -270.943134) (xy 91.569194 -270.89535) (xy 91.565234 -270.846296)
			(xy 91.246706 -270.846296) (xy 91.246194 -270.871742) (xy 91.23803 -270.921976) (xy 91.221914 -270.97025)
			(xy 91.198263 -271.015313) (xy 91.16769 -271.055999) (xy 91.130986 -271.091254) (xy 91.089102 -271.120164)
			(xy 91.043123 -271.141981) (xy 90.994239 -271.156141) (xy 90.943718 -271.162275) (xy 90.892866 -271.160226)
			(xy 90.843002 -271.150046) (xy 90.795416 -271.131999) (xy 90.751342 -271.106553) (xy 90.71192 -271.074366)
			(xy 90.678172 -271.036272) (xy 90.650971 -270.993258) (xy 90.631023 -270.946438) (xy 90.618844 -270.897024)
			(xy 90.614749 -270.846296) (xy 90.296238 -270.846296) (xy 90.295765 -270.870978) (xy 90.287827 -270.919701)
			(xy 90.272156 -270.966512) (xy 90.249162 -271.010194) (xy 90.219442 -271.04961) (xy 90.183771 -271.083734)
			(xy 90.143076 -271.111676) (xy 90.098417 -271.132711) (xy 90.050956 -271.146289) (xy 90.02649 -271.149572)
			(xy 90.019632 -271.150334) (xy 90.007186 -271.15516) (xy 90.001852 -271.159224) (xy 89.99663 -271.163492)
			(xy 89.988402 -271.174172) (xy 89.985596 -271.180306) (xy 89.95156 -271.262602) (xy 89.949136 -271.268841)
			(xy 89.947344 -271.282102) (xy 89.948004 -271.288764) (xy 89.949782 -271.301972) (xy 89.958418 -271.312894)
			(xy 89.958418 -271.313402) (xy 89.982777 -271.34558) (xy 90.022941 -271.415579) (xy 90.038428 -271.452848)
			(xy 90.038428 -271.453102) (xy 90.041125 -271.459301) (xy 90.04924 -271.470106) (xy 90.05443 -271.474438)
			(xy 90.05951 -271.478502) (xy 90.07221 -271.483836) (xy 90.167714 -271.496028) (xy 90.176844 -271.496833)
			(xy 90.194677 -271.492658) (xy 90.202512 -271.4879) (xy 90.206059 -271.485404) (xy 90.212319 -271.479404)
			(xy 90.214958 -271.475962) (xy 90.214958 -271.475708) (xy 90.229451 -271.456736) (xy 90.26334 -271.423109)
			(xy 90.302048 -271.395164) (xy 90.344633 -271.373583) (xy 90.390057 -271.35889) (xy 90.437214 -271.351444)
			(xy 90.461084 -271.350994) (xy 90.486342 -271.351485) (xy 90.536171 -271.359798) (xy 90.583951 -271.376199)
			(xy 90.62838 -271.40024) (xy 90.668246 -271.431267) (xy 90.702461 -271.468433) (xy 90.730092 -271.510723)
			(xy 90.750385 -271.556985) (xy 90.762786 -271.605956) (xy 90.766958 -271.6563) (xy 90.766958 -271.656302)
			(xy 91.084903 -271.656302) (xy 91.088998 -271.605574) (xy 91.101177 -271.55616) (xy 91.121125 -271.50934)
			(xy 91.148326 -271.466326) (xy 91.182074 -271.428232) (xy 91.221496 -271.396045) (xy 91.26557 -271.370599)
			(xy 91.313156 -271.352552) (xy 91.36302 -271.342372) (xy 91.413872 -271.340323) (xy 91.464393 -271.346457)
			(xy 91.513277 -271.360617) (xy 91.559256 -271.382434) (xy 91.60114 -271.411344) (xy 91.637844 -271.446599)
			(xy 91.668417 -271.487285) (xy 91.692068 -271.532348) (xy 91.708184 -271.580622) (xy 91.716348 -271.630856)
			(xy 91.71686 -271.656302) (xy 92.024703 -271.656302) (xy 92.028798 -271.605574) (xy 92.040977 -271.55616)
			(xy 92.060925 -271.50934) (xy 92.088126 -271.466326) (xy 92.121874 -271.428232) (xy 92.161296 -271.396045)
			(xy 92.20537 -271.370599) (xy 92.252956 -271.352552) (xy 92.30282 -271.342372) (xy 92.353672 -271.340323)
			(xy 92.404193 -271.346457) (xy 92.453077 -271.360617) (xy 92.499056 -271.382434) (xy 92.54094 -271.411344)
			(xy 92.577644 -271.446599) (xy 92.608217 -271.487285) (xy 92.631868 -271.532348) (xy 92.647984 -271.580622)
			(xy 92.656148 -271.630856) (xy 92.65666 -271.656302) (xy 92.975188 -271.656302) (xy 92.979148 -271.607248)
			(xy 92.990925 -271.559464) (xy 93.010216 -271.514188) (xy 93.036519 -271.472592) (xy 93.069154 -271.435755)
			(xy 93.107275 -271.40463) (xy 93.149896 -271.380023) (xy 93.195912 -271.362571) (xy 93.244131 -271.352727)
			(xy 93.293306 -271.350746) (xy 93.342161 -271.356678) (xy 93.389432 -271.37037) (xy 93.433894 -271.391468)
			(xy 93.474397 -271.419424) (xy 93.50989 -271.453516) (xy 93.539455 -271.49286) (xy 93.562326 -271.536437)
			(xy 93.57791 -271.583118) (xy 93.585805 -271.631695) (xy 93.5863 -271.656302) (xy 93.904811 -271.656302)
			(xy 93.908906 -271.605574) (xy 93.921085 -271.55616) (xy 93.941033 -271.50934) (xy 93.968234 -271.466326)
			(xy 94.001982 -271.428232) (xy 94.041404 -271.396045) (xy 94.085478 -271.370599) (xy 94.133064 -271.352552)
			(xy 94.182928 -271.342372) (xy 94.23378 -271.340323) (xy 94.284301 -271.346457) (xy 94.333185 -271.360617)
			(xy 94.379164 -271.382434) (xy 94.421048 -271.411344) (xy 94.457752 -271.446599) (xy 94.488325 -271.487285)
			(xy 94.511976 -271.532348) (xy 94.528092 -271.580622) (xy 94.536256 -271.630856) (xy 94.536768 -271.656302)
			(xy 94.855296 -271.656302) (xy 94.859256 -271.607248) (xy 94.871033 -271.559464) (xy 94.890324 -271.514188)
			(xy 94.916627 -271.472592) (xy 94.949262 -271.435755) (xy 94.987383 -271.40463) (xy 95.030004 -271.380023)
			(xy 95.07602 -271.362571) (xy 95.124239 -271.352727) (xy 95.173414 -271.350746) (xy 95.222269 -271.356678)
			(xy 95.26954 -271.37037) (xy 95.314002 -271.391468) (xy 95.354505 -271.419424) (xy 95.389998 -271.453516)
			(xy 95.419563 -271.49286) (xy 95.442434 -271.536437) (xy 95.458018 -271.583118) (xy 95.465913 -271.631695)
			(xy 95.466408 -271.656302) (xy 95.784919 -271.656302) (xy 95.789014 -271.605574) (xy 95.801193 -271.55616)
			(xy 95.821141 -271.50934) (xy 95.848342 -271.466326) (xy 95.88209 -271.428232) (xy 95.921512 -271.396045)
			(xy 95.965586 -271.370599) (xy 96.013172 -271.352552) (xy 96.063036 -271.342372) (xy 96.113888 -271.340323)
			(xy 96.164409 -271.346457) (xy 96.213293 -271.360617) (xy 96.259272 -271.382434) (xy 96.301156 -271.411344)
			(xy 96.33786 -271.446599) (xy 96.368433 -271.487285) (xy 96.392084 -271.532348) (xy 96.4082 -271.580622)
			(xy 96.416364 -271.630856) (xy 96.416876 -271.656302) (xy 96.416364 -271.681748) (xy 96.4082 -271.731982)
			(xy 96.392084 -271.780256) (xy 96.368433 -271.825319) (xy 96.33786 -271.866005) (xy 96.301156 -271.90126)
			(xy 96.259272 -271.93017) (xy 96.213293 -271.951987) (xy 96.164409 -271.966147) (xy 96.113888 -271.972281)
			(xy 96.063036 -271.970232) (xy 96.013172 -271.960052) (xy 95.965586 -271.942005) (xy 95.921512 -271.916559)
			(xy 95.88209 -271.884372) (xy 95.848342 -271.846278) (xy 95.821141 -271.803264) (xy 95.801193 -271.756444)
			(xy 95.789014 -271.70703) (xy 95.784919 -271.656302) (xy 95.466408 -271.656302) (xy 95.465913 -271.680909)
			(xy 95.458018 -271.729486) (xy 95.442434 -271.776167) (xy 95.419563 -271.819744) (xy 95.389998 -271.859088)
			(xy 95.354505 -271.89318) (xy 95.314002 -271.921136) (xy 95.26954 -271.942234) (xy 95.222269 -271.955926)
			(xy 95.173414 -271.961858) (xy 95.124239 -271.959877) (xy 95.07602 -271.950033) (xy 95.030004 -271.932581)
			(xy 94.987383 -271.907974) (xy 94.949262 -271.876849) (xy 94.916627 -271.840012) (xy 94.890324 -271.798416)
			(xy 94.871033 -271.75314) (xy 94.859256 -271.705356) (xy 94.855296 -271.656302) (xy 94.536768 -271.656302)
			(xy 94.536256 -271.681748) (xy 94.528092 -271.731982) (xy 94.511976 -271.780256) (xy 94.488325 -271.825319)
			(xy 94.457752 -271.866005) (xy 94.421048 -271.90126) (xy 94.379164 -271.93017) (xy 94.333185 -271.951987)
			(xy 94.284301 -271.966147) (xy 94.23378 -271.972281) (xy 94.182928 -271.970232) (xy 94.133064 -271.960052)
			(xy 94.085478 -271.942005) (xy 94.041404 -271.916559) (xy 94.001982 -271.884372) (xy 93.968234 -271.846278)
			(xy 93.941033 -271.803264) (xy 93.921085 -271.756444) (xy 93.908906 -271.70703) (xy 93.904811 -271.656302)
			(xy 93.5863 -271.656302) (xy 93.585805 -271.680909) (xy 93.57791 -271.729486) (xy 93.562326 -271.776167)
			(xy 93.539455 -271.819744) (xy 93.50989 -271.859088) (xy 93.474397 -271.89318) (xy 93.433894 -271.921136)
			(xy 93.389432 -271.942234) (xy 93.342161 -271.955926) (xy 93.293306 -271.961858) (xy 93.244131 -271.959877)
			(xy 93.195912 -271.950033) (xy 93.149896 -271.932581) (xy 93.107275 -271.907974) (xy 93.069154 -271.876849)
			(xy 93.036519 -271.840012) (xy 93.010216 -271.798416) (xy 92.990925 -271.75314) (xy 92.979148 -271.705356)
			(xy 92.975188 -271.656302) (xy 92.65666 -271.656302) (xy 92.656148 -271.681748) (xy 92.647984 -271.731982)
			(xy 92.631868 -271.780256) (xy 92.608217 -271.825319) (xy 92.577644 -271.866005) (xy 92.54094 -271.90126)
			(xy 92.499056 -271.93017) (xy 92.453077 -271.951987) (xy 92.404193 -271.966147) (xy 92.353672 -271.972281)
			(xy 92.30282 -271.970232) (xy 92.252956 -271.960052) (xy 92.20537 -271.942005) (xy 92.161296 -271.916559)
			(xy 92.121874 -271.884372) (xy 92.088126 -271.846278) (xy 92.060925 -271.803264) (xy 92.040977 -271.756444)
			(xy 92.028798 -271.70703) (xy 92.024703 -271.656302) (xy 91.71686 -271.656302) (xy 91.716348 -271.681748)
			(xy 91.708184 -271.731982) (xy 91.692068 -271.780256) (xy 91.668417 -271.825319) (xy 91.637844 -271.866005)
			(xy 91.60114 -271.90126) (xy 91.559256 -271.93017) (xy 91.513277 -271.951987) (xy 91.464393 -271.966147)
			(xy 91.413872 -271.972281) (xy 91.36302 -271.970232) (xy 91.313156 -271.960052) (xy 91.26557 -271.942005)
			(xy 91.221496 -271.916559) (xy 91.182074 -271.884372) (xy 91.148326 -271.846278) (xy 91.121125 -271.803264)
			(xy 91.101177 -271.756444) (xy 91.088998 -271.70703) (xy 91.084903 -271.656302) (xy 90.766958 -271.656302)
			(xy 90.762786 -271.706644) (xy 90.750385 -271.755615) (xy 90.730092 -271.801877) (xy 90.702461 -271.844167)
			(xy 90.668246 -271.881333) (xy 90.62838 -271.91236) (xy 90.583951 -271.936401) (xy 90.536171 -271.952802)
			(xy 90.486342 -271.961115) (xy 90.461084 -271.96161) (xy 90.437211 -271.961154) (xy 90.390047 -271.95373)
			(xy 90.344615 -271.93905) (xy 90.302024 -271.917473) (xy 90.263314 -271.889524) (xy 90.22943 -271.855887)
			(xy 90.214958 -271.836896) (xy 90.214958 -271.836642) (xy 90.212306 -271.833212) (xy 90.206049 -271.827211)
			(xy 90.202512 -271.824704) (xy 90.194683 -271.819934) (xy 90.176845 -271.815765) (xy 90.167714 -271.816576)
			(xy 90.079068 -271.828006) (xy 90.072308 -271.829081) (xy 90.059685 -271.834358) (xy 90.054176 -271.83842)
			(xy 90.048842 -271.842484) (xy 90.040968 -271.853152) (xy 90.038428 -271.859756) (xy 90.02522 -271.890744)
			(xy 90.019887 -271.902083) (xy 90.008326 -271.924317) (xy 90.002106 -271.935194) (xy 89.957656 -272.012156)
			(xy 89.951884 -272.023306) (xy 89.950945 -272.048363) (xy 89.955878 -272.059908) (xy 89.992708 -272.135346)
			(xy 89.995659 -272.14112) (xy 90.004021 -272.151026) (xy 90.009218 -272.154904) (xy 90.019632 -272.162016)
			(xy 90.024458 -272.162778) (xy 90.049053 -272.165977) (xy 90.096823 -272.179311) (xy 90.141809 -272.200191)
			(xy 90.182827 -272.228069) (xy 90.2188 -272.262212) (xy 90.248779 -272.30172) (xy 90.271978 -272.345555)
			(xy 90.287786 -272.392564) (xy 90.295786 -272.44151) (xy 90.296238 -272.466308) (xy 90.614749 -272.466308)
			(xy 90.618844 -272.41558) (xy 90.631023 -272.366166) (xy 90.650971 -272.319346) (xy 90.678172 -272.276332)
			(xy 90.71192 -272.238238) (xy 90.751342 -272.206051) (xy 90.795416 -272.180605) (xy 90.843002 -272.162558)
			(xy 90.892866 -272.152378) (xy 90.943718 -272.150329) (xy 90.994239 -272.156463) (xy 91.043123 -272.170623)
			(xy 91.089102 -272.19244) (xy 91.130986 -272.22135) (xy 91.16769 -272.256605) (xy 91.198263 -272.297291)
			(xy 91.221914 -272.342354) (xy 91.23803 -272.390628) (xy 91.246194 -272.440862) (xy 91.246706 -272.466308)
			(xy 91.565234 -272.466308) (xy 91.569194 -272.417254) (xy 91.580971 -272.36947) (xy 91.600262 -272.324194)
			(xy 91.626565 -272.282598) (xy 91.6592 -272.245761) (xy 91.697321 -272.214636) (xy 91.739942 -272.190029)
			(xy 91.785958 -272.172577) (xy 91.834177 -272.162733) (xy 91.883352 -272.160752) (xy 91.932207 -272.166684)
			(xy 91.979478 -272.180376) (xy 92.02394 -272.201474) (xy 92.064443 -272.22943) (xy 92.099936 -272.263522)
			(xy 92.129501 -272.302866) (xy 92.152372 -272.346443) (xy 92.167956 -272.393124) (xy 92.175851 -272.441701)
			(xy 92.176346 -272.466308) (xy 92.494857 -272.466308) (xy 92.498952 -272.41558) (xy 92.511131 -272.366166)
			(xy 92.531079 -272.319346) (xy 92.55828 -272.276332) (xy 92.592028 -272.238238) (xy 92.63145 -272.206051)
			(xy 92.675524 -272.180605) (xy 92.72311 -272.162558) (xy 92.772974 -272.152378) (xy 92.823826 -272.150329)
			(xy 92.874347 -272.156463) (xy 92.923231 -272.170623) (xy 92.96921 -272.19244) (xy 93.011094 -272.22135)
			(xy 93.047798 -272.256605) (xy 93.078371 -272.297291) (xy 93.102022 -272.342354) (xy 93.118138 -272.390628)
			(xy 93.126302 -272.440862) (xy 93.126814 -272.466308) (xy 93.445342 -272.466308) (xy 93.449302 -272.417254)
			(xy 93.461079 -272.36947) (xy 93.48037 -272.324194) (xy 93.506673 -272.282598) (xy 93.539308 -272.245761)
			(xy 93.577429 -272.214636) (xy 93.62005 -272.190029) (xy 93.666066 -272.172577) (xy 93.714285 -272.162733)
			(xy 93.76346 -272.160752) (xy 93.812315 -272.166684) (xy 93.859586 -272.180376) (xy 93.904048 -272.201474)
			(xy 93.944551 -272.22943) (xy 93.980044 -272.263522) (xy 94.009609 -272.302866) (xy 94.03248 -272.346443)
			(xy 94.048064 -272.393124) (xy 94.055959 -272.441701) (xy 94.056454 -272.466308) (xy 94.374711 -272.466308)
			(xy 94.378806 -272.41558) (xy 94.390985 -272.366166) (xy 94.410933 -272.319346) (xy 94.438134 -272.276332)
			(xy 94.471882 -272.238238) (xy 94.511304 -272.206051) (xy 94.555378 -272.180605) (xy 94.602964 -272.162558)
			(xy 94.652828 -272.152378) (xy 94.70368 -272.150329) (xy 94.754201 -272.156463) (xy 94.803085 -272.170623)
			(xy 94.849064 -272.19244) (xy 94.890948 -272.22135) (xy 94.927652 -272.256605) (xy 94.958225 -272.297291)
			(xy 94.981876 -272.342354) (xy 94.997992 -272.390628) (xy 95.006156 -272.440862) (xy 95.006668 -272.466308)
			(xy 95.314765 -272.466308) (xy 95.31886 -272.41558) (xy 95.331039 -272.366166) (xy 95.350987 -272.319346)
			(xy 95.378188 -272.276332) (xy 95.411936 -272.238238) (xy 95.451358 -272.206051) (xy 95.495432 -272.180605)
			(xy 95.543018 -272.162558) (xy 95.592882 -272.152378) (xy 95.643734 -272.150329) (xy 95.694255 -272.156463)
			(xy 95.743139 -272.170623) (xy 95.789118 -272.19244) (xy 95.831002 -272.22135) (xy 95.867706 -272.256605)
			(xy 95.898279 -272.297291) (xy 95.92193 -272.342354) (xy 95.938046 -272.390628) (xy 95.94621 -272.440862)
			(xy 95.946722 -272.466308) (xy 96.26525 -272.466308) (xy 96.26921 -272.417254) (xy 96.280987 -272.36947)
			(xy 96.300278 -272.324194) (xy 96.326581 -272.282598) (xy 96.359216 -272.245761) (xy 96.397337 -272.214636)
			(xy 96.439958 -272.190029) (xy 96.485974 -272.172577) (xy 96.534193 -272.162733) (xy 96.583368 -272.160752)
			(xy 96.632223 -272.166684) (xy 96.679494 -272.180376) (xy 96.723956 -272.201474) (xy 96.764459 -272.22943)
			(xy 96.799952 -272.263522) (xy 96.829517 -272.302866) (xy 96.852388 -272.346443) (xy 96.867972 -272.393124)
			(xy 96.875867 -272.441701) (xy 96.876362 -272.466308) (xy 96.875867 -272.490915) (xy 96.867972 -272.539492)
			(xy 96.852388 -272.586173) (xy 96.829517 -272.62975) (xy 96.799952 -272.669094) (xy 96.764459 -272.703186)
			(xy 96.723956 -272.731142) (xy 96.679494 -272.75224) (xy 96.632223 -272.765932) (xy 96.583368 -272.771864)
			(xy 96.534193 -272.769883) (xy 96.485974 -272.760039) (xy 96.439958 -272.742587) (xy 96.397337 -272.71798)
			(xy 96.359216 -272.686855) (xy 96.326581 -272.650018) (xy 96.300278 -272.608422) (xy 96.280987 -272.563146)
			(xy 96.26921 -272.515362) (xy 96.26525 -272.466308) (xy 95.946722 -272.466308) (xy 95.94621 -272.491754)
			(xy 95.938046 -272.541988) (xy 95.92193 -272.590262) (xy 95.898279 -272.635325) (xy 95.867706 -272.676011)
			(xy 95.831002 -272.711266) (xy 95.789118 -272.740176) (xy 95.743139 -272.761993) (xy 95.694255 -272.776153)
			(xy 95.643734 -272.782287) (xy 95.592882 -272.780238) (xy 95.543018 -272.770058) (xy 95.495432 -272.752011)
			(xy 95.451358 -272.726565) (xy 95.411936 -272.694378) (xy 95.378188 -272.656284) (xy 95.350987 -272.61327)
			(xy 95.331039 -272.56645) (xy 95.31886 -272.517036) (xy 95.314765 -272.466308) (xy 95.006668 -272.466308)
			(xy 95.006156 -272.491754) (xy 94.997992 -272.541988) (xy 94.981876 -272.590262) (xy 94.958225 -272.635325)
			(xy 94.927652 -272.676011) (xy 94.890948 -272.711266) (xy 94.849064 -272.740176) (xy 94.803085 -272.761993)
			(xy 94.754201 -272.776153) (xy 94.70368 -272.782287) (xy 94.652828 -272.780238) (xy 94.602964 -272.770058)
			(xy 94.555378 -272.752011) (xy 94.511304 -272.726565) (xy 94.471882 -272.694378) (xy 94.438134 -272.656284)
			(xy 94.410933 -272.61327) (xy 94.390985 -272.56645) (xy 94.378806 -272.517036) (xy 94.374711 -272.466308)
			(xy 94.056454 -272.466308) (xy 94.055959 -272.490915) (xy 94.048064 -272.539492) (xy 94.03248 -272.586173)
			(xy 94.009609 -272.62975) (xy 93.980044 -272.669094) (xy 93.944551 -272.703186) (xy 93.904048 -272.731142)
			(xy 93.859586 -272.75224) (xy 93.812315 -272.765932) (xy 93.76346 -272.771864) (xy 93.714285 -272.769883)
			(xy 93.666066 -272.760039) (xy 93.62005 -272.742587) (xy 93.577429 -272.71798) (xy 93.539308 -272.686855)
			(xy 93.506673 -272.650018) (xy 93.48037 -272.608422) (xy 93.461079 -272.563146) (xy 93.449302 -272.515362)
			(xy 93.445342 -272.466308) (xy 93.126814 -272.466308) (xy 93.126302 -272.491754) (xy 93.118138 -272.541988)
			(xy 93.102022 -272.590262) (xy 93.078371 -272.635325) (xy 93.047798 -272.676011) (xy 93.011094 -272.711266)
			(xy 92.96921 -272.740176) (xy 92.923231 -272.761993) (xy 92.874347 -272.776153) (xy 92.823826 -272.782287)
			(xy 92.772974 -272.780238) (xy 92.72311 -272.770058) (xy 92.675524 -272.752011) (xy 92.63145 -272.726565)
			(xy 92.592028 -272.694378) (xy 92.55828 -272.656284) (xy 92.531079 -272.61327) (xy 92.511131 -272.56645)
			(xy 92.498952 -272.517036) (xy 92.494857 -272.466308) (xy 92.176346 -272.466308) (xy 92.175851 -272.490915)
			(xy 92.167956 -272.539492) (xy 92.152372 -272.586173) (xy 92.129501 -272.62975) (xy 92.099936 -272.669094)
			(xy 92.064443 -272.703186) (xy 92.02394 -272.731142) (xy 91.979478 -272.75224) (xy 91.932207 -272.765932)
			(xy 91.883352 -272.771864) (xy 91.834177 -272.769883) (xy 91.785958 -272.760039) (xy 91.739942 -272.742587)
			(xy 91.697321 -272.71798) (xy 91.6592 -272.686855) (xy 91.626565 -272.650018) (xy 91.600262 -272.608422)
			(xy 91.580971 -272.563146) (xy 91.569194 -272.515362) (xy 91.565234 -272.466308) (xy 91.246706 -272.466308)
			(xy 91.246194 -272.491754) (xy 91.23803 -272.541988) (xy 91.221914 -272.590262) (xy 91.198263 -272.635325)
			(xy 91.16769 -272.676011) (xy 91.130986 -272.711266) (xy 91.089102 -272.740176) (xy 91.043123 -272.761993)
			(xy 90.994239 -272.776153) (xy 90.943718 -272.782287) (xy 90.892866 -272.780238) (xy 90.843002 -272.770058)
			(xy 90.795416 -272.752011) (xy 90.751342 -272.726565) (xy 90.71192 -272.694378) (xy 90.678172 -272.656284)
			(xy 90.650971 -272.61327) (xy 90.631023 -272.56645) (xy 90.618844 -272.517036) (xy 90.614749 -272.466308)
			(xy 90.296238 -272.466308) (xy 90.295752 -272.491129) (xy 90.28772 -272.540116) (xy 90.27187 -272.587159)
			(xy 90.248618 -272.631019) (xy 90.218578 -272.670539) (xy 90.182541 -272.70468) (xy 90.141455 -272.732541)
			(xy 90.096404 -272.753389) (xy 90.048573 -272.766674) (xy 90.02395 -272.769838) (xy 90.023696 -272.769838)
			(xy 90.016991 -272.770758) (xy 90.004377 -272.775649) (xy 89.998804 -272.77949) (xy 89.993724 -272.783554)
			(xy 89.985342 -272.793968) (xy 89.948004 -272.882614) (xy 89.945536 -272.889042) (xy 89.943745 -272.902688)
			(xy 89.944448 -272.909538) (xy 89.946226 -272.922746) (xy 89.954862 -272.933668) (xy 89.979732 -272.966363)
			(xy 90.020546 -273.037651) (xy 90.036142 -273.075654) (xy 90.036142 -273.075908) (xy 90.038773 -273.082094)
			(xy 90.046755 -273.092906) (xy 90.05189 -273.097244) (xy 90.063066 -273.10588) (xy 90.075512 -273.107404)
			(xy 90.165682 -273.118834) (xy 90.172562 -273.119435) (xy 90.186214 -273.117384) (xy 90.192606 -273.11477)
			(xy 90.198448 -273.11223) (xy 90.208862 -273.103848) (xy 90.21318 -273.098006) (xy 90.227645 -273.078706)
			(xy 90.261633 -273.044488) (xy 90.300572 -273.016031) (xy 90.343497 -272.994042) (xy 90.389342 -272.979066)
			(xy 90.43697 -272.971475) (xy 90.461084 -272.971006) (xy 90.486341 -272.971497) (xy 90.536168 -272.979809)
			(xy 90.583946 -272.99621) (xy 90.628373 -273.02025) (xy 90.668238 -273.051276) (xy 90.702451 -273.08844)
			(xy 90.730081 -273.130729) (xy 90.750373 -273.176989) (xy 90.762774 -273.225958) (xy 90.766946 -273.2763)
			(xy 90.766945 -273.276314) (xy 91.084903 -273.276314) (xy 91.088998 -273.225586) (xy 91.101177 -273.176172)
			(xy 91.121125 -273.129352) (xy 91.148326 -273.086338) (xy 91.182074 -273.048244) (xy 91.221496 -273.016057)
			(xy 91.26557 -272.990611) (xy 91.313156 -272.972564) (xy 91.36302 -272.962384) (xy 91.413872 -272.960335)
			(xy 91.464393 -272.966469) (xy 91.513277 -272.980629) (xy 91.559256 -273.002446) (xy 91.60114 -273.031356)
			(xy 91.637844 -273.066611) (xy 91.668417 -273.107297) (xy 91.692068 -273.15236) (xy 91.708184 -273.200634)
			(xy 91.716348 -273.250868) (xy 91.71686 -273.276314) (xy 92.024703 -273.276314) (xy 92.028798 -273.225586)
			(xy 92.040977 -273.176172) (xy 92.060925 -273.129352) (xy 92.088126 -273.086338) (xy 92.121874 -273.048244)
			(xy 92.161296 -273.016057) (xy 92.20537 -272.990611) (xy 92.252956 -272.972564) (xy 92.30282 -272.962384)
			(xy 92.353672 -272.960335) (xy 92.404193 -272.966469) (xy 92.453077 -272.980629) (xy 92.499056 -273.002446)
			(xy 92.54094 -273.031356) (xy 92.577644 -273.066611) (xy 92.608217 -273.107297) (xy 92.631868 -273.15236)
			(xy 92.647984 -273.200634) (xy 92.656148 -273.250868) (xy 92.65666 -273.276314) (xy 93.904811 -273.276314)
			(xy 93.908906 -273.225586) (xy 93.921085 -273.176172) (xy 93.941033 -273.129352) (xy 93.968234 -273.086338)
			(xy 94.001982 -273.048244) (xy 94.041404 -273.016057) (xy 94.085478 -272.990611) (xy 94.133064 -272.972564)
			(xy 94.182928 -272.962384) (xy 94.23378 -272.960335) (xy 94.284301 -272.966469) (xy 94.333185 -272.980629)
			(xy 94.379164 -273.002446) (xy 94.421048 -273.031356) (xy 94.457752 -273.066611) (xy 94.488325 -273.107297)
			(xy 94.511976 -273.15236) (xy 94.528092 -273.200634) (xy 94.536256 -273.250868) (xy 94.536768 -273.276314)
			(xy 94.855296 -273.276314) (xy 94.859256 -273.22726) (xy 94.871033 -273.179476) (xy 94.890324 -273.1342)
			(xy 94.916627 -273.092604) (xy 94.949262 -273.055767) (xy 94.987383 -273.024642) (xy 95.030004 -273.000035)
			(xy 95.07602 -272.982583) (xy 95.124239 -272.972739) (xy 95.173414 -272.970758) (xy 95.222269 -272.97669)
			(xy 95.26954 -272.990382) (xy 95.314002 -273.01148) (xy 95.354505 -273.039436) (xy 95.389998 -273.073528)
			(xy 95.419563 -273.112872) (xy 95.442434 -273.156449) (xy 95.458018 -273.20313) (xy 95.465913 -273.251707)
			(xy 95.466408 -273.276314) (xy 95.784919 -273.276314) (xy 95.789014 -273.225586) (xy 95.801193 -273.176172)
			(xy 95.821141 -273.129352) (xy 95.848342 -273.086338) (xy 95.88209 -273.048244) (xy 95.921512 -273.016057)
			(xy 95.965586 -272.990611) (xy 96.013172 -272.972564) (xy 96.063036 -272.962384) (xy 96.113888 -272.960335)
			(xy 96.164409 -272.966469) (xy 96.213293 -272.980629) (xy 96.259272 -273.002446) (xy 96.301156 -273.031356)
			(xy 96.33786 -273.066611) (xy 96.368433 -273.107297) (xy 96.392084 -273.15236) (xy 96.4082 -273.200634)
			(xy 96.416364 -273.250868) (xy 96.416876 -273.276314) (xy 96.416364 -273.30176) (xy 96.4082 -273.351994)
			(xy 96.392084 -273.400268) (xy 96.368433 -273.445331) (xy 96.33786 -273.486017) (xy 96.301156 -273.521272)
			(xy 96.259272 -273.550182) (xy 96.213293 -273.571999) (xy 96.164409 -273.586159) (xy 96.113888 -273.592293)
			(xy 96.063036 -273.590244) (xy 96.013172 -273.580064) (xy 95.965586 -273.562017) (xy 95.921512 -273.536571)
			(xy 95.88209 -273.504384) (xy 95.848342 -273.46629) (xy 95.821141 -273.423276) (xy 95.801193 -273.376456)
			(xy 95.789014 -273.327042) (xy 95.784919 -273.276314) (xy 95.466408 -273.276314) (xy 95.465913 -273.300921)
			(xy 95.458018 -273.349498) (xy 95.442434 -273.396179) (xy 95.419563 -273.439756) (xy 95.389998 -273.4791)
			(xy 95.354505 -273.513192) (xy 95.314002 -273.541148) (xy 95.26954 -273.562246) (xy 95.222269 -273.575938)
			(xy 95.173414 -273.58187) (xy 95.124239 -273.579889) (xy 95.07602 -273.570045) (xy 95.030004 -273.552593)
			(xy 94.987383 -273.527986) (xy 94.949262 -273.496861) (xy 94.916627 -273.460024) (xy 94.890324 -273.418428)
			(xy 94.871033 -273.373152) (xy 94.859256 -273.325368) (xy 94.855296 -273.276314) (xy 94.536768 -273.276314)
			(xy 94.536256 -273.30176) (xy 94.528092 -273.351994) (xy 94.511976 -273.400268) (xy 94.488325 -273.445331)
			(xy 94.457752 -273.486017) (xy 94.421048 -273.521272) (xy 94.379164 -273.550182) (xy 94.333185 -273.571999)
			(xy 94.284301 -273.586159) (xy 94.23378 -273.592293) (xy 94.182928 -273.590244) (xy 94.133064 -273.580064)
			(xy 94.085478 -273.562017) (xy 94.041404 -273.536571) (xy 94.001982 -273.504384) (xy 93.968234 -273.46629)
			(xy 93.941033 -273.423276) (xy 93.921085 -273.376456) (xy 93.908906 -273.327042) (xy 93.904811 -273.276314)
			(xy 92.65666 -273.276314) (xy 92.656148 -273.30176) (xy 92.647984 -273.351994) (xy 92.631868 -273.400268)
			(xy 92.608217 -273.445331) (xy 92.577644 -273.486017) (xy 92.54094 -273.521272) (xy 92.499056 -273.550182)
			(xy 92.453077 -273.571999) (xy 92.404193 -273.586159) (xy 92.353672 -273.592293) (xy 92.30282 -273.590244)
			(xy 92.252956 -273.580064) (xy 92.20537 -273.562017) (xy 92.161296 -273.536571) (xy 92.121874 -273.504384)
			(xy 92.088126 -273.46629) (xy 92.060925 -273.423276) (xy 92.040977 -273.376456) (xy 92.028798 -273.327042)
			(xy 92.024703 -273.276314) (xy 91.71686 -273.276314) (xy 91.716348 -273.30176) (xy 91.708184 -273.351994)
			(xy 91.692068 -273.400268) (xy 91.668417 -273.445331) (xy 91.637844 -273.486017) (xy 91.60114 -273.521272)
			(xy 91.559256 -273.550182) (xy 91.513277 -273.571999) (xy 91.464393 -273.586159) (xy 91.413872 -273.592293)
			(xy 91.36302 -273.590244) (xy 91.313156 -273.580064) (xy 91.26557 -273.562017) (xy 91.221496 -273.536571)
			(xy 91.182074 -273.504384) (xy 91.148326 -273.46629) (xy 91.121125 -273.423276) (xy 91.101177 -273.376456)
			(xy 91.088998 -273.327042) (xy 91.084903 -273.276314) (xy 90.766945 -273.276314) (xy 90.762774 -273.326642)
			(xy 90.750373 -273.375611) (xy 90.730081 -273.421871) (xy 90.702451 -273.46416) (xy 90.668238 -273.501324)
			(xy 90.628373 -273.53235) (xy 90.583946 -273.55639) (xy 90.536168 -273.572791) (xy 90.486341 -273.581103)
			(xy 90.461084 -273.581622) (xy 90.448321 -273.581484) (xy 90.422887 -273.579324) (xy 90.410284 -273.577304)
			(xy 90.410284 -273.577558) (xy 90.386831 -273.573129) (xy 90.341579 -273.557965) (xy 90.299229 -273.53596)
			(xy 90.260808 -273.507648) (xy 90.227248 -273.473714) (xy 90.212926 -273.454622) (xy 90.208862 -273.44878)
			(xy 90.198194 -273.440144) (xy 90.192352 -273.437604) (xy 90.186069 -273.435083) (xy 90.172675 -273.433149)
			(xy 90.165936 -273.433794) (xy 90.075512 -273.445224) (xy 90.063066 -273.446748) (xy 90.05189 -273.455384)
			(xy 90.046762 -273.459729) (xy 90.038786 -273.470541) (xy 90.036142 -273.47672) (xy 90.036142 -273.476974)
			(xy 90.028243 -273.496753) (xy 90.009804 -273.535148) (xy 89.999312 -273.553682) (xy 89.9541 -273.63166)
			(xy 89.948366 -273.6429) (xy 89.947559 -273.668089) (xy 89.952576 -273.679666) (xy 89.981024 -273.73707)
			(xy 89.989914 -273.755358) (xy 89.992919 -273.760989) (xy 90.001281 -273.770628) (xy 90.006424 -273.774408)
			(xy 90.01633 -273.78152) (xy 90.02649 -273.783044) (xy 90.029284 -273.783298) (xy 90.053548 -273.786884)
			(xy 90.100583 -273.80078) (xy 90.144796 -273.822009) (xy 90.185051 -273.850025) (xy 90.220317 -273.884109)
			(xy 90.249687 -273.923388) (xy 90.272409 -273.966852) (xy 90.287899 -274.013387) (xy 90.295759 -274.061798)
			(xy 90.296238 -274.08632) (xy 90.614749 -274.08632) (xy 90.618844 -274.035592) (xy 90.631023 -273.986178)
			(xy 90.650971 -273.939358) (xy 90.678172 -273.896344) (xy 90.71192 -273.85825) (xy 90.751342 -273.826063)
			(xy 90.795416 -273.800617) (xy 90.843002 -273.78257) (xy 90.892866 -273.77239) (xy 90.943718 -273.770341)
			(xy 90.994239 -273.776475) (xy 91.043123 -273.790635) (xy 91.089102 -273.812452) (xy 91.130986 -273.841362)
			(xy 91.16769 -273.876617) (xy 91.198263 -273.917303) (xy 91.221914 -273.962366) (xy 91.23803 -274.01064)
			(xy 91.246194 -274.060874) (xy 91.246706 -274.08632) (xy 91.565234 -274.08632) (xy 91.569194 -274.037266)
			(xy 91.580971 -273.989482) (xy 91.600262 -273.944206) (xy 91.626565 -273.90261) (xy 91.6592 -273.865773)
			(xy 91.697321 -273.834648) (xy 91.739942 -273.810041) (xy 91.785958 -273.792589) (xy 91.834177 -273.782745)
			(xy 91.883352 -273.780764) (xy 91.932207 -273.786696) (xy 91.979478 -273.800388) (xy 92.02394 -273.821486)
			(xy 92.064443 -273.849442) (xy 92.099936 -273.883534) (xy 92.129501 -273.922878) (xy 92.152372 -273.966455)
			(xy 92.167956 -274.013136) (xy 92.175851 -274.061713) (xy 92.176346 -274.08632) (xy 92.494857 -274.08632)
			(xy 92.498952 -274.035592) (xy 92.511131 -273.986178) (xy 92.531079 -273.939358) (xy 92.55828 -273.896344)
			(xy 92.592028 -273.85825) (xy 92.63145 -273.826063) (xy 92.675524 -273.800617) (xy 92.72311 -273.78257)
			(xy 92.772974 -273.77239) (xy 92.823826 -273.770341) (xy 92.874347 -273.776475) (xy 92.923231 -273.790635)
			(xy 92.96921 -273.812452) (xy 93.011094 -273.841362) (xy 93.047798 -273.876617) (xy 93.078371 -273.917303)
			(xy 93.102022 -273.962366) (xy 93.118138 -274.01064) (xy 93.126302 -274.060874) (xy 93.126814 -274.08632)
			(xy 93.445342 -274.08632) (xy 93.449302 -274.037266) (xy 93.461079 -273.989482) (xy 93.48037 -273.944206)
			(xy 93.506673 -273.90261) (xy 93.539308 -273.865773) (xy 93.577429 -273.834648) (xy 93.62005 -273.810041)
			(xy 93.666066 -273.792589) (xy 93.714285 -273.782745) (xy 93.76346 -273.780764) (xy 93.812315 -273.786696)
			(xy 93.859586 -273.800388) (xy 93.904048 -273.821486) (xy 93.944551 -273.849442) (xy 93.980044 -273.883534)
			(xy 94.009609 -273.922878) (xy 94.03248 -273.966455) (xy 94.048064 -274.013136) (xy 94.055959 -274.061713)
			(xy 94.056454 -274.08632) (xy 94.374711 -274.08632) (xy 94.378806 -274.035592) (xy 94.390985 -273.986178)
			(xy 94.410933 -273.939358) (xy 94.438134 -273.896344) (xy 94.471882 -273.85825) (xy 94.511304 -273.826063)
			(xy 94.555378 -273.800617) (xy 94.602964 -273.78257) (xy 94.652828 -273.77239) (xy 94.70368 -273.770341)
			(xy 94.754201 -273.776475) (xy 94.803085 -273.790635) (xy 94.849064 -273.812452) (xy 94.890948 -273.841362)
			(xy 94.927652 -273.876617) (xy 94.958225 -273.917303) (xy 94.981876 -273.962366) (xy 94.997992 -274.01064)
			(xy 95.006156 -274.060874) (xy 95.006668 -274.08632) (xy 95.314765 -274.08632) (xy 95.31886 -274.035592)
			(xy 95.331039 -273.986178) (xy 95.350987 -273.939358) (xy 95.378188 -273.896344) (xy 95.411936 -273.85825)
			(xy 95.451358 -273.826063) (xy 95.495432 -273.800617) (xy 95.543018 -273.78257) (xy 95.592882 -273.77239)
			(xy 95.643734 -273.770341) (xy 95.694255 -273.776475) (xy 95.743139 -273.790635) (xy 95.789118 -273.812452)
			(xy 95.831002 -273.841362) (xy 95.867706 -273.876617) (xy 95.898279 -273.917303) (xy 95.92193 -273.962366)
			(xy 95.938046 -274.01064) (xy 95.94621 -274.060874) (xy 95.946722 -274.08632) (xy 95.94621 -274.111766)
			(xy 95.938046 -274.162) (xy 95.92193 -274.210274) (xy 95.898279 -274.255337) (xy 95.867706 -274.296023)
			(xy 95.831002 -274.331278) (xy 95.789118 -274.360188) (xy 95.743139 -274.382005) (xy 95.694255 -274.396165)
			(xy 95.643734 -274.402299) (xy 95.592882 -274.40025) (xy 95.543018 -274.39007) (xy 95.495432 -274.372023)
			(xy 95.451358 -274.346577) (xy 95.411936 -274.31439) (xy 95.378188 -274.276296) (xy 95.350987 -274.233282)
			(xy 95.331039 -274.186462) (xy 95.31886 -274.137048) (xy 95.314765 -274.08632) (xy 95.006668 -274.08632)
			(xy 95.006156 -274.111766) (xy 94.997992 -274.162) (xy 94.981876 -274.210274) (xy 94.958225 -274.255337)
			(xy 94.927652 -274.296023) (xy 94.890948 -274.331278) (xy 94.849064 -274.360188) (xy 94.803085 -274.382005)
			(xy 94.754201 -274.396165) (xy 94.70368 -274.402299) (xy 94.652828 -274.40025) (xy 94.602964 -274.39007)
			(xy 94.555378 -274.372023) (xy 94.511304 -274.346577) (xy 94.471882 -274.31439) (xy 94.438134 -274.276296)
			(xy 94.410933 -274.233282) (xy 94.390985 -274.186462) (xy 94.378806 -274.137048) (xy 94.374711 -274.08632)
			(xy 94.056454 -274.08632) (xy 94.055959 -274.110927) (xy 94.048064 -274.159504) (xy 94.03248 -274.206185)
			(xy 94.009609 -274.249762) (xy 93.980044 -274.289106) (xy 93.944551 -274.323198) (xy 93.904048 -274.351154)
			(xy 93.859586 -274.372252) (xy 93.812315 -274.385944) (xy 93.76346 -274.391876) (xy 93.714285 -274.389895)
			(xy 93.666066 -274.380051) (xy 93.62005 -274.362599) (xy 93.577429 -274.337992) (xy 93.539308 -274.306867)
			(xy 93.506673 -274.27003) (xy 93.48037 -274.228434) (xy 93.461079 -274.183158) (xy 93.449302 -274.135374)
			(xy 93.445342 -274.08632) (xy 93.126814 -274.08632) (xy 93.126302 -274.111766) (xy 93.118138 -274.162)
			(xy 93.102022 -274.210274) (xy 93.078371 -274.255337) (xy 93.047798 -274.296023) (xy 93.011094 -274.331278)
			(xy 92.96921 -274.360188) (xy 92.923231 -274.382005) (xy 92.874347 -274.396165) (xy 92.823826 -274.402299)
			(xy 92.772974 -274.40025) (xy 92.72311 -274.39007) (xy 92.675524 -274.372023) (xy 92.63145 -274.346577)
			(xy 92.592028 -274.31439) (xy 92.55828 -274.276296) (xy 92.531079 -274.233282) (xy 92.511131 -274.186462)
			(xy 92.498952 -274.137048) (xy 92.494857 -274.08632) (xy 92.176346 -274.08632) (xy 92.175851 -274.110927)
			(xy 92.167956 -274.159504) (xy 92.152372 -274.206185) (xy 92.129501 -274.249762) (xy 92.099936 -274.289106)
			(xy 92.064443 -274.323198) (xy 92.02394 -274.351154) (xy 91.979478 -274.372252) (xy 91.932207 -274.385944)
			(xy 91.883352 -274.391876) (xy 91.834177 -274.389895) (xy 91.785958 -274.380051) (xy 91.739942 -274.362599)
			(xy 91.697321 -274.337992) (xy 91.6592 -274.306867) (xy 91.626565 -274.27003) (xy 91.600262 -274.228434)
			(xy 91.580971 -274.183158) (xy 91.569194 -274.135374) (xy 91.565234 -274.08632) (xy 91.246706 -274.08632)
			(xy 91.246194 -274.111766) (xy 91.23803 -274.162) (xy 91.221914 -274.210274) (xy 91.198263 -274.255337)
			(xy 91.16769 -274.296023) (xy 91.130986 -274.331278) (xy 91.089102 -274.360188) (xy 91.043123 -274.382005)
			(xy 90.994239 -274.396165) (xy 90.943718 -274.402299) (xy 90.892866 -274.40025) (xy 90.843002 -274.39007)
			(xy 90.795416 -274.372023) (xy 90.751342 -274.346577) (xy 90.71192 -274.31439) (xy 90.678172 -274.276296)
			(xy 90.650971 -274.233282) (xy 90.631023 -274.186462) (xy 90.618844 -274.137048) (xy 90.614749 -274.08632)
			(xy 90.296238 -274.08632) (xy 90.295751 -274.11114) (xy 90.287718 -274.160126) (xy 90.271866 -274.207167)
			(xy 90.248614 -274.251025) (xy 90.218574 -274.290544) (xy 90.182536 -274.324683) (xy 90.141451 -274.352543)
			(xy 90.096401 -274.37339) (xy 90.048571 -274.386675) (xy 90.02395 -274.38985) (xy 90.023696 -274.38985)
			(xy 90.016991 -274.39077) (xy 90.004377 -274.395663) (xy 89.998804 -274.399502) (xy 89.993724 -274.403566)
			(xy 89.985342 -274.41398) (xy 89.948004 -274.502626) (xy 89.945538 -274.509054) (xy 89.94375 -274.5227)
			(xy 89.944448 -274.52955) (xy 89.946226 -274.542758) (xy 89.954862 -274.55368) (xy 89.979731 -274.586375)
			(xy 90.020544 -274.657664) (xy 90.036142 -274.695666) (xy 90.036142 -274.69592) (xy 90.038774 -274.702105)
			(xy 90.046758 -274.712915) (xy 90.05189 -274.717256) (xy 90.063066 -274.725892) (xy 90.075512 -274.727416)
			(xy 90.165682 -274.738846) (xy 90.172562 -274.739448) (xy 90.186213 -274.737393) (xy 90.192606 -274.734782)
			(xy 90.198448 -274.732242) (xy 90.208862 -274.72386) (xy 90.21318 -274.718018) (xy 90.227644 -274.698717)
			(xy 90.261632 -274.664498) (xy 90.300571 -274.63604) (xy 90.343496 -274.61405) (xy 90.389341 -274.599073)
			(xy 90.436969 -274.591482) (xy 90.461084 -274.591018) (xy 90.48634 -274.591509) (xy 90.536165 -274.599821)
			(xy 90.583941 -274.616221) (xy 90.628367 -274.64026) (xy 90.66823 -274.671285) (xy 90.702442 -274.708448)
			(xy 90.730071 -274.750735) (xy 90.750362 -274.796993) (xy 90.762763 -274.84596) (xy 90.766934 -274.8963)
			(xy 90.766932 -274.896326) (xy 91.084903 -274.896326) (xy 91.088998 -274.845598) (xy 91.101177 -274.796184)
			(xy 91.121125 -274.749364) (xy 91.148326 -274.70635) (xy 91.182074 -274.668256) (xy 91.221496 -274.636069)
			(xy 91.26557 -274.610623) (xy 91.313156 -274.592576) (xy 91.36302 -274.582396) (xy 91.413872 -274.580347)
			(xy 91.464393 -274.586481) (xy 91.513277 -274.600641) (xy 91.559256 -274.622458) (xy 91.60114 -274.651368)
			(xy 91.637844 -274.686623) (xy 91.668417 -274.727309) (xy 91.692068 -274.772372) (xy 91.708184 -274.820646)
			(xy 91.716348 -274.87088) (xy 91.71686 -274.896326) (xy 92.024703 -274.896326) (xy 92.028798 -274.845598)
			(xy 92.040977 -274.796184) (xy 92.060925 -274.749364) (xy 92.088126 -274.70635) (xy 92.121874 -274.668256)
			(xy 92.161296 -274.636069) (xy 92.20537 -274.610623) (xy 92.252956 -274.592576) (xy 92.30282 -274.582396)
			(xy 92.353672 -274.580347) (xy 92.404193 -274.586481) (xy 92.453077 -274.600641) (xy 92.499056 -274.622458)
			(xy 92.54094 -274.651368) (xy 92.577644 -274.686623) (xy 92.608217 -274.727309) (xy 92.631868 -274.772372)
			(xy 92.647984 -274.820646) (xy 92.656148 -274.87088) (xy 92.65666 -274.896326) (xy 92.975188 -274.896326)
			(xy 92.979148 -274.847272) (xy 92.990925 -274.799488) (xy 93.010216 -274.754212) (xy 93.036519 -274.712616)
			(xy 93.069154 -274.675779) (xy 93.107275 -274.644654) (xy 93.149896 -274.620047) (xy 93.195912 -274.602595)
			(xy 93.244131 -274.592751) (xy 93.293306 -274.59077) (xy 93.342161 -274.596702) (xy 93.389432 -274.610394)
			(xy 93.433894 -274.631492) (xy 93.474397 -274.659448) (xy 93.50989 -274.69354) (xy 93.539455 -274.732884)
			(xy 93.562326 -274.776461) (xy 93.57791 -274.823142) (xy 93.585805 -274.871719) (xy 93.5863 -274.896326)
			(xy 93.904811 -274.896326) (xy 93.908906 -274.845598) (xy 93.921085 -274.796184) (xy 93.941033 -274.749364)
			(xy 93.968234 -274.70635) (xy 94.001982 -274.668256) (xy 94.041404 -274.636069) (xy 94.085478 -274.610623)
			(xy 94.133064 -274.592576) (xy 94.182928 -274.582396) (xy 94.23378 -274.580347) (xy 94.284301 -274.586481)
			(xy 94.333185 -274.600641) (xy 94.379164 -274.622458) (xy 94.421048 -274.651368) (xy 94.457752 -274.686623)
			(xy 94.488325 -274.727309) (xy 94.511976 -274.772372) (xy 94.528092 -274.820646) (xy 94.536256 -274.87088)
			(xy 94.536768 -274.896326) (xy 94.855296 -274.896326) (xy 94.859256 -274.847272) (xy 94.871033 -274.799488)
			(xy 94.890324 -274.754212) (xy 94.916627 -274.712616) (xy 94.949262 -274.675779) (xy 94.987383 -274.644654)
			(xy 95.030004 -274.620047) (xy 95.07602 -274.602595) (xy 95.124239 -274.592751) (xy 95.173414 -274.59077)
			(xy 95.222269 -274.596702) (xy 95.26954 -274.610394) (xy 95.314002 -274.631492) (xy 95.354505 -274.659448)
			(xy 95.389998 -274.69354) (xy 95.419563 -274.732884) (xy 95.442434 -274.776461) (xy 95.458018 -274.823142)
			(xy 95.465913 -274.871719) (xy 95.466408 -274.896326) (xy 95.784919 -274.896326) (xy 95.789014 -274.845598)
			(xy 95.801193 -274.796184) (xy 95.821141 -274.749364) (xy 95.848342 -274.70635) (xy 95.88209 -274.668256)
			(xy 95.921512 -274.636069) (xy 95.965586 -274.610623) (xy 96.013172 -274.592576) (xy 96.063036 -274.582396)
			(xy 96.113888 -274.580347) (xy 96.164409 -274.586481) (xy 96.213293 -274.600641) (xy 96.259272 -274.622458)
			(xy 96.301156 -274.651368) (xy 96.33786 -274.686623) (xy 96.368433 -274.727309) (xy 96.392084 -274.772372)
			(xy 96.4082 -274.820646) (xy 96.416364 -274.87088) (xy 96.416876 -274.896326) (xy 96.416364 -274.921772)
			(xy 96.4082 -274.972006) (xy 96.392084 -275.02028) (xy 96.368433 -275.065343) (xy 96.33786 -275.106029)
			(xy 96.301156 -275.141284) (xy 96.259272 -275.170194) (xy 96.213293 -275.192011) (xy 96.164409 -275.206171)
			(xy 96.113888 -275.212305) (xy 96.063036 -275.210256) (xy 96.013172 -275.200076) (xy 95.965586 -275.182029)
			(xy 95.921512 -275.156583) (xy 95.88209 -275.124396) (xy 95.848342 -275.086302) (xy 95.821141 -275.043288)
			(xy 95.801193 -274.996468) (xy 95.789014 -274.947054) (xy 95.784919 -274.896326) (xy 95.466408 -274.896326)
			(xy 95.465913 -274.920933) (xy 95.458018 -274.96951) (xy 95.442434 -275.016191) (xy 95.419563 -275.059768)
			(xy 95.389998 -275.099112) (xy 95.354505 -275.133204) (xy 95.314002 -275.16116) (xy 95.26954 -275.182258)
			(xy 95.222269 -275.19595) (xy 95.173414 -275.201882) (xy 95.124239 -275.199901) (xy 95.07602 -275.190057)
			(xy 95.030004 -275.172605) (xy 94.987383 -275.147998) (xy 94.949262 -275.116873) (xy 94.916627 -275.080036)
			(xy 94.890324 -275.03844) (xy 94.871033 -274.993164) (xy 94.859256 -274.94538) (xy 94.855296 -274.896326)
			(xy 94.536768 -274.896326) (xy 94.536256 -274.921772) (xy 94.528092 -274.972006) (xy 94.511976 -275.02028)
			(xy 94.488325 -275.065343) (xy 94.457752 -275.106029) (xy 94.421048 -275.141284) (xy 94.379164 -275.170194)
			(xy 94.333185 -275.192011) (xy 94.284301 -275.206171) (xy 94.23378 -275.212305) (xy 94.182928 -275.210256)
			(xy 94.133064 -275.200076) (xy 94.085478 -275.182029) (xy 94.041404 -275.156583) (xy 94.001982 -275.124396)
			(xy 93.968234 -275.086302) (xy 93.941033 -275.043288) (xy 93.921085 -274.996468) (xy 93.908906 -274.947054)
			(xy 93.904811 -274.896326) (xy 93.5863 -274.896326) (xy 93.585805 -274.920933) (xy 93.57791 -274.96951)
			(xy 93.562326 -275.016191) (xy 93.539455 -275.059768) (xy 93.50989 -275.099112) (xy 93.474397 -275.133204)
			(xy 93.433894 -275.16116) (xy 93.389432 -275.182258) (xy 93.342161 -275.19595) (xy 93.293306 -275.201882)
			(xy 93.244131 -275.199901) (xy 93.195912 -275.190057) (xy 93.149896 -275.172605) (xy 93.107275 -275.147998)
			(xy 93.069154 -275.116873) (xy 93.036519 -275.080036) (xy 93.010216 -275.03844) (xy 92.990925 -274.993164)
			(xy 92.979148 -274.94538) (xy 92.975188 -274.896326) (xy 92.65666 -274.896326) (xy 92.656148 -274.921772)
			(xy 92.647984 -274.972006) (xy 92.631868 -275.02028) (xy 92.608217 -275.065343) (xy 92.577644 -275.106029)
			(xy 92.54094 -275.141284) (xy 92.499056 -275.170194) (xy 92.453077 -275.192011) (xy 92.404193 -275.206171)
			(xy 92.353672 -275.212305) (xy 92.30282 -275.210256) (xy 92.252956 -275.200076) (xy 92.20537 -275.182029)
			(xy 92.161296 -275.156583) (xy 92.121874 -275.124396) (xy 92.088126 -275.086302) (xy 92.060925 -275.043288)
			(xy 92.040977 -274.996468) (xy 92.028798 -274.947054) (xy 92.024703 -274.896326) (xy 91.71686 -274.896326)
			(xy 91.716348 -274.921772) (xy 91.708184 -274.972006) (xy 91.692068 -275.02028) (xy 91.668417 -275.065343)
			(xy 91.637844 -275.106029) (xy 91.60114 -275.141284) (xy 91.559256 -275.170194) (xy 91.513277 -275.192011)
			(xy 91.464393 -275.206171) (xy 91.413872 -275.212305) (xy 91.36302 -275.210256) (xy 91.313156 -275.200076)
			(xy 91.26557 -275.182029) (xy 91.221496 -275.156583) (xy 91.182074 -275.124396) (xy 91.148326 -275.086302)
			(xy 91.121125 -275.043288) (xy 91.101177 -274.996468) (xy 91.088998 -274.947054) (xy 91.084903 -274.896326)
			(xy 90.766932 -274.896326) (xy 90.762763 -274.94664) (xy 90.750362 -274.995607) (xy 90.730071 -275.041865)
			(xy 90.702442 -275.084152) (xy 90.66823 -275.121315) (xy 90.628367 -275.15234) (xy 90.583941 -275.176379)
			(xy 90.536165 -275.192779) (xy 90.48634 -275.201091) (xy 90.461084 -275.201634) (xy 90.448321 -275.201496)
			(xy 90.422887 -275.199336) (xy 90.410284 -275.197316) (xy 90.410284 -275.19757) (xy 90.386831 -275.193141)
			(xy 90.341578 -275.177978) (xy 90.299228 -275.155973) (xy 90.260806 -275.127662) (xy 90.227245 -275.093729)
			(xy 90.212926 -275.074634) (xy 90.208862 -275.068792) (xy 90.198194 -275.060156) (xy 90.192352 -275.057616)
			(xy 90.186069 -275.055094) (xy 90.172675 -275.05316) (xy 90.165936 -275.053806) (xy 90.075512 -275.065236)
			(xy 90.063066 -275.06676) (xy 90.05189 -275.075396) (xy 90.046763 -275.079742) (xy 90.03879 -275.090555)
			(xy 90.036142 -275.096732) (xy 90.036142 -275.096986) (xy 90.028246 -275.116766) (xy 90.009813 -275.155165)
			(xy 89.999312 -275.173694) (xy 89.9541 -275.251672) (xy 89.948369 -275.262912) (xy 89.947567 -275.288098)
			(xy 89.952576 -275.299678) (xy 89.981024 -275.357082) (xy 89.989914 -275.37537) (xy 89.992911 -275.381008)
			(xy 90.001264 -275.39066) (xy 90.006424 -275.39442) (xy 90.01633 -275.401532) (xy 90.02649 -275.403056)
			(xy 90.029284 -275.40331) (xy 90.053547 -275.406896) (xy 90.100582 -275.420793) (xy 90.144794 -275.442021)
			(xy 90.185048 -275.470037) (xy 90.220313 -275.504122) (xy 90.249682 -275.543401) (xy 90.272402 -275.586865)
			(xy 90.287889 -275.633399) (xy 90.295748 -275.68181) (xy 90.296238 -275.706332) (xy 90.614749 -275.706332)
			(xy 90.618844 -275.655604) (xy 90.631023 -275.60619) (xy 90.650971 -275.55937) (xy 90.678172 -275.516356)
			(xy 90.71192 -275.478262) (xy 90.751342 -275.446075) (xy 90.795416 -275.420629) (xy 90.843002 -275.402582)
			(xy 90.892866 -275.392402) (xy 90.943718 -275.390353) (xy 90.994239 -275.396487) (xy 91.043123 -275.410647)
			(xy 91.089102 -275.432464) (xy 91.130986 -275.461374) (xy 91.16769 -275.496629) (xy 91.198263 -275.537315)
			(xy 91.221914 -275.582378) (xy 91.23803 -275.630652) (xy 91.246194 -275.680886) (xy 91.246706 -275.706332)
			(xy 91.565234 -275.706332) (xy 91.569194 -275.657278) (xy 91.580971 -275.609494) (xy 91.600262 -275.564218)
			(xy 91.626565 -275.522622) (xy 91.6592 -275.485785) (xy 91.697321 -275.45466) (xy 91.739942 -275.430053)
			(xy 91.785958 -275.412601) (xy 91.834177 -275.402757) (xy 91.883352 -275.400776) (xy 91.932207 -275.406708)
			(xy 91.979478 -275.4204) (xy 92.02394 -275.441498) (xy 92.064443 -275.469454) (xy 92.099936 -275.503546)
			(xy 92.129501 -275.54289) (xy 92.152372 -275.586467) (xy 92.167956 -275.633148) (xy 92.175851 -275.681725)
			(xy 92.176346 -275.706332) (xy 92.494857 -275.706332) (xy 92.498952 -275.655604) (xy 92.511131 -275.60619)
			(xy 92.531079 -275.55937) (xy 92.55828 -275.516356) (xy 92.592028 -275.478262) (xy 92.63145 -275.446075)
			(xy 92.675524 -275.420629) (xy 92.72311 -275.402582) (xy 92.772974 -275.392402) (xy 92.823826 -275.390353)
			(xy 92.874347 -275.396487) (xy 92.923231 -275.410647) (xy 92.96921 -275.432464) (xy 93.011094 -275.461374)
			(xy 93.047798 -275.496629) (xy 93.078371 -275.537315) (xy 93.102022 -275.582378) (xy 93.118138 -275.630652)
			(xy 93.126302 -275.680886) (xy 93.126814 -275.706332) (xy 94.374711 -275.706332) (xy 94.378806 -275.655604)
			(xy 94.390985 -275.60619) (xy 94.410933 -275.55937) (xy 94.438134 -275.516356) (xy 94.471882 -275.478262)
			(xy 94.511304 -275.446075) (xy 94.555378 -275.420629) (xy 94.602964 -275.402582) (xy 94.652828 -275.392402)
			(xy 94.70368 -275.390353) (xy 94.754201 -275.396487) (xy 94.803085 -275.410647) (xy 94.849064 -275.432464)
			(xy 94.890948 -275.461374) (xy 94.927652 -275.496629) (xy 94.958225 -275.537315) (xy 94.981876 -275.582378)
			(xy 94.997992 -275.630652) (xy 95.006156 -275.680886) (xy 95.006668 -275.706332) (xy 95.314765 -275.706332)
			(xy 95.31886 -275.655604) (xy 95.331039 -275.60619) (xy 95.350987 -275.55937) (xy 95.378188 -275.516356)
			(xy 95.411936 -275.478262) (xy 95.451358 -275.446075) (xy 95.495432 -275.420629) (xy 95.543018 -275.402582)
			(xy 95.592882 -275.392402) (xy 95.643734 -275.390353) (xy 95.694255 -275.396487) (xy 95.743139 -275.410647)
			(xy 95.789118 -275.432464) (xy 95.831002 -275.461374) (xy 95.867706 -275.496629) (xy 95.898279 -275.537315)
			(xy 95.92193 -275.582378) (xy 95.938046 -275.630652) (xy 95.94621 -275.680886) (xy 95.946722 -275.706332)
			(xy 95.94621 -275.731778) (xy 95.938046 -275.782012) (xy 95.92193 -275.830286) (xy 95.898279 -275.875349)
			(xy 95.867706 -275.916035) (xy 95.831002 -275.95129) (xy 95.789118 -275.9802) (xy 95.743139 -276.002017)
			(xy 95.694255 -276.016177) (xy 95.643734 -276.022311) (xy 95.592882 -276.020262) (xy 95.543018 -276.010082)
			(xy 95.495432 -275.992035) (xy 95.451358 -275.966589) (xy 95.411936 -275.934402) (xy 95.378188 -275.896308)
			(xy 95.350987 -275.853294) (xy 95.331039 -275.806474) (xy 95.31886 -275.75706) (xy 95.314765 -275.706332)
			(xy 95.006668 -275.706332) (xy 95.006156 -275.731778) (xy 94.997992 -275.782012) (xy 94.981876 -275.830286)
			(xy 94.958225 -275.875349) (xy 94.927652 -275.916035) (xy 94.890948 -275.95129) (xy 94.849064 -275.9802)
			(xy 94.803085 -276.002017) (xy 94.754201 -276.016177) (xy 94.70368 -276.022311) (xy 94.652828 -276.020262)
			(xy 94.602964 -276.010082) (xy 94.555378 -275.992035) (xy 94.511304 -275.966589) (xy 94.471882 -275.934402)
			(xy 94.438134 -275.896308) (xy 94.410933 -275.853294) (xy 94.390985 -275.806474) (xy 94.378806 -275.75706)
			(xy 94.374711 -275.706332) (xy 93.126814 -275.706332) (xy 93.126302 -275.731778) (xy 93.118138 -275.782012)
			(xy 93.102022 -275.830286) (xy 93.078371 -275.875349) (xy 93.047798 -275.916035) (xy 93.011094 -275.95129)
			(xy 92.96921 -275.9802) (xy 92.923231 -276.002017) (xy 92.874347 -276.016177) (xy 92.823826 -276.022311)
			(xy 92.772974 -276.020262) (xy 92.72311 -276.010082) (xy 92.675524 -275.992035) (xy 92.63145 -275.966589)
			(xy 92.592028 -275.934402) (xy 92.55828 -275.896308) (xy 92.531079 -275.853294) (xy 92.511131 -275.806474)
			(xy 92.498952 -275.75706) (xy 92.494857 -275.706332) (xy 92.176346 -275.706332) (xy 92.175851 -275.730939)
			(xy 92.167956 -275.779516) (xy 92.152372 -275.826197) (xy 92.129501 -275.869774) (xy 92.099936 -275.909118)
			(xy 92.064443 -275.94321) (xy 92.02394 -275.971166) (xy 91.979478 -275.992264) (xy 91.932207 -276.005956)
			(xy 91.883352 -276.011888) (xy 91.834177 -276.009907) (xy 91.785958 -276.000063) (xy 91.739942 -275.982611)
			(xy 91.697321 -275.958004) (xy 91.6592 -275.926879) (xy 91.626565 -275.890042) (xy 91.600262 -275.848446)
			(xy 91.580971 -275.80317) (xy 91.569194 -275.755386) (xy 91.565234 -275.706332) (xy 91.246706 -275.706332)
			(xy 91.246194 -275.731778) (xy 91.23803 -275.782012) (xy 91.221914 -275.830286) (xy 91.198263 -275.875349)
			(xy 91.16769 -275.916035) (xy 91.130986 -275.95129) (xy 91.089102 -275.9802) (xy 91.043123 -276.002017)
			(xy 90.994239 -276.016177) (xy 90.943718 -276.022311) (xy 90.892866 -276.020262) (xy 90.843002 -276.010082)
			(xy 90.795416 -275.992035) (xy 90.751342 -275.966589) (xy 90.71192 -275.934402) (xy 90.678172 -275.896308)
			(xy 90.650971 -275.853294) (xy 90.631023 -275.806474) (xy 90.618844 -275.75706) (xy 90.614749 -275.706332)
			(xy 90.296238 -275.706332) (xy 90.295762 -275.731013) (xy 90.287819 -275.77973) (xy 90.272146 -275.826537)
			(xy 90.24915 -275.870214) (xy 90.219429 -275.909625) (xy 90.183758 -275.943744) (xy 90.143064 -275.971683)
			(xy 90.098408 -275.992714) (xy 90.050951 -276.006291) (xy 90.02649 -276.009608) (xy 90.019632 -276.01037)
			(xy 90.007186 -276.015196) (xy 90.001852 -276.01926) (xy 89.996625 -276.023525) (xy 89.988385 -276.0342)
			(xy 89.985596 -276.040342) (xy 89.95156 -276.122638) (xy 89.949127 -276.128877) (xy 89.947318 -276.142139)
			(xy 89.948004 -276.1488) (xy 89.949782 -276.162008) (xy 89.958418 -276.17293) (xy 89.958418 -276.173438)
			(xy 89.982776 -276.205617) (xy 90.022935 -276.275618) (xy 90.038428 -276.312884) (xy 90.038428 -276.313138)
			(xy 90.041128 -276.319334) (xy 90.049248 -276.330134) (xy 90.05443 -276.334474) (xy 90.05951 -276.338538)
			(xy 90.07221 -276.343872) (xy 90.167714 -276.356064) (xy 90.176845 -276.356869) (xy 90.194678 -276.352696)
			(xy 90.202512 -276.347936) (xy 90.206056 -276.345438) (xy 90.212311 -276.339433) (xy 90.214958 -276.335998)
			(xy 90.214958 -276.335744) (xy 90.229453 -276.316775) (xy 90.263345 -276.283154) (xy 90.302054 -276.255216)
			(xy 90.344638 -276.233639) (xy 90.390061 -276.21895) (xy 90.437215 -276.211506) (xy 90.461084 -276.21103)
			(xy 90.486339 -276.211521) (xy 90.536162 -276.219833) (xy 90.583936 -276.236232) (xy 90.62836 -276.260271)
			(xy 90.668221 -276.291294) (xy 90.702432 -276.328455) (xy 90.73006 -276.37074) (xy 90.750351 -276.416997)
			(xy 90.762751 -276.465962) (xy 90.766922 -276.5163) (xy 90.766919 -276.516338) (xy 91.084903 -276.516338)
			(xy 91.088998 -276.46561) (xy 91.101177 -276.416196) (xy 91.121125 -276.369376) (xy 91.148326 -276.326362)
			(xy 91.182074 -276.288268) (xy 91.221496 -276.256081) (xy 91.26557 -276.230635) (xy 91.313156 -276.212588)
			(xy 91.36302 -276.202408) (xy 91.413872 -276.200359) (xy 91.464393 -276.206493) (xy 91.513277 -276.220653)
			(xy 91.559256 -276.24247) (xy 91.60114 -276.27138) (xy 91.637844 -276.306635) (xy 91.668417 -276.347321)
			(xy 91.692068 -276.392384) (xy 91.708184 -276.440658) (xy 91.716348 -276.490892) (xy 91.71686 -276.516338)
			(xy 92.024703 -276.516338) (xy 92.028798 -276.46561) (xy 92.040977 -276.416196) (xy 92.060925 -276.369376)
			(xy 92.088126 -276.326362) (xy 92.121874 -276.288268) (xy 92.161296 -276.256081) (xy 92.20537 -276.230635)
			(xy 92.252956 -276.212588) (xy 92.30282 -276.202408) (xy 92.353672 -276.200359) (xy 92.404193 -276.206493)
			(xy 92.453077 -276.220653) (xy 92.499056 -276.24247) (xy 92.54094 -276.27138) (xy 92.577644 -276.306635)
			(xy 92.608217 -276.347321) (xy 92.631868 -276.392384) (xy 92.647984 -276.440658) (xy 92.656148 -276.490892)
			(xy 92.65666 -276.516338) (xy 92.975188 -276.516338) (xy 92.979148 -276.467284) (xy 92.990925 -276.4195)
			(xy 93.010216 -276.374224) (xy 93.036519 -276.332628) (xy 93.069154 -276.295791) (xy 93.107275 -276.264666)
			(xy 93.149896 -276.240059) (xy 93.195912 -276.222607) (xy 93.244131 -276.212763) (xy 93.293306 -276.210782)
			(xy 93.342161 -276.216714) (xy 93.389432 -276.230406) (xy 93.433894 -276.251504) (xy 93.474397 -276.27946)
			(xy 93.50989 -276.313552) (xy 93.539455 -276.352896) (xy 93.562326 -276.396473) (xy 93.57791 -276.443154)
			(xy 93.585805 -276.491731) (xy 93.5863 -276.516338) (xy 93.904811 -276.516338) (xy 93.908906 -276.46561)
			(xy 93.921085 -276.416196) (xy 93.941033 -276.369376) (xy 93.968234 -276.326362) (xy 94.001982 -276.288268)
			(xy 94.041404 -276.256081) (xy 94.085478 -276.230635) (xy 94.133064 -276.212588) (xy 94.182928 -276.202408)
			(xy 94.23378 -276.200359) (xy 94.284301 -276.206493) (xy 94.333185 -276.220653) (xy 94.379164 -276.24247)
			(xy 94.421048 -276.27138) (xy 94.457752 -276.306635) (xy 94.488325 -276.347321) (xy 94.511976 -276.392384)
			(xy 94.528092 -276.440658) (xy 94.536256 -276.490892) (xy 94.536768 -276.516338) (xy 94.855296 -276.516338)
			(xy 94.859256 -276.467284) (xy 94.871033 -276.4195) (xy 94.890324 -276.374224) (xy 94.916627 -276.332628)
			(xy 94.949262 -276.295791) (xy 94.987383 -276.264666) (xy 95.030004 -276.240059) (xy 95.07602 -276.222607)
			(xy 95.124239 -276.212763) (xy 95.173414 -276.210782) (xy 95.222269 -276.216714) (xy 95.26954 -276.230406)
			(xy 95.314002 -276.251504) (xy 95.354505 -276.27946) (xy 95.389998 -276.313552) (xy 95.419563 -276.352896)
			(xy 95.442434 -276.396473) (xy 95.458018 -276.443154) (xy 95.465913 -276.491731) (xy 95.466408 -276.516338)
			(xy 95.784919 -276.516338) (xy 95.789014 -276.46561) (xy 95.801193 -276.416196) (xy 95.821141 -276.369376)
			(xy 95.848342 -276.326362) (xy 95.88209 -276.288268) (xy 95.921512 -276.256081) (xy 95.965586 -276.230635)
			(xy 96.013172 -276.212588) (xy 96.063036 -276.202408) (xy 96.113888 -276.200359) (xy 96.164409 -276.206493)
			(xy 96.213293 -276.220653) (xy 96.259272 -276.24247) (xy 96.301156 -276.27138) (xy 96.33786 -276.306635)
			(xy 96.368433 -276.347321) (xy 96.392084 -276.392384) (xy 96.4082 -276.440658) (xy 96.416364 -276.490892)
			(xy 96.416876 -276.516338) (xy 96.416364 -276.541784) (xy 96.4082 -276.592018) (xy 96.392084 -276.640292)
			(xy 96.368433 -276.685355) (xy 96.33786 -276.726041) (xy 96.301156 -276.761296) (xy 96.259272 -276.790206)
			(xy 96.213293 -276.812023) (xy 96.164409 -276.826183) (xy 96.113888 -276.832317) (xy 96.063036 -276.830268)
			(xy 96.013172 -276.820088) (xy 95.965586 -276.802041) (xy 95.921512 -276.776595) (xy 95.88209 -276.744408)
			(xy 95.848342 -276.706314) (xy 95.821141 -276.6633) (xy 95.801193 -276.61648) (xy 95.789014 -276.567066)
			(xy 95.784919 -276.516338) (xy 95.466408 -276.516338) (xy 95.465913 -276.540945) (xy 95.458018 -276.589522)
			(xy 95.442434 -276.636203) (xy 95.419563 -276.67978) (xy 95.389998 -276.719124) (xy 95.354505 -276.753216)
			(xy 95.314002 -276.781172) (xy 95.26954 -276.80227) (xy 95.222269 -276.815962) (xy 95.173414 -276.821894)
			(xy 95.124239 -276.819913) (xy 95.07602 -276.810069) (xy 95.030004 -276.792617) (xy 94.987383 -276.76801)
			(xy 94.949262 -276.736885) (xy 94.916627 -276.700048) (xy 94.890324 -276.658452) (xy 94.871033 -276.613176)
			(xy 94.859256 -276.565392) (xy 94.855296 -276.516338) (xy 94.536768 -276.516338) (xy 94.536256 -276.541784)
			(xy 94.528092 -276.592018) (xy 94.511976 -276.640292) (xy 94.488325 -276.685355) (xy 94.457752 -276.726041)
			(xy 94.421048 -276.761296) (xy 94.379164 -276.790206) (xy 94.333185 -276.812023) (xy 94.284301 -276.826183)
			(xy 94.23378 -276.832317) (xy 94.182928 -276.830268) (xy 94.133064 -276.820088) (xy 94.085478 -276.802041)
			(xy 94.041404 -276.776595) (xy 94.001982 -276.744408) (xy 93.968234 -276.706314) (xy 93.941033 -276.6633)
			(xy 93.921085 -276.61648) (xy 93.908906 -276.567066) (xy 93.904811 -276.516338) (xy 93.5863 -276.516338)
			(xy 93.585805 -276.540945) (xy 93.57791 -276.589522) (xy 93.562326 -276.636203) (xy 93.539455 -276.67978)
			(xy 93.50989 -276.719124) (xy 93.474397 -276.753216) (xy 93.433894 -276.781172) (xy 93.389432 -276.80227)
			(xy 93.342161 -276.815962) (xy 93.293306 -276.821894) (xy 93.244131 -276.819913) (xy 93.195912 -276.810069)
			(xy 93.149896 -276.792617) (xy 93.107275 -276.76801) (xy 93.069154 -276.736885) (xy 93.036519 -276.700048)
			(xy 93.010216 -276.658452) (xy 92.990925 -276.613176) (xy 92.979148 -276.565392) (xy 92.975188 -276.516338)
			(xy 92.65666 -276.516338) (xy 92.656148 -276.541784) (xy 92.647984 -276.592018) (xy 92.631868 -276.640292)
			(xy 92.608217 -276.685355) (xy 92.577644 -276.726041) (xy 92.54094 -276.761296) (xy 92.499056 -276.790206)
			(xy 92.453077 -276.812023) (xy 92.404193 -276.826183) (xy 92.353672 -276.832317) (xy 92.30282 -276.830268)
			(xy 92.252956 -276.820088) (xy 92.20537 -276.802041) (xy 92.161296 -276.776595) (xy 92.121874 -276.744408)
			(xy 92.088126 -276.706314) (xy 92.060925 -276.6633) (xy 92.040977 -276.61648) (xy 92.028798 -276.567066)
			(xy 92.024703 -276.516338) (xy 91.71686 -276.516338) (xy 91.716348 -276.541784) (xy 91.708184 -276.592018)
			(xy 91.692068 -276.640292) (xy 91.668417 -276.685355) (xy 91.637844 -276.726041) (xy 91.60114 -276.761296)
			(xy 91.559256 -276.790206) (xy 91.513277 -276.812023) (xy 91.464393 -276.826183) (xy 91.413872 -276.832317)
			(xy 91.36302 -276.830268) (xy 91.313156 -276.820088) (xy 91.26557 -276.802041) (xy 91.221496 -276.776595)
			(xy 91.182074 -276.744408) (xy 91.148326 -276.706314) (xy 91.121125 -276.6633) (xy 91.101177 -276.61648)
			(xy 91.088998 -276.567066) (xy 91.084903 -276.516338) (xy 90.766919 -276.516338) (xy 90.762751 -276.566638)
			(xy 90.750351 -276.615603) (xy 90.73006 -276.66186) (xy 90.702432 -276.704145) (xy 90.668221 -276.741306)
			(xy 90.62836 -276.772329) (xy 90.583936 -276.796368) (xy 90.536162 -276.812767) (xy 90.486339 -276.821079)
			(xy 90.461084 -276.821646) (xy 90.437211 -276.821191) (xy 90.390046 -276.813767) (xy 90.344612 -276.799088)
			(xy 90.302019 -276.777513) (xy 90.263307 -276.749566) (xy 90.229419 -276.715931) (xy 90.214958 -276.696932)
			(xy 90.214958 -276.696678) (xy 90.212303 -276.693251) (xy 90.206042 -276.687256) (xy 90.202512 -276.68474)
			(xy 90.194684 -276.679967) (xy 90.176845 -276.675795) (xy 90.167714 -276.676612) (xy 90.079068 -276.688042)
			(xy 90.072309 -276.689118) (xy 90.059688 -276.694398) (xy 90.054176 -276.698456) (xy 90.048842 -276.70252)
			(xy 90.040968 -276.713188) (xy 90.038428 -276.719792) (xy 90.02522 -276.75078) (xy 90.019886 -276.762118)
			(xy 90.008324 -276.784352) (xy 90.002106 -276.79523) (xy 89.957656 -276.872192) (xy 89.951893 -276.883342)
			(xy 89.95097 -276.908391) (xy 89.955878 -276.919944) (xy 89.992708 -276.995382) (xy 89.995662 -277.001154)
			(xy 90.004028 -277.011053) (xy 90.009218 -277.01494) (xy 90.019632 -277.022052) (xy 90.024458 -277.022814)
			(xy 90.049052 -277.026013) (xy 90.096819 -277.039348) (xy 90.141802 -277.060229) (xy 90.182818 -277.088107)
			(xy 90.218786 -277.12225) (xy 90.248762 -277.161759) (xy 90.271956 -277.205594) (xy 90.287758 -277.252603)
			(xy 90.295753 -277.301547) (xy 90.296238 -277.326344) (xy 90.614749 -277.326344) (xy 90.618844 -277.275616)
			(xy 90.631023 -277.226202) (xy 90.650971 -277.179382) (xy 90.678172 -277.136368) (xy 90.71192 -277.098274)
			(xy 90.751342 -277.066087) (xy 90.795416 -277.040641) (xy 90.843002 -277.022594) (xy 90.892866 -277.012414)
			(xy 90.943718 -277.010365) (xy 90.994239 -277.016499) (xy 91.043123 -277.030659) (xy 91.089102 -277.052476)
			(xy 91.130986 -277.081386) (xy 91.16769 -277.116641) (xy 91.198263 -277.157327) (xy 91.221914 -277.20239)
			(xy 91.23803 -277.250664) (xy 91.246194 -277.300898) (xy 91.246706 -277.326344) (xy 91.565234 -277.326344)
			(xy 91.569194 -277.27729) (xy 91.580971 -277.229506) (xy 91.600262 -277.18423) (xy 91.626565 -277.142634)
			(xy 91.6592 -277.105797) (xy 91.697321 -277.074672) (xy 91.739942 -277.050065) (xy 91.785958 -277.032613)
			(xy 91.834177 -277.022769) (xy 91.883352 -277.020788) (xy 91.932207 -277.02672) (xy 91.979478 -277.040412)
			(xy 92.02394 -277.06151) (xy 92.064443 -277.089466) (xy 92.099936 -277.123558) (xy 92.129501 -277.162902)
			(xy 92.152372 -277.206479) (xy 92.167956 -277.25316) (xy 92.175851 -277.301737) (xy 92.176346 -277.326344)
			(xy 92.494857 -277.326344) (xy 92.498952 -277.275616) (xy 92.511131 -277.226202) (xy 92.531079 -277.179382)
			(xy 92.55828 -277.136368) (xy 92.592028 -277.098274) (xy 92.63145 -277.066087) (xy 92.675524 -277.040641)
			(xy 92.72311 -277.022594) (xy 92.772974 -277.012414) (xy 92.823826 -277.010365) (xy 92.874347 -277.016499)
			(xy 92.923231 -277.030659) (xy 92.96921 -277.052476) (xy 93.011094 -277.081386) (xy 93.047798 -277.116641)
			(xy 93.078371 -277.157327) (xy 93.102022 -277.20239) (xy 93.118138 -277.250664) (xy 93.126302 -277.300898)
			(xy 93.126814 -277.326344) (xy 93.445342 -277.326344) (xy 93.449302 -277.27729) (xy 93.461079 -277.229506)
			(xy 93.48037 -277.18423) (xy 93.506673 -277.142634) (xy 93.539308 -277.105797) (xy 93.577429 -277.074672)
			(xy 93.62005 -277.050065) (xy 93.666066 -277.032613) (xy 93.714285 -277.022769) (xy 93.76346 -277.020788)
			(xy 93.812315 -277.02672) (xy 93.859586 -277.040412) (xy 93.904048 -277.06151) (xy 93.944551 -277.089466)
			(xy 93.980044 -277.123558) (xy 94.009609 -277.162902) (xy 94.03248 -277.206479) (xy 94.048064 -277.25316)
			(xy 94.055959 -277.301737) (xy 94.056454 -277.326344) (xy 94.374711 -277.326344) (xy 94.378806 -277.275616)
			(xy 94.390985 -277.226202) (xy 94.410933 -277.179382) (xy 94.438134 -277.136368) (xy 94.471882 -277.098274)
			(xy 94.511304 -277.066087) (xy 94.555378 -277.040641) (xy 94.602964 -277.022594) (xy 94.652828 -277.012414)
			(xy 94.70368 -277.010365) (xy 94.754201 -277.016499) (xy 94.803085 -277.030659) (xy 94.849064 -277.052476)
			(xy 94.890948 -277.081386) (xy 94.927652 -277.116641) (xy 94.958225 -277.157327) (xy 94.981876 -277.20239)
			(xy 94.997992 -277.250664) (xy 95.006156 -277.300898) (xy 95.006668 -277.326344) (xy 95.314765 -277.326344)
			(xy 95.31886 -277.275616) (xy 95.331039 -277.226202) (xy 95.350987 -277.179382) (xy 95.378188 -277.136368)
			(xy 95.411936 -277.098274) (xy 95.451358 -277.066087) (xy 95.495432 -277.040641) (xy 95.543018 -277.022594)
			(xy 95.592882 -277.012414) (xy 95.643734 -277.010365) (xy 95.694255 -277.016499) (xy 95.743139 -277.030659)
			(xy 95.789118 -277.052476) (xy 95.831002 -277.081386) (xy 95.867706 -277.116641) (xy 95.898279 -277.157327)
			(xy 95.92193 -277.20239) (xy 95.938046 -277.250664) (xy 95.94621 -277.300898) (xy 95.946722 -277.326344)
			(xy 95.94621 -277.35179) (xy 95.938046 -277.402024) (xy 95.92193 -277.450298) (xy 95.898279 -277.495361)
			(xy 95.867706 -277.536047) (xy 95.831002 -277.571302) (xy 95.789118 -277.600212) (xy 95.743139 -277.622029)
			(xy 95.694255 -277.636189) (xy 95.643734 -277.642323) (xy 95.592882 -277.640274) (xy 95.543018 -277.630094)
			(xy 95.495432 -277.612047) (xy 95.451358 -277.586601) (xy 95.411936 -277.554414) (xy 95.378188 -277.51632)
			(xy 95.350987 -277.473306) (xy 95.331039 -277.426486) (xy 95.31886 -277.377072) (xy 95.314765 -277.326344)
			(xy 95.006668 -277.326344) (xy 95.006156 -277.35179) (xy 94.997992 -277.402024) (xy 94.981876 -277.450298)
			(xy 94.958225 -277.495361) (xy 94.927652 -277.536047) (xy 94.890948 -277.571302) (xy 94.849064 -277.600212)
			(xy 94.803085 -277.622029) (xy 94.754201 -277.636189) (xy 94.70368 -277.642323) (xy 94.652828 -277.640274)
			(xy 94.602964 -277.630094) (xy 94.555378 -277.612047) (xy 94.511304 -277.586601) (xy 94.471882 -277.554414)
			(xy 94.438134 -277.51632) (xy 94.410933 -277.473306) (xy 94.390985 -277.426486) (xy 94.378806 -277.377072)
			(xy 94.374711 -277.326344) (xy 94.056454 -277.326344) (xy 94.055959 -277.350951) (xy 94.048064 -277.399528)
			(xy 94.03248 -277.446209) (xy 94.009609 -277.489786) (xy 93.980044 -277.52913) (xy 93.944551 -277.563222)
			(xy 93.904048 -277.591178) (xy 93.859586 -277.612276) (xy 93.812315 -277.625968) (xy 93.76346 -277.6319)
			(xy 93.714285 -277.629919) (xy 93.666066 -277.620075) (xy 93.62005 -277.602623) (xy 93.577429 -277.578016)
			(xy 93.539308 -277.546891) (xy 93.506673 -277.510054) (xy 93.48037 -277.468458) (xy 93.461079 -277.423182)
			(xy 93.449302 -277.375398) (xy 93.445342 -277.326344) (xy 93.126814 -277.326344) (xy 93.126302 -277.35179)
			(xy 93.118138 -277.402024) (xy 93.102022 -277.450298) (xy 93.078371 -277.495361) (xy 93.047798 -277.536047)
			(xy 93.011094 -277.571302) (xy 92.96921 -277.600212) (xy 92.923231 -277.622029) (xy 92.874347 -277.636189)
			(xy 92.823826 -277.642323) (xy 92.772974 -277.640274) (xy 92.72311 -277.630094) (xy 92.675524 -277.612047)
			(xy 92.63145 -277.586601) (xy 92.592028 -277.554414) (xy 92.55828 -277.51632) (xy 92.531079 -277.473306)
			(xy 92.511131 -277.426486) (xy 92.498952 -277.377072) (xy 92.494857 -277.326344) (xy 92.176346 -277.326344)
			(xy 92.175851 -277.350951) (xy 92.167956 -277.399528) (xy 92.152372 -277.446209) (xy 92.129501 -277.489786)
			(xy 92.099936 -277.52913) (xy 92.064443 -277.563222) (xy 92.02394 -277.591178) (xy 91.979478 -277.612276)
			(xy 91.932207 -277.625968) (xy 91.883352 -277.6319) (xy 91.834177 -277.629919) (xy 91.785958 -277.620075)
			(xy 91.739942 -277.602623) (xy 91.697321 -277.578016) (xy 91.6592 -277.546891) (xy 91.626565 -277.510054)
			(xy 91.600262 -277.468458) (xy 91.580971 -277.423182) (xy 91.569194 -277.375398) (xy 91.565234 -277.326344)
			(xy 91.246706 -277.326344) (xy 91.246194 -277.35179) (xy 91.23803 -277.402024) (xy 91.221914 -277.450298)
			(xy 91.198263 -277.495361) (xy 91.16769 -277.536047) (xy 91.130986 -277.571302) (xy 91.089102 -277.600212)
			(xy 91.043123 -277.622029) (xy 90.994239 -277.636189) (xy 90.943718 -277.642323) (xy 90.892866 -277.640274)
			(xy 90.843002 -277.630094) (xy 90.795416 -277.612047) (xy 90.751342 -277.586601) (xy 90.71192 -277.554414)
			(xy 90.678172 -277.51632) (xy 90.650971 -277.473306) (xy 90.631023 -277.426486) (xy 90.618844 -277.377072)
			(xy 90.614749 -277.326344) (xy 90.296238 -277.326344) (xy 90.295749 -277.351163) (xy 90.287713 -277.400146)
			(xy 90.271859 -277.447184) (xy 90.248606 -277.491038) (xy 90.218565 -277.530554) (xy 90.182528 -277.56469)
			(xy 90.141444 -277.592547) (xy 90.096395 -277.613392) (xy 90.048567 -277.626675) (xy 90.02395 -277.629874)
			(xy 90.023696 -277.629874) (xy 90.01699 -277.630793) (xy 90.004373 -277.635679) (xy 89.998804 -277.639526)
			(xy 89.993724 -277.64359) (xy 89.985342 -277.654004) (xy 89.948004 -277.74265) (xy 89.945528 -277.749077)
			(xy 89.94372 -277.762725) (xy 89.944448 -277.769574) (xy 89.946226 -277.782782) (xy 89.954862 -277.793704)
			(xy 89.97973 -277.8264) (xy 90.02054 -277.897689) (xy 90.036142 -277.93569) (xy 90.036142 -277.935944)
			(xy 90.038777 -277.942127) (xy 90.046763 -277.952933) (xy 90.05189 -277.95728) (xy 90.063066 -277.965916)
			(xy 90.075512 -277.96744) (xy 90.165682 -277.97887) (xy 90.172562 -277.979472) (xy 90.186214 -277.977419)
			(xy 90.192606 -277.974806) (xy 90.198448 -277.972266) (xy 90.208862 -277.963884) (xy 90.21318 -277.958042)
			(xy 90.227647 -277.938745) (xy 90.261638 -277.904534) (xy 90.300578 -277.876083) (xy 90.343502 -277.854099)
			(xy 90.389345 -277.839126) (xy 90.436971 -277.831537) (xy 90.461084 -277.831042) (xy 90.486338 -277.831533)
			(xy 90.536159 -277.839844) (xy 90.583932 -277.856243) (xy 90.628354 -277.880281) (xy 90.668213 -277.911303)
			(xy 90.702423 -277.948462) (xy 90.730049 -277.990746) (xy 90.750339 -278.037) (xy 90.762739 -278.085964)
			(xy 90.76691 -278.1363) (xy 90.766906 -278.13635) (xy 91.084903 -278.13635) (xy 91.088998 -278.085622)
			(xy 91.101177 -278.036208) (xy 91.121125 -277.989388) (xy 91.148326 -277.946374) (xy 91.182074 -277.90828)
			(xy 91.221496 -277.876093) (xy 91.26557 -277.850647) (xy 91.313156 -277.8326) (xy 91.36302 -277.82242)
			(xy 91.413872 -277.820371) (xy 91.464393 -277.826505) (xy 91.513277 -277.840665) (xy 91.559256 -277.862482)
			(xy 91.60114 -277.891392) (xy 91.637844 -277.926647) (xy 91.668417 -277.967333) (xy 91.692068 -278.012396)
			(xy 91.708184 -278.06067) (xy 91.716348 -278.110904) (xy 91.71686 -278.13635) (xy 92.024703 -278.13635)
			(xy 92.028798 -278.085622) (xy 92.040977 -278.036208) (xy 92.060925 -277.989388) (xy 92.088126 -277.946374)
			(xy 92.121874 -277.90828) (xy 92.161296 -277.876093) (xy 92.20537 -277.850647) (xy 92.252956 -277.8326)
			(xy 92.30282 -277.82242) (xy 92.353672 -277.820371) (xy 92.404193 -277.826505) (xy 92.453077 -277.840665)
			(xy 92.499056 -277.862482) (xy 92.54094 -277.891392) (xy 92.577644 -277.926647) (xy 92.608217 -277.967333)
			(xy 92.631868 -278.012396) (xy 92.647984 -278.06067) (xy 92.656148 -278.110904) (xy 92.65666 -278.13635)
			(xy 93.904811 -278.13635) (xy 93.908906 -278.085622) (xy 93.921085 -278.036208) (xy 93.941033 -277.989388)
			(xy 93.968234 -277.946374) (xy 94.001982 -277.90828) (xy 94.041404 -277.876093) (xy 94.085478 -277.850647)
			(xy 94.133064 -277.8326) (xy 94.182928 -277.82242) (xy 94.23378 -277.820371) (xy 94.284301 -277.826505)
			(xy 94.333185 -277.840665) (xy 94.379164 -277.862482) (xy 94.421048 -277.891392) (xy 94.457752 -277.926647)
			(xy 94.488325 -277.967333) (xy 94.511976 -278.012396) (xy 94.528092 -278.06067) (xy 94.536256 -278.110904)
			(xy 94.536768 -278.13635) (xy 94.855296 -278.13635) (xy 94.859256 -278.087296) (xy 94.871033 -278.039512)
			(xy 94.890324 -277.994236) (xy 94.916627 -277.95264) (xy 94.949262 -277.915803) (xy 94.987383 -277.884678)
			(xy 95.030004 -277.860071) (xy 95.07602 -277.842619) (xy 95.124239 -277.832775) (xy 95.173414 -277.830794)
			(xy 95.222269 -277.836726) (xy 95.26954 -277.850418) (xy 95.314002 -277.871516) (xy 95.354505 -277.899472)
			(xy 95.389998 -277.933564) (xy 95.419563 -277.972908) (xy 95.442434 -278.016485) (xy 95.458018 -278.063166)
			(xy 95.465913 -278.111743) (xy 95.466408 -278.13635) (xy 95.784919 -278.13635) (xy 95.789014 -278.085622)
			(xy 95.801193 -278.036208) (xy 95.821141 -277.989388) (xy 95.848342 -277.946374) (xy 95.88209 -277.90828)
			(xy 95.921512 -277.876093) (xy 95.965586 -277.850647) (xy 96.013172 -277.8326) (xy 96.063036 -277.82242)
			(xy 96.113888 -277.820371) (xy 96.164409 -277.826505) (xy 96.213293 -277.840665) (xy 96.259272 -277.862482)
			(xy 96.301156 -277.891392) (xy 96.33786 -277.926647) (xy 96.368433 -277.967333) (xy 96.392084 -278.012396)
			(xy 96.4082 -278.06067) (xy 96.416364 -278.110904) (xy 96.416876 -278.13635) (xy 96.416364 -278.161796)
			(xy 96.4082 -278.21203) (xy 96.392084 -278.260304) (xy 96.368433 -278.305367) (xy 96.33786 -278.346053)
			(xy 96.301156 -278.381308) (xy 96.259272 -278.410218) (xy 96.213293 -278.432035) (xy 96.164409 -278.446195)
			(xy 96.113888 -278.452329) (xy 96.063036 -278.45028) (xy 96.013172 -278.4401) (xy 95.965586 -278.422053)
			(xy 95.921512 -278.396607) (xy 95.88209 -278.36442) (xy 95.848342 -278.326326) (xy 95.821141 -278.283312)
			(xy 95.801193 -278.236492) (xy 95.789014 -278.187078) (xy 95.784919 -278.13635) (xy 95.466408 -278.13635)
			(xy 95.465913 -278.160957) (xy 95.458018 -278.209534) (xy 95.442434 -278.256215) (xy 95.419563 -278.299792)
			(xy 95.389998 -278.339136) (xy 95.354505 -278.373228) (xy 95.314002 -278.401184) (xy 95.26954 -278.422282)
			(xy 95.222269 -278.435974) (xy 95.173414 -278.441906) (xy 95.124239 -278.439925) (xy 95.07602 -278.430081)
			(xy 95.030004 -278.412629) (xy 94.987383 -278.388022) (xy 94.949262 -278.356897) (xy 94.916627 -278.32006)
			(xy 94.890324 -278.278464) (xy 94.871033 -278.233188) (xy 94.859256 -278.185404) (xy 94.855296 -278.13635)
			(xy 94.536768 -278.13635) (xy 94.536256 -278.161796) (xy 94.528092 -278.21203) (xy 94.511976 -278.260304)
			(xy 94.488325 -278.305367) (xy 94.457752 -278.346053) (xy 94.421048 -278.381308) (xy 94.379164 -278.410218)
			(xy 94.333185 -278.432035) (xy 94.284301 -278.446195) (xy 94.23378 -278.452329) (xy 94.182928 -278.45028)
			(xy 94.133064 -278.4401) (xy 94.085478 -278.422053) (xy 94.041404 -278.396607) (xy 94.001982 -278.36442)
			(xy 93.968234 -278.326326) (xy 93.941033 -278.283312) (xy 93.921085 -278.236492) (xy 93.908906 -278.187078)
			(xy 93.904811 -278.13635) (xy 92.65666 -278.13635) (xy 92.656148 -278.161796) (xy 92.647984 -278.21203)
			(xy 92.631868 -278.260304) (xy 92.608217 -278.305367) (xy 92.577644 -278.346053) (xy 92.54094 -278.381308)
			(xy 92.499056 -278.410218) (xy 92.453077 -278.432035) (xy 92.404193 -278.446195) (xy 92.353672 -278.452329)
			(xy 92.30282 -278.45028) (xy 92.252956 -278.4401) (xy 92.20537 -278.422053) (xy 92.161296 -278.396607)
			(xy 92.121874 -278.36442) (xy 92.088126 -278.326326) (xy 92.060925 -278.283312) (xy 92.040977 -278.236492)
			(xy 92.028798 -278.187078) (xy 92.024703 -278.13635) (xy 91.71686 -278.13635) (xy 91.716348 -278.161796)
			(xy 91.708184 -278.21203) (xy 91.692068 -278.260304) (xy 91.668417 -278.305367) (xy 91.637844 -278.346053)
			(xy 91.60114 -278.381308) (xy 91.559256 -278.410218) (xy 91.513277 -278.432035) (xy 91.464393 -278.446195)
			(xy 91.413872 -278.452329) (xy 91.36302 -278.45028) (xy 91.313156 -278.4401) (xy 91.26557 -278.422053)
			(xy 91.221496 -278.396607) (xy 91.182074 -278.36442) (xy 91.148326 -278.326326) (xy 91.121125 -278.283312)
			(xy 91.101177 -278.236492) (xy 91.088998 -278.187078) (xy 91.084903 -278.13635) (xy 90.766906 -278.13635)
			(xy 90.762739 -278.186636) (xy 90.750339 -278.2356) (xy 90.730049 -278.281854) (xy 90.702423 -278.324138)
			(xy 90.668213 -278.361297) (xy 90.628354 -278.392319) (xy 90.583932 -278.416357) (xy 90.536159 -278.432756)
			(xy 90.486338 -278.441067) (xy 90.461084 -278.441658) (xy 90.448321 -278.44152) (xy 90.422887 -278.43936)
			(xy 90.410284 -278.43734) (xy 90.410284 -278.437594) (xy 90.386832 -278.433164) (xy 90.341582 -278.417998)
			(xy 90.299236 -278.39599) (xy 90.26082 -278.367674) (xy 90.227266 -278.333737) (xy 90.212926 -278.314658)
			(xy 90.208862 -278.308816) (xy 90.198194 -278.30018) (xy 90.192352 -278.29764) (xy 90.186068 -278.295121)
			(xy 90.172675 -278.29319) (xy 90.165936 -278.29383) (xy 90.075512 -278.30526) (xy 90.063066 -278.306784)
			(xy 90.05189 -278.31542) (xy 90.046757 -278.319761) (xy 90.038769 -278.330568) (xy 90.036142 -278.336756)
			(xy 90.036142 -278.33701) (xy 90.028245 -278.35679) (xy 90.00981 -278.395187) (xy 89.999312 -278.413718)
			(xy 89.9541 -278.491696) (xy 89.948375 -278.502936) (xy 89.947584 -278.528117) (xy 89.952576 -278.539702)
			(xy 89.981024 -278.597106) (xy 89.989914 -278.615394) (xy 89.992913 -278.62103) (xy 90.001268 -278.630679)
			(xy 90.006424 -278.634444) (xy 90.01633 -278.641556) (xy 90.02649 -278.64308) (xy 90.029284 -278.643334)
			(xy 90.053547 -278.646921) (xy 90.100579 -278.660817) (xy 90.144789 -278.682046) (xy 90.185042 -278.710063)
			(xy 90.220304 -278.744148) (xy 90.24967 -278.783427) (xy 90.272387 -278.826891) (xy 90.287871 -278.873425)
			(xy 90.295726 -278.921835) (xy 90.296238 -278.946356) (xy 90.614749 -278.946356) (xy 90.618844 -278.895628)
			(xy 90.631023 -278.846214) (xy 90.650971 -278.799394) (xy 90.678172 -278.75638) (xy 90.71192 -278.718286)
			(xy 90.751342 -278.686099) (xy 90.795416 -278.660653) (xy 90.843002 -278.642606) (xy 90.892866 -278.632426)
			(xy 90.943718 -278.630377) (xy 90.994239 -278.636511) (xy 91.043123 -278.650671) (xy 91.089102 -278.672488)
			(xy 91.130986 -278.701398) (xy 91.16769 -278.736653) (xy 91.198263 -278.777339) (xy 91.221914 -278.822402)
			(xy 91.23803 -278.870676) (xy 91.246194 -278.92091) (xy 91.246706 -278.946356) (xy 91.565234 -278.946356)
			(xy 91.569194 -278.897302) (xy 91.580971 -278.849518) (xy 91.600262 -278.804242) (xy 91.626565 -278.762646)
			(xy 91.6592 -278.725809) (xy 91.697321 -278.694684) (xy 91.739942 -278.670077) (xy 91.785958 -278.652625)
			(xy 91.834177 -278.642781) (xy 91.883352 -278.6408) (xy 91.932207 -278.646732) (xy 91.979478 -278.660424)
			(xy 92.02394 -278.681522) (xy 92.064443 -278.709478) (xy 92.099936 -278.74357) (xy 92.129501 -278.782914)
			(xy 92.152372 -278.826491) (xy 92.167956 -278.873172) (xy 92.175851 -278.921749) (xy 92.176346 -278.946356)
			(xy 92.494857 -278.946356) (xy 92.498952 -278.895628) (xy 92.511131 -278.846214) (xy 92.531079 -278.799394)
			(xy 92.55828 -278.75638) (xy 92.592028 -278.718286) (xy 92.63145 -278.686099) (xy 92.675524 -278.660653)
			(xy 92.72311 -278.642606) (xy 92.772974 -278.632426) (xy 92.823826 -278.630377) (xy 92.874347 -278.636511)
			(xy 92.923231 -278.650671) (xy 92.96921 -278.672488) (xy 93.011094 -278.701398) (xy 93.047798 -278.736653)
			(xy 93.078371 -278.777339) (xy 93.102022 -278.822402) (xy 93.118138 -278.870676) (xy 93.126302 -278.92091)
			(xy 93.126814 -278.946356) (xy 93.445342 -278.946356) (xy 93.449302 -278.897302) (xy 93.461079 -278.849518)
			(xy 93.48037 -278.804242) (xy 93.506673 -278.762646) (xy 93.539308 -278.725809) (xy 93.577429 -278.694684)
			(xy 93.62005 -278.670077) (xy 93.666066 -278.652625) (xy 93.714285 -278.642781) (xy 93.76346 -278.6408)
			(xy 93.812315 -278.646732) (xy 93.859586 -278.660424) (xy 93.904048 -278.681522) (xy 93.944551 -278.709478)
			(xy 93.980044 -278.74357) (xy 94.009609 -278.782914) (xy 94.03248 -278.826491) (xy 94.048064 -278.873172)
			(xy 94.055959 -278.921749) (xy 94.056454 -278.946356) (xy 94.374711 -278.946356) (xy 94.378806 -278.895628)
			(xy 94.390985 -278.846214) (xy 94.410933 -278.799394) (xy 94.438134 -278.75638) (xy 94.471882 -278.718286)
			(xy 94.511304 -278.686099) (xy 94.555378 -278.660653) (xy 94.602964 -278.642606) (xy 94.652828 -278.632426)
			(xy 94.70368 -278.630377) (xy 94.754201 -278.636511) (xy 94.803085 -278.650671) (xy 94.849064 -278.672488)
			(xy 94.890948 -278.701398) (xy 94.927652 -278.736653) (xy 94.958225 -278.777339) (xy 94.981876 -278.822402)
			(xy 94.997992 -278.870676) (xy 95.006156 -278.92091) (xy 95.006668 -278.946356) (xy 95.314765 -278.946356)
			(xy 95.31886 -278.895628) (xy 95.331039 -278.846214) (xy 95.350987 -278.799394) (xy 95.378188 -278.75638)
			(xy 95.411936 -278.718286) (xy 95.451358 -278.686099) (xy 95.495432 -278.660653) (xy 95.543018 -278.642606)
			(xy 95.592882 -278.632426) (xy 95.643734 -278.630377) (xy 95.694255 -278.636511) (xy 95.743139 -278.650671)
			(xy 95.789118 -278.672488) (xy 95.831002 -278.701398) (xy 95.867706 -278.736653) (xy 95.898279 -278.777339)
			(xy 95.92193 -278.822402) (xy 95.938046 -278.870676) (xy 95.94621 -278.92091) (xy 95.946722 -278.946356)
			(xy 95.94621 -278.971802) (xy 95.938046 -279.022036) (xy 95.92193 -279.07031) (xy 95.898279 -279.115373)
			(xy 95.867706 -279.156059) (xy 95.831002 -279.191314) (xy 95.789118 -279.220224) (xy 95.743139 -279.242041)
			(xy 95.694255 -279.256201) (xy 95.643734 -279.262335) (xy 95.592882 -279.260286) (xy 95.543018 -279.250106)
			(xy 95.495432 -279.232059) (xy 95.451358 -279.206613) (xy 95.411936 -279.174426) (xy 95.378188 -279.136332)
			(xy 95.350987 -279.093318) (xy 95.331039 -279.046498) (xy 95.31886 -278.997084) (xy 95.314765 -278.946356)
			(xy 95.006668 -278.946356) (xy 95.006156 -278.971802) (xy 94.997992 -279.022036) (xy 94.981876 -279.07031)
			(xy 94.958225 -279.115373) (xy 94.927652 -279.156059) (xy 94.890948 -279.191314) (xy 94.849064 -279.220224)
			(xy 94.803085 -279.242041) (xy 94.754201 -279.256201) (xy 94.70368 -279.262335) (xy 94.652828 -279.260286)
			(xy 94.602964 -279.250106) (xy 94.555378 -279.232059) (xy 94.511304 -279.206613) (xy 94.471882 -279.174426)
			(xy 94.438134 -279.136332) (xy 94.410933 -279.093318) (xy 94.390985 -279.046498) (xy 94.378806 -278.997084)
			(xy 94.374711 -278.946356) (xy 94.056454 -278.946356) (xy 94.055959 -278.970963) (xy 94.048064 -279.01954)
			(xy 94.03248 -279.066221) (xy 94.009609 -279.109798) (xy 93.980044 -279.149142) (xy 93.944551 -279.183234)
			(xy 93.904048 -279.21119) (xy 93.859586 -279.232288) (xy 93.812315 -279.24598) (xy 93.76346 -279.251912)
			(xy 93.714285 -279.249931) (xy 93.666066 -279.240087) (xy 93.62005 -279.222635) (xy 93.577429 -279.198028)
			(xy 93.539308 -279.166903) (xy 93.506673 -279.130066) (xy 93.48037 -279.08847) (xy 93.461079 -279.043194)
			(xy 93.449302 -278.99541) (xy 93.445342 -278.946356) (xy 93.126814 -278.946356) (xy 93.126302 -278.971802)
			(xy 93.118138 -279.022036) (xy 93.102022 -279.07031) (xy 93.078371 -279.115373) (xy 93.047798 -279.156059)
			(xy 93.011094 -279.191314) (xy 92.96921 -279.220224) (xy 92.923231 -279.242041) (xy 92.874347 -279.256201)
			(xy 92.823826 -279.262335) (xy 92.772974 -279.260286) (xy 92.72311 -279.250106) (xy 92.675524 -279.232059)
			(xy 92.63145 -279.206613) (xy 92.592028 -279.174426) (xy 92.55828 -279.136332) (xy 92.531079 -279.093318)
			(xy 92.511131 -279.046498) (xy 92.498952 -278.997084) (xy 92.494857 -278.946356) (xy 92.176346 -278.946356)
			(xy 92.175851 -278.970963) (xy 92.167956 -279.01954) (xy 92.152372 -279.066221) (xy 92.129501 -279.109798)
			(xy 92.099936 -279.149142) (xy 92.064443 -279.183234) (xy 92.02394 -279.21119) (xy 91.979478 -279.232288)
			(xy 91.932207 -279.24598) (xy 91.883352 -279.251912) (xy 91.834177 -279.249931) (xy 91.785958 -279.240087)
			(xy 91.739942 -279.222635) (xy 91.697321 -279.198028) (xy 91.6592 -279.166903) (xy 91.626565 -279.130066)
			(xy 91.600262 -279.08847) (xy 91.580971 -279.043194) (xy 91.569194 -278.99541) (xy 91.565234 -278.946356)
			(xy 91.246706 -278.946356) (xy 91.246194 -278.971802) (xy 91.23803 -279.022036) (xy 91.221914 -279.07031)
			(xy 91.198263 -279.115373) (xy 91.16769 -279.156059) (xy 91.130986 -279.191314) (xy 91.089102 -279.220224)
			(xy 91.043123 -279.242041) (xy 90.994239 -279.256201) (xy 90.943718 -279.262335) (xy 90.892866 -279.260286)
			(xy 90.843002 -279.250106) (xy 90.795416 -279.232059) (xy 90.751342 -279.206613) (xy 90.71192 -279.174426)
			(xy 90.678172 -279.136332) (xy 90.650971 -279.093318) (xy 90.631023 -279.046498) (xy 90.618844 -278.997084)
			(xy 90.614749 -278.946356) (xy 90.296238 -278.946356) (xy 90.295748 -278.971174) (xy 90.28771 -279.020156)
			(xy 90.271855 -279.067192) (xy 90.248601 -279.111045) (xy 90.21856 -279.150559) (xy 90.182524 -279.184693)
			(xy 90.14144 -279.212549) (xy 90.096392 -279.233393) (xy 90.048566 -279.246676) (xy 90.02395 -279.249886)
			(xy 90.023696 -279.249886) (xy 90.01699 -279.250805) (xy 90.004373 -279.255692) (xy 89.998804 -279.259538)
			(xy 89.993724 -279.263602) (xy 89.985342 -279.274016) (xy 89.948004 -279.362662) (xy 89.945529 -279.369089)
			(xy 89.943725 -279.382737) (xy 89.944448 -279.389586) (xy 89.946226 -279.402794) (xy 89.954862 -279.413716)
			(xy 89.97973 -279.446413) (xy 90.020538 -279.517702) (xy 90.036142 -279.555702) (xy 90.036142 -279.555956)
			(xy 90.038778 -279.562139) (xy 90.046766 -279.572942) (xy 90.05189 -279.577292) (xy 90.063066 -279.585928)
			(xy 90.075512 -279.587452) (xy 90.165682 -279.598882) (xy 90.172562 -279.599484) (xy 90.186214 -279.597431)
			(xy 90.192606 -279.594818) (xy 90.198448 -279.592278) (xy 90.208862 -279.583896) (xy 90.21318 -279.578054)
			(xy 90.227646 -279.558757) (xy 90.261637 -279.524544) (xy 90.300577 -279.496092) (xy 90.343501 -279.474107)
			(xy 90.389345 -279.459134) (xy 90.436971 -279.451544) (xy 90.461084 -279.451054) (xy 90.486346 -279.451546)
			(xy 90.53618 -279.459859) (xy 90.583967 -279.476262) (xy 90.628402 -279.500307) (xy 90.668273 -279.531338)
			(xy 90.702492 -279.568508) (xy 90.730127 -279.610804) (xy 90.750423 -279.657072) (xy 90.762826 -279.706049)
			(xy 90.766995 -279.756362) (xy 91.084903 -279.756362) (xy 91.088998 -279.705634) (xy 91.101177 -279.65622)
			(xy 91.121125 -279.6094) (xy 91.148326 -279.566386) (xy 91.182074 -279.528292) (xy 91.221496 -279.496105)
			(xy 91.26557 -279.470659) (xy 91.313156 -279.452612) (xy 91.36302 -279.442432) (xy 91.413872 -279.440383)
			(xy 91.464393 -279.446517) (xy 91.513277 -279.460677) (xy 91.559256 -279.482494) (xy 91.60114 -279.511404)
			(xy 91.637844 -279.546659) (xy 91.668417 -279.587345) (xy 91.692068 -279.632408) (xy 91.708184 -279.680682)
			(xy 91.716348 -279.730916) (xy 91.71686 -279.756362) (xy 92.024703 -279.756362) (xy 92.028798 -279.705634)
			(xy 92.040977 -279.65622) (xy 92.060925 -279.6094) (xy 92.088126 -279.566386) (xy 92.121874 -279.528292)
			(xy 92.161296 -279.496105) (xy 92.20537 -279.470659) (xy 92.252956 -279.452612) (xy 92.30282 -279.442432)
			(xy 92.353672 -279.440383) (xy 92.404193 -279.446517) (xy 92.453077 -279.460677) (xy 92.499056 -279.482494)
			(xy 92.54094 -279.511404) (xy 92.577644 -279.546659) (xy 92.608217 -279.587345) (xy 92.631868 -279.632408)
			(xy 92.647984 -279.680682) (xy 92.656148 -279.730916) (xy 92.65666 -279.756362) (xy 92.975188 -279.756362)
			(xy 92.979148 -279.707308) (xy 92.990925 -279.659524) (xy 93.010216 -279.614248) (xy 93.036519 -279.572652)
			(xy 93.069154 -279.535815) (xy 93.107275 -279.50469) (xy 93.149896 -279.480083) (xy 93.195912 -279.462631)
			(xy 93.244131 -279.452787) (xy 93.293306 -279.450806) (xy 93.342161 -279.456738) (xy 93.389432 -279.47043)
			(xy 93.433894 -279.491528) (xy 93.474397 -279.519484) (xy 93.50989 -279.553576) (xy 93.539455 -279.59292)
			(xy 93.562326 -279.636497) (xy 93.57791 -279.683178) (xy 93.585805 -279.731755) (xy 93.5863 -279.756362)
			(xy 93.904811 -279.756362) (xy 93.908906 -279.705634) (xy 93.921085 -279.65622) (xy 93.941033 -279.6094)
			(xy 93.968234 -279.566386) (xy 94.001982 -279.528292) (xy 94.041404 -279.496105) (xy 94.085478 -279.470659)
			(xy 94.133064 -279.452612) (xy 94.182928 -279.442432) (xy 94.23378 -279.440383) (xy 94.284301 -279.446517)
			(xy 94.333185 -279.460677) (xy 94.379164 -279.482494) (xy 94.421048 -279.511404) (xy 94.457752 -279.546659)
			(xy 94.488325 -279.587345) (xy 94.511976 -279.632408) (xy 94.528092 -279.680682) (xy 94.536256 -279.730916)
			(xy 94.536768 -279.756362) (xy 94.855296 -279.756362) (xy 94.859256 -279.707308) (xy 94.871033 -279.659524)
			(xy 94.890324 -279.614248) (xy 94.916627 -279.572652) (xy 94.949262 -279.535815) (xy 94.987383 -279.50469)
			(xy 95.030004 -279.480083) (xy 95.07602 -279.462631) (xy 95.124239 -279.452787) (xy 95.173414 -279.450806)
			(xy 95.222269 -279.456738) (xy 95.26954 -279.47043) (xy 95.314002 -279.491528) (xy 95.354505 -279.519484)
			(xy 95.389998 -279.553576) (xy 95.419563 -279.59292) (xy 95.442434 -279.636497) (xy 95.458018 -279.683178)
			(xy 95.465913 -279.731755) (xy 95.466408 -279.756362) (xy 95.465913 -279.780969) (xy 95.458018 -279.829546)
			(xy 95.442434 -279.876227) (xy 95.419563 -279.919804) (xy 95.389998 -279.959148) (xy 95.354505 -279.99324)
			(xy 95.314002 -280.021196) (xy 95.26954 -280.042294) (xy 95.222269 -280.055986) (xy 95.173414 -280.061918)
			(xy 95.124239 -280.059937) (xy 95.07602 -280.050093) (xy 95.030004 -280.032641) (xy 94.987383 -280.008034)
			(xy 94.949262 -279.976909) (xy 94.916627 -279.940072) (xy 94.890324 -279.898476) (xy 94.871033 -279.8532)
			(xy 94.859256 -279.805416) (xy 94.855296 -279.756362) (xy 94.536768 -279.756362) (xy 94.536256 -279.781808)
			(xy 94.528092 -279.832042) (xy 94.511976 -279.880316) (xy 94.488325 -279.925379) (xy 94.457752 -279.966065)
			(xy 94.421048 -280.00132) (xy 94.379164 -280.03023) (xy 94.333185 -280.052047) (xy 94.284301 -280.066207)
			(xy 94.23378 -280.072341) (xy 94.182928 -280.070292) (xy 94.133064 -280.060112) (xy 94.085478 -280.042065)
			(xy 94.041404 -280.016619) (xy 94.001982 -279.984432) (xy 93.968234 -279.946338) (xy 93.941033 -279.903324)
			(xy 93.921085 -279.856504) (xy 93.908906 -279.80709) (xy 93.904811 -279.756362) (xy 93.5863 -279.756362)
			(xy 93.585805 -279.780969) (xy 93.57791 -279.829546) (xy 93.562326 -279.876227) (xy 93.539455 -279.919804)
			(xy 93.50989 -279.959148) (xy 93.474397 -279.99324) (xy 93.433894 -280.021196) (xy 93.389432 -280.042294)
			(xy 93.342161 -280.055986) (xy 93.293306 -280.061918) (xy 93.244131 -280.059937) (xy 93.195912 -280.050093)
			(xy 93.149896 -280.032641) (xy 93.107275 -280.008034) (xy 93.069154 -279.976909) (xy 93.036519 -279.940072)
			(xy 93.010216 -279.898476) (xy 92.990925 -279.8532) (xy 92.979148 -279.805416) (xy 92.975188 -279.756362)
			(xy 92.65666 -279.756362) (xy 92.656148 -279.781808) (xy 92.647984 -279.832042) (xy 92.631868 -279.880316)
			(xy 92.608217 -279.925379) (xy 92.577644 -279.966065) (xy 92.54094 -280.00132) (xy 92.499056 -280.03023)
			(xy 92.453077 -280.052047) (xy 92.404193 -280.066207) (xy 92.353672 -280.072341) (xy 92.30282 -280.070292)
			(xy 92.252956 -280.060112) (xy 92.20537 -280.042065) (xy 92.161296 -280.016619) (xy 92.121874 -279.984432)
			(xy 92.088126 -279.946338) (xy 92.060925 -279.903324) (xy 92.040977 -279.856504) (xy 92.028798 -279.80709)
			(xy 92.024703 -279.756362) (xy 91.71686 -279.756362) (xy 91.716348 -279.781808) (xy 91.708184 -279.832042)
			(xy 91.692068 -279.880316) (xy 91.668417 -279.925379) (xy 91.637844 -279.966065) (xy 91.60114 -280.00132)
			(xy 91.559256 -280.03023) (xy 91.513277 -280.052047) (xy 91.464393 -280.066207) (xy 91.413872 -280.072341)
			(xy 91.36302 -280.070292) (xy 91.313156 -280.060112) (xy 91.26557 -280.042065) (xy 91.221496 -280.016619)
			(xy 91.182074 -279.984432) (xy 91.148326 -279.946338) (xy 91.121125 -279.903324) (xy 91.101177 -279.856504)
			(xy 91.088998 -279.80709) (xy 91.084903 -279.756362) (xy 90.766995 -279.756362) (xy 90.766998 -279.7564)
			(xy 90.762826 -279.806751) (xy 90.750423 -279.855728) (xy 90.730127 -279.901996) (xy 90.702492 -279.944292)
			(xy 90.668273 -279.981462) (xy 90.628402 -280.012493) (xy 90.583967 -280.036538) (xy 90.53618 -280.052941)
			(xy 90.486346 -280.061254) (xy 90.461084 -280.06167) (xy 90.448321 -280.061532) (xy 90.422887 -280.059372)
			(xy 90.410284 -280.057352) (xy 90.410284 -280.057606) (xy 90.386832 -280.053177) (xy 90.341582 -280.038011)
			(xy 90.299234 -280.016003) (xy 90.260818 -279.987688) (xy 90.227262 -279.953752) (xy 90.212926 -279.93467)
			(xy 90.208862 -279.928828) (xy 90.198194 -279.920192) (xy 90.192352 -279.917652) (xy 90.186069 -279.915133)
			(xy 90.172675 -279.913201) (xy 90.165936 -279.913842) (xy 90.075512 -279.925272) (xy 90.063066 -279.926796)
			(xy 90.05189 -279.935432) (xy 90.046758 -279.939774) (xy 90.038772 -279.950582) (xy 90.036142 -279.956768)
			(xy 90.036142 -279.957022) (xy 90.028245 -279.976801) (xy 90.009809 -280.015199) (xy 89.999312 -280.03373)
			(xy 89.9541 -280.111708) (xy 89.948378 -280.122948) (xy 89.947592 -280.148126) (xy 89.952576 -280.159714)
			(xy 89.981024 -280.217118) (xy 89.989914 -280.235406) (xy 89.992914 -280.241041) (xy 90.001271 -280.250688)
			(xy 90.006424 -280.254456) (xy 90.01633 -280.261568) (xy 90.02649 -280.263092) (xy 90.029284 -280.263346)
			(xy 90.053546 -280.266933) (xy 90.100578 -280.280829) (xy 90.144787 -280.302059) (xy 90.185039 -280.330076)
			(xy 90.220299 -280.364161) (xy 90.249664 -280.40344) (xy 90.272379 -280.446904) (xy 90.287862 -280.493438)
			(xy 90.295715 -280.541847) (xy 90.296238 -280.566368) (xy 90.614749 -280.566368) (xy 90.618844 -280.51564)
			(xy 90.631023 -280.466226) (xy 90.650971 -280.419406) (xy 90.678172 -280.376392) (xy 90.71192 -280.338298)
			(xy 90.751342 -280.306111) (xy 90.795416 -280.280665) (xy 90.843002 -280.262618) (xy 90.892866 -280.252438)
			(xy 90.943718 -280.250389) (xy 90.994239 -280.256523) (xy 91.043123 -280.270683) (xy 91.089102 -280.2925)
			(xy 91.130986 -280.32141) (xy 91.16769 -280.356665) (xy 91.198263 -280.397351) (xy 91.221914 -280.442414)
			(xy 91.23803 -280.490688) (xy 91.246194 -280.540922) (xy 91.246706 -280.566368) (xy 91.565234 -280.566368)
			(xy 91.569194 -280.517314) (xy 91.580971 -280.46953) (xy 91.600262 -280.424254) (xy 91.626565 -280.382658)
			(xy 91.6592 -280.345821) (xy 91.697321 -280.314696) (xy 91.739942 -280.290089) (xy 91.785958 -280.272637)
			(xy 91.834177 -280.262793) (xy 91.883352 -280.260812) (xy 91.932207 -280.266744) (xy 91.979478 -280.280436)
			(xy 92.02394 -280.301534) (xy 92.064443 -280.32949) (xy 92.099936 -280.363582) (xy 92.129501 -280.402926)
			(xy 92.152372 -280.446503) (xy 92.167956 -280.493184) (xy 92.175851 -280.541761) (xy 92.176346 -280.566368)
			(xy 92.494857 -280.566368) (xy 92.498952 -280.51564) (xy 92.511131 -280.466226) (xy 92.531079 -280.419406)
			(xy 92.55828 -280.376392) (xy 92.592028 -280.338298) (xy 92.63145 -280.306111) (xy 92.675524 -280.280665)
			(xy 92.72311 -280.262618) (xy 92.772974 -280.252438) (xy 92.823826 -280.250389) (xy 92.874347 -280.256523)
			(xy 92.923231 -280.270683) (xy 92.96921 -280.2925) (xy 93.011094 -280.32141) (xy 93.047798 -280.356665)
			(xy 93.078371 -280.397351) (xy 93.102022 -280.442414) (xy 93.118138 -280.490688) (xy 93.126302 -280.540922)
			(xy 93.126814 -280.566368) (xy 94.374711 -280.566368) (xy 94.378806 -280.51564) (xy 94.390985 -280.466226)
			(xy 94.410933 -280.419406) (xy 94.438134 -280.376392) (xy 94.471882 -280.338298) (xy 94.511304 -280.306111)
			(xy 94.555378 -280.280665) (xy 94.602964 -280.262618) (xy 94.652828 -280.252438) (xy 94.70368 -280.250389)
			(xy 94.754201 -280.256523) (xy 94.803085 -280.270683) (xy 94.849064 -280.2925) (xy 94.890948 -280.32141)
			(xy 94.927652 -280.356665) (xy 94.958225 -280.397351) (xy 94.981876 -280.442414) (xy 94.997992 -280.490688)
			(xy 95.006156 -280.540922) (xy 95.006668 -280.566368) (xy 95.314765 -280.566368) (xy 95.31886 -280.51564)
			(xy 95.331039 -280.466226) (xy 95.350987 -280.419406) (xy 95.378188 -280.376392) (xy 95.411936 -280.338298)
			(xy 95.451358 -280.306111) (xy 95.495432 -280.280665) (xy 95.543018 -280.262618) (xy 95.592882 -280.252438)
			(xy 95.643734 -280.250389) (xy 95.694255 -280.256523) (xy 95.743139 -280.270683) (xy 95.789118 -280.2925)
			(xy 95.831002 -280.32141) (xy 95.867706 -280.356665) (xy 95.898279 -280.397351) (xy 95.92193 -280.442414)
			(xy 95.938046 -280.490688) (xy 95.94621 -280.540922) (xy 95.946722 -280.566368) (xy 95.94621 -280.591814)
			(xy 95.938046 -280.642048) (xy 95.92193 -280.690322) (xy 95.898279 -280.735385) (xy 95.867706 -280.776071)
			(xy 95.831002 -280.811326) (xy 95.789118 -280.840236) (xy 95.743139 -280.862053) (xy 95.694255 -280.876213)
			(xy 95.643734 -280.882347) (xy 95.592882 -280.880298) (xy 95.543018 -280.870118) (xy 95.495432 -280.852071)
			(xy 95.451358 -280.826625) (xy 95.411936 -280.794438) (xy 95.378188 -280.756344) (xy 95.350987 -280.71333)
			(xy 95.331039 -280.66651) (xy 95.31886 -280.617096) (xy 95.314765 -280.566368) (xy 95.006668 -280.566368)
			(xy 95.006156 -280.591814) (xy 94.997992 -280.642048) (xy 94.981876 -280.690322) (xy 94.958225 -280.735385)
			(xy 94.927652 -280.776071) (xy 94.890948 -280.811326) (xy 94.849064 -280.840236) (xy 94.803085 -280.862053)
			(xy 94.754201 -280.876213) (xy 94.70368 -280.882347) (xy 94.652828 -280.880298) (xy 94.602964 -280.870118)
			(xy 94.555378 -280.852071) (xy 94.511304 -280.826625) (xy 94.471882 -280.794438) (xy 94.438134 -280.756344)
			(xy 94.410933 -280.71333) (xy 94.390985 -280.66651) (xy 94.378806 -280.617096) (xy 94.374711 -280.566368)
			(xy 93.126814 -280.566368) (xy 93.126302 -280.591814) (xy 93.118138 -280.642048) (xy 93.102022 -280.690322)
			(xy 93.078371 -280.735385) (xy 93.047798 -280.776071) (xy 93.011094 -280.811326) (xy 92.96921 -280.840236)
			(xy 92.923231 -280.862053) (xy 92.874347 -280.876213) (xy 92.823826 -280.882347) (xy 92.772974 -280.880298)
			(xy 92.72311 -280.870118) (xy 92.675524 -280.852071) (xy 92.63145 -280.826625) (xy 92.592028 -280.794438)
			(xy 92.55828 -280.756344) (xy 92.531079 -280.71333) (xy 92.511131 -280.66651) (xy 92.498952 -280.617096)
			(xy 92.494857 -280.566368) (xy 92.176346 -280.566368) (xy 92.175851 -280.590975) (xy 92.167956 -280.639552)
			(xy 92.152372 -280.686233) (xy 92.129501 -280.72981) (xy 92.099936 -280.769154) (xy 92.064443 -280.803246)
			(xy 92.02394 -280.831202) (xy 91.979478 -280.8523) (xy 91.932207 -280.865992) (xy 91.883352 -280.871924)
			(xy 91.834177 -280.869943) (xy 91.785958 -280.860099) (xy 91.739942 -280.842647) (xy 91.697321 -280.81804)
			(xy 91.6592 -280.786915) (xy 91.626565 -280.750078) (xy 91.600262 -280.708482) (xy 91.580971 -280.663206)
			(xy 91.569194 -280.615422) (xy 91.565234 -280.566368) (xy 91.246706 -280.566368) (xy 91.246194 -280.591814)
			(xy 91.23803 -280.642048) (xy 91.221914 -280.690322) (xy 91.198263 -280.735385) (xy 91.16769 -280.776071)
			(xy 91.130986 -280.811326) (xy 91.089102 -280.840236) (xy 91.043123 -280.862053) (xy 90.994239 -280.876213)
			(xy 90.943718 -280.882347) (xy 90.892866 -280.880298) (xy 90.843002 -280.870118) (xy 90.795416 -280.852071)
			(xy 90.751342 -280.826625) (xy 90.71192 -280.794438) (xy 90.678172 -280.756344) (xy 90.650971 -280.71333)
			(xy 90.631023 -280.66651) (xy 90.618844 -280.617096) (xy 90.614749 -280.566368) (xy 90.296238 -280.566368)
			(xy 90.295759 -280.591047) (xy 90.287812 -280.63976) (xy 90.272135 -280.686562) (xy 90.249137 -280.730234)
			(xy 90.219416 -280.76964) (xy 90.183745 -280.803755) (xy 90.143053 -280.831689) (xy 90.098399 -280.852717)
			(xy 90.050945 -280.866292) (xy 90.02649 -280.869644) (xy 90.019632 -280.870406) (xy 90.007186 -280.875232)
			(xy 90.001852 -280.879296) (xy 89.996628 -280.883563) (xy 89.988394 -280.894241) (xy 89.985596 -280.900378)
			(xy 89.95156 -280.982674) (xy 89.949132 -280.988913) (xy 89.947333 -281.002175) (xy 89.948004 -281.008836)
			(xy 89.949782 -281.022044) (xy 89.958418 -281.032966) (xy 89.958418 -281.033474) (xy 89.982779 -281.065651)
			(xy 90.022946 -281.135649) (xy 90.038428 -281.17292) (xy 90.038428 -281.173174) (xy 90.041122 -281.179375)
			(xy 90.049234 -281.190185) (xy 90.05443 -281.19451) (xy 90.05951 -281.198574) (xy 90.07221 -281.203908)
			(xy 90.167714 -281.2161) (xy 90.176845 -281.216906) (xy 90.19468 -281.212735) (xy 90.202512 -281.207972)
			(xy 90.206058 -281.205475) (xy 90.212316 -281.199473) (xy 90.214958 -281.196034) (xy 90.214958 -281.19578)
			(xy 90.229452 -281.176809) (xy 90.263342 -281.143185) (xy 90.302051 -281.115243) (xy 90.344635 -281.093664)
			(xy 90.390059 -281.078973) (xy 90.437214 -281.071528) (xy 90.461084 -281.071066) (xy 90.486345 -281.071558)
			(xy 90.536177 -281.079871) (xy 90.583962 -281.096273) (xy 90.628395 -281.120317) (xy 90.668265 -281.151347)
			(xy 90.702483 -281.188516) (xy 90.730116 -281.23081) (xy 90.750411 -281.277076) (xy 90.762814 -281.326051)
			(xy 90.766984 -281.376374) (xy 91.084903 -281.376374) (xy 91.088998 -281.325646) (xy 91.101177 -281.276232)
			(xy 91.121125 -281.229412) (xy 91.148326 -281.186398) (xy 91.182074 -281.148304) (xy 91.221496 -281.116117)
			(xy 91.26557 -281.090671) (xy 91.313156 -281.072624) (xy 91.36302 -281.062444) (xy 91.413872 -281.060395)
			(xy 91.464393 -281.066529) (xy 91.513277 -281.080689) (xy 91.559256 -281.102506) (xy 91.60114 -281.131416)
			(xy 91.637844 -281.166671) (xy 91.668417 -281.207357) (xy 91.692068 -281.25242) (xy 91.708184 -281.300694)
			(xy 91.716348 -281.350928) (xy 91.71686 -281.376374) (xy 92.024703 -281.376374) (xy 92.028798 -281.325646)
			(xy 92.040977 -281.276232) (xy 92.060925 -281.229412) (xy 92.088126 -281.186398) (xy 92.121874 -281.148304)
			(xy 92.161296 -281.116117) (xy 92.20537 -281.090671) (xy 92.252956 -281.072624) (xy 92.30282 -281.062444)
			(xy 92.353672 -281.060395) (xy 92.404193 -281.066529) (xy 92.453077 -281.080689) (xy 92.499056 -281.102506)
			(xy 92.54094 -281.131416) (xy 92.577644 -281.166671) (xy 92.608217 -281.207357) (xy 92.631868 -281.25242)
			(xy 92.647984 -281.300694) (xy 92.656148 -281.350928) (xy 92.65666 -281.376374) (xy 92.975188 -281.376374)
			(xy 92.979148 -281.32732) (xy 92.990925 -281.279536) (xy 93.010216 -281.23426) (xy 93.036519 -281.192664)
			(xy 93.069154 -281.155827) (xy 93.107275 -281.124702) (xy 93.149896 -281.100095) (xy 93.195912 -281.082643)
			(xy 93.244131 -281.072799) (xy 93.293306 -281.070818) (xy 93.342161 -281.07675) (xy 93.389432 -281.090442)
			(xy 93.433894 -281.11154) (xy 93.474397 -281.139496) (xy 93.50989 -281.173588) (xy 93.539455 -281.212932)
			(xy 93.562326 -281.256509) (xy 93.57791 -281.30319) (xy 93.585805 -281.351767) (xy 93.5863 -281.376374)
			(xy 93.904811 -281.376374) (xy 93.908906 -281.325646) (xy 93.921085 -281.276232) (xy 93.941033 -281.229412)
			(xy 93.968234 -281.186398) (xy 94.001982 -281.148304) (xy 94.041404 -281.116117) (xy 94.085478 -281.090671)
			(xy 94.133064 -281.072624) (xy 94.182928 -281.062444) (xy 94.23378 -281.060395) (xy 94.284301 -281.066529)
			(xy 94.333185 -281.080689) (xy 94.379164 -281.102506) (xy 94.421048 -281.131416) (xy 94.457752 -281.166671)
			(xy 94.488325 -281.207357) (xy 94.511976 -281.25242) (xy 94.528092 -281.300694) (xy 94.536256 -281.350928)
			(xy 94.536768 -281.376374) (xy 94.855296 -281.376374) (xy 94.859256 -281.32732) (xy 94.871033 -281.279536)
			(xy 94.890324 -281.23426) (xy 94.916627 -281.192664) (xy 94.949262 -281.155827) (xy 94.987383 -281.124702)
			(xy 95.030004 -281.100095) (xy 95.07602 -281.082643) (xy 95.124239 -281.072799) (xy 95.173414 -281.070818)
			(xy 95.222269 -281.07675) (xy 95.26954 -281.090442) (xy 95.314002 -281.11154) (xy 95.354505 -281.139496)
			(xy 95.389998 -281.173588) (xy 95.419563 -281.212932) (xy 95.442434 -281.256509) (xy 95.458018 -281.30319)
			(xy 95.465913 -281.351767) (xy 95.466408 -281.376374) (xy 95.784919 -281.376374) (xy 95.789014 -281.325646)
			(xy 95.801193 -281.276232) (xy 95.821141 -281.229412) (xy 95.848342 -281.186398) (xy 95.88209 -281.148304)
			(xy 95.921512 -281.116117) (xy 95.965586 -281.090671) (xy 96.013172 -281.072624) (xy 96.063036 -281.062444)
			(xy 96.113888 -281.060395) (xy 96.164409 -281.066529) (xy 96.213293 -281.080689) (xy 96.259272 -281.102506)
			(xy 96.301156 -281.131416) (xy 96.33786 -281.166671) (xy 96.368433 -281.207357) (xy 96.392084 -281.25242)
			(xy 96.4082 -281.300694) (xy 96.416364 -281.350928) (xy 96.416876 -281.376374) (xy 96.416364 -281.40182)
			(xy 96.4082 -281.452054) (xy 96.392084 -281.500328) (xy 96.368433 -281.545391) (xy 96.33786 -281.586077)
			(xy 96.301156 -281.621332) (xy 96.259272 -281.650242) (xy 96.213293 -281.672059) (xy 96.164409 -281.686219)
			(xy 96.113888 -281.692353) (xy 96.063036 -281.690304) (xy 96.013172 -281.680124) (xy 95.965586 -281.662077)
			(xy 95.921512 -281.636631) (xy 95.88209 -281.604444) (xy 95.848342 -281.56635) (xy 95.821141 -281.523336)
			(xy 95.801193 -281.476516) (xy 95.789014 -281.427102) (xy 95.784919 -281.376374) (xy 95.466408 -281.376374)
			(xy 95.465913 -281.400981) (xy 95.458018 -281.449558) (xy 95.442434 -281.496239) (xy 95.419563 -281.539816)
			(xy 95.389998 -281.57916) (xy 95.354505 -281.613252) (xy 95.314002 -281.641208) (xy 95.26954 -281.662306)
			(xy 95.222269 -281.675998) (xy 95.173414 -281.68193) (xy 95.124239 -281.679949) (xy 95.07602 -281.670105)
			(xy 95.030004 -281.652653) (xy 94.987383 -281.628046) (xy 94.949262 -281.596921) (xy 94.916627 -281.560084)
			(xy 94.890324 -281.518488) (xy 94.871033 -281.473212) (xy 94.859256 -281.425428) (xy 94.855296 -281.376374)
			(xy 94.536768 -281.376374) (xy 94.536256 -281.40182) (xy 94.528092 -281.452054) (xy 94.511976 -281.500328)
			(xy 94.488325 -281.545391) (xy 94.457752 -281.586077) (xy 94.421048 -281.621332) (xy 94.379164 -281.650242)
			(xy 94.333185 -281.672059) (xy 94.284301 -281.686219) (xy 94.23378 -281.692353) (xy 94.182928 -281.690304)
			(xy 94.133064 -281.680124) (xy 94.085478 -281.662077) (xy 94.041404 -281.636631) (xy 94.001982 -281.604444)
			(xy 93.968234 -281.56635) (xy 93.941033 -281.523336) (xy 93.921085 -281.476516) (xy 93.908906 -281.427102)
			(xy 93.904811 -281.376374) (xy 93.5863 -281.376374) (xy 93.585805 -281.400981) (xy 93.57791 -281.449558)
			(xy 93.562326 -281.496239) (xy 93.539455 -281.539816) (xy 93.50989 -281.57916) (xy 93.474397 -281.613252)
			(xy 93.433894 -281.641208) (xy 93.389432 -281.662306) (xy 93.342161 -281.675998) (xy 93.293306 -281.68193)
			(xy 93.244131 -281.679949) (xy 93.195912 -281.670105) (xy 93.149896 -281.652653) (xy 93.107275 -281.628046)
			(xy 93.069154 -281.596921) (xy 93.036519 -281.560084) (xy 93.010216 -281.518488) (xy 92.990925 -281.473212)
			(xy 92.979148 -281.425428) (xy 92.975188 -281.376374) (xy 92.65666 -281.376374) (xy 92.656148 -281.40182)
			(xy 92.647984 -281.452054) (xy 92.631868 -281.500328) (xy 92.608217 -281.545391) (xy 92.577644 -281.586077)
			(xy 92.54094 -281.621332) (xy 92.499056 -281.650242) (xy 92.453077 -281.672059) (xy 92.404193 -281.686219)
			(xy 92.353672 -281.692353) (xy 92.30282 -281.690304) (xy 92.252956 -281.680124) (xy 92.20537 -281.662077)
			(xy 92.161296 -281.636631) (xy 92.121874 -281.604444) (xy 92.088126 -281.56635) (xy 92.060925 -281.523336)
			(xy 92.040977 -281.476516) (xy 92.028798 -281.427102) (xy 92.024703 -281.376374) (xy 91.71686 -281.376374)
			(xy 91.716348 -281.40182) (xy 91.708184 -281.452054) (xy 91.692068 -281.500328) (xy 91.668417 -281.545391)
			(xy 91.637844 -281.586077) (xy 91.60114 -281.621332) (xy 91.559256 -281.650242) (xy 91.513277 -281.672059)
			(xy 91.464393 -281.686219) (xy 91.413872 -281.692353) (xy 91.36302 -281.690304) (xy 91.313156 -281.680124)
			(xy 91.26557 -281.662077) (xy 91.221496 -281.636631) (xy 91.182074 -281.604444) (xy 91.148326 -281.56635)
			(xy 91.121125 -281.523336) (xy 91.101177 -281.476516) (xy 91.088998 -281.427102) (xy 91.084903 -281.376374)
			(xy 90.766984 -281.376374) (xy 90.766986 -281.3764) (xy 90.762814 -281.426749) (xy 90.750411 -281.475724)
			(xy 90.730116 -281.52199) (xy 90.702483 -281.564284) (xy 90.668265 -281.601453) (xy 90.628395 -281.632483)
			(xy 90.583962 -281.656527) (xy 90.536177 -281.672929) (xy 90.486345 -281.681242) (xy 90.461084 -281.681682)
			(xy 90.437211 -281.681227) (xy 90.390044 -281.673804) (xy 90.34461 -281.659126) (xy 90.302015 -281.637552)
			(xy 90.2633 -281.609608) (xy 90.229409 -281.575975) (xy 90.214958 -281.556968) (xy 90.214958 -281.556714)
			(xy 90.212305 -281.553285) (xy 90.206046 -281.547287) (xy 90.202512 -281.544776) (xy 90.194683 -281.540008)
			(xy 90.176845 -281.535842) (xy 90.167714 -281.536648) (xy 90.079068 -281.548078) (xy 90.072309 -281.549155)
			(xy 90.05969 -281.554438) (xy 90.054176 -281.558492) (xy 90.048842 -281.562556) (xy 90.040968 -281.573224)
			(xy 90.038428 -281.579828) (xy 90.02522 -281.610816) (xy 90.019886 -281.622154) (xy 90.008322 -281.644387)
			(xy 90.002106 -281.655266) (xy 89.957656 -281.732228) (xy 89.951877 -281.743378) (xy 89.950926 -281.768441)
			(xy 89.955878 -281.77998) (xy 89.992708 -281.855418) (xy 89.995657 -281.861194) (xy 90.004015 -281.871105)
			(xy 90.009218 -281.874976) (xy 90.019632 -281.882088) (xy 90.024458 -281.88285) (xy 90.049054 -281.886049)
			(xy 90.096826 -281.899382) (xy 90.141814 -281.920262) (xy 90.182835 -281.94814) (xy 90.21881 -281.982281)
			(xy 90.248793 -282.02179) (xy 90.271995 -282.065625) (xy 90.287807 -282.112634) (xy 90.295811 -282.161581)
			(xy 90.296238 -282.18638) (xy 90.614749 -282.18638) (xy 90.618844 -282.135652) (xy 90.631023 -282.086238)
			(xy 90.650971 -282.039418) (xy 90.678172 -281.996404) (xy 90.71192 -281.95831) (xy 90.751342 -281.926123)
			(xy 90.795416 -281.900677) (xy 90.843002 -281.88263) (xy 90.892866 -281.87245) (xy 90.943718 -281.870401)
			(xy 90.994239 -281.876535) (xy 91.043123 -281.890695) (xy 91.089102 -281.912512) (xy 91.130986 -281.941422)
			(xy 91.16769 -281.976677) (xy 91.198263 -282.017363) (xy 91.221914 -282.062426) (xy 91.23803 -282.1107)
			(xy 91.246194 -282.160934) (xy 91.246706 -282.18638) (xy 91.565234 -282.18638) (xy 91.569194 -282.137326)
			(xy 91.580971 -282.089542) (xy 91.600262 -282.044266) (xy 91.626565 -282.00267) (xy 91.6592 -281.965833)
			(xy 91.697321 -281.934708) (xy 91.739942 -281.910101) (xy 91.785958 -281.892649) (xy 91.834177 -281.882805)
			(xy 91.883352 -281.880824) (xy 91.932207 -281.886756) (xy 91.979478 -281.900448) (xy 92.02394 -281.921546)
			(xy 92.064443 -281.949502) (xy 92.099936 -281.983594) (xy 92.129501 -282.022938) (xy 92.152372 -282.066515)
			(xy 92.167956 -282.113196) (xy 92.175851 -282.161773) (xy 92.176346 -282.18638) (xy 92.494857 -282.18638)
			(xy 92.498952 -282.135652) (xy 92.511131 -282.086238) (xy 92.531079 -282.039418) (xy 92.55828 -281.996404)
			(xy 92.592028 -281.95831) (xy 92.63145 -281.926123) (xy 92.675524 -281.900677) (xy 92.72311 -281.88263)
			(xy 92.772974 -281.87245) (xy 92.823826 -281.870401) (xy 92.874347 -281.876535) (xy 92.923231 -281.890695)
			(xy 92.96921 -281.912512) (xy 93.011094 -281.941422) (xy 93.047798 -281.976677) (xy 93.078371 -282.017363)
			(xy 93.102022 -282.062426) (xy 93.118138 -282.1107) (xy 93.126302 -282.160934) (xy 93.126814 -282.18638)
			(xy 93.445342 -282.18638) (xy 93.449302 -282.137326) (xy 93.461079 -282.089542) (xy 93.48037 -282.044266)
			(xy 93.506673 -282.00267) (xy 93.539308 -281.965833) (xy 93.577429 -281.934708) (xy 93.62005 -281.910101)
			(xy 93.666066 -281.892649) (xy 93.714285 -281.882805) (xy 93.76346 -281.880824) (xy 93.812315 -281.886756)
			(xy 93.859586 -281.900448) (xy 93.904048 -281.921546) (xy 93.944551 -281.949502) (xy 93.980044 -281.983594)
			(xy 94.009609 -282.022938) (xy 94.03248 -282.066515) (xy 94.048064 -282.113196) (xy 94.055959 -282.161773)
			(xy 94.056454 -282.18638) (xy 94.374711 -282.18638) (xy 94.378806 -282.135652) (xy 94.390985 -282.086238)
			(xy 94.410933 -282.039418) (xy 94.438134 -281.996404) (xy 94.471882 -281.95831) (xy 94.511304 -281.926123)
			(xy 94.555378 -281.900677) (xy 94.602964 -281.88263) (xy 94.652828 -281.87245) (xy 94.70368 -281.870401)
			(xy 94.754201 -281.876535) (xy 94.803085 -281.890695) (xy 94.849064 -281.912512) (xy 94.890948 -281.941422)
			(xy 94.927652 -281.976677) (xy 94.958225 -282.017363) (xy 94.981876 -282.062426) (xy 94.997992 -282.1107)
			(xy 95.006156 -282.160934) (xy 95.006668 -282.18638) (xy 95.314765 -282.18638) (xy 95.31886 -282.135652)
			(xy 95.331039 -282.086238) (xy 95.350987 -282.039418) (xy 95.378188 -281.996404) (xy 95.411936 -281.95831)
			(xy 95.451358 -281.926123) (xy 95.495432 -281.900677) (xy 95.543018 -281.88263) (xy 95.592882 -281.87245)
			(xy 95.643734 -281.870401) (xy 95.694255 -281.876535) (xy 95.743139 -281.890695) (xy 95.789118 -281.912512)
			(xy 95.831002 -281.941422) (xy 95.867706 -281.976677) (xy 95.898279 -282.017363) (xy 95.92193 -282.062426)
			(xy 95.938046 -282.1107) (xy 95.94621 -282.160934) (xy 95.946722 -282.18638) (xy 95.94621 -282.211826)
			(xy 95.938046 -282.26206) (xy 95.92193 -282.310334) (xy 95.898279 -282.355397) (xy 95.867706 -282.396083)
			(xy 95.831002 -282.431338) (xy 95.789118 -282.460248) (xy 95.743139 -282.482065) (xy 95.694255 -282.496225)
			(xy 95.643734 -282.502359) (xy 95.592882 -282.50031) (xy 95.543018 -282.49013) (xy 95.495432 -282.472083)
			(xy 95.451358 -282.446637) (xy 95.411936 -282.41445) (xy 95.378188 -282.376356) (xy 95.350987 -282.333342)
			(xy 95.331039 -282.286522) (xy 95.31886 -282.237108) (xy 95.314765 -282.18638) (xy 95.006668 -282.18638)
			(xy 95.006156 -282.211826) (xy 94.997992 -282.26206) (xy 94.981876 -282.310334) (xy 94.958225 -282.355397)
			(xy 94.927652 -282.396083) (xy 94.890948 -282.431338) (xy 94.849064 -282.460248) (xy 94.803085 -282.482065)
			(xy 94.754201 -282.496225) (xy 94.70368 -282.502359) (xy 94.652828 -282.50031) (xy 94.602964 -282.49013)
			(xy 94.555378 -282.472083) (xy 94.511304 -282.446637) (xy 94.471882 -282.41445) (xy 94.438134 -282.376356)
			(xy 94.410933 -282.333342) (xy 94.390985 -282.286522) (xy 94.378806 -282.237108) (xy 94.374711 -282.18638)
			(xy 94.056454 -282.18638) (xy 94.055959 -282.210987) (xy 94.048064 -282.259564) (xy 94.03248 -282.306245)
			(xy 94.009609 -282.349822) (xy 93.980044 -282.389166) (xy 93.944551 -282.423258) (xy 93.904048 -282.451214)
			(xy 93.859586 -282.472312) (xy 93.812315 -282.486004) (xy 93.76346 -282.491936) (xy 93.714285 -282.489955)
			(xy 93.666066 -282.480111) (xy 93.62005 -282.462659) (xy 93.577429 -282.438052) (xy 93.539308 -282.406927)
			(xy 93.506673 -282.37009) (xy 93.48037 -282.328494) (xy 93.461079 -282.283218) (xy 93.449302 -282.235434)
			(xy 93.445342 -282.18638) (xy 93.126814 -282.18638) (xy 93.126302 -282.211826) (xy 93.118138 -282.26206)
			(xy 93.102022 -282.310334) (xy 93.078371 -282.355397) (xy 93.047798 -282.396083) (xy 93.011094 -282.431338)
			(xy 92.96921 -282.460248) (xy 92.923231 -282.482065) (xy 92.874347 -282.496225) (xy 92.823826 -282.502359)
			(xy 92.772974 -282.50031) (xy 92.72311 -282.49013) (xy 92.675524 -282.472083) (xy 92.63145 -282.446637)
			(xy 92.592028 -282.41445) (xy 92.55828 -282.376356) (xy 92.531079 -282.333342) (xy 92.511131 -282.286522)
			(xy 92.498952 -282.237108) (xy 92.494857 -282.18638) (xy 92.176346 -282.18638) (xy 92.175851 -282.210987)
			(xy 92.167956 -282.259564) (xy 92.152372 -282.306245) (xy 92.129501 -282.349822) (xy 92.099936 -282.389166)
			(xy 92.064443 -282.423258) (xy 92.02394 -282.451214) (xy 91.979478 -282.472312) (xy 91.932207 -282.486004)
			(xy 91.883352 -282.491936) (xy 91.834177 -282.489955) (xy 91.785958 -282.480111) (xy 91.739942 -282.462659)
			(xy 91.697321 -282.438052) (xy 91.6592 -282.406927) (xy 91.626565 -282.37009) (xy 91.600262 -282.328494)
			(xy 91.580971 -282.283218) (xy 91.569194 -282.235434) (xy 91.565234 -282.18638) (xy 91.246706 -282.18638)
			(xy 91.246194 -282.211826) (xy 91.23803 -282.26206) (xy 91.221914 -282.310334) (xy 91.198263 -282.355397)
			(xy 91.16769 -282.396083) (xy 91.130986 -282.431338) (xy 91.089102 -282.460248) (xy 91.043123 -282.482065)
			(xy 90.994239 -282.496225) (xy 90.943718 -282.502359) (xy 90.892866 -282.50031) (xy 90.843002 -282.49013)
			(xy 90.795416 -282.472083) (xy 90.751342 -282.446637) (xy 90.71192 -282.41445) (xy 90.678172 -282.376356)
			(xy 90.650971 -282.333342) (xy 90.631023 -282.286522) (xy 90.618844 -282.237108) (xy 90.614749 -282.18638)
			(xy 90.296238 -282.18638) (xy 90.295754 -282.211202) (xy 90.287726 -282.260193) (xy 90.271878 -282.30724)
			(xy 90.248628 -282.351103) (xy 90.218589 -282.390627) (xy 90.182551 -282.424772) (xy 90.141464 -282.452636)
			(xy 90.09641 -282.473486) (xy 90.048577 -282.486774) (xy 90.02395 -282.48991) (xy 90.023696 -282.48991)
			(xy 90.016991 -282.49083) (xy 90.004375 -282.495719) (xy 89.998804 -282.499562) (xy 89.993724 -282.503626)
			(xy 89.985342 -282.51404) (xy 89.948004 -282.602686) (xy 89.945532 -282.609113) (xy 89.943734 -282.622761)
			(xy 89.944448 -282.62961) (xy 89.946226 -282.642818) (xy 89.954862 -282.65374) (xy 89.979728 -282.686437)
			(xy 90.020534 -282.757728) (xy 90.036142 -282.795726) (xy 90.036142 -282.79598) (xy 90.03878 -282.802161)
			(xy 90.046771 -282.81296) (xy 90.05189 -282.817316) (xy 90.063066 -282.825952) (xy 90.075512 -282.827476)
			(xy 90.165682 -282.838906) (xy 90.172562 -282.839508) (xy 90.186214 -282.837456) (xy 90.192606 -282.834842)
			(xy 90.198448 -282.832302) (xy 90.208862 -282.82392) (xy 90.21318 -282.818078) (xy 90.227646 -282.798779)
			(xy 90.261635 -282.764564) (xy 90.300574 -282.73611) (xy 90.343499 -282.714123) (xy 90.389343 -282.699148)
			(xy 90.43697 -282.691558) (xy 90.461084 -282.691078) (xy 90.486344 -282.691569) (xy 90.536175 -282.699882)
			(xy 90.583957 -282.716284) (xy 90.628389 -282.740327) (xy 90.668257 -282.771355) (xy 90.702473 -282.808523)
			(xy 90.730106 -282.850816) (xy 90.7504 -282.89708) (xy 90.762802 -282.946053) (xy 90.766973 -282.996386)
			(xy 91.084903 -282.996386) (xy 91.088998 -282.945658) (xy 91.101177 -282.896244) (xy 91.121125 -282.849424)
			(xy 91.148326 -282.80641) (xy 91.182074 -282.768316) (xy 91.221496 -282.736129) (xy 91.26557 -282.710683)
			(xy 91.313156 -282.692636) (xy 91.36302 -282.682456) (xy 91.413872 -282.680407) (xy 91.464393 -282.686541)
			(xy 91.513277 -282.700701) (xy 91.559256 -282.722518) (xy 91.60114 -282.751428) (xy 91.637844 -282.786683)
			(xy 91.668417 -282.827369) (xy 91.692068 -282.872432) (xy 91.708184 -282.920706) (xy 91.716348 -282.97094)
			(xy 91.71686 -282.996386) (xy 92.024703 -282.996386) (xy 92.028798 -282.945658) (xy 92.040977 -282.896244)
			(xy 92.060925 -282.849424) (xy 92.088126 -282.80641) (xy 92.121874 -282.768316) (xy 92.161296 -282.736129)
			(xy 92.20537 -282.710683) (xy 92.252956 -282.692636) (xy 92.30282 -282.682456) (xy 92.353672 -282.680407)
			(xy 92.404193 -282.686541) (xy 92.453077 -282.700701) (xy 92.499056 -282.722518) (xy 92.54094 -282.751428)
			(xy 92.577644 -282.786683) (xy 92.608217 -282.827369) (xy 92.631868 -282.872432) (xy 92.647984 -282.920706)
			(xy 92.656148 -282.97094) (xy 92.65666 -282.996386) (xy 93.904811 -282.996386) (xy 93.908906 -282.945658)
			(xy 93.921085 -282.896244) (xy 93.941033 -282.849424) (xy 93.968234 -282.80641) (xy 94.001982 -282.768316)
			(xy 94.041404 -282.736129) (xy 94.085478 -282.710683) (xy 94.133064 -282.692636) (xy 94.182928 -282.682456)
			(xy 94.23378 -282.680407) (xy 94.284301 -282.686541) (xy 94.333185 -282.700701) (xy 94.379164 -282.722518)
			(xy 94.421048 -282.751428) (xy 94.457752 -282.786683) (xy 94.488325 -282.827369) (xy 94.511976 -282.872432)
			(xy 94.528092 -282.920706) (xy 94.536256 -282.97094) (xy 94.536768 -282.996386) (xy 94.855296 -282.996386)
			(xy 94.859256 -282.947332) (xy 94.871033 -282.899548) (xy 94.890324 -282.854272) (xy 94.916627 -282.812676)
			(xy 94.949262 -282.775839) (xy 94.987383 -282.744714) (xy 95.030004 -282.720107) (xy 95.07602 -282.702655)
			(xy 95.124239 -282.692811) (xy 95.173414 -282.69083) (xy 95.222269 -282.696762) (xy 95.26954 -282.710454)
			(xy 95.314002 -282.731552) (xy 95.354505 -282.759508) (xy 95.389998 -282.7936) (xy 95.419563 -282.832944)
			(xy 95.442434 -282.876521) (xy 95.458018 -282.923202) (xy 95.465913 -282.971779) (xy 95.466408 -282.996386)
			(xy 95.784919 -282.996386) (xy 95.789014 -282.945658) (xy 95.801193 -282.896244) (xy 95.821141 -282.849424)
			(xy 95.848342 -282.80641) (xy 95.88209 -282.768316) (xy 95.921512 -282.736129) (xy 95.965586 -282.710683)
			(xy 96.013172 -282.692636) (xy 96.063036 -282.682456) (xy 96.113888 -282.680407) (xy 96.164409 -282.686541)
			(xy 96.213293 -282.700701) (xy 96.259272 -282.722518) (xy 96.301156 -282.751428) (xy 96.33786 -282.786683)
			(xy 96.368433 -282.827369) (xy 96.392084 -282.872432) (xy 96.4082 -282.920706) (xy 96.416364 -282.97094)
			(xy 96.416876 -282.996386) (xy 96.416364 -283.021832) (xy 96.4082 -283.072066) (xy 96.392084 -283.12034)
			(xy 96.368433 -283.165403) (xy 96.33786 -283.206089) (xy 96.301156 -283.241344) (xy 96.259272 -283.270254)
			(xy 96.213293 -283.292071) (xy 96.164409 -283.306231) (xy 96.113888 -283.312365) (xy 96.063036 -283.310316)
			(xy 96.013172 -283.300136) (xy 95.965586 -283.282089) (xy 95.921512 -283.256643) (xy 95.88209 -283.224456)
			(xy 95.848342 -283.186362) (xy 95.821141 -283.143348) (xy 95.801193 -283.096528) (xy 95.789014 -283.047114)
			(xy 95.784919 -282.996386) (xy 95.466408 -282.996386) (xy 95.465913 -283.020993) (xy 95.458018 -283.06957)
			(xy 95.442434 -283.116251) (xy 95.419563 -283.159828) (xy 95.389998 -283.199172) (xy 95.354505 -283.233264)
			(xy 95.314002 -283.26122) (xy 95.26954 -283.282318) (xy 95.222269 -283.29601) (xy 95.173414 -283.301942)
			(xy 95.124239 -283.299961) (xy 95.07602 -283.290117) (xy 95.030004 -283.272665) (xy 94.987383 -283.248058)
			(xy 94.949262 -283.216933) (xy 94.916627 -283.180096) (xy 94.890324 -283.1385) (xy 94.871033 -283.093224)
			(xy 94.859256 -283.04544) (xy 94.855296 -282.996386) (xy 94.536768 -282.996386) (xy 94.536256 -283.021832)
			(xy 94.528092 -283.072066) (xy 94.511976 -283.12034) (xy 94.488325 -283.165403) (xy 94.457752 -283.206089)
			(xy 94.421048 -283.241344) (xy 94.379164 -283.270254) (xy 94.333185 -283.292071) (xy 94.284301 -283.306231)
			(xy 94.23378 -283.312365) (xy 94.182928 -283.310316) (xy 94.133064 -283.300136) (xy 94.085478 -283.282089)
			(xy 94.041404 -283.256643) (xy 94.001982 -283.224456) (xy 93.968234 -283.186362) (xy 93.941033 -283.143348)
			(xy 93.921085 -283.096528) (xy 93.908906 -283.047114) (xy 93.904811 -282.996386) (xy 92.65666 -282.996386)
			(xy 92.656148 -283.021832) (xy 92.647984 -283.072066) (xy 92.631868 -283.12034) (xy 92.608217 -283.165403)
			(xy 92.577644 -283.206089) (xy 92.54094 -283.241344) (xy 92.499056 -283.270254) (xy 92.453077 -283.292071)
			(xy 92.404193 -283.306231) (xy 92.353672 -283.312365) (xy 92.30282 -283.310316) (xy 92.252956 -283.300136)
			(xy 92.20537 -283.282089) (xy 92.161296 -283.256643) (xy 92.121874 -283.224456) (xy 92.088126 -283.186362)
			(xy 92.060925 -283.143348) (xy 92.040977 -283.096528) (xy 92.028798 -283.047114) (xy 92.024703 -282.996386)
			(xy 91.71686 -282.996386) (xy 91.716348 -283.021832) (xy 91.708184 -283.072066) (xy 91.692068 -283.12034)
			(xy 91.668417 -283.165403) (xy 91.637844 -283.206089) (xy 91.60114 -283.241344) (xy 91.559256 -283.270254)
			(xy 91.513277 -283.292071) (xy 91.464393 -283.306231) (xy 91.413872 -283.312365) (xy 91.36302 -283.310316)
			(xy 91.313156 -283.300136) (xy 91.26557 -283.282089) (xy 91.221496 -283.256643) (xy 91.182074 -283.224456)
			(xy 91.148326 -283.186362) (xy 91.121125 -283.143348) (xy 91.101177 -283.096528) (xy 91.088998 -283.047114)
			(xy 91.084903 -282.996386) (xy 90.766973 -282.996386) (xy 90.766974 -282.9964) (xy 90.762802 -283.046747)
			(xy 90.7504 -283.09572) (xy 90.730106 -283.141984) (xy 90.702473 -283.184277) (xy 90.668257 -283.221445)
			(xy 90.628389 -283.252473) (xy 90.583957 -283.276516) (xy 90.536175 -283.292918) (xy 90.486344 -283.301231)
			(xy 90.461084 -283.301694) (xy 90.448321 -283.301556) (xy 90.422887 -283.299395) (xy 90.410284 -283.297376)
			(xy 90.410284 -283.29763) (xy 90.386832 -283.293201) (xy 90.34158 -283.278036) (xy 90.299232 -283.256029)
			(xy 90.260813 -283.227715) (xy 90.227256 -283.193781) (xy 90.212926 -283.174694) (xy 90.208862 -283.168852)
			(xy 90.198194 -283.160216) (xy 90.192352 -283.157676) (xy 90.186069 -283.155156) (xy 90.172675 -283.153223)
			(xy 90.165936 -283.153866) (xy 90.075512 -283.165296) (xy 90.063066 -283.16682) (xy 90.05189 -283.175456)
			(xy 90.04676 -283.1798) (xy 90.038779 -283.190609) (xy 90.036142 -283.196792) (xy 90.036142 -283.197046)
			(xy 90.028244 -283.216825) (xy 90.009807 -283.255222) (xy 89.999312 -283.273754) (xy 89.9541 -283.351732)
			(xy 89.948359 -283.362972) (xy 89.94754 -283.388167) (xy 89.952576 -283.399738) (xy 89.981024 -283.457142)
			(xy 89.989914 -283.47543) (xy 89.992916 -283.481063) (xy 90.001275 -283.490706) (xy 90.006424 -283.49448)
			(xy 90.01633 -283.501592) (xy 90.02649 -283.503116) (xy 90.029284 -283.50337) (xy 90.053549 -283.506956)
			(xy 90.100586 -283.520852) (xy 90.144801 -283.54208) (xy 90.185059 -283.570095) (xy 90.220327 -283.604179)
			(xy 90.249701 -283.643457) (xy 90.272426 -283.686921) (xy 90.28792 -283.733457) (xy 90.295784 -283.781869)
			(xy 90.296238 -283.806392) (xy 90.614749 -283.806392) (xy 90.618844 -283.755664) (xy 90.631023 -283.70625)
			(xy 90.650971 -283.65943) (xy 90.678172 -283.616416) (xy 90.71192 -283.578322) (xy 90.751342 -283.546135)
			(xy 90.795416 -283.520689) (xy 90.843002 -283.502642) (xy 90.892866 -283.492462) (xy 90.943718 -283.490413)
			(xy 90.994239 -283.496547) (xy 91.043123 -283.510707) (xy 91.089102 -283.532524) (xy 91.130986 -283.561434)
			(xy 91.16769 -283.596689) (xy 91.198263 -283.637375) (xy 91.221914 -283.682438) (xy 91.23803 -283.730712)
			(xy 91.246194 -283.780946) (xy 91.246706 -283.806392) (xy 91.565234 -283.806392) (xy 91.569194 -283.757338)
			(xy 91.580971 -283.709554) (xy 91.600262 -283.664278) (xy 91.626565 -283.622682) (xy 91.6592 -283.585845)
			(xy 91.697321 -283.55472) (xy 91.739942 -283.530113) (xy 91.785958 -283.512661) (xy 91.834177 -283.502817)
			(xy 91.883352 -283.500836) (xy 91.932207 -283.506768) (xy 91.979478 -283.52046) (xy 92.02394 -283.541558)
			(xy 92.064443 -283.569514) (xy 92.099936 -283.603606) (xy 92.129501 -283.64295) (xy 92.152372 -283.686527)
			(xy 92.167956 -283.733208) (xy 92.175851 -283.781785) (xy 92.176346 -283.806392) (xy 92.494857 -283.806392)
			(xy 92.498952 -283.755664) (xy 92.511131 -283.70625) (xy 92.531079 -283.65943) (xy 92.55828 -283.616416)
			(xy 92.592028 -283.578322) (xy 92.63145 -283.546135) (xy 92.675524 -283.520689) (xy 92.72311 -283.502642)
			(xy 92.772974 -283.492462) (xy 92.823826 -283.490413) (xy 92.874347 -283.496547) (xy 92.923231 -283.510707)
			(xy 92.96921 -283.532524) (xy 93.011094 -283.561434) (xy 93.047798 -283.596689) (xy 93.078371 -283.637375)
			(xy 93.102022 -283.682438) (xy 93.118138 -283.730712) (xy 93.126302 -283.780946) (xy 93.126814 -283.806392)
			(xy 93.445342 -283.806392) (xy 93.449302 -283.757338) (xy 93.461079 -283.709554) (xy 93.48037 -283.664278)
			(xy 93.506673 -283.622682) (xy 93.539308 -283.585845) (xy 93.577429 -283.55472) (xy 93.62005 -283.530113)
			(xy 93.666066 -283.512661) (xy 93.714285 -283.502817) (xy 93.76346 -283.500836) (xy 93.812315 -283.506768)
			(xy 93.859586 -283.52046) (xy 93.904048 -283.541558) (xy 93.944551 -283.569514) (xy 93.980044 -283.603606)
			(xy 94.009609 -283.64295) (xy 94.03248 -283.686527) (xy 94.048064 -283.733208) (xy 94.055959 -283.781785)
			(xy 94.056454 -283.806392) (xy 94.374711 -283.806392) (xy 94.378806 -283.755664) (xy 94.390985 -283.70625)
			(xy 94.410933 -283.65943) (xy 94.438134 -283.616416) (xy 94.471882 -283.578322) (xy 94.511304 -283.546135)
			(xy 94.555378 -283.520689) (xy 94.602964 -283.502642) (xy 94.652828 -283.492462) (xy 94.70368 -283.490413)
			(xy 94.754201 -283.496547) (xy 94.803085 -283.510707) (xy 94.849064 -283.532524) (xy 94.890948 -283.561434)
			(xy 94.927652 -283.596689) (xy 94.958225 -283.637375) (xy 94.981876 -283.682438) (xy 94.997992 -283.730712)
			(xy 95.006156 -283.780946) (xy 95.006668 -283.806392) (xy 95.314765 -283.806392) (xy 95.31886 -283.755664)
			(xy 95.331039 -283.70625) (xy 95.350987 -283.65943) (xy 95.378188 -283.616416) (xy 95.411936 -283.578322)
			(xy 95.451358 -283.546135) (xy 95.495432 -283.520689) (xy 95.543018 -283.502642) (xy 95.592882 -283.492462)
			(xy 95.643734 -283.490413) (xy 95.694255 -283.496547) (xy 95.743139 -283.510707) (xy 95.789118 -283.532524)
			(xy 95.831002 -283.561434) (xy 95.867706 -283.596689) (xy 95.898279 -283.637375) (xy 95.92193 -283.682438)
			(xy 95.938046 -283.730712) (xy 95.94621 -283.780946) (xy 95.946722 -283.806392) (xy 95.94621 -283.831838)
			(xy 95.938046 -283.882072) (xy 95.92193 -283.930346) (xy 95.898279 -283.975409) (xy 95.867706 -284.016095)
			(xy 95.831002 -284.05135) (xy 95.789118 -284.08026) (xy 95.743139 -284.102077) (xy 95.694255 -284.116237)
			(xy 95.643734 -284.122371) (xy 95.592882 -284.120322) (xy 95.543018 -284.110142) (xy 95.495432 -284.092095)
			(xy 95.451358 -284.066649) (xy 95.411936 -284.034462) (xy 95.378188 -283.996368) (xy 95.350987 -283.953354)
			(xy 95.331039 -283.906534) (xy 95.31886 -283.85712) (xy 95.314765 -283.806392) (xy 95.006668 -283.806392)
			(xy 95.006156 -283.831838) (xy 94.997992 -283.882072) (xy 94.981876 -283.930346) (xy 94.958225 -283.975409)
			(xy 94.927652 -284.016095) (xy 94.890948 -284.05135) (xy 94.849064 -284.08026) (xy 94.803085 -284.102077)
			(xy 94.754201 -284.116237) (xy 94.70368 -284.122371) (xy 94.652828 -284.120322) (xy 94.602964 -284.110142)
			(xy 94.555378 -284.092095) (xy 94.511304 -284.066649) (xy 94.471882 -284.034462) (xy 94.438134 -283.996368)
			(xy 94.410933 -283.953354) (xy 94.390985 -283.906534) (xy 94.378806 -283.85712) (xy 94.374711 -283.806392)
			(xy 94.056454 -283.806392) (xy 94.055959 -283.830999) (xy 94.048064 -283.879576) (xy 94.03248 -283.926257)
			(xy 94.009609 -283.969834) (xy 93.980044 -284.009178) (xy 93.944551 -284.04327) (xy 93.904048 -284.071226)
			(xy 93.859586 -284.092324) (xy 93.812315 -284.106016) (xy 93.76346 -284.111948) (xy 93.714285 -284.109967)
			(xy 93.666066 -284.100123) (xy 93.62005 -284.082671) (xy 93.577429 -284.058064) (xy 93.539308 -284.026939)
			(xy 93.506673 -283.990102) (xy 93.48037 -283.948506) (xy 93.461079 -283.90323) (xy 93.449302 -283.855446)
			(xy 93.445342 -283.806392) (xy 93.126814 -283.806392) (xy 93.126302 -283.831838) (xy 93.118138 -283.882072)
			(xy 93.102022 -283.930346) (xy 93.078371 -283.975409) (xy 93.047798 -284.016095) (xy 93.011094 -284.05135)
			(xy 92.96921 -284.08026) (xy 92.923231 -284.102077) (xy 92.874347 -284.116237) (xy 92.823826 -284.122371)
			(xy 92.772974 -284.120322) (xy 92.72311 -284.110142) (xy 92.675524 -284.092095) (xy 92.63145 -284.066649)
			(xy 92.592028 -284.034462) (xy 92.55828 -283.996368) (xy 92.531079 -283.953354) (xy 92.511131 -283.906534)
			(xy 92.498952 -283.85712) (xy 92.494857 -283.806392) (xy 92.176346 -283.806392) (xy 92.175851 -283.830999)
			(xy 92.167956 -283.879576) (xy 92.152372 -283.926257) (xy 92.129501 -283.969834) (xy 92.099936 -284.009178)
			(xy 92.064443 -284.04327) (xy 92.02394 -284.071226) (xy 91.979478 -284.092324) (xy 91.932207 -284.106016)
			(xy 91.883352 -284.111948) (xy 91.834177 -284.109967) (xy 91.785958 -284.100123) (xy 91.739942 -284.082671)
			(xy 91.697321 -284.058064) (xy 91.6592 -284.026939) (xy 91.626565 -283.990102) (xy 91.600262 -283.948506)
			(xy 91.580971 -283.90323) (xy 91.569194 -283.855446) (xy 91.565234 -283.806392) (xy 91.246706 -283.806392)
			(xy 91.246194 -283.831838) (xy 91.23803 -283.882072) (xy 91.221914 -283.930346) (xy 91.198263 -283.975409)
			(xy 91.16769 -284.016095) (xy 91.130986 -284.05135) (xy 91.089102 -284.08026) (xy 91.043123 -284.102077)
			(xy 90.994239 -284.116237) (xy 90.943718 -284.122371) (xy 90.892866 -284.120322) (xy 90.843002 -284.110142)
			(xy 90.795416 -284.092095) (xy 90.751342 -284.066649) (xy 90.71192 -284.034462) (xy 90.678172 -283.996368)
			(xy 90.650971 -283.953354) (xy 90.631023 -283.906534) (xy 90.618844 -283.85712) (xy 90.614749 -283.806392)
			(xy 90.296238 -283.806392) (xy 90.295753 -283.831214) (xy 90.287723 -283.880203) (xy 90.271875 -283.927248)
			(xy 90.248624 -283.97111) (xy 90.218584 -284.010632) (xy 90.182546 -284.044775) (xy 90.14146 -284.072638)
			(xy 90.096407 -284.093487) (xy 90.048575 -284.106774) (xy 90.02395 -284.109922) (xy 90.023696 -284.109922)
			(xy 90.016991 -284.110842) (xy 90.004376 -284.115732) (xy 89.998804 -284.119574) (xy 89.993724 -284.123638)
			(xy 89.985342 -284.134052) (xy 89.948004 -284.222698) (xy 89.945534 -284.229125) (xy 89.943739 -284.242772)
			(xy 89.944448 -284.249622) (xy 89.946226 -284.26283) (xy 89.954862 -284.273752) (xy 89.979728 -284.30645)
			(xy 90.020532 -284.377741) (xy 90.036142 -284.415738) (xy 90.036142 -284.415992) (xy 90.038772 -284.422179)
			(xy 90.046751 -284.432993) (xy 90.05189 -284.437328) (xy 90.063066 -284.445964) (xy 90.075512 -284.447488)
			(xy 90.165682 -284.458918) (xy 90.172562 -284.45952) (xy 90.186214 -284.457468) (xy 90.192606 -284.454854)
			(xy 90.198448 -284.452314) (xy 90.208862 -284.443932) (xy 90.21318 -284.43809) (xy 90.227645 -284.418791)
			(xy 90.261634 -284.384574) (xy 90.300573 -284.356119) (xy 90.343498 -284.334131) (xy 90.389343 -284.319156)
			(xy 90.43697 -284.311565) (xy 90.461084 -284.31109) (xy 90.486343 -284.311581) (xy 90.536172 -284.319894)
			(xy 90.583953 -284.336295) (xy 90.628382 -284.360337) (xy 90.668248 -284.391364) (xy 90.702464 -284.42853)
			(xy 90.730095 -284.470821) (xy 90.750388 -284.517084) (xy 90.76279 -284.566055) (xy 90.766962 -284.616398)
			(xy 91.084903 -284.616398) (xy 91.088998 -284.56567) (xy 91.101177 -284.516256) (xy 91.121125 -284.469436)
			(xy 91.148326 -284.426422) (xy 91.182074 -284.388328) (xy 91.221496 -284.356141) (xy 91.26557 -284.330695)
			(xy 91.313156 -284.312648) (xy 91.36302 -284.302468) (xy 91.413872 -284.300419) (xy 91.464393 -284.306553)
			(xy 91.513277 -284.320713) (xy 91.559256 -284.34253) (xy 91.60114 -284.37144) (xy 91.637844 -284.406695)
			(xy 91.668417 -284.447381) (xy 91.692068 -284.492444) (xy 91.708184 -284.540718) (xy 91.716348 -284.590952)
			(xy 91.71686 -284.616398) (xy 92.024703 -284.616398) (xy 92.028798 -284.56567) (xy 92.040977 -284.516256)
			(xy 92.060925 -284.469436) (xy 92.088126 -284.426422) (xy 92.121874 -284.388328) (xy 92.161296 -284.356141)
			(xy 92.20537 -284.330695) (xy 92.252956 -284.312648) (xy 92.30282 -284.302468) (xy 92.353672 -284.300419)
			(xy 92.404193 -284.306553) (xy 92.453077 -284.320713) (xy 92.499056 -284.34253) (xy 92.54094 -284.37144)
			(xy 92.577644 -284.406695) (xy 92.608217 -284.447381) (xy 92.631868 -284.492444) (xy 92.647984 -284.540718)
			(xy 92.656148 -284.590952) (xy 92.65666 -284.616398) (xy 92.975188 -284.616398) (xy 92.979148 -284.567344)
			(xy 92.990925 -284.51956) (xy 93.010216 -284.474284) (xy 93.036519 -284.432688) (xy 93.069154 -284.395851)
			(xy 93.107275 -284.364726) (xy 93.149896 -284.340119) (xy 93.195912 -284.322667) (xy 93.244131 -284.312823)
			(xy 93.293306 -284.310842) (xy 93.342161 -284.316774) (xy 93.389432 -284.330466) (xy 93.433894 -284.351564)
			(xy 93.474397 -284.37952) (xy 93.50989 -284.413612) (xy 93.539455 -284.452956) (xy 93.562326 -284.496533)
			(xy 93.57791 -284.543214) (xy 93.585805 -284.591791) (xy 93.5863 -284.616398) (xy 93.904811 -284.616398)
			(xy 93.908906 -284.56567) (xy 93.921085 -284.516256) (xy 93.941033 -284.469436) (xy 93.968234 -284.426422)
			(xy 94.001982 -284.388328) (xy 94.041404 -284.356141) (xy 94.085478 -284.330695) (xy 94.133064 -284.312648)
			(xy 94.182928 -284.302468) (xy 94.23378 -284.300419) (xy 94.284301 -284.306553) (xy 94.333185 -284.320713)
			(xy 94.379164 -284.34253) (xy 94.421048 -284.37144) (xy 94.457752 -284.406695) (xy 94.488325 -284.447381)
			(xy 94.511976 -284.492444) (xy 94.528092 -284.540718) (xy 94.536256 -284.590952) (xy 94.536768 -284.616398)
			(xy 94.855296 -284.616398) (xy 94.859256 -284.567344) (xy 94.871033 -284.51956) (xy 94.890324 -284.474284)
			(xy 94.916627 -284.432688) (xy 94.949262 -284.395851) (xy 94.987383 -284.364726) (xy 95.030004 -284.340119)
			(xy 95.07602 -284.322667) (xy 95.124239 -284.312823) (xy 95.173414 -284.310842) (xy 95.222269 -284.316774)
			(xy 95.26954 -284.330466) (xy 95.314002 -284.351564) (xy 95.354505 -284.37952) (xy 95.389998 -284.413612)
			(xy 95.419563 -284.452956) (xy 95.442434 -284.496533) (xy 95.458018 -284.543214) (xy 95.465913 -284.591791)
			(xy 95.466408 -284.616398) (xy 95.784919 -284.616398) (xy 95.789014 -284.56567) (xy 95.801193 -284.516256)
			(xy 95.821141 -284.469436) (xy 95.848342 -284.426422) (xy 95.88209 -284.388328) (xy 95.921512 -284.356141)
			(xy 95.965586 -284.330695) (xy 96.013172 -284.312648) (xy 96.063036 -284.302468) (xy 96.113888 -284.300419)
			(xy 96.164409 -284.306553) (xy 96.213293 -284.320713) (xy 96.259272 -284.34253) (xy 96.301156 -284.37144)
			(xy 96.33786 -284.406695) (xy 96.368433 -284.447381) (xy 96.392084 -284.492444) (xy 96.4082 -284.540718)
			(xy 96.416364 -284.590952) (xy 96.416876 -284.616398) (xy 96.416364 -284.641844) (xy 96.4082 -284.692078)
			(xy 96.392084 -284.740352) (xy 96.368433 -284.785415) (xy 96.33786 -284.826101) (xy 96.301156 -284.861356)
			(xy 96.259272 -284.890266) (xy 96.213293 -284.912083) (xy 96.164409 -284.926243) (xy 96.113888 -284.932377)
			(xy 96.063036 -284.930328) (xy 96.013172 -284.920148) (xy 95.965586 -284.902101) (xy 95.921512 -284.876655)
			(xy 95.88209 -284.844468) (xy 95.848342 -284.806374) (xy 95.821141 -284.76336) (xy 95.801193 -284.71654)
			(xy 95.789014 -284.667126) (xy 95.784919 -284.616398) (xy 95.466408 -284.616398) (xy 95.465913 -284.641005)
			(xy 95.458018 -284.689582) (xy 95.442434 -284.736263) (xy 95.419563 -284.77984) (xy 95.389998 -284.819184)
			(xy 95.354505 -284.853276) (xy 95.314002 -284.881232) (xy 95.26954 -284.90233) (xy 95.222269 -284.916022)
			(xy 95.173414 -284.921954) (xy 95.124239 -284.919973) (xy 95.07602 -284.910129) (xy 95.030004 -284.892677)
			(xy 94.987383 -284.86807) (xy 94.949262 -284.836945) (xy 94.916627 -284.800108) (xy 94.890324 -284.758512)
			(xy 94.871033 -284.713236) (xy 94.859256 -284.665452) (xy 94.855296 -284.616398) (xy 94.536768 -284.616398)
			(xy 94.536256 -284.641844) (xy 94.528092 -284.692078) (xy 94.511976 -284.740352) (xy 94.488325 -284.785415)
			(xy 94.457752 -284.826101) (xy 94.421048 -284.861356) (xy 94.379164 -284.890266) (xy 94.333185 -284.912083)
			(xy 94.284301 -284.926243) (xy 94.23378 -284.932377) (xy 94.182928 -284.930328) (xy 94.133064 -284.920148)
			(xy 94.085478 -284.902101) (xy 94.041404 -284.876655) (xy 94.001982 -284.844468) (xy 93.968234 -284.806374)
			(xy 93.941033 -284.76336) (xy 93.921085 -284.71654) (xy 93.908906 -284.667126) (xy 93.904811 -284.616398)
			(xy 93.5863 -284.616398) (xy 93.585805 -284.641005) (xy 93.57791 -284.689582) (xy 93.562326 -284.736263)
			(xy 93.539455 -284.77984) (xy 93.50989 -284.819184) (xy 93.474397 -284.853276) (xy 93.433894 -284.881232)
			(xy 93.389432 -284.90233) (xy 93.342161 -284.916022) (xy 93.293306 -284.921954) (xy 93.244131 -284.919973)
			(xy 93.195912 -284.910129) (xy 93.149896 -284.892677) (xy 93.107275 -284.86807) (xy 93.069154 -284.836945)
			(xy 93.036519 -284.800108) (xy 93.010216 -284.758512) (xy 92.990925 -284.713236) (xy 92.979148 -284.665452)
			(xy 92.975188 -284.616398) (xy 92.65666 -284.616398) (xy 92.656148 -284.641844) (xy 92.647984 -284.692078)
			(xy 92.631868 -284.740352) (xy 92.608217 -284.785415) (xy 92.577644 -284.826101) (xy 92.54094 -284.861356)
			(xy 92.499056 -284.890266) (xy 92.453077 -284.912083) (xy 92.404193 -284.926243) (xy 92.353672 -284.932377)
			(xy 92.30282 -284.930328) (xy 92.252956 -284.920148) (xy 92.20537 -284.902101) (xy 92.161296 -284.876655)
			(xy 92.121874 -284.844468) (xy 92.088126 -284.806374) (xy 92.060925 -284.76336) (xy 92.040977 -284.71654)
			(xy 92.028798 -284.667126) (xy 92.024703 -284.616398) (xy 91.71686 -284.616398) (xy 91.716348 -284.641844)
			(xy 91.708184 -284.692078) (xy 91.692068 -284.740352) (xy 91.668417 -284.785415) (xy 91.637844 -284.826101)
			(xy 91.60114 -284.861356) (xy 91.559256 -284.890266) (xy 91.513277 -284.912083) (xy 91.464393 -284.926243)
			(xy 91.413872 -284.932377) (xy 91.36302 -284.930328) (xy 91.313156 -284.920148) (xy 91.26557 -284.902101)
			(xy 91.221496 -284.876655) (xy 91.182074 -284.844468) (xy 91.148326 -284.806374) (xy 91.121125 -284.76336)
			(xy 91.101177 -284.71654) (xy 91.088998 -284.667126) (xy 91.084903 -284.616398) (xy 90.766962 -284.616398)
			(xy 90.766962 -284.6164) (xy 90.76279 -284.666745) (xy 90.750388 -284.715716) (xy 90.730095 -284.761979)
			(xy 90.702464 -284.80427) (xy 90.668248 -284.841436) (xy 90.628382 -284.872463) (xy 90.583953 -284.896505)
			(xy 90.536172 -284.912906) (xy 90.486343 -284.921219) (xy 90.461084 -284.921706) (xy 90.448321 -284.921568)
			(xy 90.422887 -284.919408) (xy 90.410284 -284.917388) (xy 90.410284 -284.917642) (xy 90.386832 -284.913213)
			(xy 90.34158 -284.898048) (xy 90.299231 -284.876043) (xy 90.260811 -284.847729) (xy 90.227253 -284.813795)
			(xy 90.212926 -284.794706) (xy 90.208862 -284.788864) (xy 90.198194 -284.780228) (xy 90.192352 -284.777688)
			(xy 90.186069 -284.775167) (xy 90.172675 -284.773234) (xy 90.165936 -284.773878) (xy 90.075512 -284.785308)
			(xy 90.063066 -284.786832) (xy 90.05189 -284.795468) (xy 90.046761 -284.799812) (xy 90.038782 -284.810623)
			(xy 90.036142 -284.816804) (xy 90.036142 -284.817058) (xy 90.028243 -284.836837) (xy 90.009806 -284.875233)
			(xy 89.999312 -284.893766) (xy 89.9541 -284.971744) (xy 89.948362 -284.982984) (xy 89.947548 -285.008176)
			(xy 89.952576 -285.01975) (xy 89.981024 -285.077154) (xy 89.989914 -285.095442) (xy 89.992917 -285.101075)
			(xy 90.001278 -285.110715) (xy 90.006424 -285.114492) (xy 90.01633 -285.121604) (xy 90.02649 -285.123128)
			(xy 90.029284 -285.123382) (xy 90.053548 -285.126968) (xy 90.100585 -285.140864) (xy 90.144799 -285.162092)
			(xy 90.185056 -285.190108) (xy 90.220323 -285.224192) (xy 90.249695 -285.26347) (xy 90.272419 -285.306934)
			(xy 90.287911 -285.35347) (xy 90.295773 -285.401881) (xy 90.296238 -285.426404) (xy 90.614749 -285.426404)
			(xy 90.618844 -285.375676) (xy 90.631023 -285.326262) (xy 90.650971 -285.279442) (xy 90.678172 -285.236428)
			(xy 90.71192 -285.198334) (xy 90.751342 -285.166147) (xy 90.795416 -285.140701) (xy 90.843002 -285.122654)
			(xy 90.892866 -285.112474) (xy 90.943718 -285.110425) (xy 90.994239 -285.116559) (xy 91.043123 -285.130719)
			(xy 91.089102 -285.152536) (xy 91.130986 -285.181446) (xy 91.16769 -285.216701) (xy 91.198263 -285.257387)
			(xy 91.221914 -285.30245) (xy 91.23803 -285.350724) (xy 91.246194 -285.400958) (xy 91.246706 -285.426404)
			(xy 91.565234 -285.426404) (xy 91.569194 -285.37735) (xy 91.580971 -285.329566) (xy 91.600262 -285.28429)
			(xy 91.626565 -285.242694) (xy 91.6592 -285.205857) (xy 91.697321 -285.174732) (xy 91.739942 -285.150125)
			(xy 91.785958 -285.132673) (xy 91.834177 -285.122829) (xy 91.883352 -285.120848) (xy 91.932207 -285.12678)
			(xy 91.979478 -285.140472) (xy 92.02394 -285.16157) (xy 92.064443 -285.189526) (xy 92.099936 -285.223618)
			(xy 92.129501 -285.262962) (xy 92.152372 -285.306539) (xy 92.167956 -285.35322) (xy 92.175851 -285.401797)
			(xy 92.176346 -285.426404) (xy 92.494857 -285.426404) (xy 92.498952 -285.375676) (xy 92.511131 -285.326262)
			(xy 92.531079 -285.279442) (xy 92.55828 -285.236428) (xy 92.592028 -285.198334) (xy 92.63145 -285.166147)
			(xy 92.675524 -285.140701) (xy 92.72311 -285.122654) (xy 92.772974 -285.112474) (xy 92.823826 -285.110425)
			(xy 92.874347 -285.116559) (xy 92.923231 -285.130719) (xy 92.96921 -285.152536) (xy 93.011094 -285.181446)
			(xy 93.047798 -285.216701) (xy 93.078371 -285.257387) (xy 93.102022 -285.30245) (xy 93.118138 -285.350724)
			(xy 93.126302 -285.400958) (xy 93.126814 -285.426404) (xy 94.374711 -285.426404) (xy 94.378806 -285.375676)
			(xy 94.390985 -285.326262) (xy 94.410933 -285.279442) (xy 94.438134 -285.236428) (xy 94.471882 -285.198334)
			(xy 94.511304 -285.166147) (xy 94.555378 -285.140701) (xy 94.602964 -285.122654) (xy 94.652828 -285.112474)
			(xy 94.70368 -285.110425) (xy 94.754201 -285.116559) (xy 94.803085 -285.130719) (xy 94.849064 -285.152536)
			(xy 94.890948 -285.181446) (xy 94.927652 -285.216701) (xy 94.958225 -285.257387) (xy 94.981876 -285.30245)
			(xy 94.997992 -285.350724) (xy 95.006156 -285.400958) (xy 95.006668 -285.426404) (xy 95.314765 -285.426404)
			(xy 95.31886 -285.375676) (xy 95.331039 -285.326262) (xy 95.350987 -285.279442) (xy 95.378188 -285.236428)
			(xy 95.411936 -285.198334) (xy 95.451358 -285.166147) (xy 95.495432 -285.140701) (xy 95.543018 -285.122654)
			(xy 95.592882 -285.112474) (xy 95.643734 -285.110425) (xy 95.694255 -285.116559) (xy 95.743139 -285.130719)
			(xy 95.789118 -285.152536) (xy 95.831002 -285.181446) (xy 95.867706 -285.216701) (xy 95.898279 -285.257387)
			(xy 95.92193 -285.30245) (xy 95.938046 -285.350724) (xy 95.94621 -285.400958) (xy 95.946722 -285.426404)
			(xy 95.94621 -285.45185) (xy 95.938046 -285.502084) (xy 95.92193 -285.550358) (xy 95.898279 -285.595421)
			(xy 95.867706 -285.636107) (xy 95.831002 -285.671362) (xy 95.789118 -285.700272) (xy 95.743139 -285.722089)
			(xy 95.694255 -285.736249) (xy 95.643734 -285.742383) (xy 95.592882 -285.740334) (xy 95.543018 -285.730154)
			(xy 95.495432 -285.712107) (xy 95.451358 -285.686661) (xy 95.411936 -285.654474) (xy 95.378188 -285.61638)
			(xy 95.350987 -285.573366) (xy 95.331039 -285.526546) (xy 95.31886 -285.477132) (xy 95.314765 -285.426404)
			(xy 95.006668 -285.426404) (xy 95.006156 -285.45185) (xy 94.997992 -285.502084) (xy 94.981876 -285.550358)
			(xy 94.958225 -285.595421) (xy 94.927652 -285.636107) (xy 94.890948 -285.671362) (xy 94.849064 -285.700272)
			(xy 94.803085 -285.722089) (xy 94.754201 -285.736249) (xy 94.70368 -285.742383) (xy 94.652828 -285.740334)
			(xy 94.602964 -285.730154) (xy 94.555378 -285.712107) (xy 94.511304 -285.686661) (xy 94.471882 -285.654474)
			(xy 94.438134 -285.61638) (xy 94.410933 -285.573366) (xy 94.390985 -285.526546) (xy 94.378806 -285.477132)
			(xy 94.374711 -285.426404) (xy 93.126814 -285.426404) (xy 93.126302 -285.45185) (xy 93.118138 -285.502084)
			(xy 93.102022 -285.550358) (xy 93.078371 -285.595421) (xy 93.047798 -285.636107) (xy 93.011094 -285.671362)
			(xy 92.96921 -285.700272) (xy 92.923231 -285.722089) (xy 92.874347 -285.736249) (xy 92.823826 -285.742383)
			(xy 92.772974 -285.740334) (xy 92.72311 -285.730154) (xy 92.675524 -285.712107) (xy 92.63145 -285.686661)
			(xy 92.592028 -285.654474) (xy 92.55828 -285.61638) (xy 92.531079 -285.573366) (xy 92.511131 -285.526546)
			(xy 92.498952 -285.477132) (xy 92.494857 -285.426404) (xy 92.176346 -285.426404) (xy 92.175851 -285.451011)
			(xy 92.167956 -285.499588) (xy 92.152372 -285.546269) (xy 92.129501 -285.589846) (xy 92.099936 -285.62919)
			(xy 92.064443 -285.663282) (xy 92.02394 -285.691238) (xy 91.979478 -285.712336) (xy 91.932207 -285.726028)
			(xy 91.883352 -285.73196) (xy 91.834177 -285.729979) (xy 91.785958 -285.720135) (xy 91.739942 -285.702683)
			(xy 91.697321 -285.678076) (xy 91.6592 -285.646951) (xy 91.626565 -285.610114) (xy 91.600262 -285.568518)
			(xy 91.580971 -285.523242) (xy 91.569194 -285.475458) (xy 91.565234 -285.426404) (xy 91.246706 -285.426404)
			(xy 91.246194 -285.45185) (xy 91.23803 -285.502084) (xy 91.221914 -285.550358) (xy 91.198263 -285.595421)
			(xy 91.16769 -285.636107) (xy 91.130986 -285.671362) (xy 91.089102 -285.700272) (xy 91.043123 -285.722089)
			(xy 90.994239 -285.736249) (xy 90.943718 -285.742383) (xy 90.892866 -285.740334) (xy 90.843002 -285.730154)
			(xy 90.795416 -285.712107) (xy 90.751342 -285.686661) (xy 90.71192 -285.654474) (xy 90.678172 -285.61638)
			(xy 90.650971 -285.573366) (xy 90.631023 -285.526546) (xy 90.618844 -285.477132) (xy 90.614749 -285.426404)
			(xy 90.296238 -285.426404) (xy 90.295764 -285.451086) (xy 90.287825 -285.499807) (xy 90.272154 -285.546618)
			(xy 90.249159 -285.590299) (xy 90.219439 -285.629714) (xy 90.183768 -285.663836) (xy 90.143073 -285.691778)
			(xy 90.098415 -285.712811) (xy 90.050955 -285.72639) (xy 90.02649 -285.72968) (xy 90.019632 -285.730442)
			(xy 90.007186 -285.735268) (xy 90.001852 -285.739332) (xy 89.996631 -285.743601) (xy 89.988404 -285.754281)
			(xy 89.985596 -285.760414) (xy 89.95156 -285.84271) (xy 89.949123 -285.848948) (xy 89.947308 -285.862212)
			(xy 89.948004 -285.868872) (xy 89.949782 -285.88208) (xy 89.958418 -285.893002) (xy 89.958418 -285.89351)
			(xy 89.982777 -285.925688) (xy 90.02294 -285.995688) (xy 90.038428 -286.032956) (xy 90.038428 -286.03321)
			(xy 90.041125 -286.039408) (xy 90.049241 -286.050212) (xy 90.05443 -286.054546) (xy 90.05951 -286.05861)
			(xy 90.07221 -286.063944) (xy 90.167714 -286.076136) (xy 90.176844 -286.076942) (xy 90.194677 -286.072767)
			(xy 90.202512 -286.068008) (xy 90.206059 -286.065512) (xy 90.21232 -286.059513) (xy 90.214958 -286.05607)
			(xy 90.214958 -286.055816) (xy 90.229451 -286.036843) (xy 90.26334 -286.003216) (xy 90.302048 -285.97527)
			(xy 90.344632 -285.953689) (xy 90.390056 -285.938995) (xy 90.437213 -285.931549) (xy 90.461084 -285.931102)
			(xy 90.486342 -285.931593) (xy 90.536169 -285.939906) (xy 90.583948 -285.956306) (xy 90.628376 -285.980347)
			(xy 90.66824 -286.011373) (xy 90.702454 -286.048538) (xy 90.730085 -286.090827) (xy 90.750377 -286.137087)
			(xy 90.762778 -286.186057) (xy 90.76695 -286.2364) (xy 90.766949 -286.23641) (xy 91.084903 -286.23641)
			(xy 91.088998 -286.185682) (xy 91.101177 -286.136268) (xy 91.121125 -286.089448) (xy 91.148326 -286.046434)
			(xy 91.182074 -286.00834) (xy 91.221496 -285.976153) (xy 91.26557 -285.950707) (xy 91.313156 -285.93266)
			(xy 91.36302 -285.92248) (xy 91.413872 -285.920431) (xy 91.464393 -285.926565) (xy 91.513277 -285.940725)
			(xy 91.559256 -285.962542) (xy 91.60114 -285.991452) (xy 91.637844 -286.026707) (xy 91.668417 -286.067393)
			(xy 91.692068 -286.112456) (xy 91.708184 -286.16073) (xy 91.716348 -286.210964) (xy 91.71686 -286.23641)
			(xy 92.024703 -286.23641) (xy 92.028798 -286.185682) (xy 92.040977 -286.136268) (xy 92.060925 -286.089448)
			(xy 92.088126 -286.046434) (xy 92.121874 -286.00834) (xy 92.161296 -285.976153) (xy 92.20537 -285.950707)
			(xy 92.252956 -285.93266) (xy 92.30282 -285.92248) (xy 92.353672 -285.920431) (xy 92.404193 -285.926565)
			(xy 92.453077 -285.940725) (xy 92.499056 -285.962542) (xy 92.54094 -285.991452) (xy 92.577644 -286.026707)
			(xy 92.608217 -286.067393) (xy 92.631868 -286.112456) (xy 92.647984 -286.16073) (xy 92.656148 -286.210964)
			(xy 92.65666 -286.23641) (xy 92.975188 -286.23641) (xy 92.979148 -286.187356) (xy 92.990925 -286.139572)
			(xy 93.010216 -286.094296) (xy 93.036519 -286.0527) (xy 93.069154 -286.015863) (xy 93.107275 -285.984738)
			(xy 93.149896 -285.960131) (xy 93.195912 -285.942679) (xy 93.244131 -285.932835) (xy 93.293306 -285.930854)
			(xy 93.342161 -285.936786) (xy 93.389432 -285.950478) (xy 93.433894 -285.971576) (xy 93.474397 -285.999532)
			(xy 93.50989 -286.033624) (xy 93.539455 -286.072968) (xy 93.562326 -286.116545) (xy 93.57791 -286.163226)
			(xy 93.585805 -286.211803) (xy 93.5863 -286.23641) (xy 93.904811 -286.23641) (xy 93.908906 -286.185682)
			(xy 93.921085 -286.136268) (xy 93.941033 -286.089448) (xy 93.968234 -286.046434) (xy 94.001982 -286.00834)
			(xy 94.041404 -285.976153) (xy 94.085478 -285.950707) (xy 94.133064 -285.93266) (xy 94.182928 -285.92248)
			(xy 94.23378 -285.920431) (xy 94.284301 -285.926565) (xy 94.333185 -285.940725) (xy 94.379164 -285.962542)
			(xy 94.421048 -285.991452) (xy 94.457752 -286.026707) (xy 94.488325 -286.067393) (xy 94.511976 -286.112456)
			(xy 94.528092 -286.16073) (xy 94.536256 -286.210964) (xy 94.536768 -286.23641) (xy 94.855296 -286.23641)
			(xy 94.859256 -286.187356) (xy 94.871033 -286.139572) (xy 94.890324 -286.094296) (xy 94.916627 -286.0527)
			(xy 94.949262 -286.015863) (xy 94.987383 -285.984738) (xy 95.030004 -285.960131) (xy 95.07602 -285.942679)
			(xy 95.124239 -285.932835) (xy 95.173414 -285.930854) (xy 95.222269 -285.936786) (xy 95.26954 -285.950478)
			(xy 95.314002 -285.971576) (xy 95.354505 -285.999532) (xy 95.389998 -286.033624) (xy 95.419563 -286.072968)
			(xy 95.442434 -286.116545) (xy 95.458018 -286.163226) (xy 95.465913 -286.211803) (xy 95.466408 -286.23641)
			(xy 95.784919 -286.23641) (xy 95.789014 -286.185682) (xy 95.801193 -286.136268) (xy 95.821141 -286.089448)
			(xy 95.848342 -286.046434) (xy 95.88209 -286.00834) (xy 95.921512 -285.976153) (xy 95.965586 -285.950707)
			(xy 96.013172 -285.93266) (xy 96.063036 -285.92248) (xy 96.113888 -285.920431) (xy 96.164409 -285.926565)
			(xy 96.213293 -285.940725) (xy 96.259272 -285.962542) (xy 96.301156 -285.991452) (xy 96.33786 -286.026707)
			(xy 96.368433 -286.067393) (xy 96.392084 -286.112456) (xy 96.4082 -286.16073) (xy 96.416364 -286.210964)
			(xy 96.416876 -286.23641) (xy 96.416364 -286.261856) (xy 96.4082 -286.31209) (xy 96.392084 -286.360364)
			(xy 96.368433 -286.405427) (xy 96.33786 -286.446113) (xy 96.301156 -286.481368) (xy 96.259272 -286.510278)
			(xy 96.213293 -286.532095) (xy 96.164409 -286.546255) (xy 96.113888 -286.552389) (xy 96.063036 -286.55034)
			(xy 96.013172 -286.54016) (xy 95.965586 -286.522113) (xy 95.921512 -286.496667) (xy 95.88209 -286.46448)
			(xy 95.848342 -286.426386) (xy 95.821141 -286.383372) (xy 95.801193 -286.336552) (xy 95.789014 -286.287138)
			(xy 95.784919 -286.23641) (xy 95.466408 -286.23641) (xy 95.465913 -286.261017) (xy 95.458018 -286.309594)
			(xy 95.442434 -286.356275) (xy 95.419563 -286.399852) (xy 95.389998 -286.439196) (xy 95.354505 -286.473288)
			(xy 95.314002 -286.501244) (xy 95.26954 -286.522342) (xy 95.222269 -286.536034) (xy 95.173414 -286.541966)
			(xy 95.124239 -286.539985) (xy 95.07602 -286.530141) (xy 95.030004 -286.512689) (xy 94.987383 -286.488082)
			(xy 94.949262 -286.456957) (xy 94.916627 -286.42012) (xy 94.890324 -286.378524) (xy 94.871033 -286.333248)
			(xy 94.859256 -286.285464) (xy 94.855296 -286.23641) (xy 94.536768 -286.23641) (xy 94.536256 -286.261856)
			(xy 94.528092 -286.31209) (xy 94.511976 -286.360364) (xy 94.488325 -286.405427) (xy 94.457752 -286.446113)
			(xy 94.421048 -286.481368) (xy 94.379164 -286.510278) (xy 94.333185 -286.532095) (xy 94.284301 -286.546255)
			(xy 94.23378 -286.552389) (xy 94.182928 -286.55034) (xy 94.133064 -286.54016) (xy 94.085478 -286.522113)
			(xy 94.041404 -286.496667) (xy 94.001982 -286.46448) (xy 93.968234 -286.426386) (xy 93.941033 -286.383372)
			(xy 93.921085 -286.336552) (xy 93.908906 -286.287138) (xy 93.904811 -286.23641) (xy 93.5863 -286.23641)
			(xy 93.585805 -286.261017) (xy 93.57791 -286.309594) (xy 93.562326 -286.356275) (xy 93.539455 -286.399852)
			(xy 93.50989 -286.439196) (xy 93.474397 -286.473288) (xy 93.433894 -286.501244) (xy 93.389432 -286.522342)
			(xy 93.342161 -286.536034) (xy 93.293306 -286.541966) (xy 93.244131 -286.539985) (xy 93.195912 -286.530141)
			(xy 93.149896 -286.512689) (xy 93.107275 -286.488082) (xy 93.069154 -286.456957) (xy 93.036519 -286.42012)
			(xy 93.010216 -286.378524) (xy 92.990925 -286.333248) (xy 92.979148 -286.285464) (xy 92.975188 -286.23641)
			(xy 92.65666 -286.23641) (xy 92.656148 -286.261856) (xy 92.647984 -286.31209) (xy 92.631868 -286.360364)
			(xy 92.608217 -286.405427) (xy 92.577644 -286.446113) (xy 92.54094 -286.481368) (xy 92.499056 -286.510278)
			(xy 92.453077 -286.532095) (xy 92.404193 -286.546255) (xy 92.353672 -286.552389) (xy 92.30282 -286.55034)
			(xy 92.252956 -286.54016) (xy 92.20537 -286.522113) (xy 92.161296 -286.496667) (xy 92.121874 -286.46448)
			(xy 92.088126 -286.426386) (xy 92.060925 -286.383372) (xy 92.040977 -286.336552) (xy 92.028798 -286.287138)
			(xy 92.024703 -286.23641) (xy 91.71686 -286.23641) (xy 91.716348 -286.261856) (xy 91.708184 -286.31209)
			(xy 91.692068 -286.360364) (xy 91.668417 -286.405427) (xy 91.637844 -286.446113) (xy 91.60114 -286.481368)
			(xy 91.559256 -286.510278) (xy 91.513277 -286.532095) (xy 91.464393 -286.546255) (xy 91.413872 -286.552389)
			(xy 91.36302 -286.55034) (xy 91.313156 -286.54016) (xy 91.26557 -286.522113) (xy 91.221496 -286.496667)
			(xy 91.182074 -286.46448) (xy 91.148326 -286.426386) (xy 91.121125 -286.383372) (xy 91.101177 -286.336552)
			(xy 91.088998 -286.287138) (xy 91.084903 -286.23641) (xy 90.766949 -286.23641) (xy 90.762778 -286.286743)
			(xy 90.750377 -286.335713) (xy 90.730085 -286.381973) (xy 90.702454 -286.424262) (xy 90.66824 -286.461427)
			(xy 90.628376 -286.492453) (xy 90.583948 -286.516494) (xy 90.536169 -286.532894) (xy 90.486342 -286.541207)
			(xy 90.461084 -286.541718) (xy 90.437211 -286.541262) (xy 90.390047 -286.533838) (xy 90.344614 -286.519159)
			(xy 90.302023 -286.497581) (xy 90.263312 -286.469633) (xy 90.229427 -286.435997) (xy 90.214958 -286.417004)
			(xy 90.214958 -286.41675) (xy 90.212307 -286.413319) (xy 90.20605 -286.407318) (xy 90.202512 -286.404812)
			(xy 90.194683 -286.400042) (xy 90.176845 -286.395872) (xy 90.167714 -286.396684) (xy 90.079068 -286.408114)
			(xy 90.072308 -286.409189) (xy 90.059685 -286.414466) (xy 90.054176 -286.418528) (xy 90.048842 -286.422592)
			(xy 90.040968 -286.43326) (xy 90.038428 -286.439864) (xy 90.02522 -286.470852) (xy 90.019887 -286.482191)
			(xy 90.008326 -286.504424) (xy 90.002106 -286.515302) (xy 89.957656 -286.59201) (xy 89.951897 -286.603159)
			(xy 89.950982 -286.628205) (xy 89.955878 -286.639762) (xy 89.992962 -286.715454) (xy 89.995923 -286.721112)
			(xy 90.004148 -286.730875) (xy 90.009218 -286.734758) (xy 90.019378 -286.74187) (xy 90.031824 -286.743648)
			(xy 90.05474 -286.747181) (xy 90.099219 -286.760267) (xy 90.141209 -286.779926) (xy 90.179746 -286.805707)
			(xy 90.213942 -286.837016) (xy 90.243014 -286.873134) (xy 90.266292 -286.913231) (xy 90.275156 -286.934656)
			(xy 90.285074 -286.961593) (xy 90.295811 -287.017974) (xy 90.29648 -287.046162) (xy 90.614749 -287.046162)
			(xy 90.618844 -286.995434) (xy 90.631023 -286.94602) (xy 90.650971 -286.8992) (xy 90.678172 -286.856186)
			(xy 90.71192 -286.818092) (xy 90.751342 -286.785905) (xy 90.795416 -286.760459) (xy 90.843002 -286.742412)
			(xy 90.892866 -286.732232) (xy 90.943718 -286.730183) (xy 90.994239 -286.736317) (xy 91.043123 -286.750477)
			(xy 91.089102 -286.772294) (xy 91.130986 -286.801204) (xy 91.16769 -286.836459) (xy 91.198263 -286.877145)
			(xy 91.221914 -286.922208) (xy 91.23803 -286.970482) (xy 91.246194 -287.020716) (xy 91.246706 -287.046162)
			(xy 91.565234 -287.046162) (xy 91.569194 -286.997108) (xy 91.580971 -286.949324) (xy 91.600262 -286.904048)
			(xy 91.626565 -286.862452) (xy 91.6592 -286.825615) (xy 91.697321 -286.79449) (xy 91.739942 -286.769883)
			(xy 91.785958 -286.752431) (xy 91.834177 -286.742587) (xy 91.883352 -286.740606) (xy 91.932207 -286.746538)
			(xy 91.979478 -286.76023) (xy 92.02394 -286.781328) (xy 92.064443 -286.809284) (xy 92.099936 -286.843376)
			(xy 92.129501 -286.88272) (xy 92.152372 -286.926297) (xy 92.167956 -286.972978) (xy 92.175851 -287.021555)
			(xy 92.176346 -287.046162) (xy 92.494857 -287.046162) (xy 92.498952 -286.995434) (xy 92.511131 -286.94602)
			(xy 92.531079 -286.8992) (xy 92.55828 -286.856186) (xy 92.592028 -286.818092) (xy 92.63145 -286.785905)
			(xy 92.675524 -286.760459) (xy 92.72311 -286.742412) (xy 92.772974 -286.732232) (xy 92.823826 -286.730183)
			(xy 92.874347 -286.736317) (xy 92.923231 -286.750477) (xy 92.96921 -286.772294) (xy 93.011094 -286.801204)
			(xy 93.047798 -286.836459) (xy 93.078371 -286.877145) (xy 93.102022 -286.922208) (xy 93.118138 -286.970482)
			(xy 93.126302 -287.020716) (xy 93.126814 -287.046162) (xy 93.445342 -287.046162) (xy 93.449302 -286.997108)
			(xy 93.461079 -286.949324) (xy 93.48037 -286.904048) (xy 93.506673 -286.862452) (xy 93.539308 -286.825615)
			(xy 93.577429 -286.79449) (xy 93.62005 -286.769883) (xy 93.666066 -286.752431) (xy 93.714285 -286.742587)
			(xy 93.76346 -286.740606) (xy 93.812315 -286.746538) (xy 93.859586 -286.76023) (xy 93.904048 -286.781328)
			(xy 93.944551 -286.809284) (xy 93.980044 -286.843376) (xy 94.009609 -286.88272) (xy 94.03248 -286.926297)
			(xy 94.048064 -286.972978) (xy 94.055959 -287.021555) (xy 94.056454 -287.046162) (xy 94.374711 -287.046162)
			(xy 94.378806 -286.995434) (xy 94.390985 -286.94602) (xy 94.410933 -286.8992) (xy 94.438134 -286.856186)
			(xy 94.471882 -286.818092) (xy 94.511304 -286.785905) (xy 94.555378 -286.760459) (xy 94.602964 -286.742412)
			(xy 94.652828 -286.732232) (xy 94.70368 -286.730183) (xy 94.754201 -286.736317) (xy 94.803085 -286.750477)
			(xy 94.849064 -286.772294) (xy 94.890948 -286.801204) (xy 94.927652 -286.836459) (xy 94.958225 -286.877145)
			(xy 94.981876 -286.922208) (xy 94.997992 -286.970482) (xy 95.006156 -287.020716) (xy 95.006668 -287.046162)
			(xy 95.314765 -287.046162) (xy 95.31886 -286.995434) (xy 95.331039 -286.94602) (xy 95.350987 -286.8992)
			(xy 95.378188 -286.856186) (xy 95.411936 -286.818092) (xy 95.451358 -286.785905) (xy 95.495432 -286.760459)
			(xy 95.543018 -286.742412) (xy 95.592882 -286.732232) (xy 95.643734 -286.730183) (xy 95.694255 -286.736317)
			(xy 95.743139 -286.750477) (xy 95.789118 -286.772294) (xy 95.831002 -286.801204) (xy 95.867706 -286.836459)
			(xy 95.898279 -286.877145) (xy 95.92193 -286.922208) (xy 95.938046 -286.970482) (xy 95.94621 -287.020716)
			(xy 95.946722 -287.046162) (xy 95.94621 -287.071608) (xy 95.938046 -287.121842) (xy 95.92193 -287.170116)
			(xy 95.898279 -287.215179) (xy 95.867706 -287.255865) (xy 95.831002 -287.29112) (xy 95.789118 -287.32003)
			(xy 95.743139 -287.341847) (xy 95.694255 -287.356007) (xy 95.643734 -287.362141) (xy 95.592882 -287.360092)
			(xy 95.543018 -287.349912) (xy 95.495432 -287.331865) (xy 95.451358 -287.306419) (xy 95.411936 -287.274232)
			(xy 95.378188 -287.236138) (xy 95.350987 -287.193124) (xy 95.331039 -287.146304) (xy 95.31886 -287.09689)
			(xy 95.314765 -287.046162) (xy 95.006668 -287.046162) (xy 95.006156 -287.071608) (xy 94.997992 -287.121842)
			(xy 94.981876 -287.170116) (xy 94.958225 -287.215179) (xy 94.927652 -287.255865) (xy 94.890948 -287.29112)
			(xy 94.849064 -287.32003) (xy 94.803085 -287.341847) (xy 94.754201 -287.356007) (xy 94.70368 -287.362141)
			(xy 94.652828 -287.360092) (xy 94.602964 -287.349912) (xy 94.555378 -287.331865) (xy 94.511304 -287.306419)
			(xy 94.471882 -287.274232) (xy 94.438134 -287.236138) (xy 94.410933 -287.193124) (xy 94.390985 -287.146304)
			(xy 94.378806 -287.09689) (xy 94.374711 -287.046162) (xy 94.056454 -287.046162) (xy 94.055959 -287.070769)
			(xy 94.048064 -287.119346) (xy 94.03248 -287.166027) (xy 94.009609 -287.209604) (xy 93.980044 -287.248948)
			(xy 93.944551 -287.28304) (xy 93.904048 -287.310996) (xy 93.859586 -287.332094) (xy 93.812315 -287.345786)
			(xy 93.76346 -287.351718) (xy 93.714285 -287.349737) (xy 93.666066 -287.339893) (xy 93.62005 -287.322441)
			(xy 93.577429 -287.297834) (xy 93.539308 -287.266709) (xy 93.506673 -287.229872) (xy 93.48037 -287.188276)
			(xy 93.461079 -287.143) (xy 93.449302 -287.095216) (xy 93.445342 -287.046162) (xy 93.126814 -287.046162)
			(xy 93.126302 -287.071608) (xy 93.118138 -287.121842) (xy 93.102022 -287.170116) (xy 93.078371 -287.215179)
			(xy 93.047798 -287.255865) (xy 93.011094 -287.29112) (xy 92.96921 -287.32003) (xy 92.923231 -287.341847)
			(xy 92.874347 -287.356007) (xy 92.823826 -287.362141) (xy 92.772974 -287.360092) (xy 92.72311 -287.349912)
			(xy 92.675524 -287.331865) (xy 92.63145 -287.306419) (xy 92.592028 -287.274232) (xy 92.55828 -287.236138)
			(xy 92.531079 -287.193124) (xy 92.511131 -287.146304) (xy 92.498952 -287.09689) (xy 92.494857 -287.046162)
			(xy 92.176346 -287.046162) (xy 92.175851 -287.070769) (xy 92.167956 -287.119346) (xy 92.152372 -287.166027)
			(xy 92.129501 -287.209604) (xy 92.099936 -287.248948) (xy 92.064443 -287.28304) (xy 92.02394 -287.310996)
			(xy 91.979478 -287.332094) (xy 91.932207 -287.345786) (xy 91.883352 -287.351718) (xy 91.834177 -287.349737)
			(xy 91.785958 -287.339893) (xy 91.739942 -287.322441) (xy 91.697321 -287.297834) (xy 91.6592 -287.266709)
			(xy 91.626565 -287.229872) (xy 91.600262 -287.188276) (xy 91.580971 -287.143) (xy 91.569194 -287.095216)
			(xy 91.565234 -287.046162) (xy 91.246706 -287.046162) (xy 91.246194 -287.071608) (xy 91.23803 -287.121842)
			(xy 91.221914 -287.170116) (xy 91.198263 -287.215179) (xy 91.16769 -287.255865) (xy 91.130986 -287.29112)
			(xy 91.089102 -287.32003) (xy 91.043123 -287.341847) (xy 90.994239 -287.356007) (xy 90.943718 -287.362141)
			(xy 90.892866 -287.360092) (xy 90.843002 -287.349912) (xy 90.795416 -287.331865) (xy 90.751342 -287.306419)
			(xy 90.71192 -287.274232) (xy 90.678172 -287.236138) (xy 90.650971 -287.193124) (xy 90.631023 -287.146304)
			(xy 90.618844 -287.09689) (xy 90.614749 -287.046162) (xy 90.29648 -287.046162) (xy 90.296492 -287.04667)
			(xy 90.296005 -287.071531) (xy 90.28795 -287.120596) (xy 90.272048 -287.167706) (xy 90.248719 -287.211615)
			(xy 90.218581 -287.251162) (xy 90.182432 -287.285301) (xy 90.141226 -287.313128) (xy 90.096055 -287.333907)
			(xy 90.048112 -287.34709) (xy 90.023442 -287.3502) (xy 90.016584 -287.350962) (xy 90.005281 -287.354504)
			(xy 89.987399 -287.369993) (xy 89.982294 -287.38068) (xy 89.958926 -287.436306) (xy 89.957083 -287.440987)
			(xy 89.955039 -287.450836) (xy 89.954862 -287.455864) (xy 89.954862 -287.504886) (xy 89.959942 -287.520126)
			(xy 89.963498 -287.524952) (xy 89.985488 -287.55538) (xy 90.021935 -287.621012) (xy 90.036142 -287.655762)
			(xy 90.036142 -287.656016) (xy 90.038774 -287.662202) (xy 90.046757 -287.673012) (xy 90.05189 -287.677352)
			(xy 90.063066 -287.685988) (xy 90.075512 -287.687512) (xy 90.165682 -287.698942) (xy 90.172562 -287.699543)
			(xy 90.186214 -287.697493) (xy 90.192606 -287.694878) (xy 90.198448 -287.692338) (xy 90.208862 -287.683956)
			(xy 90.21318 -287.678114) (xy 90.227645 -287.658814) (xy 90.261632 -287.624595) (xy 90.300571 -287.596137)
			(xy 90.343496 -287.574147) (xy 90.389341 -287.559171) (xy 90.436969 -287.551579) (xy 90.461084 -287.551114)
			(xy 90.486341 -287.551605) (xy 90.536166 -287.559917) (xy 90.583943 -287.576317) (xy 90.628369 -287.600357)
			(xy 90.668232 -287.631382) (xy 90.702445 -287.668545) (xy 90.730074 -287.710833) (xy 90.750366 -287.757091)
			(xy 90.762766 -287.806059) (xy 90.766938 -287.8564) (xy 90.766936 -287.856422) (xy 91.084903 -287.856422)
			(xy 91.088998 -287.805694) (xy 91.101177 -287.75628) (xy 91.121125 -287.70946) (xy 91.148326 -287.666446)
			(xy 91.182074 -287.628352) (xy 91.221496 -287.596165) (xy 91.26557 -287.570719) (xy 91.313156 -287.552672)
			(xy 91.36302 -287.542492) (xy 91.413872 -287.540443) (xy 91.464393 -287.546577) (xy 91.513277 -287.560737)
			(xy 91.559256 -287.582554) (xy 91.60114 -287.611464) (xy 91.637844 -287.646719) (xy 91.668417 -287.687405)
			(xy 91.692068 -287.732468) (xy 91.708184 -287.780742) (xy 91.716348 -287.830976) (xy 91.71686 -287.856422)
			(xy 92.024703 -287.856422) (xy 92.028798 -287.805694) (xy 92.040977 -287.75628) (xy 92.060925 -287.70946)
			(xy 92.088126 -287.666446) (xy 92.121874 -287.628352) (xy 92.161296 -287.596165) (xy 92.20537 -287.570719)
			(xy 92.252956 -287.552672) (xy 92.30282 -287.542492) (xy 92.353672 -287.540443) (xy 92.404193 -287.546577)
			(xy 92.453077 -287.560737) (xy 92.499056 -287.582554) (xy 92.54094 -287.611464) (xy 92.577644 -287.646719)
			(xy 92.608217 -287.687405) (xy 92.631868 -287.732468) (xy 92.647984 -287.780742) (xy 92.656148 -287.830976)
			(xy 92.65666 -287.856422) (xy 93.904811 -287.856422) (xy 93.908906 -287.805694) (xy 93.921085 -287.75628)
			(xy 93.941033 -287.70946) (xy 93.968234 -287.666446) (xy 94.001982 -287.628352) (xy 94.041404 -287.596165)
			(xy 94.085478 -287.570719) (xy 94.133064 -287.552672) (xy 94.182928 -287.542492) (xy 94.23378 -287.540443)
			(xy 94.284301 -287.546577) (xy 94.333185 -287.560737) (xy 94.379164 -287.582554) (xy 94.421048 -287.611464)
			(xy 94.457752 -287.646719) (xy 94.488325 -287.687405) (xy 94.511976 -287.732468) (xy 94.528092 -287.780742)
			(xy 94.536256 -287.830976) (xy 94.536768 -287.856422) (xy 94.855296 -287.856422) (xy 94.859256 -287.807368)
			(xy 94.871033 -287.759584) (xy 94.890324 -287.714308) (xy 94.916627 -287.672712) (xy 94.949262 -287.635875)
			(xy 94.987383 -287.60475) (xy 95.030004 -287.580143) (xy 95.07602 -287.562691) (xy 95.124239 -287.552847)
			(xy 95.173414 -287.550866) (xy 95.222269 -287.556798) (xy 95.26954 -287.57049) (xy 95.314002 -287.591588)
			(xy 95.354505 -287.619544) (xy 95.389998 -287.653636) (xy 95.419563 -287.69298) (xy 95.442434 -287.736557)
			(xy 95.458018 -287.783238) (xy 95.465913 -287.831815) (xy 95.466408 -287.856422) (xy 95.784919 -287.856422)
			(xy 95.789014 -287.805694) (xy 95.801193 -287.75628) (xy 95.821141 -287.70946) (xy 95.848342 -287.666446)
			(xy 95.88209 -287.628352) (xy 95.921512 -287.596165) (xy 95.965586 -287.570719) (xy 96.013172 -287.552672)
			(xy 96.063036 -287.542492) (xy 96.113888 -287.540443) (xy 96.164409 -287.546577) (xy 96.213293 -287.560737)
			(xy 96.259272 -287.582554) (xy 96.301156 -287.611464) (xy 96.33786 -287.646719) (xy 96.368433 -287.687405)
			(xy 96.392084 -287.732468) (xy 96.4082 -287.780742) (xy 96.416364 -287.830976) (xy 96.416876 -287.856422)
			(xy 96.416364 -287.881868) (xy 96.4082 -287.932102) (xy 96.392084 -287.980376) (xy 96.368433 -288.025439)
			(xy 96.33786 -288.066125) (xy 96.301156 -288.10138) (xy 96.259272 -288.13029) (xy 96.213293 -288.152107)
			(xy 96.164409 -288.166267) (xy 96.113888 -288.172401) (xy 96.063036 -288.170352) (xy 96.013172 -288.160172)
			(xy 95.965586 -288.142125) (xy 95.921512 -288.116679) (xy 95.88209 -288.084492) (xy 95.848342 -288.046398)
			(xy 95.821141 -288.003384) (xy 95.801193 -287.956564) (xy 95.789014 -287.90715) (xy 95.784919 -287.856422)
			(xy 95.466408 -287.856422) (xy 95.465913 -287.881029) (xy 95.458018 -287.929606) (xy 95.442434 -287.976287)
			(xy 95.419563 -288.019864) (xy 95.389998 -288.059208) (xy 95.354505 -288.0933) (xy 95.314002 -288.121256)
			(xy 95.26954 -288.142354) (xy 95.222269 -288.156046) (xy 95.173414 -288.161978) (xy 95.124239 -288.159997)
			(xy 95.07602 -288.150153) (xy 95.030004 -288.132701) (xy 94.987383 -288.108094) (xy 94.949262 -288.076969)
			(xy 94.916627 -288.040132) (xy 94.890324 -287.998536) (xy 94.871033 -287.95326) (xy 94.859256 -287.905476)
			(xy 94.855296 -287.856422) (xy 94.536768 -287.856422) (xy 94.536256 -287.881868) (xy 94.528092 -287.932102)
			(xy 94.511976 -287.980376) (xy 94.488325 -288.025439) (xy 94.457752 -288.066125) (xy 94.421048 -288.10138)
			(xy 94.379164 -288.13029) (xy 94.333185 -288.152107) (xy 94.284301 -288.166267) (xy 94.23378 -288.172401)
			(xy 94.182928 -288.170352) (xy 94.133064 -288.160172) (xy 94.085478 -288.142125) (xy 94.041404 -288.116679)
			(xy 94.001982 -288.084492) (xy 93.968234 -288.046398) (xy 93.941033 -288.003384) (xy 93.921085 -287.956564)
			(xy 93.908906 -287.90715) (xy 93.904811 -287.856422) (xy 92.65666 -287.856422) (xy 92.656148 -287.881868)
			(xy 92.647984 -287.932102) (xy 92.631868 -287.980376) (xy 92.608217 -288.025439) (xy 92.577644 -288.066125)
			(xy 92.54094 -288.10138) (xy 92.499056 -288.13029) (xy 92.453077 -288.152107) (xy 92.404193 -288.166267)
			(xy 92.353672 -288.172401) (xy 92.30282 -288.170352) (xy 92.252956 -288.160172) (xy 92.20537 -288.142125)
			(xy 92.161296 -288.116679) (xy 92.121874 -288.084492) (xy 92.088126 -288.046398) (xy 92.060925 -288.003384)
			(xy 92.040977 -287.956564) (xy 92.028798 -287.90715) (xy 92.024703 -287.856422) (xy 91.71686 -287.856422)
			(xy 91.716348 -287.881868) (xy 91.708184 -287.932102) (xy 91.692068 -287.980376) (xy 91.668417 -288.025439)
			(xy 91.637844 -288.066125) (xy 91.60114 -288.10138) (xy 91.559256 -288.13029) (xy 91.513277 -288.152107)
			(xy 91.464393 -288.166267) (xy 91.413872 -288.172401) (xy 91.36302 -288.170352) (xy 91.313156 -288.160172)
			(xy 91.26557 -288.142125) (xy 91.221496 -288.116679) (xy 91.182074 -288.084492) (xy 91.148326 -288.046398)
			(xy 91.121125 -288.003384) (xy 91.101177 -287.956564) (xy 91.088998 -287.90715) (xy 91.084903 -287.856422)
			(xy 90.766936 -287.856422) (xy 90.762766 -287.906741) (xy 90.750366 -287.955709) (xy 90.730074 -288.001967)
			(xy 90.702445 -288.044255) (xy 90.668232 -288.081418) (xy 90.628369 -288.112443) (xy 90.583943 -288.136483)
			(xy 90.536166 -288.152883) (xy 90.486341 -288.161195) (xy 90.461084 -288.16173) (xy 90.448321 -288.161592)
			(xy 90.422887 -288.159432) (xy 90.410284 -288.157412) (xy 90.410284 -288.157666) (xy 90.386831 -288.153237)
			(xy 90.341578 -288.138073) (xy 90.299228 -288.116069) (xy 90.260807 -288.087757) (xy 90.227246 -288.053824)
			(xy 90.212926 -288.03473) (xy 90.208862 -288.028888) (xy 90.198194 -288.020252) (xy 90.192352 -288.017712)
			(xy 90.186069 -288.01519) (xy 90.172675 -288.013256) (xy 90.165936 -288.013902) (xy 90.075512 -288.025332)
			(xy 90.063066 -288.026856) (xy 90.05189 -288.035492) (xy 90.046763 -288.039837) (xy 90.038788 -288.05065)
			(xy 90.036142 -288.056828) (xy 90.036142 -288.057082) (xy 90.028246 -288.076862) (xy 90.009813 -288.115261)
			(xy 89.999312 -288.13379) (xy 89.977468 -288.171382) (xy 89.953338 -288.212784) (xy 89.948153 -288.223863)
			(xy 89.947748 -288.248282) (xy 89.952576 -288.25952) (xy 89.984834 -288.32429) (xy 89.987777 -288.329797)
			(xy 89.995867 -288.339305) (xy 90.000836 -288.343086) (xy 90.028776 -288.362898) (xy 90.040206 -288.36493)
			(xy 90.063721 -288.369247) (xy 90.109121 -288.384223) (xy 90.151633 -288.406092) (xy 90.190218 -288.434318)
			(xy 90.223933 -288.468212) (xy 90.251955 -288.506945) (xy 90.273598 -288.549572) (xy 90.288334 -288.595051)
			(xy 90.295803 -288.642271) (xy 90.296238 -288.666174) (xy 90.614749 -288.666174) (xy 90.618844 -288.615446)
			(xy 90.631023 -288.566032) (xy 90.650971 -288.519212) (xy 90.678172 -288.476198) (xy 90.71192 -288.438104)
			(xy 90.751342 -288.405917) (xy 90.795416 -288.380471) (xy 90.843002 -288.362424) (xy 90.892866 -288.352244)
			(xy 90.943718 -288.350195) (xy 90.994239 -288.356329) (xy 91.043123 -288.370489) (xy 91.089102 -288.392306)
			(xy 91.130986 -288.421216) (xy 91.16769 -288.456471) (xy 91.198263 -288.497157) (xy 91.221914 -288.54222)
			(xy 91.23803 -288.590494) (xy 91.246194 -288.640728) (xy 91.246706 -288.666174) (xy 91.565234 -288.666174)
			(xy 91.569194 -288.61712) (xy 91.580971 -288.569336) (xy 91.600262 -288.52406) (xy 91.626565 -288.482464)
			(xy 91.6592 -288.445627) (xy 91.697321 -288.414502) (xy 91.739942 -288.389895) (xy 91.785958 -288.372443)
			(xy 91.834177 -288.362599) (xy 91.883352 -288.360618) (xy 91.932207 -288.36655) (xy 91.979478 -288.380242)
			(xy 92.02394 -288.40134) (xy 92.064443 -288.429296) (xy 92.099936 -288.463388) (xy 92.129501 -288.502732)
			(xy 92.152372 -288.546309) (xy 92.167956 -288.59299) (xy 92.175851 -288.641567) (xy 92.176346 -288.666174)
			(xy 92.494857 -288.666174) (xy 92.498952 -288.615446) (xy 92.511131 -288.566032) (xy 92.531079 -288.519212)
			(xy 92.55828 -288.476198) (xy 92.592028 -288.438104) (xy 92.63145 -288.405917) (xy 92.675524 -288.380471)
			(xy 92.72311 -288.362424) (xy 92.772974 -288.352244) (xy 92.823826 -288.350195) (xy 92.874347 -288.356329)
			(xy 92.923231 -288.370489) (xy 92.96921 -288.392306) (xy 93.011094 -288.421216) (xy 93.047798 -288.456471)
			(xy 93.078371 -288.497157) (xy 93.102022 -288.54222) (xy 93.118138 -288.590494) (xy 93.126302 -288.640728)
			(xy 93.126814 -288.666174) (xy 93.445342 -288.666174) (xy 93.449302 -288.61712) (xy 93.461079 -288.569336)
			(xy 93.48037 -288.52406) (xy 93.506673 -288.482464) (xy 93.539308 -288.445627) (xy 93.577429 -288.414502)
			(xy 93.62005 -288.389895) (xy 93.666066 -288.372443) (xy 93.714285 -288.362599) (xy 93.76346 -288.360618)
			(xy 93.812315 -288.36655) (xy 93.859586 -288.380242) (xy 93.904048 -288.40134) (xy 93.944551 -288.429296)
			(xy 93.980044 -288.463388) (xy 94.009609 -288.502732) (xy 94.03248 -288.546309) (xy 94.048064 -288.59299)
			(xy 94.055959 -288.641567) (xy 94.056454 -288.666174) (xy 94.374711 -288.666174) (xy 94.378806 -288.615446)
			(xy 94.390985 -288.566032) (xy 94.410933 -288.519212) (xy 94.438134 -288.476198) (xy 94.471882 -288.438104)
			(xy 94.511304 -288.405917) (xy 94.555378 -288.380471) (xy 94.602964 -288.362424) (xy 94.652828 -288.352244)
			(xy 94.70368 -288.350195) (xy 94.754201 -288.356329) (xy 94.803085 -288.370489) (xy 94.849064 -288.392306)
			(xy 94.890948 -288.421216) (xy 94.927652 -288.456471) (xy 94.958225 -288.497157) (xy 94.981876 -288.54222)
			(xy 94.997992 -288.590494) (xy 95.006156 -288.640728) (xy 95.006668 -288.666174) (xy 95.314765 -288.666174)
			(xy 95.31886 -288.615446) (xy 95.331039 -288.566032) (xy 95.350987 -288.519212) (xy 95.378188 -288.476198)
			(xy 95.411936 -288.438104) (xy 95.451358 -288.405917) (xy 95.495432 -288.380471) (xy 95.543018 -288.362424)
			(xy 95.592882 -288.352244) (xy 95.643734 -288.350195) (xy 95.694255 -288.356329) (xy 95.743139 -288.370489)
			(xy 95.789118 -288.392306) (xy 95.831002 -288.421216) (xy 95.867706 -288.456471) (xy 95.898279 -288.497157)
			(xy 95.92193 -288.54222) (xy 95.938046 -288.590494) (xy 95.94621 -288.640728) (xy 95.946722 -288.666174)
			(xy 95.94621 -288.69162) (xy 95.938046 -288.741854) (xy 95.92193 -288.790128) (xy 95.898279 -288.835191)
			(xy 95.867706 -288.875877) (xy 95.831002 -288.911132) (xy 95.789118 -288.940042) (xy 95.743139 -288.961859)
			(xy 95.694255 -288.976019) (xy 95.643734 -288.982153) (xy 95.592882 -288.980104) (xy 95.543018 -288.969924)
			(xy 95.495432 -288.951877) (xy 95.451358 -288.926431) (xy 95.411936 -288.894244) (xy 95.378188 -288.85615)
			(xy 95.350987 -288.813136) (xy 95.331039 -288.766316) (xy 95.31886 -288.716902) (xy 95.314765 -288.666174)
			(xy 95.006668 -288.666174) (xy 95.006156 -288.69162) (xy 94.997992 -288.741854) (xy 94.981876 -288.790128)
			(xy 94.958225 -288.835191) (xy 94.927652 -288.875877) (xy 94.890948 -288.911132) (xy 94.849064 -288.940042)
			(xy 94.803085 -288.961859) (xy 94.754201 -288.976019) (xy 94.70368 -288.982153) (xy 94.652828 -288.980104)
			(xy 94.602964 -288.969924) (xy 94.555378 -288.951877) (xy 94.511304 -288.926431) (xy 94.471882 -288.894244)
			(xy 94.438134 -288.85615) (xy 94.410933 -288.813136) (xy 94.390985 -288.766316) (xy 94.378806 -288.716902)
			(xy 94.374711 -288.666174) (xy 94.056454 -288.666174) (xy 94.055959 -288.690781) (xy 94.048064 -288.739358)
			(xy 94.03248 -288.786039) (xy 94.009609 -288.829616) (xy 93.980044 -288.86896) (xy 93.944551 -288.903052)
			(xy 93.904048 -288.931008) (xy 93.859586 -288.952106) (xy 93.812315 -288.965798) (xy 93.76346 -288.97173)
			(xy 93.714285 -288.969749) (xy 93.666066 -288.959905) (xy 93.62005 -288.942453) (xy 93.577429 -288.917846)
			(xy 93.539308 -288.886721) (xy 93.506673 -288.849884) (xy 93.48037 -288.808288) (xy 93.461079 -288.763012)
			(xy 93.449302 -288.715228) (xy 93.445342 -288.666174) (xy 93.126814 -288.666174) (xy 93.126302 -288.69162)
			(xy 93.118138 -288.741854) (xy 93.102022 -288.790128) (xy 93.078371 -288.835191) (xy 93.047798 -288.875877)
			(xy 93.011094 -288.911132) (xy 92.96921 -288.940042) (xy 92.923231 -288.961859) (xy 92.874347 -288.976019)
			(xy 92.823826 -288.982153) (xy 92.772974 -288.980104) (xy 92.72311 -288.969924) (xy 92.675524 -288.951877)
			(xy 92.63145 -288.926431) (xy 92.592028 -288.894244) (xy 92.55828 -288.85615) (xy 92.531079 -288.813136)
			(xy 92.511131 -288.766316) (xy 92.498952 -288.716902) (xy 92.494857 -288.666174) (xy 92.176346 -288.666174)
			(xy 92.175851 -288.690781) (xy 92.167956 -288.739358) (xy 92.152372 -288.786039) (xy 92.129501 -288.829616)
			(xy 92.099936 -288.86896) (xy 92.064443 -288.903052) (xy 92.02394 -288.931008) (xy 91.979478 -288.952106)
			(xy 91.932207 -288.965798) (xy 91.883352 -288.97173) (xy 91.834177 -288.969749) (xy 91.785958 -288.959905)
			(xy 91.739942 -288.942453) (xy 91.697321 -288.917846) (xy 91.6592 -288.886721) (xy 91.626565 -288.849884)
			(xy 91.600262 -288.808288) (xy 91.580971 -288.763012) (xy 91.569194 -288.715228) (xy 91.565234 -288.666174)
			(xy 91.246706 -288.666174) (xy 91.246194 -288.69162) (xy 91.23803 -288.741854) (xy 91.221914 -288.790128)
			(xy 91.198263 -288.835191) (xy 91.16769 -288.875877) (xy 91.130986 -288.911132) (xy 91.089102 -288.940042)
			(xy 91.043123 -288.961859) (xy 90.994239 -288.976019) (xy 90.943718 -288.982153) (xy 90.892866 -288.980104)
			(xy 90.843002 -288.969924) (xy 90.795416 -288.951877) (xy 90.751342 -288.926431) (xy 90.71192 -288.894244)
			(xy 90.678172 -288.85615) (xy 90.650971 -288.813136) (xy 90.631023 -288.766316) (xy 90.618844 -288.716902)
			(xy 90.614749 -288.666174) (xy 90.296238 -288.666174) (xy 90.295754 -288.690996) (xy 90.287727 -288.739988)
			(xy 90.27188 -288.787036) (xy 90.24863 -288.8309) (xy 90.218591 -288.870425) (xy 90.182553 -288.90457)
			(xy 90.141466 -288.932435) (xy 90.096412 -288.953286) (xy 90.048578 -288.966573) (xy 90.02395 -288.969704)
			(xy 90.023696 -288.969704) (xy 90.016991 -288.970624) (xy 90.004374 -288.975512) (xy 89.998804 -288.979356)
			(xy 89.993724 -288.98342) (xy 89.985342 -288.993834) (xy 89.948004 -289.08248) (xy 89.945531 -289.088907)
			(xy 89.943732 -289.102555) (xy 89.944448 -289.109404) (xy 89.946226 -289.122612) (xy 89.954862 -289.133534)
			(xy 89.979729 -289.166231) (xy 90.020535 -289.237522) (xy 90.036142 -289.27552) (xy 90.036142 -289.275774)
			(xy 90.03878 -289.281955) (xy 90.04677 -289.292756) (xy 90.05189 -289.29711) (xy 90.063066 -289.305746)
			(xy 90.075512 -289.30727) (xy 90.165682 -289.3187) (xy 90.172562 -289.319302) (xy 90.186214 -289.317249)
			(xy 90.192606 -289.314636) (xy 90.198448 -289.312096) (xy 90.208862 -289.303714) (xy 90.21318 -289.297872)
			(xy 90.227646 -289.278574) (xy 90.261635 -289.244359) (xy 90.300575 -289.215905) (xy 90.343499 -289.193919)
			(xy 90.389344 -289.178945) (xy 90.43697 -289.171354) (xy 90.461084 -289.170872) (xy 90.486344 -289.171363)
			(xy 90.536176 -289.179677) (xy 90.58396 -289.196079) (xy 90.628392 -289.220122) (xy 90.668261 -289.251151)
			(xy 90.702478 -289.288319) (xy 90.730111 -289.330613) (xy 90.750405 -289.376878) (xy 90.762808 -289.425852)
			(xy 90.766978 -289.47618) (xy 91.084903 -289.47618) (xy 91.088998 -289.425452) (xy 91.101177 -289.376038)
			(xy 91.121125 -289.329218) (xy 91.148326 -289.286204) (xy 91.182074 -289.24811) (xy 91.221496 -289.215923)
			(xy 91.26557 -289.190477) (xy 91.313156 -289.17243) (xy 91.36302 -289.16225) (xy 91.413872 -289.160201)
			(xy 91.464393 -289.166335) (xy 91.513277 -289.180495) (xy 91.559256 -289.202312) (xy 91.60114 -289.231222)
			(xy 91.637844 -289.266477) (xy 91.668417 -289.307163) (xy 91.692068 -289.352226) (xy 91.708184 -289.4005)
			(xy 91.716348 -289.450734) (xy 91.71686 -289.47618) (xy 92.024703 -289.47618) (xy 92.028798 -289.425452)
			(xy 92.040977 -289.376038) (xy 92.060925 -289.329218) (xy 92.088126 -289.286204) (xy 92.121874 -289.24811)
			(xy 92.161296 -289.215923) (xy 92.20537 -289.190477) (xy 92.252956 -289.17243) (xy 92.30282 -289.16225)
			(xy 92.353672 -289.160201) (xy 92.404193 -289.166335) (xy 92.453077 -289.180495) (xy 92.499056 -289.202312)
			(xy 92.54094 -289.231222) (xy 92.577644 -289.266477) (xy 92.608217 -289.307163) (xy 92.631868 -289.352226)
			(xy 92.647984 -289.4005) (xy 92.656148 -289.450734) (xy 92.65666 -289.47618) (xy 92.975188 -289.47618)
			(xy 92.979148 -289.427126) (xy 92.990925 -289.379342) (xy 93.010216 -289.334066) (xy 93.036519 -289.29247)
			(xy 93.069154 -289.255633) (xy 93.107275 -289.224508) (xy 93.149896 -289.199901) (xy 93.195912 -289.182449)
			(xy 93.244131 -289.172605) (xy 93.293306 -289.170624) (xy 93.342161 -289.176556) (xy 93.389432 -289.190248)
			(xy 93.433894 -289.211346) (xy 93.474397 -289.239302) (xy 93.50989 -289.273394) (xy 93.539455 -289.312738)
			(xy 93.562326 -289.356315) (xy 93.57791 -289.402996) (xy 93.585805 -289.451573) (xy 93.5863 -289.47618)
			(xy 93.904811 -289.47618) (xy 93.908906 -289.425452) (xy 93.921085 -289.376038) (xy 93.941033 -289.329218)
			(xy 93.968234 -289.286204) (xy 94.001982 -289.24811) (xy 94.041404 -289.215923) (xy 94.085478 -289.190477)
			(xy 94.133064 -289.17243) (xy 94.182928 -289.16225) (xy 94.23378 -289.160201) (xy 94.284301 -289.166335)
			(xy 94.333185 -289.180495) (xy 94.379164 -289.202312) (xy 94.421048 -289.231222) (xy 94.457752 -289.266477)
			(xy 94.488325 -289.307163) (xy 94.511976 -289.352226) (xy 94.528092 -289.4005) (xy 94.536256 -289.450734)
			(xy 94.536768 -289.47618) (xy 94.855296 -289.47618) (xy 94.859256 -289.427126) (xy 94.871033 -289.379342)
			(xy 94.890324 -289.334066) (xy 94.916627 -289.29247) (xy 94.949262 -289.255633) (xy 94.987383 -289.224508)
			(xy 95.030004 -289.199901) (xy 95.07602 -289.182449) (xy 95.124239 -289.172605) (xy 95.173414 -289.170624)
			(xy 95.222269 -289.176556) (xy 95.26954 -289.190248) (xy 95.314002 -289.211346) (xy 95.354505 -289.239302)
			(xy 95.389998 -289.273394) (xy 95.419563 -289.312738) (xy 95.442434 -289.356315) (xy 95.458018 -289.402996)
			(xy 95.465913 -289.451573) (xy 95.466408 -289.47618) (xy 95.784919 -289.47618) (xy 95.789014 -289.425452)
			(xy 95.801193 -289.376038) (xy 95.821141 -289.329218) (xy 95.848342 -289.286204) (xy 95.88209 -289.24811)
			(xy 95.921512 -289.215923) (xy 95.965586 -289.190477) (xy 96.013172 -289.17243) (xy 96.063036 -289.16225)
			(xy 96.113888 -289.160201) (xy 96.164409 -289.166335) (xy 96.213293 -289.180495) (xy 96.259272 -289.202312)
			(xy 96.301156 -289.231222) (xy 96.33786 -289.266477) (xy 96.368433 -289.307163) (xy 96.392084 -289.352226)
			(xy 96.4082 -289.4005) (xy 96.416364 -289.450734) (xy 96.416876 -289.47618) (xy 96.416364 -289.501626)
			(xy 96.4082 -289.55186) (xy 96.392084 -289.600134) (xy 96.368433 -289.645197) (xy 96.33786 -289.685883)
			(xy 96.301156 -289.721138) (xy 96.259272 -289.750048) (xy 96.213293 -289.771865) (xy 96.164409 -289.786025)
			(xy 96.113888 -289.792159) (xy 96.063036 -289.79011) (xy 96.013172 -289.77993) (xy 95.965586 -289.761883)
			(xy 95.921512 -289.736437) (xy 95.88209 -289.70425) (xy 95.848342 -289.666156) (xy 95.821141 -289.623142)
			(xy 95.801193 -289.576322) (xy 95.789014 -289.526908) (xy 95.784919 -289.47618) (xy 95.466408 -289.47618)
			(xy 95.465913 -289.500787) (xy 95.458018 -289.549364) (xy 95.442434 -289.596045) (xy 95.419563 -289.639622)
			(xy 95.389998 -289.678966) (xy 95.354505 -289.713058) (xy 95.314002 -289.741014) (xy 95.26954 -289.762112)
			(xy 95.222269 -289.775804) (xy 95.173414 -289.781736) (xy 95.124239 -289.779755) (xy 95.07602 -289.769911)
			(xy 95.030004 -289.752459) (xy 94.987383 -289.727852) (xy 94.949262 -289.696727) (xy 94.916627 -289.65989)
			(xy 94.890324 -289.618294) (xy 94.871033 -289.573018) (xy 94.859256 -289.525234) (xy 94.855296 -289.47618)
			(xy 94.536768 -289.47618) (xy 94.536256 -289.501626) (xy 94.528092 -289.55186) (xy 94.511976 -289.600134)
			(xy 94.488325 -289.645197) (xy 94.457752 -289.685883) (xy 94.421048 -289.721138) (xy 94.379164 -289.750048)
			(xy 94.333185 -289.771865) (xy 94.284301 -289.786025) (xy 94.23378 -289.792159) (xy 94.182928 -289.79011)
			(xy 94.133064 -289.77993) (xy 94.085478 -289.761883) (xy 94.041404 -289.736437) (xy 94.001982 -289.70425)
			(xy 93.968234 -289.666156) (xy 93.941033 -289.623142) (xy 93.921085 -289.576322) (xy 93.908906 -289.526908)
			(xy 93.904811 -289.47618) (xy 93.5863 -289.47618) (xy 93.585805 -289.500787) (xy 93.57791 -289.549364)
			(xy 93.562326 -289.596045) (xy 93.539455 -289.639622) (xy 93.50989 -289.678966) (xy 93.474397 -289.713058)
			(xy 93.433894 -289.741014) (xy 93.389432 -289.762112) (xy 93.342161 -289.775804) (xy 93.293306 -289.781736)
			(xy 93.244131 -289.779755) (xy 93.195912 -289.769911) (xy 93.149896 -289.752459) (xy 93.107275 -289.727852)
			(xy 93.069154 -289.696727) (xy 93.036519 -289.65989) (xy 93.010216 -289.618294) (xy 92.990925 -289.573018)
			(xy 92.979148 -289.525234) (xy 92.975188 -289.47618) (xy 92.65666 -289.47618) (xy 92.656148 -289.501626)
			(xy 92.647984 -289.55186) (xy 92.631868 -289.600134) (xy 92.608217 -289.645197) (xy 92.577644 -289.685883)
			(xy 92.54094 -289.721138) (xy 92.499056 -289.750048) (xy 92.453077 -289.771865) (xy 92.404193 -289.786025)
			(xy 92.353672 -289.792159) (xy 92.30282 -289.79011) (xy 92.252956 -289.77993) (xy 92.20537 -289.761883)
			(xy 92.161296 -289.736437) (xy 92.121874 -289.70425) (xy 92.088126 -289.666156) (xy 92.060925 -289.623142)
			(xy 92.040977 -289.576322) (xy 92.028798 -289.526908) (xy 92.024703 -289.47618) (xy 91.71686 -289.47618)
			(xy 91.716348 -289.501626) (xy 91.708184 -289.55186) (xy 91.692068 -289.600134) (xy 91.668417 -289.645197)
			(xy 91.637844 -289.685883) (xy 91.60114 -289.721138) (xy 91.559256 -289.750048) (xy 91.513277 -289.771865)
			(xy 91.464393 -289.786025) (xy 91.413872 -289.792159) (xy 91.36302 -289.79011) (xy 91.313156 -289.77993)
			(xy 91.26557 -289.761883) (xy 91.221496 -289.736437) (xy 91.182074 -289.70425) (xy 91.148326 -289.666156)
			(xy 91.121125 -289.623142) (xy 91.101177 -289.576322) (xy 91.088998 -289.526908) (xy 91.084903 -289.47618)
			(xy 90.766978 -289.47618) (xy 90.76698 -289.4762) (xy 90.762808 -289.526548) (xy 90.750405 -289.575522)
			(xy 90.730111 -289.621787) (xy 90.702478 -289.664081) (xy 90.668261 -289.701249) (xy 90.628392 -289.732278)
			(xy 90.58396 -289.756321) (xy 90.536176 -289.772723) (xy 90.486344 -289.781037) (xy 90.461084 -289.781488)
			(xy 90.448321 -289.78135) (xy 90.422887 -289.77919) (xy 90.410284 -289.77717) (xy 90.410284 -289.777424)
			(xy 90.386832 -289.772995) (xy 90.341581 -289.757829) (xy 90.299233 -289.735823) (xy 90.260814 -289.707509)
			(xy 90.227258 -289.673573) (xy 90.212926 -289.654488) (xy 90.208862 -289.648646) (xy 90.198194 -289.64001)
			(xy 90.192352 -289.63747) (xy 90.186069 -289.63495) (xy 90.172675 -289.633017) (xy 90.165936 -289.63366)
			(xy 90.075512 -289.64509) (xy 90.063066 -289.646614) (xy 90.05189 -289.65525) (xy 90.04676 -289.659593)
			(xy 90.038777 -289.670403) (xy 90.036142 -289.676586) (xy 90.036142 -289.67684) (xy 90.028244 -289.696619)
			(xy 90.009808 -289.735016) (xy 89.999312 -289.753548) (xy 89.9541 -289.831526) (xy 89.948357 -289.842766)
			(xy 89.947536 -289.867962) (xy 89.952576 -289.879532) (xy 89.981024 -289.936936) (xy 89.989914 -289.955224)
			(xy 89.992916 -289.960858) (xy 90.001274 -289.970502) (xy 90.006424 -289.974274) (xy 90.01633 -289.981386)
			(xy 90.02649 -289.98291) (xy 90.029284 -289.983164) (xy 90.053549 -289.98675) (xy 90.100586 -290.000646)
			(xy 90.144802 -290.021873) (xy 90.185061 -290.049888) (xy 90.22033 -290.083972) (xy 90.249704 -290.123251)
			(xy 90.27243 -290.166715) (xy 90.287924 -290.21325) (xy 90.29579 -290.261663) (xy 90.296238 -290.286186)
			(xy 90.614749 -290.286186) (xy 90.618844 -290.235458) (xy 90.631023 -290.186044) (xy 90.650971 -290.139224)
			(xy 90.678172 -290.09621) (xy 90.71192 -290.058116) (xy 90.751342 -290.025929) (xy 90.795416 -290.000483)
			(xy 90.843002 -289.982436) (xy 90.892866 -289.972256) (xy 90.943718 -289.970207) (xy 90.994239 -289.976341)
			(xy 91.043123 -289.990501) (xy 91.089102 -290.012318) (xy 91.130986 -290.041228) (xy 91.16769 -290.076483)
			(xy 91.198263 -290.117169) (xy 91.221914 -290.162232) (xy 91.23803 -290.210506) (xy 91.246194 -290.26074)
			(xy 91.246706 -290.286186) (xy 91.565234 -290.286186) (xy 91.569194 -290.237132) (xy 91.580971 -290.189348)
			(xy 91.600262 -290.144072) (xy 91.626565 -290.102476) (xy 91.6592 -290.065639) (xy 91.697321 -290.034514)
			(xy 91.739942 -290.009907) (xy 91.785958 -289.992455) (xy 91.834177 -289.982611) (xy 91.883352 -289.98063)
			(xy 91.932207 -289.986562) (xy 91.979478 -290.000254) (xy 92.02394 -290.021352) (xy 92.064443 -290.049308)
			(xy 92.099936 -290.0834) (xy 92.129501 -290.122744) (xy 92.152372 -290.166321) (xy 92.167956 -290.213002)
			(xy 92.175851 -290.261579) (xy 92.176346 -290.286186) (xy 92.494857 -290.286186) (xy 92.498952 -290.235458)
			(xy 92.511131 -290.186044) (xy 92.531079 -290.139224) (xy 92.55828 -290.09621) (xy 92.592028 -290.058116)
			(xy 92.63145 -290.025929) (xy 92.675524 -290.000483) (xy 92.72311 -289.982436) (xy 92.772974 -289.972256)
			(xy 92.823826 -289.970207) (xy 92.874347 -289.976341) (xy 92.923231 -289.990501) (xy 92.96921 -290.012318)
			(xy 93.011094 -290.041228) (xy 93.047798 -290.076483) (xy 93.078371 -290.117169) (xy 93.102022 -290.162232)
			(xy 93.118138 -290.210506) (xy 93.126302 -290.26074) (xy 93.126814 -290.286186) (xy 94.374711 -290.286186)
			(xy 94.378806 -290.235458) (xy 94.390985 -290.186044) (xy 94.410933 -290.139224) (xy 94.438134 -290.09621)
			(xy 94.471882 -290.058116) (xy 94.511304 -290.025929) (xy 94.555378 -290.000483) (xy 94.602964 -289.982436)
			(xy 94.652828 -289.972256) (xy 94.70368 -289.970207) (xy 94.754201 -289.976341) (xy 94.803085 -289.990501)
			(xy 94.849064 -290.012318) (xy 94.890948 -290.041228) (xy 94.927652 -290.076483) (xy 94.958225 -290.117169)
			(xy 94.981876 -290.162232) (xy 94.997992 -290.210506) (xy 95.006156 -290.26074) (xy 95.006668 -290.286186)
			(xy 95.314765 -290.286186) (xy 95.31886 -290.235458) (xy 95.331039 -290.186044) (xy 95.350987 -290.139224)
			(xy 95.378188 -290.09621) (xy 95.411936 -290.058116) (xy 95.451358 -290.025929) (xy 95.495432 -290.000483)
			(xy 95.543018 -289.982436) (xy 95.592882 -289.972256) (xy 95.643734 -289.970207) (xy 95.694255 -289.976341)
			(xy 95.743139 -289.990501) (xy 95.789118 -290.012318) (xy 95.831002 -290.041228) (xy 95.867706 -290.076483)
			(xy 95.898279 -290.117169) (xy 95.92193 -290.162232) (xy 95.938046 -290.210506) (xy 95.94621 -290.26074)
			(xy 95.946722 -290.286186) (xy 95.94621 -290.311632) (xy 95.938046 -290.361866) (xy 95.92193 -290.41014)
			(xy 95.898279 -290.455203) (xy 95.867706 -290.495889) (xy 95.831002 -290.531144) (xy 95.789118 -290.560054)
			(xy 95.743139 -290.581871) (xy 95.694255 -290.596031) (xy 95.643734 -290.602165) (xy 95.592882 -290.600116)
			(xy 95.543018 -290.589936) (xy 95.495432 -290.571889) (xy 95.451358 -290.546443) (xy 95.411936 -290.514256)
			(xy 95.378188 -290.476162) (xy 95.350987 -290.433148) (xy 95.331039 -290.386328) (xy 95.31886 -290.336914)
			(xy 95.314765 -290.286186) (xy 95.006668 -290.286186) (xy 95.006156 -290.311632) (xy 94.997992 -290.361866)
			(xy 94.981876 -290.41014) (xy 94.958225 -290.455203) (xy 94.927652 -290.495889) (xy 94.890948 -290.531144)
			(xy 94.849064 -290.560054) (xy 94.803085 -290.581871) (xy 94.754201 -290.596031) (xy 94.70368 -290.602165)
			(xy 94.652828 -290.600116) (xy 94.602964 -290.589936) (xy 94.555378 -290.571889) (xy 94.511304 -290.546443)
			(xy 94.471882 -290.514256) (xy 94.438134 -290.476162) (xy 94.410933 -290.433148) (xy 94.390985 -290.386328)
			(xy 94.378806 -290.336914) (xy 94.374711 -290.286186) (xy 93.126814 -290.286186) (xy 93.126302 -290.311632)
			(xy 93.118138 -290.361866) (xy 93.102022 -290.41014) (xy 93.078371 -290.455203) (xy 93.047798 -290.495889)
			(xy 93.011094 -290.531144) (xy 92.96921 -290.560054) (xy 92.923231 -290.581871) (xy 92.874347 -290.596031)
			(xy 92.823826 -290.602165) (xy 92.772974 -290.600116) (xy 92.72311 -290.589936) (xy 92.675524 -290.571889)
			(xy 92.63145 -290.546443) (xy 92.592028 -290.514256) (xy 92.55828 -290.476162) (xy 92.531079 -290.433148)
			(xy 92.511131 -290.386328) (xy 92.498952 -290.336914) (xy 92.494857 -290.286186) (xy 92.176346 -290.286186)
			(xy 92.175851 -290.310793) (xy 92.167956 -290.35937) (xy 92.152372 -290.406051) (xy 92.129501 -290.449628)
			(xy 92.099936 -290.488972) (xy 92.064443 -290.523064) (xy 92.02394 -290.55102) (xy 91.979478 -290.572118)
			(xy 91.932207 -290.58581) (xy 91.883352 -290.591742) (xy 91.834177 -290.589761) (xy 91.785958 -290.579917)
			(xy 91.739942 -290.562465) (xy 91.697321 -290.537858) (xy 91.6592 -290.506733) (xy 91.626565 -290.469896)
			(xy 91.600262 -290.4283) (xy 91.580971 -290.383024) (xy 91.569194 -290.33524) (xy 91.565234 -290.286186)
			(xy 91.246706 -290.286186) (xy 91.246194 -290.311632) (xy 91.23803 -290.361866) (xy 91.221914 -290.41014)
			(xy 91.198263 -290.455203) (xy 91.16769 -290.495889) (xy 91.130986 -290.531144) (xy 91.089102 -290.560054)
			(xy 91.043123 -290.581871) (xy 90.994239 -290.596031) (xy 90.943718 -290.602165) (xy 90.892866 -290.600116)
			(xy 90.843002 -290.589936) (xy 90.795416 -290.571889) (xy 90.751342 -290.546443) (xy 90.71192 -290.514256)
			(xy 90.678172 -290.476162) (xy 90.650971 -290.433148) (xy 90.631023 -290.386328) (xy 90.618844 -290.336914)
			(xy 90.614749 -290.286186) (xy 90.296238 -290.286186) (xy 90.295765 -290.310869) (xy 90.287829 -290.359592)
			(xy 90.272159 -290.406405) (xy 90.249166 -290.450089) (xy 90.219446 -290.489506) (xy 90.183774 -290.523631)
			(xy 90.143079 -290.551574) (xy 90.098419 -290.57261) (xy 90.050958 -290.586189) (xy 90.02649 -290.589462)
			(xy 90.019632 -290.590224) (xy 90.007186 -290.59505) (xy 90.001852 -290.599114) (xy 89.996629 -290.603382)
			(xy 89.988399 -290.614061) (xy 89.985596 -290.620196) (xy 89.95156 -290.702492) (xy 89.949134 -290.708731)
			(xy 89.94734 -290.721992) (xy 89.948004 -290.728654) (xy 89.949782 -290.741862) (xy 89.958418 -290.752784)
			(xy 89.958418 -290.753292) (xy 89.982778 -290.785469) (xy 90.022943 -290.855469) (xy 90.038428 -290.892738)
			(xy 90.038428 -290.892992) (xy 90.041124 -290.899191) (xy 90.049238 -290.909998) (xy 90.05443 -290.914328)
			(xy 90.05951 -290.918392) (xy 90.07221 -290.923726) (xy 90.167714 -290.935918) (xy 90.176845 -290.936723)
			(xy 90.194681 -290.932554) (xy 90.202512 -290.92779) (xy 90.206058 -290.925294) (xy 90.212318 -290.919293)
			(xy 90.214958 -290.915852) (xy 90.214958 -290.915598) (xy 90.229452 -290.896626) (xy 90.263341 -290.863)
			(xy 90.302049 -290.835057) (xy 90.344634 -290.813476) (xy 90.390057 -290.798784) (xy 90.437214 -290.791338)
			(xy 90.461084 -290.790884) (xy 90.486343 -290.791375) (xy 90.536173 -290.799688) (xy 90.583955 -290.816089)
			(xy 90.628385 -290.840132) (xy 90.668253 -290.87116) (xy 90.702469 -290.908327) (xy 90.7301 -290.950618)
			(xy 90.750394 -290.996882) (xy 90.762796 -291.045854) (xy 90.766967 -291.096192) (xy 91.084903 -291.096192)
			(xy 91.088998 -291.045464) (xy 91.101177 -290.99605) (xy 91.121125 -290.94923) (xy 91.148326 -290.906216)
			(xy 91.182074 -290.868122) (xy 91.221496 -290.835935) (xy 91.26557 -290.810489) (xy 91.313156 -290.792442)
			(xy 91.36302 -290.782262) (xy 91.413872 -290.780213) (xy 91.464393 -290.786347) (xy 91.513277 -290.800507)
			(xy 91.559256 -290.822324) (xy 91.60114 -290.851234) (xy 91.637844 -290.886489) (xy 91.668417 -290.927175)
			(xy 91.692068 -290.972238) (xy 91.708184 -291.020512) (xy 91.716348 -291.070746) (xy 91.71686 -291.096192)
			(xy 92.024703 -291.096192) (xy 92.028798 -291.045464) (xy 92.040977 -290.99605) (xy 92.060925 -290.94923)
			(xy 92.088126 -290.906216) (xy 92.121874 -290.868122) (xy 92.161296 -290.835935) (xy 92.20537 -290.810489)
			(xy 92.252956 -290.792442) (xy 92.30282 -290.782262) (xy 92.353672 -290.780213) (xy 92.404193 -290.786347)
			(xy 92.453077 -290.800507) (xy 92.499056 -290.822324) (xy 92.54094 -290.851234) (xy 92.577644 -290.886489)
			(xy 92.608217 -290.927175) (xy 92.631868 -290.972238) (xy 92.647984 -291.020512) (xy 92.656148 -291.070746)
			(xy 92.65666 -291.096192) (xy 92.975188 -291.096192) (xy 92.979148 -291.047138) (xy 92.990925 -290.999354)
			(xy 93.010216 -290.954078) (xy 93.036519 -290.912482) (xy 93.069154 -290.875645) (xy 93.107275 -290.84452)
			(xy 93.149896 -290.819913) (xy 93.195912 -290.802461) (xy 93.244131 -290.792617) (xy 93.293306 -290.790636)
			(xy 93.342161 -290.796568) (xy 93.389432 -290.81026) (xy 93.433894 -290.831358) (xy 93.474397 -290.859314)
			(xy 93.50989 -290.893406) (xy 93.539455 -290.93275) (xy 93.562326 -290.976327) (xy 93.57791 -291.023008)
			(xy 93.585805 -291.071585) (xy 93.5863 -291.096192) (xy 93.904811 -291.096192) (xy 93.908906 -291.045464)
			(xy 93.921085 -290.99605) (xy 93.941033 -290.94923) (xy 93.968234 -290.906216) (xy 94.001982 -290.868122)
			(xy 94.041404 -290.835935) (xy 94.085478 -290.810489) (xy 94.133064 -290.792442) (xy 94.182928 -290.782262)
			(xy 94.23378 -290.780213) (xy 94.284301 -290.786347) (xy 94.333185 -290.800507) (xy 94.379164 -290.822324)
			(xy 94.421048 -290.851234) (xy 94.457752 -290.886489) (xy 94.488325 -290.927175) (xy 94.511976 -290.972238)
			(xy 94.528092 -291.020512) (xy 94.536256 -291.070746) (xy 94.536768 -291.096192) (xy 94.855296 -291.096192)
			(xy 94.859256 -291.047138) (xy 94.871033 -290.999354) (xy 94.890324 -290.954078) (xy 94.916627 -290.912482)
			(xy 94.949262 -290.875645) (xy 94.987383 -290.84452) (xy 95.030004 -290.819913) (xy 95.07602 -290.802461)
			(xy 95.124239 -290.792617) (xy 95.173414 -290.790636) (xy 95.222269 -290.796568) (xy 95.26954 -290.81026)
			(xy 95.314002 -290.831358) (xy 95.354505 -290.859314) (xy 95.389998 -290.893406) (xy 95.419563 -290.93275)
			(xy 95.442434 -290.976327) (xy 95.458018 -291.023008) (xy 95.465913 -291.071585) (xy 95.466408 -291.096192)
			(xy 95.784919 -291.096192) (xy 95.789014 -291.045464) (xy 95.801193 -290.99605) (xy 95.821141 -290.94923)
			(xy 95.848342 -290.906216) (xy 95.88209 -290.868122) (xy 95.921512 -290.835935) (xy 95.965586 -290.810489)
			(xy 96.013172 -290.792442) (xy 96.063036 -290.782262) (xy 96.113888 -290.780213) (xy 96.164409 -290.786347)
			(xy 96.213293 -290.800507) (xy 96.259272 -290.822324) (xy 96.301156 -290.851234) (xy 96.33786 -290.886489)
			(xy 96.368433 -290.927175) (xy 96.392084 -290.972238) (xy 96.4082 -291.020512) (xy 96.416364 -291.070746)
			(xy 96.416876 -291.096192) (xy 96.416364 -291.121638) (xy 96.4082 -291.171872) (xy 96.392084 -291.220146)
			(xy 96.368433 -291.265209) (xy 96.33786 -291.305895) (xy 96.301156 -291.34115) (xy 96.259272 -291.37006)
			(xy 96.213293 -291.391877) (xy 96.164409 -291.406037) (xy 96.113888 -291.412171) (xy 96.063036 -291.410122)
			(xy 96.013172 -291.399942) (xy 95.965586 -291.381895) (xy 95.921512 -291.356449) (xy 95.88209 -291.324262)
			(xy 95.848342 -291.286168) (xy 95.821141 -291.243154) (xy 95.801193 -291.196334) (xy 95.789014 -291.14692)
			(xy 95.784919 -291.096192) (xy 95.466408 -291.096192) (xy 95.465913 -291.120799) (xy 95.458018 -291.169376)
			(xy 95.442434 -291.216057) (xy 95.419563 -291.259634) (xy 95.389998 -291.298978) (xy 95.354505 -291.33307)
			(xy 95.314002 -291.361026) (xy 95.26954 -291.382124) (xy 95.222269 -291.395816) (xy 95.173414 -291.401748)
			(xy 95.124239 -291.399767) (xy 95.07602 -291.389923) (xy 95.030004 -291.372471) (xy 94.987383 -291.347864)
			(xy 94.949262 -291.316739) (xy 94.916627 -291.279902) (xy 94.890324 -291.238306) (xy 94.871033 -291.19303)
			(xy 94.859256 -291.145246) (xy 94.855296 -291.096192) (xy 94.536768 -291.096192) (xy 94.536256 -291.121638)
			(xy 94.528092 -291.171872) (xy 94.511976 -291.220146) (xy 94.488325 -291.265209) (xy 94.457752 -291.305895)
			(xy 94.421048 -291.34115) (xy 94.379164 -291.37006) (xy 94.333185 -291.391877) (xy 94.284301 -291.406037)
			(xy 94.23378 -291.412171) (xy 94.182928 -291.410122) (xy 94.133064 -291.399942) (xy 94.085478 -291.381895)
			(xy 94.041404 -291.356449) (xy 94.001982 -291.324262) (xy 93.968234 -291.286168) (xy 93.941033 -291.243154)
			(xy 93.921085 -291.196334) (xy 93.908906 -291.14692) (xy 93.904811 -291.096192) (xy 93.5863 -291.096192)
			(xy 93.585805 -291.120799) (xy 93.57791 -291.169376) (xy 93.562326 -291.216057) (xy 93.539455 -291.259634)
			(xy 93.50989 -291.298978) (xy 93.474397 -291.33307) (xy 93.433894 -291.361026) (xy 93.389432 -291.382124)
			(xy 93.342161 -291.395816) (xy 93.293306 -291.401748) (xy 93.244131 -291.399767) (xy 93.195912 -291.389923)
			(xy 93.149896 -291.372471) (xy 93.107275 -291.347864) (xy 93.069154 -291.316739) (xy 93.036519 -291.279902)
			(xy 93.010216 -291.238306) (xy 92.990925 -291.19303) (xy 92.979148 -291.145246) (xy 92.975188 -291.096192)
			(xy 92.65666 -291.096192) (xy 92.656148 -291.121638) (xy 92.647984 -291.171872) (xy 92.631868 -291.220146)
			(xy 92.608217 -291.265209) (xy 92.577644 -291.305895) (xy 92.54094 -291.34115) (xy 92.499056 -291.37006)
			(xy 92.453077 -291.391877) (xy 92.404193 -291.406037) (xy 92.353672 -291.412171) (xy 92.30282 -291.410122)
			(xy 92.252956 -291.399942) (xy 92.20537 -291.381895) (xy 92.161296 -291.356449) (xy 92.121874 -291.324262)
			(xy 92.088126 -291.286168) (xy 92.060925 -291.243154) (xy 92.040977 -291.196334) (xy 92.028798 -291.14692)
			(xy 92.024703 -291.096192) (xy 91.71686 -291.096192) (xy 91.716348 -291.121638) (xy 91.708184 -291.171872)
			(xy 91.692068 -291.220146) (xy 91.668417 -291.265209) (xy 91.637844 -291.305895) (xy 91.60114 -291.34115)
			(xy 91.559256 -291.37006) (xy 91.513277 -291.391877) (xy 91.464393 -291.406037) (xy 91.413872 -291.412171)
			(xy 91.36302 -291.410122) (xy 91.313156 -291.399942) (xy 91.26557 -291.381895) (xy 91.221496 -291.356449)
			(xy 91.182074 -291.324262) (xy 91.148326 -291.286168) (xy 91.121125 -291.243154) (xy 91.101177 -291.196334)
			(xy 91.088998 -291.14692) (xy 91.084903 -291.096192) (xy 90.766967 -291.096192) (xy 90.766968 -291.0962)
			(xy 90.762796 -291.146546) (xy 90.750394 -291.195518) (xy 90.7301 -291.241782) (xy 90.702469 -291.284073)
			(xy 90.668253 -291.32124) (xy 90.628385 -291.352268) (xy 90.583955 -291.376311) (xy 90.536173 -291.392712)
			(xy 90.486343 -291.401025) (xy 90.461084 -291.4015) (xy 90.43721 -291.401045) (xy 90.390044 -291.393622)
			(xy 90.344608 -291.378945) (xy 90.302013 -291.357372) (xy 90.263297 -291.329428) (xy 90.229405 -291.295797)
			(xy 90.214958 -291.276786) (xy 90.214958 -291.276532) (xy 90.212306 -291.273102) (xy 90.206048 -291.267102)
			(xy 90.202512 -291.264594) (xy 90.194683 -291.259825) (xy 90.176845 -291.255657) (xy 90.167714 -291.256466)
			(xy 90.079068 -291.267896) (xy 90.072308 -291.268971) (xy 90.059684 -291.274247) (xy 90.054176 -291.27831)
			(xy 90.048842 -291.282374) (xy 90.040968 -291.293042) (xy 90.038428 -291.299646) (xy 90.02522 -291.330634)
			(xy 90.019887 -291.341973) (xy 90.008327 -291.364207) (xy 90.002106 -291.375084) (xy 89.957656 -291.452046)
			(xy 89.951881 -291.463196) (xy 89.950938 -291.488256) (xy 89.955878 -291.499798) (xy 89.992708 -291.575236)
			(xy 89.995658 -291.581011) (xy 90.004019 -291.590918) (xy 90.009218 -291.594794) (xy 90.019632 -291.601906)
			(xy 90.024458 -291.602668) (xy 90.049054 -291.605867) (xy 90.096824 -291.6192) (xy 90.14181 -291.640081)
			(xy 90.18283 -291.667959) (xy 90.218803 -291.702101) (xy 90.248784 -291.741609) (xy 90.271984 -291.785444)
			(xy 90.287793 -291.832453) (xy 90.295795 -291.8814) (xy 90.296238 -291.906198) (xy 90.614749 -291.906198)
			(xy 90.618844 -291.85547) (xy 90.631023 -291.806056) (xy 90.650971 -291.759236) (xy 90.678172 -291.716222)
			(xy 90.71192 -291.678128) (xy 90.751342 -291.645941) (xy 90.795416 -291.620495) (xy 90.843002 -291.602448)
			(xy 90.892866 -291.592268) (xy 90.943718 -291.590219) (xy 90.994239 -291.596353) (xy 91.043123 -291.610513)
			(xy 91.089102 -291.63233) (xy 91.130986 -291.66124) (xy 91.16769 -291.696495) (xy 91.198263 -291.737181)
			(xy 91.221914 -291.782244) (xy 91.23803 -291.830518) (xy 91.246194 -291.880752) (xy 91.246706 -291.906198)
			(xy 91.565234 -291.906198) (xy 91.569194 -291.857144) (xy 91.580971 -291.80936) (xy 91.600262 -291.764084)
			(xy 91.626565 -291.722488) (xy 91.6592 -291.685651) (xy 91.697321 -291.654526) (xy 91.739942 -291.629919)
			(xy 91.785958 -291.612467) (xy 91.834177 -291.602623) (xy 91.883352 -291.600642) (xy 91.932207 -291.606574)
			(xy 91.979478 -291.620266) (xy 92.02394 -291.641364) (xy 92.064443 -291.66932) (xy 92.099936 -291.703412)
			(xy 92.129501 -291.742756) (xy 92.152372 -291.786333) (xy 92.167956 -291.833014) (xy 92.175851 -291.881591)
			(xy 92.176346 -291.906198) (xy 92.494857 -291.906198) (xy 92.498952 -291.85547) (xy 92.511131 -291.806056)
			(xy 92.531079 -291.759236) (xy 92.55828 -291.716222) (xy 92.592028 -291.678128) (xy 92.63145 -291.645941)
			(xy 92.675524 -291.620495) (xy 92.72311 -291.602448) (xy 92.772974 -291.592268) (xy 92.823826 -291.590219)
			(xy 92.874347 -291.596353) (xy 92.923231 -291.610513) (xy 92.96921 -291.63233) (xy 93.011094 -291.66124)
			(xy 93.047798 -291.696495) (xy 93.078371 -291.737181) (xy 93.102022 -291.782244) (xy 93.118138 -291.830518)
			(xy 93.126302 -291.880752) (xy 93.126814 -291.906198) (xy 93.445342 -291.906198) (xy 93.449302 -291.857144)
			(xy 93.461079 -291.80936) (xy 93.48037 -291.764084) (xy 93.506673 -291.722488) (xy 93.539308 -291.685651)
			(xy 93.577429 -291.654526) (xy 93.62005 -291.629919) (xy 93.666066 -291.612467) (xy 93.714285 -291.602623)
			(xy 93.76346 -291.600642) (xy 93.812315 -291.606574) (xy 93.859586 -291.620266) (xy 93.904048 -291.641364)
			(xy 93.944551 -291.66932) (xy 93.980044 -291.703412) (xy 94.009609 -291.742756) (xy 94.03248 -291.786333)
			(xy 94.048064 -291.833014) (xy 94.055959 -291.881591) (xy 94.056454 -291.906198) (xy 94.374711 -291.906198)
			(xy 94.378806 -291.85547) (xy 94.390985 -291.806056) (xy 94.410933 -291.759236) (xy 94.438134 -291.716222)
			(xy 94.471882 -291.678128) (xy 94.511304 -291.645941) (xy 94.555378 -291.620495) (xy 94.602964 -291.602448)
			(xy 94.652828 -291.592268) (xy 94.70368 -291.590219) (xy 94.754201 -291.596353) (xy 94.803085 -291.610513)
			(xy 94.849064 -291.63233) (xy 94.890948 -291.66124) (xy 94.927652 -291.696495) (xy 94.958225 -291.737181)
			(xy 94.981876 -291.782244) (xy 94.997992 -291.830518) (xy 95.006156 -291.880752) (xy 95.006668 -291.906198)
			(xy 95.314765 -291.906198) (xy 95.31886 -291.85547) (xy 95.331039 -291.806056) (xy 95.350987 -291.759236)
			(xy 95.378188 -291.716222) (xy 95.411936 -291.678128) (xy 95.451358 -291.645941) (xy 95.495432 -291.620495)
			(xy 95.543018 -291.602448) (xy 95.592882 -291.592268) (xy 95.643734 -291.590219) (xy 95.694255 -291.596353)
			(xy 95.743139 -291.610513) (xy 95.789118 -291.63233) (xy 95.831002 -291.66124) (xy 95.867706 -291.696495)
			(xy 95.898279 -291.737181) (xy 95.92193 -291.782244) (xy 95.938046 -291.830518) (xy 95.94621 -291.880752)
			(xy 95.946722 -291.906198) (xy 95.94621 -291.931644) (xy 95.938046 -291.981878) (xy 95.92193 -292.030152)
			(xy 95.898279 -292.075215) (xy 95.867706 -292.115901) (xy 95.831002 -292.151156) (xy 95.789118 -292.180066)
			(xy 95.743139 -292.201883) (xy 95.694255 -292.216043) (xy 95.643734 -292.222177) (xy 95.592882 -292.220128)
			(xy 95.543018 -292.209948) (xy 95.495432 -292.191901) (xy 95.451358 -292.166455) (xy 95.411936 -292.134268)
			(xy 95.378188 -292.096174) (xy 95.350987 -292.05316) (xy 95.331039 -292.00634) (xy 95.31886 -291.956926)
			(xy 95.314765 -291.906198) (xy 95.006668 -291.906198) (xy 95.006156 -291.931644) (xy 94.997992 -291.981878)
			(xy 94.981876 -292.030152) (xy 94.958225 -292.075215) (xy 94.927652 -292.115901) (xy 94.890948 -292.151156)
			(xy 94.849064 -292.180066) (xy 94.803085 -292.201883) (xy 94.754201 -292.216043) (xy 94.70368 -292.222177)
			(xy 94.652828 -292.220128) (xy 94.602964 -292.209948) (xy 94.555378 -292.191901) (xy 94.511304 -292.166455)
			(xy 94.471882 -292.134268) (xy 94.438134 -292.096174) (xy 94.410933 -292.05316) (xy 94.390985 -292.00634)
			(xy 94.378806 -291.956926) (xy 94.374711 -291.906198) (xy 94.056454 -291.906198) (xy 94.055959 -291.930805)
			(xy 94.048064 -291.979382) (xy 94.03248 -292.026063) (xy 94.009609 -292.06964) (xy 93.980044 -292.108984)
			(xy 93.944551 -292.143076) (xy 93.904048 -292.171032) (xy 93.859586 -292.19213) (xy 93.812315 -292.205822)
			(xy 93.76346 -292.211754) (xy 93.714285 -292.209773) (xy 93.666066 -292.199929) (xy 93.62005 -292.182477)
			(xy 93.577429 -292.15787) (xy 93.539308 -292.126745) (xy 93.506673 -292.089908) (xy 93.48037 -292.048312)
			(xy 93.461079 -292.003036) (xy 93.449302 -291.955252) (xy 93.445342 -291.906198) (xy 93.126814 -291.906198)
			(xy 93.126302 -291.931644) (xy 93.118138 -291.981878) (xy 93.102022 -292.030152) (xy 93.078371 -292.075215)
			(xy 93.047798 -292.115901) (xy 93.011094 -292.151156) (xy 92.96921 -292.180066) (xy 92.923231 -292.201883)
			(xy 92.874347 -292.216043) (xy 92.823826 -292.222177) (xy 92.772974 -292.220128) (xy 92.72311 -292.209948)
			(xy 92.675524 -292.191901) (xy 92.63145 -292.166455) (xy 92.592028 -292.134268) (xy 92.55828 -292.096174)
			(xy 92.531079 -292.05316) (xy 92.511131 -292.00634) (xy 92.498952 -291.956926) (xy 92.494857 -291.906198)
			(xy 92.176346 -291.906198) (xy 92.175851 -291.930805) (xy 92.167956 -291.979382) (xy 92.152372 -292.026063)
			(xy 92.129501 -292.06964) (xy 92.099936 -292.108984) (xy 92.064443 -292.143076) (xy 92.02394 -292.171032)
			(xy 91.979478 -292.19213) (xy 91.932207 -292.205822) (xy 91.883352 -292.211754) (xy 91.834177 -292.209773)
			(xy 91.785958 -292.199929) (xy 91.739942 -292.182477) (xy 91.697321 -292.15787) (xy 91.6592 -292.126745)
			(xy 91.626565 -292.089908) (xy 91.600262 -292.048312) (xy 91.580971 -292.003036) (xy 91.569194 -291.955252)
			(xy 91.565234 -291.906198) (xy 91.246706 -291.906198) (xy 91.246194 -291.931644) (xy 91.23803 -291.981878)
			(xy 91.221914 -292.030152) (xy 91.198263 -292.075215) (xy 91.16769 -292.115901) (xy 91.130986 -292.151156)
			(xy 91.089102 -292.180066) (xy 91.043123 -292.201883) (xy 90.994239 -292.216043) (xy 90.943718 -292.222177)
			(xy 90.892866 -292.220128) (xy 90.843002 -292.209948) (xy 90.795416 -292.191901) (xy 90.751342 -292.166455)
			(xy 90.71192 -292.134268) (xy 90.678172 -292.096174) (xy 90.650971 -292.05316) (xy 90.631023 -292.00634)
			(xy 90.618844 -291.956926) (xy 90.614749 -291.906198) (xy 90.296238 -291.906198) (xy 90.295752 -291.931019)
			(xy 90.287722 -291.980008) (xy 90.271873 -292.027052) (xy 90.248622 -292.070913) (xy 90.218582 -292.110435)
			(xy 90.182544 -292.144577) (xy 90.141458 -292.172439) (xy 90.096406 -292.193288) (xy 90.048575 -292.206574)
			(xy 90.02395 -292.209728) (xy 90.023696 -292.209728) (xy 90.016991 -292.210648) (xy 90.004376 -292.215538)
			(xy 89.998804 -292.21938) (xy 89.993724 -292.223444) (xy 89.985342 -292.233858) (xy 89.948004 -292.322504)
			(xy 89.945535 -292.328932) (xy 89.943741 -292.342578) (xy 89.944448 -292.349428) (xy 89.946226 -292.362636)
			(xy 89.954862 -292.373558) (xy 89.979727 -292.406256) (xy 90.020531 -292.477547) (xy 90.036142 -292.515544)
			(xy 90.036142 -292.515798) (xy 90.038772 -292.521985) (xy 90.046753 -292.532798) (xy 90.05189 -292.537134)
			(xy 90.063066 -292.54577) (xy 90.075512 -292.547294) (xy 90.165682 -292.558724) (xy 90.172562 -292.559326)
			(xy 90.186214 -292.557274) (xy 90.192606 -292.55466) (xy 90.198448 -292.55212) (xy 90.208862 -292.543738)
			(xy 90.21318 -292.537896) (xy 90.227645 -292.518597) (xy 90.261633 -292.48438) (xy 90.300573 -292.455924)
			(xy 90.343497 -292.433935) (xy 90.389342 -292.41896) (xy 90.43697 -292.411369) (xy 90.461084 -292.410896)
			(xy 90.486342 -292.411387) (xy 90.53617 -292.4197) (xy 90.58395 -292.4361) (xy 90.628379 -292.460142)
			(xy 90.668244 -292.491169) (xy 90.702459 -292.528334) (xy 90.73009 -292.570624) (xy 90.750383 -292.616886)
			(xy 90.762784 -292.665856) (xy 90.766956 -292.7162) (xy 90.766956 -292.716204) (xy 91.084903 -292.716204)
			(xy 91.088998 -292.665476) (xy 91.101177 -292.616062) (xy 91.121125 -292.569242) (xy 91.148326 -292.526228)
			(xy 91.182074 -292.488134) (xy 91.221496 -292.455947) (xy 91.26557 -292.430501) (xy 91.313156 -292.412454)
			(xy 91.36302 -292.402274) (xy 91.413872 -292.400225) (xy 91.464393 -292.406359) (xy 91.513277 -292.420519)
			(xy 91.559256 -292.442336) (xy 91.60114 -292.471246) (xy 91.637844 -292.506501) (xy 91.668417 -292.547187)
			(xy 91.692068 -292.59225) (xy 91.708184 -292.640524) (xy 91.716348 -292.690758) (xy 91.71686 -292.716204)
			(xy 92.024703 -292.716204) (xy 92.028798 -292.665476) (xy 92.040977 -292.616062) (xy 92.060925 -292.569242)
			(xy 92.088126 -292.526228) (xy 92.121874 -292.488134) (xy 92.161296 -292.455947) (xy 92.20537 -292.430501)
			(xy 92.252956 -292.412454) (xy 92.30282 -292.402274) (xy 92.353672 -292.400225) (xy 92.404193 -292.406359)
			(xy 92.453077 -292.420519) (xy 92.499056 -292.442336) (xy 92.54094 -292.471246) (xy 92.577644 -292.506501)
			(xy 92.608217 -292.547187) (xy 92.631868 -292.59225) (xy 92.647984 -292.640524) (xy 92.656148 -292.690758)
			(xy 92.65666 -292.716204) (xy 93.904811 -292.716204) (xy 93.908906 -292.665476) (xy 93.921085 -292.616062)
			(xy 93.941033 -292.569242) (xy 93.968234 -292.526228) (xy 94.001982 -292.488134) (xy 94.041404 -292.455947)
			(xy 94.085478 -292.430501) (xy 94.133064 -292.412454) (xy 94.182928 -292.402274) (xy 94.23378 -292.400225)
			(xy 94.284301 -292.406359) (xy 94.333185 -292.420519) (xy 94.379164 -292.442336) (xy 94.421048 -292.471246)
			(xy 94.457752 -292.506501) (xy 94.488325 -292.547187) (xy 94.511976 -292.59225) (xy 94.528092 -292.640524)
			(xy 94.536256 -292.690758) (xy 94.536768 -292.716204) (xy 94.855296 -292.716204) (xy 94.859256 -292.66715)
			(xy 94.871033 -292.619366) (xy 94.890324 -292.57409) (xy 94.916627 -292.532494) (xy 94.949262 -292.495657)
			(xy 94.987383 -292.464532) (xy 95.030004 -292.439925) (xy 95.07602 -292.422473) (xy 95.124239 -292.412629)
			(xy 95.173414 -292.410648) (xy 95.222269 -292.41658) (xy 95.26954 -292.430272) (xy 95.314002 -292.45137)
			(xy 95.354505 -292.479326) (xy 95.389998 -292.513418) (xy 95.419563 -292.552762) (xy 95.442434 -292.596339)
			(xy 95.458018 -292.64302) (xy 95.465913 -292.691597) (xy 95.466408 -292.716204) (xy 95.784919 -292.716204)
			(xy 95.789014 -292.665476) (xy 95.801193 -292.616062) (xy 95.821141 -292.569242) (xy 95.848342 -292.526228)
			(xy 95.88209 -292.488134) (xy 95.921512 -292.455947) (xy 95.965586 -292.430501) (xy 96.013172 -292.412454)
			(xy 96.063036 -292.402274) (xy 96.113888 -292.400225) (xy 96.164409 -292.406359) (xy 96.213293 -292.420519)
			(xy 96.259272 -292.442336) (xy 96.301156 -292.471246) (xy 96.33786 -292.506501) (xy 96.368433 -292.547187)
			(xy 96.392084 -292.59225) (xy 96.4082 -292.640524) (xy 96.416364 -292.690758) (xy 96.416876 -292.716204)
			(xy 96.416364 -292.74165) (xy 96.4082 -292.791884) (xy 96.392084 -292.840158) (xy 96.368433 -292.885221)
			(xy 96.33786 -292.925907) (xy 96.301156 -292.961162) (xy 96.259272 -292.990072) (xy 96.213293 -293.011889)
			(xy 96.164409 -293.026049) (xy 96.113888 -293.032183) (xy 96.063036 -293.030134) (xy 96.013172 -293.019954)
			(xy 95.965586 -293.001907) (xy 95.921512 -292.976461) (xy 95.88209 -292.944274) (xy 95.848342 -292.90618)
			(xy 95.821141 -292.863166) (xy 95.801193 -292.816346) (xy 95.789014 -292.766932) (xy 95.784919 -292.716204)
			(xy 95.466408 -292.716204) (xy 95.465913 -292.740811) (xy 95.458018 -292.789388) (xy 95.442434 -292.836069)
			(xy 95.419563 -292.879646) (xy 95.389998 -292.91899) (xy 95.354505 -292.953082) (xy 95.314002 -292.981038)
			(xy 95.26954 -293.002136) (xy 95.222269 -293.015828) (xy 95.173414 -293.02176) (xy 95.124239 -293.019779)
			(xy 95.07602 -293.009935) (xy 95.030004 -292.992483) (xy 94.987383 -292.967876) (xy 94.949262 -292.936751)
			(xy 94.916627 -292.899914) (xy 94.890324 -292.858318) (xy 94.871033 -292.813042) (xy 94.859256 -292.765258)
			(xy 94.855296 -292.716204) (xy 94.536768 -292.716204) (xy 94.536256 -292.74165) (xy 94.528092 -292.791884)
			(xy 94.511976 -292.840158) (xy 94.488325 -292.885221) (xy 94.457752 -292.925907) (xy 94.421048 -292.961162)
			(xy 94.379164 -292.990072) (xy 94.333185 -293.011889) (xy 94.284301 -293.026049) (xy 94.23378 -293.032183)
			(xy 94.182928 -293.030134) (xy 94.133064 -293.019954) (xy 94.085478 -293.001907) (xy 94.041404 -292.976461)
			(xy 94.001982 -292.944274) (xy 93.968234 -292.90618) (xy 93.941033 -292.863166) (xy 93.921085 -292.816346)
			(xy 93.908906 -292.766932) (xy 93.904811 -292.716204) (xy 92.65666 -292.716204) (xy 92.656148 -292.74165)
			(xy 92.647984 -292.791884) (xy 92.631868 -292.840158) (xy 92.608217 -292.885221) (xy 92.577644 -292.925907)
			(xy 92.54094 -292.961162) (xy 92.499056 -292.990072) (xy 92.453077 -293.011889) (xy 92.404193 -293.026049)
			(xy 92.353672 -293.032183) (xy 92.30282 -293.030134) (xy 92.252956 -293.019954) (xy 92.20537 -293.001907)
			(xy 92.161296 -292.976461) (xy 92.121874 -292.944274) (xy 92.088126 -292.90618) (xy 92.060925 -292.863166)
			(xy 92.040977 -292.816346) (xy 92.028798 -292.766932) (xy 92.024703 -292.716204) (xy 91.71686 -292.716204)
			(xy 91.716348 -292.74165) (xy 91.708184 -292.791884) (xy 91.692068 -292.840158) (xy 91.668417 -292.885221)
			(xy 91.637844 -292.925907) (xy 91.60114 -292.961162) (xy 91.559256 -292.990072) (xy 91.513277 -293.011889)
			(xy 91.464393 -293.026049) (xy 91.413872 -293.032183) (xy 91.36302 -293.030134) (xy 91.313156 -293.019954)
			(xy 91.26557 -293.001907) (xy 91.221496 -292.976461) (xy 91.182074 -292.944274) (xy 91.148326 -292.90618)
			(xy 91.121125 -292.863166) (xy 91.101177 -292.816346) (xy 91.088998 -292.766932) (xy 91.084903 -292.716204)
			(xy 90.766956 -292.716204) (xy 90.762784 -292.766544) (xy 90.750383 -292.815514) (xy 90.73009 -292.861776)
			(xy 90.702459 -292.904066) (xy 90.668244 -292.941231) (xy 90.628379 -292.972258) (xy 90.58395 -292.9963)
			(xy 90.53617 -293.0127) (xy 90.486342 -293.021013) (xy 90.461084 -293.021512) (xy 90.448321 -293.021374)
			(xy 90.422887 -293.019214) (xy 90.410284 -293.017194) (xy 90.410284 -293.017448) (xy 90.386831 -293.013019)
			(xy 90.341579 -292.997855) (xy 90.29923 -292.975849) (xy 90.26081 -292.947536) (xy 90.227251 -292.913602)
			(xy 90.212926 -292.894512) (xy 90.208862 -292.88867) (xy 90.198194 -292.880034) (xy 90.192352 -292.877494)
			(xy 90.186069 -292.874973) (xy 90.172675 -292.873039) (xy 90.165936 -292.873684) (xy 90.075512 -292.885114)
			(xy 90.063066 -292.886638) (xy 90.05189 -292.895274) (xy 90.046762 -292.899618) (xy 90.038784 -292.91043)
			(xy 90.036142 -292.91661) (xy 90.036142 -292.916864) (xy 90.028243 -292.936643) (xy 90.009805 -292.975039)
			(xy 89.999312 -292.993572) (xy 89.9541 -293.07155) (xy 89.948363 -293.08279) (xy 89.947552 -293.107981)
			(xy 89.952576 -293.119556) (xy 89.981024 -293.17696) (xy 89.989914 -293.195248) (xy 89.992918 -293.20088)
			(xy 90.001279 -293.21052) (xy 90.006424 -293.214298) (xy 90.01633 -293.22141) (xy 90.02649 -293.222934)
			(xy 90.029284 -293.223188) (xy 90.053548 -293.226774) (xy 90.100584 -293.24067) (xy 90.144798 -293.261898)
			(xy 90.185054 -293.289914) (xy 90.220321 -293.323998) (xy 90.249692 -293.363277) (xy 90.272415 -293.406741)
			(xy 90.287906 -293.453276) (xy 90.295768 -293.501687) (xy 90.296238 -293.52621) (xy 90.614749 -293.52621)
			(xy 90.618844 -293.475482) (xy 90.631023 -293.426068) (xy 90.650971 -293.379248) (xy 90.678172 -293.336234)
			(xy 90.71192 -293.29814) (xy 90.751342 -293.265953) (xy 90.795416 -293.240507) (xy 90.843002 -293.22246)
			(xy 90.892866 -293.21228) (xy 90.943718 -293.210231) (xy 90.994239 -293.216365) (xy 91.043123 -293.230525)
			(xy 91.089102 -293.252342) (xy 91.130986 -293.281252) (xy 91.16769 -293.316507) (xy 91.198263 -293.357193)
			(xy 91.221914 -293.402256) (xy 91.23803 -293.45053) (xy 91.246194 -293.500764) (xy 91.246706 -293.52621)
			(xy 91.565234 -293.52621) (xy 91.569194 -293.477156) (xy 91.580971 -293.429372) (xy 91.600262 -293.384096)
			(xy 91.626565 -293.3425) (xy 91.6592 -293.305663) (xy 91.697321 -293.274538) (xy 91.739942 -293.249931)
			(xy 91.785958 -293.232479) (xy 91.834177 -293.222635) (xy 91.883352 -293.220654) (xy 91.932207 -293.226586)
			(xy 91.979478 -293.240278) (xy 92.02394 -293.261376) (xy 92.064443 -293.289332) (xy 92.099936 -293.323424)
			(xy 92.129501 -293.362768) (xy 92.152372 -293.406345) (xy 92.167956 -293.453026) (xy 92.175851 -293.501603)
			(xy 92.176346 -293.52621) (xy 92.505288 -293.52621) (xy 92.509248 -293.477156) (xy 92.521025 -293.429372)
			(xy 92.540316 -293.384096) (xy 92.566619 -293.3425) (xy 92.599254 -293.305663) (xy 92.637375 -293.274538)
			(xy 92.679996 -293.249931) (xy 92.726012 -293.232479) (xy 92.774231 -293.222635) (xy 92.823406 -293.220654)
			(xy 92.872261 -293.226586) (xy 92.919532 -293.240278) (xy 92.963994 -293.261376) (xy 93.004497 -293.289332)
			(xy 93.03999 -293.323424) (xy 93.069555 -293.362768) (xy 93.092426 -293.406345) (xy 93.10801 -293.453026)
			(xy 93.115905 -293.501603) (xy 93.1164 -293.52621) (xy 93.445342 -293.52621) (xy 93.449302 -293.477156)
			(xy 93.461079 -293.429372) (xy 93.48037 -293.384096) (xy 93.506673 -293.3425) (xy 93.539308 -293.305663)
			(xy 93.577429 -293.274538) (xy 93.62005 -293.249931) (xy 93.666066 -293.232479) (xy 93.714285 -293.222635)
			(xy 93.76346 -293.220654) (xy 93.812315 -293.226586) (xy 93.859586 -293.240278) (xy 93.904048 -293.261376)
			(xy 93.944551 -293.289332) (xy 93.980044 -293.323424) (xy 94.009609 -293.362768) (xy 94.03248 -293.406345)
			(xy 94.048064 -293.453026) (xy 94.055959 -293.501603) (xy 94.056454 -293.52621) (xy 94.385142 -293.52621)
			(xy 94.389102 -293.477156) (xy 94.400879 -293.429372) (xy 94.42017 -293.384096) (xy 94.446473 -293.3425)
			(xy 94.479108 -293.305663) (xy 94.517229 -293.274538) (xy 94.55985 -293.249931) (xy 94.605866 -293.232479)
			(xy 94.654085 -293.222635) (xy 94.70326 -293.220654) (xy 94.752115 -293.226586) (xy 94.799386 -293.240278)
			(xy 94.843848 -293.261376) (xy 94.884351 -293.289332) (xy 94.919844 -293.323424) (xy 94.949409 -293.362768)
			(xy 94.97228 -293.406345) (xy 94.987864 -293.453026) (xy 94.995759 -293.501603) (xy 94.996254 -293.52621)
			(xy 95.314765 -293.52621) (xy 95.31886 -293.475482) (xy 95.331039 -293.426068) (xy 95.350987 -293.379248)
			(xy 95.378188 -293.336234) (xy 95.411936 -293.29814) (xy 95.451358 -293.265953) (xy 95.495432 -293.240507)
			(xy 95.543018 -293.22246) (xy 95.592882 -293.21228) (xy 95.643734 -293.210231) (xy 95.694255 -293.216365)
			(xy 95.743139 -293.230525) (xy 95.789118 -293.252342) (xy 95.831002 -293.281252) (xy 95.867706 -293.316507)
			(xy 95.898279 -293.357193) (xy 95.92193 -293.402256) (xy 95.938046 -293.45053) (xy 95.94621 -293.500764)
			(xy 95.946722 -293.52621) (xy 95.94621 -293.551656) (xy 95.938046 -293.60189) (xy 95.92193 -293.650164)
			(xy 95.898279 -293.695227) (xy 95.867706 -293.735913) (xy 95.831002 -293.771168) (xy 95.789118 -293.800078)
			(xy 95.743139 -293.821895) (xy 95.694255 -293.836055) (xy 95.643734 -293.842189) (xy 95.592882 -293.84014)
			(xy 95.543018 -293.82996) (xy 95.495432 -293.811913) (xy 95.451358 -293.786467) (xy 95.411936 -293.75428)
			(xy 95.378188 -293.716186) (xy 95.350987 -293.673172) (xy 95.331039 -293.626352) (xy 95.31886 -293.576938)
			(xy 95.314765 -293.52621) (xy 94.996254 -293.52621) (xy 94.995759 -293.550817) (xy 94.987864 -293.599394)
			(xy 94.97228 -293.646075) (xy 94.949409 -293.689652) (xy 94.919844 -293.728996) (xy 94.884351 -293.763088)
			(xy 94.843848 -293.791044) (xy 94.799386 -293.812142) (xy 94.752115 -293.825834) (xy 94.70326 -293.831766)
			(xy 94.654085 -293.829785) (xy 94.605866 -293.819941) (xy 94.55985 -293.802489) (xy 94.517229 -293.777882)
			(xy 94.479108 -293.746757) (xy 94.446473 -293.70992) (xy 94.42017 -293.668324) (xy 94.400879 -293.623048)
			(xy 94.389102 -293.575264) (xy 94.385142 -293.52621) (xy 94.056454 -293.52621) (xy 94.055959 -293.550817)
			(xy 94.048064 -293.599394) (xy 94.03248 -293.646075) (xy 94.009609 -293.689652) (xy 93.980044 -293.728996)
			(xy 93.944551 -293.763088) (xy 93.904048 -293.791044) (xy 93.859586 -293.812142) (xy 93.812315 -293.825834)
			(xy 93.76346 -293.831766) (xy 93.714285 -293.829785) (xy 93.666066 -293.819941) (xy 93.62005 -293.802489)
			(xy 93.577429 -293.777882) (xy 93.539308 -293.746757) (xy 93.506673 -293.70992) (xy 93.48037 -293.668324)
			(xy 93.461079 -293.623048) (xy 93.449302 -293.575264) (xy 93.445342 -293.52621) (xy 93.1164 -293.52621)
			(xy 93.115905 -293.550817) (xy 93.10801 -293.599394) (xy 93.092426 -293.646075) (xy 93.069555 -293.689652)
			(xy 93.03999 -293.728996) (xy 93.004497 -293.763088) (xy 92.963994 -293.791044) (xy 92.919532 -293.812142)
			(xy 92.872261 -293.825834) (xy 92.823406 -293.831766) (xy 92.774231 -293.829785) (xy 92.726012 -293.819941)
			(xy 92.679996 -293.802489) (xy 92.637375 -293.777882) (xy 92.599254 -293.746757) (xy 92.566619 -293.70992)
			(xy 92.540316 -293.668324) (xy 92.521025 -293.623048) (xy 92.509248 -293.575264) (xy 92.505288 -293.52621)
			(xy 92.176346 -293.52621) (xy 92.175851 -293.550817) (xy 92.167956 -293.599394) (xy 92.152372 -293.646075)
			(xy 92.129501 -293.689652) (xy 92.099936 -293.728996) (xy 92.064443 -293.763088) (xy 92.02394 -293.791044)
			(xy 91.979478 -293.812142) (xy 91.932207 -293.825834) (xy 91.883352 -293.831766) (xy 91.834177 -293.829785)
			(xy 91.785958 -293.819941) (xy 91.739942 -293.802489) (xy 91.697321 -293.777882) (xy 91.6592 -293.746757)
			(xy 91.626565 -293.70992) (xy 91.600262 -293.668324) (xy 91.580971 -293.623048) (xy 91.569194 -293.575264)
			(xy 91.565234 -293.52621) (xy 91.246706 -293.52621) (xy 91.246194 -293.551656) (xy 91.23803 -293.60189)
			(xy 91.221914 -293.650164) (xy 91.198263 -293.695227) (xy 91.16769 -293.735913) (xy 91.130986 -293.771168)
			(xy 91.089102 -293.800078) (xy 91.043123 -293.821895) (xy 90.994239 -293.836055) (xy 90.943718 -293.842189)
			(xy 90.892866 -293.84014) (xy 90.843002 -293.82996) (xy 90.795416 -293.811913) (xy 90.751342 -293.786467)
			(xy 90.71192 -293.75428) (xy 90.678172 -293.716186) (xy 90.650971 -293.673172) (xy 90.631023 -293.626352)
			(xy 90.618844 -293.576938) (xy 90.614749 -293.52621) (xy 90.296238 -293.52621) (xy 90.295767 -293.550202)
			(xy 90.28826 -293.597594) (xy 90.273432 -293.643228) (xy 90.251648 -293.685982) (xy 90.223445 -293.724802)
			(xy 90.189517 -293.758732) (xy 90.150699 -293.786938) (xy 90.107947 -293.808724) (xy 90.062313 -293.823555)
			(xy 90.014922 -293.831065) (xy 89.99093 -293.831518) (xy 89.538556 -293.831518) (xy 89.526533 -293.832192)
			(xy 89.505081 -293.843064) (xy 89.497408 -293.852346) (xy 89.484962 -293.868856) (xy 89.476326 -293.879778)
			(xy 89.472516 -293.906956) (xy 89.512394 -294.001952) (xy 89.516263 -294.01013) (xy 89.528662 -294.023289)
			(xy 89.544849 -294.031342) (xy 89.553796 -294.032686) (xy 89.578431 -294.035838) (xy 89.626292 -294.049094)
			(xy 89.671375 -294.069923) (xy 89.712493 -294.097775) (xy 89.74856 -294.131915) (xy 89.778626 -294.171443)
			(xy 89.801897 -294.215316) (xy 89.817759 -294.262377) (xy 89.825795 -294.311385) (xy 89.826338 -294.336216)
			(xy 90.15528 -294.336216) (xy 90.15924 -294.287162) (xy 90.171017 -294.239378) (xy 90.190308 -294.194102)
			(xy 90.216611 -294.152506) (xy 90.249246 -294.115669) (xy 90.287367 -294.084544) (xy 90.329988 -294.059937)
			(xy 90.376004 -294.042485) (xy 90.424223 -294.032641) (xy 90.473398 -294.03066) (xy 90.522253 -294.036592)
			(xy 90.569524 -294.050284) (xy 90.613986 -294.071382) (xy 90.654489 -294.099338) (xy 90.689982 -294.13343)
			(xy 90.719547 -294.172774) (xy 90.742418 -294.216351) (xy 90.758002 -294.263032) (xy 90.765897 -294.311609)
			(xy 90.766392 -294.336216) (xy 91.095334 -294.336216) (xy 91.099294 -294.287162) (xy 91.111071 -294.239378)
			(xy 91.130362 -294.194102) (xy 91.156665 -294.152506) (xy 91.1893 -294.115669) (xy 91.227421 -294.084544)
			(xy 91.270042 -294.059937) (xy 91.316058 -294.042485) (xy 91.364277 -294.032641) (xy 91.413452 -294.03066)
			(xy 91.462307 -294.036592) (xy 91.509578 -294.050284) (xy 91.55404 -294.071382) (xy 91.594543 -294.099338)
			(xy 91.630036 -294.13343) (xy 91.659601 -294.172774) (xy 91.682472 -294.216351) (xy 91.698056 -294.263032)
			(xy 91.705951 -294.311609) (xy 91.706446 -294.336216) (xy 92.035134 -294.336216) (xy 92.039094 -294.287162)
			(xy 92.050871 -294.239378) (xy 92.070162 -294.194102) (xy 92.096465 -294.152506) (xy 92.1291 -294.115669)
			(xy 92.167221 -294.084544) (xy 92.209842 -294.059937) (xy 92.255858 -294.042485) (xy 92.304077 -294.032641)
			(xy 92.353252 -294.03066) (xy 92.402107 -294.036592) (xy 92.449378 -294.050284) (xy 92.49384 -294.071382)
			(xy 92.534343 -294.099338) (xy 92.569836 -294.13343) (xy 92.599401 -294.172774) (xy 92.622272 -294.216351)
			(xy 92.637856 -294.263032) (xy 92.645751 -294.311609) (xy 92.646246 -294.336216) (xy 92.975188 -294.336216)
			(xy 92.979148 -294.287162) (xy 92.990925 -294.239378) (xy 93.010216 -294.194102) (xy 93.036519 -294.152506)
			(xy 93.069154 -294.115669) (xy 93.107275 -294.084544) (xy 93.149896 -294.059937) (xy 93.195912 -294.042485)
			(xy 93.244131 -294.032641) (xy 93.293306 -294.03066) (xy 93.342161 -294.036592) (xy 93.389432 -294.050284)
			(xy 93.433894 -294.071382) (xy 93.474397 -294.099338) (xy 93.50989 -294.13343) (xy 93.539455 -294.172774)
			(xy 93.562326 -294.216351) (xy 93.57791 -294.263032) (xy 93.585805 -294.311609) (xy 93.5863 -294.336216)
			(xy 93.915242 -294.336216) (xy 93.919202 -294.287162) (xy 93.930979 -294.239378) (xy 93.95027 -294.194102)
			(xy 93.976573 -294.152506) (xy 94.009208 -294.115669) (xy 94.047329 -294.084544) (xy 94.08995 -294.059937)
			(xy 94.135966 -294.042485) (xy 94.184185 -294.032641) (xy 94.23336 -294.03066) (xy 94.282215 -294.036592)
			(xy 94.329486 -294.050284) (xy 94.373948 -294.071382) (xy 94.414451 -294.099338) (xy 94.449944 -294.13343)
			(xy 94.479509 -294.172774) (xy 94.50238 -294.216351) (xy 94.517964 -294.263032) (xy 94.525859 -294.311609)
			(xy 94.526354 -294.336216) (xy 94.855296 -294.336216) (xy 94.859256 -294.287162) (xy 94.871033 -294.239378)
			(xy 94.890324 -294.194102) (xy 94.916627 -294.152506) (xy 94.949262 -294.115669) (xy 94.987383 -294.084544)
			(xy 95.030004 -294.059937) (xy 95.07602 -294.042485) (xy 95.124239 -294.032641) (xy 95.173414 -294.03066)
			(xy 95.222269 -294.036592) (xy 95.26954 -294.050284) (xy 95.314002 -294.071382) (xy 95.354505 -294.099338)
			(xy 95.389998 -294.13343) (xy 95.419563 -294.172774) (xy 95.442434 -294.216351) (xy 95.458018 -294.263032)
			(xy 95.465913 -294.311609) (xy 95.466408 -294.336216) (xy 95.79535 -294.336216) (xy 95.79931 -294.287162)
			(xy 95.811087 -294.239378) (xy 95.830378 -294.194102) (xy 95.856681 -294.152506) (xy 95.889316 -294.115669)
			(xy 95.927437 -294.084544) (xy 95.970058 -294.059937) (xy 96.016074 -294.042485) (xy 96.064293 -294.032641)
			(xy 96.113468 -294.03066) (xy 96.162323 -294.036592) (xy 96.209594 -294.050284) (xy 96.254056 -294.071382)
			(xy 96.294559 -294.099338) (xy 96.330052 -294.13343) (xy 96.359617 -294.172774) (xy 96.382488 -294.216351)
			(xy 96.398072 -294.263032) (xy 96.405967 -294.311609) (xy 96.406462 -294.336216) (xy 96.405967 -294.360823)
			(xy 96.398072 -294.4094) (xy 96.382488 -294.456081) (xy 96.359617 -294.499658) (xy 96.330052 -294.539002)
			(xy 96.294559 -294.573094) (xy 96.254056 -294.60105) (xy 96.209594 -294.622148) (xy 96.162323 -294.63584)
			(xy 96.113468 -294.641772) (xy 96.064293 -294.639791) (xy 96.016074 -294.629947) (xy 95.970058 -294.612495)
			(xy 95.927437 -294.587888) (xy 95.889316 -294.556763) (xy 95.856681 -294.519926) (xy 95.830378 -294.47833)
			(xy 95.811087 -294.433054) (xy 95.79931 -294.38527) (xy 95.79535 -294.336216) (xy 95.466408 -294.336216)
			(xy 95.465913 -294.360823) (xy 95.458018 -294.4094) (xy 95.442434 -294.456081) (xy 95.419563 -294.499658)
			(xy 95.389998 -294.539002) (xy 95.354505 -294.573094) (xy 95.314002 -294.60105) (xy 95.26954 -294.622148)
			(xy 95.222269 -294.63584) (xy 95.173414 -294.641772) (xy 95.124239 -294.639791) (xy 95.07602 -294.629947)
			(xy 95.030004 -294.612495) (xy 94.987383 -294.587888) (xy 94.949262 -294.556763) (xy 94.916627 -294.519926)
			(xy 94.890324 -294.47833) (xy 94.871033 -294.433054) (xy 94.859256 -294.38527) (xy 94.855296 -294.336216)
			(xy 94.526354 -294.336216) (xy 94.525859 -294.360823) (xy 94.517964 -294.4094) (xy 94.50238 -294.456081)
			(xy 94.479509 -294.499658) (xy 94.449944 -294.539002) (xy 94.414451 -294.573094) (xy 94.373948 -294.60105)
			(xy 94.329486 -294.622148) (xy 94.282215 -294.63584) (xy 94.23336 -294.641772) (xy 94.184185 -294.639791)
			(xy 94.135966 -294.629947) (xy 94.08995 -294.612495) (xy 94.047329 -294.587888) (xy 94.009208 -294.556763)
			(xy 93.976573 -294.519926) (xy 93.95027 -294.47833) (xy 93.930979 -294.433054) (xy 93.919202 -294.38527)
			(xy 93.915242 -294.336216) (xy 93.5863 -294.336216) (xy 93.585805 -294.360823) (xy 93.57791 -294.4094)
			(xy 93.562326 -294.456081) (xy 93.539455 -294.499658) (xy 93.50989 -294.539002) (xy 93.474397 -294.573094)
			(xy 93.433894 -294.60105) (xy 93.389432 -294.622148) (xy 93.342161 -294.63584) (xy 93.293306 -294.641772)
			(xy 93.244131 -294.639791) (xy 93.195912 -294.629947) (xy 93.149896 -294.612495) (xy 93.107275 -294.587888)
			(xy 93.069154 -294.556763) (xy 93.036519 -294.519926) (xy 93.010216 -294.47833) (xy 92.990925 -294.433054)
			(xy 92.979148 -294.38527) (xy 92.975188 -294.336216) (xy 92.646246 -294.336216) (xy 92.645751 -294.360823)
			(xy 92.637856 -294.4094) (xy 92.622272 -294.456081) (xy 92.599401 -294.499658) (xy 92.569836 -294.539002)
			(xy 92.534343 -294.573094) (xy 92.49384 -294.60105) (xy 92.449378 -294.622148) (xy 92.402107 -294.63584)
			(xy 92.353252 -294.641772) (xy 92.304077 -294.639791) (xy 92.255858 -294.629947) (xy 92.209842 -294.612495)
			(xy 92.167221 -294.587888) (xy 92.1291 -294.556763) (xy 92.096465 -294.519926) (xy 92.070162 -294.47833)
			(xy 92.050871 -294.433054) (xy 92.039094 -294.38527) (xy 92.035134 -294.336216) (xy 91.706446 -294.336216)
			(xy 91.705951 -294.360823) (xy 91.698056 -294.4094) (xy 91.682472 -294.456081) (xy 91.659601 -294.499658)
			(xy 91.630036 -294.539002) (xy 91.594543 -294.573094) (xy 91.55404 -294.60105) (xy 91.509578 -294.622148)
			(xy 91.462307 -294.63584) (xy 91.413452 -294.641772) (xy 91.364277 -294.639791) (xy 91.316058 -294.629947)
			(xy 91.270042 -294.612495) (xy 91.227421 -294.587888) (xy 91.1893 -294.556763) (xy 91.156665 -294.519926)
			(xy 91.130362 -294.47833) (xy 91.111071 -294.433054) (xy 91.099294 -294.38527) (xy 91.095334 -294.336216)
			(xy 90.766392 -294.336216) (xy 90.765897 -294.360823) (xy 90.758002 -294.4094) (xy 90.742418 -294.456081)
			(xy 90.719547 -294.499658) (xy 90.689982 -294.539002) (xy 90.654489 -294.573094) (xy 90.613986 -294.60105)
			(xy 90.569524 -294.622148) (xy 90.522253 -294.63584) (xy 90.473398 -294.641772) (xy 90.424223 -294.639791)
			(xy 90.376004 -294.629947) (xy 90.329988 -294.612495) (xy 90.287367 -294.587888) (xy 90.249246 -294.556763)
			(xy 90.216611 -294.519926) (xy 90.190308 -294.47833) (xy 90.171017 -294.433054) (xy 90.15924 -294.38527)
			(xy 90.15528 -294.336216) (xy 89.826338 -294.336216) (xy 89.825816 -294.361471) (xy 89.817503 -294.411293)
			(xy 89.801102 -294.459067) (xy 89.777061 -294.50349) (xy 89.746037 -294.54335) (xy 89.708875 -294.57756)
			(xy 89.666589 -294.605186) (xy 89.620333 -294.625476) (xy 89.571368 -294.637876) (xy 89.52103 -294.642047)
			(xy 89.470692 -294.637876) (xy 89.421727 -294.625476) (xy 89.375471 -294.605186) (xy 89.333185 -294.57756)
			(xy 89.296023 -294.54335) (xy 89.264999 -294.50349) (xy 89.240958 -294.459067) (xy 89.224557 -294.411293)
			(xy 89.216244 -294.361471) (xy 89.215722 -294.336216) (xy 89.215722 -294.335708) (xy 89.216083 -294.314839)
			(xy 89.221809 -294.273495) (xy 89.233114 -294.233317) (xy 89.241122 -294.214042) (xy 89.24671 -294.201342)
			(xy 89.243662 -294.17391) (xy 89.172288 -294.0812) (xy 89.146888 -294.070786) (xy 89.133426 -294.072818)
			(xy 89.132918 -294.072818) (xy 89.112659 -294.075727) (xy 89.071849 -294.078901) (xy 89.051384 -294.079168)
			(xy 89.050876 -294.079168) (xy 89.03041 -294.078908) (xy 88.989601 -294.07573) (xy 88.969342 -294.072818)
			(xy 88.968834 -294.072818) (xy 88.959883 -294.071853) (xy 88.942281 -294.075568) (xy 88.927079 -294.085188)
			(xy 88.921336 -294.092122) (xy 88.858344 -294.17391) (xy 88.855296 -294.201342) (xy 88.860884 -294.214042)
			(xy 88.868909 -294.233311) (xy 88.880215 -294.273492) (xy 88.885941 -294.314838) (xy 88.886284 -294.335708)
			(xy 88.886284 -294.336216) (xy 88.885762 -294.361471) (xy 88.877449 -294.411293) (xy 88.861048 -294.459067)
			(xy 88.837007 -294.50349) (xy 88.805983 -294.54335) (xy 88.768821 -294.57756) (xy 88.726535 -294.605186)
			(xy 88.680279 -294.625476) (xy 88.631314 -294.637876) (xy 88.580976 -294.642047) (xy 88.530638 -294.637876)
			(xy 88.481673 -294.625476) (xy 88.435417 -294.605186) (xy 88.393131 -294.57756) (xy 88.355969 -294.54335)
			(xy 88.324945 -294.50349) (xy 88.300904 -294.459067) (xy 88.284503 -294.411293) (xy 88.27619 -294.361471)
			(xy 88.275668 -294.336216) (xy 88.276154 -294.311383) (xy 88.284192 -294.262371) (xy 88.30006 -294.215308)
			(xy 88.323338 -294.171434) (xy 88.353412 -294.131908) (xy 88.389488 -294.097773) (xy 88.430615 -294.069928)
			(xy 88.475708 -294.04911) (xy 88.523576 -294.035867) (xy 88.54821 -294.032686) (xy 88.548464 -294.032686)
			(xy 88.557421 -294.031376) (xy 88.573622 -294.023331) (xy 88.585996 -294.010137) (xy 88.589866 -294.001952)
			(xy 88.624156 -293.919656) (xy 88.627356 -293.911192) (xy 88.628174 -293.893129) (xy 88.622616 -293.875923)
			(xy 88.617298 -293.868602) (xy 88.590882 -293.832534) (xy 88.580976 -293.832534) (xy 88.533224 -293.831518)
			(xy 87.690706 -293.831518) (xy 87.688674 -293.831518) (xy 87.640922 -293.832534) (xy 87.59317 -293.831518)
			(xy 86.750906 -293.831518) (xy 86.748874 -293.831518) (xy 86.701122 -293.832534) (xy 86.65337 -293.831518)
			(xy 86.394036 -293.831518) (xy 86.383971 -293.831953) (xy 86.365385 -293.839686) (xy 86.357968 -293.846504)
			(xy 86.244176 -293.960296) (xy 86.23732 -293.96769) (xy 86.229573 -293.986289) (xy 86.22919 -293.996364)
			(xy 86.22919 -294.038528) (xy 86.228761 -294.048596) (xy 86.221039 -294.067192) (xy 86.214204 -294.074596)
			(xy 86.071456 -294.217344) (xy 86.065581 -294.223721) (xy 86.058125 -294.239362) (xy 86.056302 -294.256593)
			(xy 86.057994 -294.265096) (xy 86.061913 -294.28255) (xy 86.066115 -294.318075) (xy 86.066376 -294.335962)
			(xy 86.066376 -294.336216) (xy 86.395318 -294.336216) (xy 86.399278 -294.287162) (xy 86.411055 -294.239378)
			(xy 86.430346 -294.194102) (xy 86.456649 -294.152506) (xy 86.489284 -294.115669) (xy 86.527405 -294.084544)
			(xy 86.570026 -294.059937) (xy 86.616042 -294.042485) (xy 86.664261 -294.032641) (xy 86.713436 -294.03066)
			(xy 86.762291 -294.036592) (xy 86.809562 -294.050284) (xy 86.854024 -294.071382) (xy 86.894527 -294.099338)
			(xy 86.93002 -294.13343) (xy 86.959585 -294.172774) (xy 86.982456 -294.216351) (xy 86.99804 -294.263032)
			(xy 87.005935 -294.311609) (xy 87.00643 -294.336216) (xy 87.005935 -294.360823) (xy 86.99804 -294.4094)
			(xy 86.982456 -294.456081) (xy 86.959585 -294.499658) (xy 86.93002 -294.539002) (xy 86.894527 -294.573094)
			(xy 86.854024 -294.60105) (xy 86.809562 -294.622148) (xy 86.762291 -294.63584) (xy 86.713436 -294.641772)
			(xy 86.664261 -294.639791) (xy 86.616042 -294.629947) (xy 86.570026 -294.612495) (xy 86.527405 -294.587888)
			(xy 86.489284 -294.556763) (xy 86.456649 -294.519926) (xy 86.430346 -294.47833) (xy 86.411055 -294.433054)
			(xy 86.399278 -294.38527) (xy 86.395318 -294.336216) (xy 86.066376 -294.336216) (xy 86.065929 -294.360207)
			(xy 86.05842 -294.407599) (xy 86.043589 -294.453233) (xy 86.021803 -294.495984) (xy 85.993596 -294.534801)
			(xy 85.959664 -294.568727) (xy 85.920843 -294.596928) (xy 85.878088 -294.618708) (xy 85.832452 -294.633531)
			(xy 85.785059 -294.641032) (xy 85.761068 -294.641524) (xy 85.760814 -294.641524) (xy 85.742928 -294.641255)
			(xy 85.707402 -294.637059) (xy 85.689948 -294.633142) (xy 85.681442 -294.631435) (xy 85.664198 -294.633226)
			(xy 85.648556 -294.640703) (xy 85.642196 -294.646604) (xy 85.504528 -294.784272) (xy 85.49769 -294.791673)
			(xy 85.489977 -294.810272) (xy 85.489542 -294.82034) (xy 85.49005 -294.90289) (xy 85.497924 -294.921432)
			(xy 85.505036 -294.928544) (xy 85.521997 -294.945877) (xy 85.550759 -294.984919) (xy 85.572985 -295.028018)
			(xy 85.588114 -295.07409) (xy 85.595765 -295.121976) (xy 85.596222 -295.146222) (xy 85.925164 -295.146222)
			(xy 85.929124 -295.097168) (xy 85.940901 -295.049384) (xy 85.960192 -295.004108) (xy 85.986495 -294.962512)
			(xy 86.01913 -294.925675) (xy 86.057251 -294.89455) (xy 86.099872 -294.869943) (xy 86.145888 -294.852491)
			(xy 86.194107 -294.842647) (xy 86.243282 -294.840666) (xy 86.292137 -294.846598) (xy 86.339408 -294.86029)
			(xy 86.38387 -294.881388) (xy 86.424373 -294.909344) (xy 86.459866 -294.943436) (xy 86.489431 -294.98278)
			(xy 86.512302 -295.026357) (xy 86.527886 -295.073038) (xy 86.535781 -295.121615) (xy 86.536276 -295.146222)
			(xy 86.865218 -295.146222) (xy 86.869178 -295.097168) (xy 86.880955 -295.049384) (xy 86.900246 -295.004108)
			(xy 86.926549 -294.962512) (xy 86.959184 -294.925675) (xy 86.997305 -294.89455) (xy 87.039926 -294.869943)
			(xy 87.085942 -294.852491) (xy 87.134161 -294.842647) (xy 87.183336 -294.840666) (xy 87.232191 -294.846598)
			(xy 87.279462 -294.86029) (xy 87.323924 -294.881388) (xy 87.364427 -294.909344) (xy 87.39992 -294.943436)
			(xy 87.429485 -294.98278) (xy 87.452356 -295.026357) (xy 87.46794 -295.073038) (xy 87.475835 -295.121615)
			(xy 87.47633 -295.146222) (xy 87.805272 -295.146222) (xy 87.809232 -295.097168) (xy 87.821009 -295.049384)
			(xy 87.8403 -295.004108) (xy 87.866603 -294.962512) (xy 87.899238 -294.925675) (xy 87.937359 -294.89455)
			(xy 87.97998 -294.869943) (xy 88.025996 -294.852491) (xy 88.074215 -294.842647) (xy 88.12339 -294.840666)
			(xy 88.172245 -294.846598) (xy 88.219516 -294.86029) (xy 88.263978 -294.881388) (xy 88.304481 -294.909344)
			(xy 88.339974 -294.943436) (xy 88.369539 -294.98278) (xy 88.39241 -295.026357) (xy 88.407994 -295.073038)
			(xy 88.415889 -295.121615) (xy 88.416384 -295.146222) (xy 88.745326 -295.146222) (xy 88.749286 -295.097168)
			(xy 88.761063 -295.049384) (xy 88.780354 -295.004108) (xy 88.806657 -294.962512) (xy 88.839292 -294.925675)
			(xy 88.877413 -294.89455) (xy 88.920034 -294.869943) (xy 88.96605 -294.852491) (xy 89.014269 -294.842647)
			(xy 89.063444 -294.840666) (xy 89.112299 -294.846598) (xy 89.15957 -294.86029) (xy 89.204032 -294.881388)
			(xy 89.244535 -294.909344) (xy 89.280028 -294.943436) (xy 89.309593 -294.98278) (xy 89.332464 -295.026357)
			(xy 89.348048 -295.073038) (xy 89.355943 -295.121615) (xy 89.356438 -295.146222) (xy 89.685126 -295.146222)
			(xy 89.689086 -295.097168) (xy 89.700863 -295.049384) (xy 89.720154 -295.004108) (xy 89.746457 -294.962512)
			(xy 89.779092 -294.925675) (xy 89.817213 -294.89455) (xy 89.859834 -294.869943) (xy 89.90585 -294.852491)
			(xy 89.954069 -294.842647) (xy 90.003244 -294.840666) (xy 90.052099 -294.846598) (xy 90.09937 -294.86029)
			(xy 90.143832 -294.881388) (xy 90.184335 -294.909344) (xy 90.219828 -294.943436) (xy 90.249393 -294.98278)
			(xy 90.272264 -295.026357) (xy 90.287848 -295.073038) (xy 90.295743 -295.121615) (xy 90.296238 -295.146222)
			(xy 90.62518 -295.146222) (xy 90.62914 -295.097168) (xy 90.640917 -295.049384) (xy 90.660208 -295.004108)
			(xy 90.686511 -294.962512) (xy 90.719146 -294.925675) (xy 90.757267 -294.89455) (xy 90.799888 -294.869943)
			(xy 90.845904 -294.852491) (xy 90.894123 -294.842647) (xy 90.943298 -294.840666) (xy 90.992153 -294.846598)
			(xy 91.039424 -294.86029) (xy 91.083886 -294.881388) (xy 91.124389 -294.909344) (xy 91.159882 -294.943436)
			(xy 91.189447 -294.98278) (xy 91.212318 -295.026357) (xy 91.227902 -295.073038) (xy 91.235797 -295.121615)
			(xy 91.236292 -295.146222) (xy 91.565234 -295.146222) (xy 91.569194 -295.097168) (xy 91.580971 -295.049384)
			(xy 91.600262 -295.004108) (xy 91.626565 -294.962512) (xy 91.6592 -294.925675) (xy 91.697321 -294.89455)
			(xy 91.739942 -294.869943) (xy 91.785958 -294.852491) (xy 91.834177 -294.842647) (xy 91.883352 -294.840666)
			(xy 91.932207 -294.846598) (xy 91.979478 -294.86029) (xy 92.02394 -294.881388) (xy 92.064443 -294.909344)
			(xy 92.099936 -294.943436) (xy 92.129501 -294.98278) (xy 92.152372 -295.026357) (xy 92.167956 -295.073038)
			(xy 92.175851 -295.121615) (xy 92.176346 -295.146222) (xy 92.505288 -295.146222) (xy 92.509248 -295.097168)
			(xy 92.521025 -295.049384) (xy 92.540316 -295.004108) (xy 92.566619 -294.962512) (xy 92.599254 -294.925675)
			(xy 92.637375 -294.89455) (xy 92.679996 -294.869943) (xy 92.726012 -294.852491) (xy 92.774231 -294.842647)
			(xy 92.823406 -294.840666) (xy 92.872261 -294.846598) (xy 92.919532 -294.86029) (xy 92.963994 -294.881388)
			(xy 93.004497 -294.909344) (xy 93.03999 -294.943436) (xy 93.069555 -294.98278) (xy 93.092426 -295.026357)
			(xy 93.10801 -295.073038) (xy 93.115905 -295.121615) (xy 93.1164 -295.146222) (xy 93.445342 -295.146222)
			(xy 93.449302 -295.097168) (xy 93.461079 -295.049384) (xy 93.48037 -295.004108) (xy 93.506673 -294.962512)
			(xy 93.539308 -294.925675) (xy 93.577429 -294.89455) (xy 93.62005 -294.869943) (xy 93.666066 -294.852491)
			(xy 93.714285 -294.842647) (xy 93.76346 -294.840666) (xy 93.812315 -294.846598) (xy 93.859586 -294.86029)
			(xy 93.904048 -294.881388) (xy 93.944551 -294.909344) (xy 93.980044 -294.943436) (xy 94.009609 -294.98278)
			(xy 94.03248 -295.026357) (xy 94.048064 -295.073038) (xy 94.055959 -295.121615) (xy 94.056454 -295.146222)
			(xy 94.385142 -295.146222) (xy 94.389102 -295.097168) (xy 94.400879 -295.049384) (xy 94.42017 -295.004108)
			(xy 94.446473 -294.962512) (xy 94.479108 -294.925675) (xy 94.517229 -294.89455) (xy 94.55985 -294.869943)
			(xy 94.605866 -294.852491) (xy 94.654085 -294.842647) (xy 94.70326 -294.840666) (xy 94.752115 -294.846598)
			(xy 94.799386 -294.86029) (xy 94.843848 -294.881388) (xy 94.884351 -294.909344) (xy 94.919844 -294.943436)
			(xy 94.949409 -294.98278) (xy 94.97228 -295.026357) (xy 94.987864 -295.073038) (xy 94.995759 -295.121615)
			(xy 94.996254 -295.146222) (xy 95.325196 -295.146222) (xy 95.329156 -295.097168) (xy 95.340933 -295.049384)
			(xy 95.360224 -295.004108) (xy 95.386527 -294.962512) (xy 95.419162 -294.925675) (xy 95.457283 -294.89455)
			(xy 95.499904 -294.869943) (xy 95.54592 -294.852491) (xy 95.594139 -294.842647) (xy 95.643314 -294.840666)
			(xy 95.692169 -294.846598) (xy 95.73944 -294.86029) (xy 95.783902 -294.881388) (xy 95.824405 -294.909344)
			(xy 95.859898 -294.943436) (xy 95.889463 -294.98278) (xy 95.912334 -295.026357) (xy 95.927918 -295.073038)
			(xy 95.935813 -295.121615) (xy 95.936308 -295.146222) (xy 95.935813 -295.170829) (xy 95.927918 -295.219406)
			(xy 95.912334 -295.266087) (xy 95.889463 -295.309664) (xy 95.859898 -295.349008) (xy 95.824405 -295.3831)
			(xy 95.783902 -295.411056) (xy 95.73944 -295.432154) (xy 95.692169 -295.445846) (xy 95.643314 -295.451778)
			(xy 95.594139 -295.449797) (xy 95.54592 -295.439953) (xy 95.499904 -295.422501) (xy 95.457283 -295.397894)
			(xy 95.419162 -295.366769) (xy 95.386527 -295.329932) (xy 95.360224 -295.288336) (xy 95.340933 -295.24306)
			(xy 95.329156 -295.195276) (xy 95.325196 -295.146222) (xy 94.996254 -295.146222) (xy 94.995759 -295.170829)
			(xy 94.987864 -295.219406) (xy 94.97228 -295.266087) (xy 94.949409 -295.309664) (xy 94.919844 -295.349008)
			(xy 94.884351 -295.3831) (xy 94.843848 -295.411056) (xy 94.799386 -295.432154) (xy 94.752115 -295.445846)
			(xy 94.70326 -295.451778) (xy 94.654085 -295.449797) (xy 94.605866 -295.439953) (xy 94.55985 -295.422501)
			(xy 94.517229 -295.397894) (xy 94.479108 -295.366769) (xy 94.446473 -295.329932) (xy 94.42017 -295.288336)
			(xy 94.400879 -295.24306) (xy 94.389102 -295.195276) (xy 94.385142 -295.146222) (xy 94.056454 -295.146222)
			(xy 94.055959 -295.170829) (xy 94.048064 -295.219406) (xy 94.03248 -295.266087) (xy 94.009609 -295.309664)
			(xy 93.980044 -295.349008) (xy 93.944551 -295.3831) (xy 93.904048 -295.411056) (xy 93.859586 -295.432154)
			(xy 93.812315 -295.445846) (xy 93.76346 -295.451778) (xy 93.714285 -295.449797) (xy 93.666066 -295.439953)
			(xy 93.62005 -295.422501) (xy 93.577429 -295.397894) (xy 93.539308 -295.366769) (xy 93.506673 -295.329932)
			(xy 93.48037 -295.288336) (xy 93.461079 -295.24306) (xy 93.449302 -295.195276) (xy 93.445342 -295.146222)
			(xy 93.1164 -295.146222) (xy 93.115905 -295.170829) (xy 93.10801 -295.219406) (xy 93.092426 -295.266087)
			(xy 93.069555 -295.309664) (xy 93.03999 -295.349008) (xy 93.004497 -295.3831) (xy 92.963994 -295.411056)
			(xy 92.919532 -295.432154) (xy 92.872261 -295.445846) (xy 92.823406 -295.451778) (xy 92.774231 -295.449797)
			(xy 92.726012 -295.439953) (xy 92.679996 -295.422501) (xy 92.637375 -295.397894) (xy 92.599254 -295.366769)
			(xy 92.566619 -295.329932) (xy 92.540316 -295.288336) (xy 92.521025 -295.24306) (xy 92.509248 -295.195276)
			(xy 92.505288 -295.146222) (xy 92.176346 -295.146222) (xy 92.175851 -295.170829) (xy 92.167956 -295.219406)
			(xy 92.152372 -295.266087) (xy 92.129501 -295.309664) (xy 92.099936 -295.349008) (xy 92.064443 -295.3831)
			(xy 92.02394 -295.411056) (xy 91.979478 -295.432154) (xy 91.932207 -295.445846) (xy 91.883352 -295.451778)
			(xy 91.834177 -295.449797) (xy 91.785958 -295.439953) (xy 91.739942 -295.422501) (xy 91.697321 -295.397894)
			(xy 91.6592 -295.366769) (xy 91.626565 -295.329932) (xy 91.600262 -295.288336) (xy 91.580971 -295.24306)
			(xy 91.569194 -295.195276) (xy 91.565234 -295.146222) (xy 91.236292 -295.146222) (xy 91.235797 -295.170829)
			(xy 91.227902 -295.219406) (xy 91.212318 -295.266087) (xy 91.189447 -295.309664) (xy 91.159882 -295.349008)
			(xy 91.124389 -295.3831) (xy 91.083886 -295.411056) (xy 91.039424 -295.432154) (xy 90.992153 -295.445846)
			(xy 90.943298 -295.451778) (xy 90.894123 -295.449797) (xy 90.845904 -295.439953) (xy 90.799888 -295.422501)
			(xy 90.757267 -295.397894) (xy 90.719146 -295.366769) (xy 90.686511 -295.329932) (xy 90.660208 -295.288336)
			(xy 90.640917 -295.24306) (xy 90.62914 -295.195276) (xy 90.62518 -295.146222) (xy 90.296238 -295.146222)
			(xy 90.295743 -295.170829) (xy 90.287848 -295.219406) (xy 90.272264 -295.266087) (xy 90.249393 -295.309664)
			(xy 90.219828 -295.349008) (xy 90.184335 -295.3831) (xy 90.143832 -295.411056) (xy 90.09937 -295.432154)
			(xy 90.052099 -295.445846) (xy 90.003244 -295.451778) (xy 89.954069 -295.449797) (xy 89.90585 -295.439953)
			(xy 89.859834 -295.422501) (xy 89.817213 -295.397894) (xy 89.779092 -295.366769) (xy 89.746457 -295.329932)
			(xy 89.720154 -295.288336) (xy 89.700863 -295.24306) (xy 89.689086 -295.195276) (xy 89.685126 -295.146222)
			(xy 89.356438 -295.146222) (xy 89.355943 -295.170829) (xy 89.348048 -295.219406) (xy 89.332464 -295.266087)
			(xy 89.309593 -295.309664) (xy 89.280028 -295.349008) (xy 89.244535 -295.3831) (xy 89.204032 -295.411056)
			(xy 89.15957 -295.432154) (xy 89.112299 -295.445846) (xy 89.063444 -295.451778) (xy 89.014269 -295.449797)
			(xy 88.96605 -295.439953) (xy 88.920034 -295.422501) (xy 88.877413 -295.397894) (xy 88.839292 -295.366769)
			(xy 88.806657 -295.329932) (xy 88.780354 -295.288336) (xy 88.761063 -295.24306) (xy 88.749286 -295.195276)
			(xy 88.745326 -295.146222) (xy 88.416384 -295.146222) (xy 88.415889 -295.170829) (xy 88.407994 -295.219406)
			(xy 88.39241 -295.266087) (xy 88.369539 -295.309664) (xy 88.339974 -295.349008) (xy 88.304481 -295.3831)
			(xy 88.263978 -295.411056) (xy 88.219516 -295.432154) (xy 88.172245 -295.445846) (xy 88.12339 -295.451778)
			(xy 88.074215 -295.449797) (xy 88.025996 -295.439953) (xy 87.97998 -295.422501) (xy 87.937359 -295.397894)
			(xy 87.899238 -295.366769) (xy 87.866603 -295.329932) (xy 87.8403 -295.288336) (xy 87.821009 -295.24306)
			(xy 87.809232 -295.195276) (xy 87.805272 -295.146222) (xy 87.47633 -295.146222) (xy 87.475835 -295.170829)
			(xy 87.46794 -295.219406) (xy 87.452356 -295.266087) (xy 87.429485 -295.309664) (xy 87.39992 -295.349008)
			(xy 87.364427 -295.3831) (xy 87.323924 -295.411056) (xy 87.279462 -295.432154) (xy 87.232191 -295.445846)
			(xy 87.183336 -295.451778) (xy 87.134161 -295.449797) (xy 87.085942 -295.439953) (xy 87.039926 -295.422501)
			(xy 86.997305 -295.397894) (xy 86.959184 -295.366769) (xy 86.926549 -295.329932) (xy 86.900246 -295.288336)
			(xy 86.880955 -295.24306) (xy 86.869178 -295.195276) (xy 86.865218 -295.146222) (xy 86.536276 -295.146222)
			(xy 86.535781 -295.170829) (xy 86.527886 -295.219406) (xy 86.512302 -295.266087) (xy 86.489431 -295.309664)
			(xy 86.459866 -295.349008) (xy 86.424373 -295.3831) (xy 86.38387 -295.411056) (xy 86.339408 -295.432154)
			(xy 86.292137 -295.445846) (xy 86.243282 -295.451778) (xy 86.194107 -295.449797) (xy 86.145888 -295.439953)
			(xy 86.099872 -295.422501) (xy 86.057251 -295.397894) (xy 86.01913 -295.366769) (xy 85.986495 -295.329932)
			(xy 85.960192 -295.288336) (xy 85.940901 -295.24306) (xy 85.929124 -295.195276) (xy 85.925164 -295.146222)
			(xy 85.596222 -295.146222) (xy 85.59575 -295.170212) (xy 85.588241 -295.217602) (xy 85.573412 -295.263234)
			(xy 85.551627 -295.305985) (xy 85.523424 -295.344802) (xy 85.489496 -295.378729) (xy 85.450678 -295.406932)
			(xy 85.407927 -295.428715) (xy 85.362295 -295.443543) (xy 85.314905 -295.45105) (xy 85.290914 -295.45153)
			(xy 85.266671 -295.451058) (xy 85.218794 -295.443387) (xy 85.172731 -295.42825) (xy 85.129636 -295.406027)
			(xy 85.090592 -295.377278) (xy 85.073236 -295.360344) (xy 85.066124 -295.353232) (xy 85.047582 -295.345358)
			(xy 84.965032 -295.34485) (xy 84.954968 -295.345287) (xy 84.936387 -295.353024) (xy 84.928964 -295.359836)
			(xy 84.807044 -295.481756) (xy 84.80075 -295.488701) (xy 84.793211 -295.505843) (xy 84.792319 -295.524548)
			(xy 84.794852 -295.533572) (xy 84.828126 -295.633394) (xy 84.850224 -295.651936) (xy 84.864448 -295.653968)
			(xy 84.888377 -295.657872) (xy 84.934675 -295.672257) (xy 84.978117 -295.69378) (xy 85.01761 -295.721899)
			(xy 85.052162 -295.755908) (xy 85.080903 -295.794952) (xy 85.10311 -295.838048) (xy 85.118226 -295.884112)
			(xy 85.12587 -295.931987) (xy 85.126322 -295.956228) (xy 85.455264 -295.956228) (xy 85.459224 -295.907174)
			(xy 85.471001 -295.85939) (xy 85.490292 -295.814114) (xy 85.516595 -295.772518) (xy 85.54923 -295.735681)
			(xy 85.587351 -295.704556) (xy 85.629972 -295.679949) (xy 85.675988 -295.662497) (xy 85.724207 -295.652653)
			(xy 85.773382 -295.650672) (xy 85.822237 -295.656604) (xy 85.869508 -295.670296) (xy 85.91397 -295.691394)
			(xy 85.954473 -295.71935) (xy 85.989966 -295.753442) (xy 86.019531 -295.792786) (xy 86.042402 -295.836363)
			(xy 86.057986 -295.883044) (xy 86.065881 -295.931621) (xy 86.066376 -295.956228) (xy 86.395318 -295.956228)
			(xy 86.399278 -295.907174) (xy 86.411055 -295.85939) (xy 86.430346 -295.814114) (xy 86.456649 -295.772518)
			(xy 86.489284 -295.735681) (xy 86.527405 -295.704556) (xy 86.570026 -295.679949) (xy 86.616042 -295.662497)
			(xy 86.664261 -295.652653) (xy 86.713436 -295.650672) (xy 86.762291 -295.656604) (xy 86.809562 -295.670296)
			(xy 86.854024 -295.691394) (xy 86.894527 -295.71935) (xy 86.93002 -295.753442) (xy 86.959585 -295.792786)
			(xy 86.982456 -295.836363) (xy 86.99804 -295.883044) (xy 87.005935 -295.931621) (xy 87.00643 -295.956228)
			(xy 88.275172 -295.956228) (xy 88.279132 -295.907174) (xy 88.290909 -295.85939) (xy 88.3102 -295.814114)
			(xy 88.336503 -295.772518) (xy 88.369138 -295.735681) (xy 88.407259 -295.704556) (xy 88.44988 -295.679949)
			(xy 88.495896 -295.662497) (xy 88.544115 -295.652653) (xy 88.59329 -295.650672) (xy 88.642145 -295.656604)
			(xy 88.689416 -295.670296) (xy 88.733878 -295.691394) (xy 88.774381 -295.71935) (xy 88.809874 -295.753442)
			(xy 88.839439 -295.792786) (xy 88.86231 -295.836363) (xy 88.877894 -295.883044) (xy 88.885789 -295.931621)
			(xy 88.886284 -295.956228) (xy 89.215226 -295.956228) (xy 89.219186 -295.907174) (xy 89.230963 -295.85939)
			(xy 89.250254 -295.814114) (xy 89.276557 -295.772518) (xy 89.309192 -295.735681) (xy 89.347313 -295.704556)
			(xy 89.389934 -295.679949) (xy 89.43595 -295.662497) (xy 89.484169 -295.652653) (xy 89.533344 -295.650672)
			(xy 89.582199 -295.656604) (xy 89.62947 -295.670296) (xy 89.673932 -295.691394) (xy 89.714435 -295.71935)
			(xy 89.749928 -295.753442) (xy 89.779493 -295.792786) (xy 89.802364 -295.836363) (xy 89.817948 -295.883044)
			(xy 89.825843 -295.931621) (xy 89.826338 -295.956228) (xy 90.15528 -295.956228) (xy 90.15924 -295.907174)
			(xy 90.171017 -295.85939) (xy 90.190308 -295.814114) (xy 90.216611 -295.772518) (xy 90.249246 -295.735681)
			(xy 90.287367 -295.704556) (xy 90.329988 -295.679949) (xy 90.376004 -295.662497) (xy 90.424223 -295.652653)
			(xy 90.473398 -295.650672) (xy 90.522253 -295.656604) (xy 90.569524 -295.670296) (xy 90.613986 -295.691394)
			(xy 90.654489 -295.71935) (xy 90.689982 -295.753442) (xy 90.719547 -295.792786) (xy 90.742418 -295.836363)
			(xy 90.758002 -295.883044) (xy 90.765897 -295.931621) (xy 90.766392 -295.956228) (xy 91.095334 -295.956228)
			(xy 91.099294 -295.907174) (xy 91.111071 -295.85939) (xy 91.130362 -295.814114) (xy 91.156665 -295.772518)
			(xy 91.1893 -295.735681) (xy 91.227421 -295.704556) (xy 91.270042 -295.679949) (xy 91.316058 -295.662497)
			(xy 91.364277 -295.652653) (xy 91.413452 -295.650672) (xy 91.462307 -295.656604) (xy 91.509578 -295.670296)
			(xy 91.55404 -295.691394) (xy 91.594543 -295.71935) (xy 91.630036 -295.753442) (xy 91.659601 -295.792786)
			(xy 91.682472 -295.836363) (xy 91.698056 -295.883044) (xy 91.705951 -295.931621) (xy 91.706446 -295.956228)
			(xy 92.035134 -295.956228) (xy 92.039094 -295.907174) (xy 92.050871 -295.85939) (xy 92.070162 -295.814114)
			(xy 92.096465 -295.772518) (xy 92.1291 -295.735681) (xy 92.167221 -295.704556) (xy 92.209842 -295.679949)
			(xy 92.255858 -295.662497) (xy 92.304077 -295.652653) (xy 92.353252 -295.650672) (xy 92.402107 -295.656604)
			(xy 92.449378 -295.670296) (xy 92.49384 -295.691394) (xy 92.534343 -295.71935) (xy 92.569836 -295.753442)
			(xy 92.599401 -295.792786) (xy 92.622272 -295.836363) (xy 92.637856 -295.883044) (xy 92.645751 -295.931621)
			(xy 92.646246 -295.956228) (xy 94.855296 -295.956228) (xy 94.859256 -295.907174) (xy 94.871033 -295.85939)
			(xy 94.890324 -295.814114) (xy 94.916627 -295.772518) (xy 94.949262 -295.735681) (xy 94.987383 -295.704556)
			(xy 95.030004 -295.679949) (xy 95.07602 -295.662497) (xy 95.124239 -295.652653) (xy 95.173414 -295.650672)
			(xy 95.222269 -295.656604) (xy 95.26954 -295.670296) (xy 95.314002 -295.691394) (xy 95.354505 -295.71935)
			(xy 95.389998 -295.753442) (xy 95.419563 -295.792786) (xy 95.442434 -295.836363) (xy 95.458018 -295.883044)
			(xy 95.465913 -295.931621) (xy 95.466408 -295.956228) (xy 95.465913 -295.980835) (xy 95.458018 -296.029412)
			(xy 95.442434 -296.076093) (xy 95.419563 -296.11967) (xy 95.389998 -296.159014) (xy 95.354505 -296.193106)
			(xy 95.314002 -296.221062) (xy 95.26954 -296.24216) (xy 95.222269 -296.255852) (xy 95.173414 -296.261784)
			(xy 95.124239 -296.259803) (xy 95.07602 -296.249959) (xy 95.030004 -296.232507) (xy 94.987383 -296.2079)
			(xy 94.949262 -296.176775) (xy 94.916627 -296.139938) (xy 94.890324 -296.098342) (xy 94.871033 -296.053066)
			(xy 94.859256 -296.005282) (xy 94.855296 -295.956228) (xy 92.646246 -295.956228) (xy 92.645751 -295.980835)
			(xy 92.637856 -296.029412) (xy 92.622272 -296.076093) (xy 92.599401 -296.11967) (xy 92.569836 -296.159014)
			(xy 92.534343 -296.193106) (xy 92.49384 -296.221062) (xy 92.449378 -296.24216) (xy 92.402107 -296.255852)
			(xy 92.353252 -296.261784) (xy 92.304077 -296.259803) (xy 92.255858 -296.249959) (xy 92.209842 -296.232507)
			(xy 92.167221 -296.2079) (xy 92.1291 -296.176775) (xy 92.096465 -296.139938) (xy 92.070162 -296.098342)
			(xy 92.050871 -296.053066) (xy 92.039094 -296.005282) (xy 92.035134 -295.956228) (xy 91.706446 -295.956228)
			(xy 91.705951 -295.980835) (xy 91.698056 -296.029412) (xy 91.682472 -296.076093) (xy 91.659601 -296.11967)
			(xy 91.630036 -296.159014) (xy 91.594543 -296.193106) (xy 91.55404 -296.221062) (xy 91.509578 -296.24216)
			(xy 91.462307 -296.255852) (xy 91.413452 -296.261784) (xy 91.364277 -296.259803) (xy 91.316058 -296.249959)
			(xy 91.270042 -296.232507) (xy 91.227421 -296.2079) (xy 91.1893 -296.176775) (xy 91.156665 -296.139938)
			(xy 91.130362 -296.098342) (xy 91.111071 -296.053066) (xy 91.099294 -296.005282) (xy 91.095334 -295.956228)
			(xy 90.766392 -295.956228) (xy 90.765897 -295.980835) (xy 90.758002 -296.029412) (xy 90.742418 -296.076093)
			(xy 90.719547 -296.11967) (xy 90.689982 -296.159014) (xy 90.654489 -296.193106) (xy 90.613986 -296.221062)
			(xy 90.569524 -296.24216) (xy 90.522253 -296.255852) (xy 90.473398 -296.261784) (xy 90.424223 -296.259803)
			(xy 90.376004 -296.249959) (xy 90.329988 -296.232507) (xy 90.287367 -296.2079) (xy 90.249246 -296.176775)
			(xy 90.216611 -296.139938) (xy 90.190308 -296.098342) (xy 90.171017 -296.053066) (xy 90.15924 -296.005282)
			(xy 90.15528 -295.956228) (xy 89.826338 -295.956228) (xy 89.825843 -295.980835) (xy 89.817948 -296.029412)
			(xy 89.802364 -296.076093) (xy 89.779493 -296.11967) (xy 89.749928 -296.159014) (xy 89.714435 -296.193106)
			(xy 89.673932 -296.221062) (xy 89.62947 -296.24216) (xy 89.582199 -296.255852) (xy 89.533344 -296.261784)
			(xy 89.484169 -296.259803) (xy 89.43595 -296.249959) (xy 89.389934 -296.232507) (xy 89.347313 -296.2079)
			(xy 89.309192 -296.176775) (xy 89.276557 -296.139938) (xy 89.250254 -296.098342) (xy 89.230963 -296.053066)
			(xy 89.219186 -296.005282) (xy 89.215226 -295.956228) (xy 88.886284 -295.956228) (xy 88.885789 -295.980835)
			(xy 88.877894 -296.029412) (xy 88.86231 -296.076093) (xy 88.839439 -296.11967) (xy 88.809874 -296.159014)
			(xy 88.774381 -296.193106) (xy 88.733878 -296.221062) (xy 88.689416 -296.24216) (xy 88.642145 -296.255852)
			(xy 88.59329 -296.261784) (xy 88.544115 -296.259803) (xy 88.495896 -296.249959) (xy 88.44988 -296.232507)
			(xy 88.407259 -296.2079) (xy 88.369138 -296.176775) (xy 88.336503 -296.139938) (xy 88.3102 -296.098342)
			(xy 88.290909 -296.053066) (xy 88.279132 -296.005282) (xy 88.275172 -295.956228) (xy 87.00643 -295.956228)
			(xy 87.005935 -295.980835) (xy 86.99804 -296.029412) (xy 86.982456 -296.076093) (xy 86.959585 -296.11967)
			(xy 86.93002 -296.159014) (xy 86.894527 -296.193106) (xy 86.854024 -296.221062) (xy 86.809562 -296.24216)
			(xy 86.762291 -296.255852) (xy 86.713436 -296.261784) (xy 86.664261 -296.259803) (xy 86.616042 -296.249959)
			(xy 86.570026 -296.232507) (xy 86.527405 -296.2079) (xy 86.489284 -296.176775) (xy 86.456649 -296.139938)
			(xy 86.430346 -296.098342) (xy 86.411055 -296.053066) (xy 86.399278 -296.005282) (xy 86.395318 -295.956228)
			(xy 86.066376 -295.956228) (xy 86.065881 -295.980835) (xy 86.057986 -296.029412) (xy 86.042402 -296.076093)
			(xy 86.019531 -296.11967) (xy 85.989966 -296.159014) (xy 85.954473 -296.193106) (xy 85.91397 -296.221062)
			(xy 85.869508 -296.24216) (xy 85.822237 -296.255852) (xy 85.773382 -296.261784) (xy 85.724207 -296.259803)
			(xy 85.675988 -296.249959) (xy 85.629972 -296.232507) (xy 85.587351 -296.2079) (xy 85.54923 -296.176775)
			(xy 85.516595 -296.139938) (xy 85.490292 -296.098342) (xy 85.471001 -296.053066) (xy 85.459224 -296.005282)
			(xy 85.455264 -295.956228) (xy 85.126322 -295.956228) (xy 85.125849 -295.980218) (xy 85.11834 -296.027607)
			(xy 85.10351 -296.073238) (xy 85.081725 -296.115988) (xy 85.053522 -296.154804) (xy 85.019594 -296.188731)
			(xy 84.980776 -296.216933) (xy 84.938026 -296.238715) (xy 84.892394 -296.253543) (xy 84.845004 -296.26105)
			(xy 84.821014 -296.261536) (xy 84.796779 -296.261065) (xy 84.748918 -296.253396) (xy 84.70287 -296.238264)
			(xy 84.659789 -296.21605) (xy 84.620758 -296.18731) (xy 84.586756 -296.152767) (xy 84.558636 -296.113286)
			(xy 84.537104 -296.06986) (xy 84.522702 -296.023579) (xy 84.518754 -295.999662) (xy 84.516722 -295.985438)
			(xy 84.49818 -295.96334) (xy 84.398358 -295.930066) (xy 84.389337 -295.927526) (xy 84.370634 -295.928424)
			(xy 84.353502 -295.93598) (xy 84.346542 -295.942258) (xy 83.199478 -297.089322) (xy 83.189513 -297.089801)
			(xy 83.171079 -297.097379) (xy 83.163664 -297.104054) (xy 81.952635 -298.315083) (xy 87.657172 -298.315083)
			(xy 87.657172 -298.251161) (xy 87.665183 -298.187743) (xy 87.68108 -298.125829) (xy 87.704612 -298.066396)
			(xy 87.735406 -298.010381) (xy 87.772979 -297.958666) (xy 87.816736 -297.912069) (xy 87.865989 -297.871324)
			(xy 87.91996 -297.837073) (xy 87.977799 -297.809856) (xy 88.038592 -297.790103) (xy 88.101382 -297.778125)
			(xy 88.165178 -297.774112) (xy 88.228974 -297.778125) (xy 88.291764 -297.790103) (xy 88.352557 -297.809856)
			(xy 88.410396 -297.837073) (xy 88.464367 -297.871324) (xy 88.51362 -297.912069) (xy 88.557377 -297.958666)
			(xy 88.59495 -298.010381) (xy 88.625744 -298.066396) (xy 88.649276 -298.125829) (xy 88.665173 -298.187743)
			(xy 88.673184 -298.251161) (xy 88.673686 -298.283122) (xy 88.673184 -298.315083) (xy 88.665173 -298.378501)
			(xy 88.649276 -298.440415) (xy 88.625744 -298.499848) (xy 88.59495 -298.555863) (xy 88.557377 -298.607578)
			(xy 88.51362 -298.654175) (xy 88.464367 -298.69492) (xy 88.410396 -298.729171) (xy 88.352557 -298.756388)
			(xy 88.291764 -298.776141) (xy 88.228974 -298.788119) (xy 88.165178 -298.792133) (xy 88.101382 -298.788119)
			(xy 88.038592 -298.776141) (xy 87.977799 -298.756388) (xy 87.91996 -298.729171) (xy 87.865989 -298.69492)
			(xy 87.816736 -298.654175) (xy 87.772979 -298.607578) (xy 87.735406 -298.555863) (xy 87.704612 -298.499848)
			(xy 87.68108 -298.440415) (xy 87.665183 -298.378501) (xy 87.657172 -298.315083) (xy 81.952635 -298.315083)
			(xy 78.488032 -301.779686) (xy 92.19006 -301.779686) (xy 92.194131 -301.724064) (xy 92.206257 -301.669627)
			(xy 92.22618 -301.617536) (xy 92.253476 -301.568901) (xy 92.287562 -301.524758) (xy 92.327711 -301.486049)
			(xy 92.373069 -301.453598) (xy 92.422669 -301.428097) (xy 92.475453 -301.41009) (xy 92.530296 -301.39996)
			(xy 92.58603 -301.397923) (xy 92.641467 -301.404023) (xy 92.695424 -301.418129) (xy 92.746753 -301.439941)
			(xy 92.794359 -301.468995) (xy 92.837227 -301.50467) (xy 92.874444 -301.546207) (xy 92.905217 -301.59272)
			(xy 92.928889 -301.643217) (xy 92.944957 -301.696624) (xy 92.953077 -301.7518) (xy 92.953586 -301.779686)
			(xy 92.953077 -301.807572) (xy 92.944957 -301.862748) (xy 92.928889 -301.916155) (xy 92.905217 -301.966652)
			(xy 92.874444 -302.013165) (xy 92.837227 -302.054702) (xy 92.794359 -302.090377) (xy 92.746753 -302.119431)
			(xy 92.695424 -302.141243) (xy 92.641467 -302.155349) (xy 92.58603 -302.161449) (xy 92.530296 -302.159412)
			(xy 92.475453 -302.149282) (xy 92.422669 -302.131275) (xy 92.373069 -302.105774) (xy 92.327711 -302.073323)
			(xy 92.287562 -302.034614) (xy 92.253476 -301.990471) (xy 92.22618 -301.941836) (xy 92.206257 -301.889745)
			(xy 92.194131 -301.835308) (xy 92.19006 -301.779686) (xy 78.488032 -301.779686) (xy 75.487276 -304.780442)
			(xy 78.81214 -304.780442) (xy 78.81617 -304.638107) (xy 78.828245 -304.496227) (xy 78.848328 -304.355259)
			(xy 78.876355 -304.215652) (xy 78.912235 -304.077854) (xy 78.955853 -303.942307) (xy 79.00707 -303.809445)
			(xy 79.065721 -303.679693) (xy 79.131619 -303.553467) (xy 79.204553 -303.431171) (xy 79.28429 -303.313198)
			(xy 79.370572 -303.199925) (xy 79.463125 -303.091714) (xy 79.561652 -302.988913) (xy 79.665837 -302.891851)
			(xy 79.775346 -302.800839) (xy 79.889829 -302.716167) (xy 80.008919 -302.638109) (xy 80.132234 -302.566913)
			(xy 80.25938 -302.502807) (xy 80.389949 -302.445998) (xy 80.523523 -302.396666) (xy 80.659674 -302.35497)
			(xy 80.797965 -302.321044) (xy 80.937955 -302.294996) (xy 81.079194 -302.27691) (xy 81.22123 -302.266843)
			(xy 81.363608 -302.264828) (xy 81.505872 -302.270871) (xy 81.647566 -302.284953) (xy 81.788236 -302.307029)
			(xy 81.927433 -302.337029) (xy 82.064709 -302.374855) (xy 82.199625 -302.420387) (xy 82.331749 -302.473478)
			(xy 82.460658 -302.53396) (xy 82.585939 -302.601638) (xy 82.70719 -302.676295) (xy 82.824023 -302.757693)
			(xy 82.873373 -302.7964) (xy 84.778634 -302.7964) (xy 84.782549 -302.719211) (xy 84.794252 -302.642815)
			(xy 84.813625 -302.567994) (xy 84.840468 -302.495517) (xy 84.874505 -302.426128) (xy 84.915388 -302.360538)
			(xy 84.962697 -302.299421) (xy 85.015946 -302.243403) (xy 85.074589 -302.193061) (xy 85.138025 -302.148909)
			(xy 85.205602 -302.111402) (xy 85.276627 -302.080924) (xy 85.35037 -302.057788) (xy 85.426076 -302.042231)
			(xy 85.502968 -302.034413) (xy 85.541612 -302.03394) (xy 85.579854 -302.034414) (xy 85.655949 -302.042117)
			(xy 85.730889 -302.057403) (xy 85.803921 -302.08012) (xy 85.8393 -302.094646) (xy 85.848893 -302.098199)
			(xy 85.869331 -302.098199) (xy 85.878924 -302.094646) (xy 85.91431 -302.08014) (xy 85.987342 -302.057433)
			(xy 86.06228 -302.042148) (xy 86.138372 -302.034437) (xy 86.176612 -302.03394) (xy 86.215259 -302.034334)
			(xy 86.292157 -302.042155) (xy 86.367869 -302.057715) (xy 86.441619 -302.080855) (xy 86.512649 -302.111338)
			(xy 86.58023 -302.148849) (xy 86.643671 -302.193006) (xy 86.702318 -302.243354) (xy 86.755571 -302.299377)
			(xy 86.802883 -302.3605) (xy 86.843769 -302.426096) (xy 86.877808 -302.495491) (xy 86.904653 -302.567974)
			(xy 86.924027 -302.642801) (xy 86.935731 -302.719205) (xy 86.939646 -302.7964) (xy 86.935731 -302.873595)
			(xy 86.924027 -302.949999) (xy 86.904653 -303.024826) (xy 86.877808 -303.097309) (xy 86.843769 -303.166704)
			(xy 86.802883 -303.2323) (xy 86.785179 -303.255172) (xy 92.274134 -303.255172) (xy 92.278205 -303.19955)
			(xy 92.290331 -303.145113) (xy 92.310254 -303.093022) (xy 92.33755 -303.044387) (xy 92.371636 -303.000244)
			(xy 92.411785 -302.961535) (xy 92.457143 -302.929084) (xy 92.506743 -302.903583) (xy 92.559527 -302.885576)
			(xy 92.61437 -302.875446) (xy 92.670104 -302.873409) (xy 92.725541 -302.879509) (xy 92.779498 -302.893615)
			(xy 92.830827 -302.915427) (xy 92.878433 -302.944481) (xy 92.921301 -302.980156) (xy 92.958518 -303.021693)
			(xy 92.989291 -303.068206) (xy 93.012963 -303.118703) (xy 93.029031 -303.17211) (xy 93.037151 -303.227286)
			(xy 93.03766 -303.255172) (xy 93.037151 -303.283058) (xy 93.029031 -303.338234) (xy 93.012963 -303.391641)
			(xy 92.989291 -303.442138) (xy 92.958518 -303.488651) (xy 92.921301 -303.530188) (xy 92.878433 -303.565863)
			(xy 92.830827 -303.594917) (xy 92.779498 -303.616729) (xy 92.725541 -303.630835) (xy 92.670104 -303.636935)
			(xy 92.61437 -303.634898) (xy 92.559527 -303.624768) (xy 92.506743 -303.606761) (xy 92.457143 -303.58126)
			(xy 92.411785 -303.548809) (xy 92.371636 -303.5101) (xy 92.33755 -303.465957) (xy 92.310254 -303.417322)
			(xy 92.290331 -303.365231) (xy 92.278205 -303.310794) (xy 92.274134 -303.255172) (xy 86.785179 -303.255172)
			(xy 86.755571 -303.293423) (xy 86.702318 -303.349446) (xy 86.643671 -303.399794) (xy 86.58023 -303.443951)
			(xy 86.512649 -303.481462) (xy 86.441619 -303.511945) (xy 86.367869 -303.535085) (xy 86.292157 -303.550645)
			(xy 86.215259 -303.558466) (xy 86.176612 -303.558956) (xy 86.138371 -303.558474) (xy 86.062276 -303.550774)
			(xy 85.987335 -303.53549) (xy 85.914303 -303.512775) (xy 85.878924 -303.49825) (xy 85.869331 -303.494697)
			(xy 85.848893 -303.494697) (xy 85.8393 -303.49825) (xy 85.803924 -303.512781) (xy 85.730888 -303.535481)
			(xy 85.655947 -303.550759) (xy 85.579853 -303.558462) (xy 85.541612 -303.558956) (xy 85.502968 -303.558387)
			(xy 85.426076 -303.550569) (xy 85.35037 -303.535012) (xy 85.276627 -303.511876) (xy 85.205602 -303.481398)
			(xy 85.138025 -303.443891) (xy 85.074589 -303.399739) (xy 85.015946 -303.349397) (xy 84.962697 -303.293379)
			(xy 84.915388 -303.232262) (xy 84.874505 -303.166672) (xy 84.840468 -303.097283) (xy 84.813625 -303.024806)
			(xy 84.794252 -302.949985) (xy 84.782549 -302.873589) (xy 84.778634 -302.7964) (xy 82.873373 -302.7964)
			(xy 82.936064 -302.84557) (xy 83.042954 -302.939645) (xy 83.144351 -303.039617) (xy 83.239929 -303.145165)
			(xy 83.329383 -303.255951) (xy 83.412425 -303.37162) (xy 83.488791 -303.491803) (xy 83.558235 -303.616113)
			(xy 83.620535 -303.744154) (xy 83.675491 -303.875513) (xy 83.722928 -304.009772) (xy 83.729734 -304.033174)
			(xy 92.945966 -304.033174) (xy 92.946468 -304.001213) (xy 92.954479 -303.937795) (xy 92.970376 -303.875881)
			(xy 92.993908 -303.816448) (xy 93.024702 -303.760433) (xy 93.062275 -303.708718) (xy 93.106032 -303.662121)
			(xy 93.155285 -303.621376) (xy 93.209256 -303.587125) (xy 93.267095 -303.559908) (xy 93.327888 -303.540155)
			(xy 93.390678 -303.528177) (xy 93.454474 -303.524164) (xy 93.51827 -303.528177) (xy 93.58106 -303.540155)
			(xy 93.641853 -303.559908) (xy 93.699692 -303.587125) (xy 93.753663 -303.621376) (xy 93.802916 -303.662121)
			(xy 93.846673 -303.708718) (xy 93.884246 -303.760433) (xy 93.91504 -303.816448) (xy 93.938572 -303.875881)
			(xy 93.954469 -303.937795) (xy 93.96248 -304.001213) (xy 93.962982 -304.033174) (xy 93.962469 -304.065957)
			(xy 93.954045 -304.13098) (xy 93.937332 -304.19438) (xy 93.912609 -304.255106) (xy 93.880284 -304.312151)
			(xy 93.840896 -304.364567) (xy 93.795096 -304.411486) (xy 93.769688 -304.432208) (xy 93.762771 -304.438106)
			(xy 93.753283 -304.453598) (xy 93.751146 -304.462434) (xy 93.745304 -304.492152) (xy 93.743955 -304.500954)
			(xy 93.74683 -304.518517) (xy 93.750892 -304.526442) (xy 93.765761 -304.554834) (xy 93.786839 -304.615355)
			(xy 93.797504 -304.678548) (xy 93.798136 -304.710592) (xy 93.79765 -304.737843) (xy 93.789894 -304.791791)
			(xy 93.774539 -304.844086) (xy 93.751897 -304.893663) (xy 93.722431 -304.939513) (xy 93.68674 -304.980704)
			(xy 93.645549 -305.016395) (xy 93.599699 -305.045861) (xy 93.550122 -305.068503) (xy 93.497827 -305.083858)
			(xy 93.443879 -305.091614) (xy 93.389377 -305.091614) (xy 93.335429 -305.083858) (xy 93.283134 -305.068503)
			(xy 93.233557 -305.045861) (xy 93.187707 -305.016395) (xy 93.146516 -304.980704) (xy 93.110825 -304.939513)
			(xy 93.081359 -304.893663) (xy 93.058717 -304.844086) (xy 93.043362 -304.791791) (xy 93.035606 -304.737843)
			(xy 93.03512 -304.710592) (xy 93.035659 -304.681226) (xy 93.0447 -304.623194) (xy 93.062521 -304.567231)
			(xy 93.088702 -304.514657) (xy 93.105224 -304.490374) (xy 93.110038 -304.482893) (xy 93.114699 -304.465737)
			(xy 93.114368 -304.456846) (xy 93.111574 -304.426366) (xy 93.110508 -304.417453) (xy 93.102963 -304.401181)
			(xy 93.096842 -304.394616) (xy 93.073395 -304.370658) (xy 93.032348 -304.317659) (xy 92.99862 -304.259726)
			(xy 92.972796 -304.197864) (xy 92.955324 -304.133145) (xy 92.946506 -304.066692) (xy 92.945966 -304.033174)
			(xy 83.729734 -304.033174) (xy 83.762692 -304.146499) (xy 83.794658 -304.285257) (xy 83.818723 -304.425601)
			(xy 83.834809 -304.567082) (xy 83.842864 -304.709246) (xy 83.843071 -304.738489) (xy 91.753938 -304.738489)
			(xy 91.753938 -304.674567) (xy 91.761949 -304.611149) (xy 91.777846 -304.549235) (xy 91.801378 -304.489802)
			(xy 91.832172 -304.433787) (xy 91.869745 -304.382072) (xy 91.913502 -304.335475) (xy 91.962755 -304.29473)
			(xy 92.016726 -304.260479) (xy 92.074565 -304.233262) (xy 92.135358 -304.213509) (xy 92.198148 -304.201531)
			(xy 92.261944 -304.197518) (xy 92.32574 -304.201531) (xy 92.38853 -304.213509) (xy 92.449323 -304.233262)
			(xy 92.507162 -304.260479) (xy 92.561133 -304.29473) (xy 92.610386 -304.335475) (xy 92.654143 -304.382072)
			(xy 92.691716 -304.433787) (xy 92.72251 -304.489802) (xy 92.746042 -304.549235) (xy 92.761939 -304.611149)
			(xy 92.76995 -304.674567) (xy 92.770452 -304.706528) (xy 92.76995 -304.738489) (xy 92.761939 -304.801907)
			(xy 92.746042 -304.863821) (xy 92.72251 -304.923254) (xy 92.691716 -304.979269) (xy 92.654143 -305.030984)
			(xy 92.610386 -305.077581) (xy 92.561133 -305.118326) (xy 92.507162 -305.152577) (xy 92.449323 -305.179794)
			(xy 92.38853 -305.199547) (xy 92.32574 -305.211525) (xy 92.261944 -305.215539) (xy 92.198148 -305.211525)
			(xy 92.135358 -305.199547) (xy 92.074565 -305.179794) (xy 92.016726 -305.152577) (xy 91.962755 -305.118326)
			(xy 91.913502 -305.077581) (xy 91.869745 -305.030984) (xy 91.832172 -304.979269) (xy 91.801378 -304.923254)
			(xy 91.777846 -304.863821) (xy 91.761949 -304.801907) (xy 91.753938 -304.738489) (xy 83.843071 -304.738489)
			(xy 83.843368 -304.780442) (xy 83.842864 -304.851638) (xy 83.834809 -304.993802) (xy 83.818723 -305.135283)
			(xy 83.794658 -305.275627) (xy 83.762692 -305.414385) (xy 83.722928 -305.551112) (xy 83.675491 -305.685371)
			(xy 83.620535 -305.81673) (xy 83.558235 -305.944771) (xy 83.488791 -306.069081) (xy 83.412425 -306.189264)
			(xy 83.329383 -306.304933) (xy 83.239929 -306.415719) (xy 83.196059 -306.464165) (xy 87.854784 -306.464165)
			(xy 87.854784 -306.400243) (xy 87.862795 -306.336825) (xy 87.878692 -306.274911) (xy 87.902224 -306.215478)
			(xy 87.933018 -306.159463) (xy 87.970591 -306.107748) (xy 88.014348 -306.061151) (xy 88.063601 -306.020406)
			(xy 88.117572 -305.986155) (xy 88.175411 -305.958938) (xy 88.236204 -305.939185) (xy 88.298994 -305.927207)
			(xy 88.36279 -305.923194) (xy 88.426586 -305.927207) (xy 88.489376 -305.939185) (xy 88.550169 -305.958938)
			(xy 88.608008 -305.986155) (xy 88.659611 -306.018903) (xy 93.552258 -306.018903) (xy 93.552258 -305.954981)
			(xy 93.560269 -305.891563) (xy 93.576166 -305.829649) (xy 93.599698 -305.770216) (xy 93.630492 -305.714201)
			(xy 93.668065 -305.662486) (xy 93.711822 -305.615889) (xy 93.761075 -305.575144) (xy 93.815046 -305.540893)
			(xy 93.872885 -305.513676) (xy 93.933678 -305.493923) (xy 93.996468 -305.481945) (xy 94.060264 -305.477932)
			(xy 94.12406 -305.481945) (xy 94.18685 -305.493923) (xy 94.247643 -305.513676) (xy 94.305482 -305.540893)
			(xy 94.359453 -305.575144) (xy 94.408706 -305.615889) (xy 94.452463 -305.662486) (xy 94.490036 -305.714201)
			(xy 94.52083 -305.770216) (xy 94.544362 -305.829649) (xy 94.560259 -305.891563) (xy 94.56827 -305.954981)
			(xy 94.568772 -305.986942) (xy 94.56827 -306.018903) (xy 94.560259 -306.082321) (xy 94.544362 -306.144235)
			(xy 94.52083 -306.203668) (xy 94.490036 -306.259683) (xy 94.452463 -306.311398) (xy 94.408706 -306.357995)
			(xy 94.359453 -306.39874) (xy 94.305482 -306.432991) (xy 94.247643 -306.460208) (xy 94.18685 -306.479961)
			(xy 94.12406 -306.491939) (xy 94.060264 -306.495953) (xy 93.996468 -306.491939) (xy 93.933678 -306.479961)
			(xy 93.872885 -306.460208) (xy 93.815046 -306.432991) (xy 93.761075 -306.39874) (xy 93.711822 -306.357995)
			(xy 93.668065 -306.311398) (xy 93.630492 -306.259683) (xy 93.599698 -306.203668) (xy 93.576166 -306.144235)
			(xy 93.560269 -306.082321) (xy 93.552258 -306.018903) (xy 88.659611 -306.018903) (xy 88.661979 -306.020406)
			(xy 88.711232 -306.061151) (xy 88.754989 -306.107748) (xy 88.792562 -306.159463) (xy 88.823356 -306.215478)
			(xy 88.846888 -306.274911) (xy 88.862785 -306.336825) (xy 88.870796 -306.400243) (xy 88.871298 -306.432204)
			(xy 88.870796 -306.464165) (xy 88.862785 -306.527583) (xy 88.846888 -306.589497) (xy 88.823356 -306.64893)
			(xy 88.792562 -306.704945) (xy 88.754989 -306.75666) (xy 88.711232 -306.803257) (xy 88.661979 -306.844002)
			(xy 88.608008 -306.878253) (xy 88.550169 -306.90547) (xy 88.489376 -306.925223) (xy 88.426586 -306.937201)
			(xy 88.36279 -306.941215) (xy 88.298994 -306.937201) (xy 88.236204 -306.925223) (xy 88.175411 -306.90547)
			(xy 88.117572 -306.878253) (xy 88.063601 -306.844002) (xy 88.014348 -306.803257) (xy 87.970591 -306.75666)
			(xy 87.933018 -306.704945) (xy 87.902224 -306.64893) (xy 87.878692 -306.589497) (xy 87.862795 -306.527583)
			(xy 87.854784 -306.464165) (xy 83.196059 -306.464165) (xy 83.144351 -306.521267) (xy 83.042954 -306.621239)
			(xy 82.936064 -306.715314) (xy 82.824023 -306.803191) (xy 82.70719 -306.884589) (xy 82.585939 -306.959246)
			(xy 82.460658 -307.026924) (xy 82.331749 -307.087406) (xy 82.199625 -307.140497) (xy 82.064709 -307.186029)
			(xy 81.927433 -307.223855) (xy 81.788236 -307.253855) (xy 81.647566 -307.275931) (xy 81.505872 -307.290013)
			(xy 81.363608 -307.296056) (xy 81.22123 -307.294041) (xy 81.079194 -307.283974) (xy 80.937955 -307.265888)
			(xy 80.797965 -307.23984) (xy 80.659674 -307.205914) (xy 80.523523 -307.164218) (xy 80.389949 -307.114886)
			(xy 80.25938 -307.058077) (xy 80.132234 -306.993971) (xy 80.008919 -306.922775) (xy 79.889829 -306.844717)
			(xy 79.775346 -306.760045) (xy 79.665837 -306.669033) (xy 79.561652 -306.571971) (xy 79.463125 -306.46917)
			(xy 79.370572 -306.360959) (xy 79.28429 -306.247686) (xy 79.204553 -306.129713) (xy 79.131619 -306.007417)
			(xy 79.065721 -305.881191) (xy 79.00707 -305.751439) (xy 78.955853 -305.618577) (xy 78.912235 -305.48303)
			(xy 78.876355 -305.345232) (xy 78.848328 -305.205625) (xy 78.828245 -305.064657) (xy 78.81617 -304.922777)
			(xy 78.81214 -304.780442) (xy 75.487276 -304.780442) (xy 72.882549 -307.385169) (xy 88.750896 -307.385169)
			(xy 88.750896 -307.321247) (xy 88.758907 -307.257829) (xy 88.774804 -307.195915) (xy 88.798336 -307.136482)
			(xy 88.82913 -307.080467) (xy 88.866703 -307.028752) (xy 88.91046 -306.982155) (xy 88.959713 -306.94141)
			(xy 89.013684 -306.907159) (xy 89.071523 -306.879942) (xy 89.132316 -306.860189) (xy 89.195106 -306.848211)
			(xy 89.258902 -306.844198) (xy 89.322698 -306.848211) (xy 89.385488 -306.860189) (xy 89.446281 -306.879942)
			(xy 89.50412 -306.907159) (xy 89.558091 -306.94141) (xy 89.607344 -306.982155) (xy 89.651101 -307.028752)
			(xy 89.688674 -307.080467) (xy 89.707611 -307.114913) (xy 90.238828 -307.114913) (xy 90.238828 -307.050991)
			(xy 90.246839 -306.987573) (xy 90.262736 -306.925659) (xy 90.286268 -306.866226) (xy 90.317062 -306.810211)
			(xy 90.354635 -306.758496) (xy 90.398392 -306.711899) (xy 90.447645 -306.671154) (xy 90.501616 -306.636903)
			(xy 90.559455 -306.609686) (xy 90.620248 -306.589933) (xy 90.683038 -306.577955) (xy 90.746834 -306.573942)
			(xy 90.81063 -306.577955) (xy 90.833276 -306.582275) (xy 91.420182 -306.582275) (xy 91.420182 -306.518353)
			(xy 91.428193 -306.454935) (xy 91.44409 -306.393021) (xy 91.467622 -306.333588) (xy 91.498416 -306.277573)
			(xy 91.535989 -306.225858) (xy 91.579746 -306.179261) (xy 91.628999 -306.138516) (xy 91.68297 -306.104265)
			(xy 91.740809 -306.077048) (xy 91.801602 -306.057295) (xy 91.864392 -306.045317) (xy 91.928188 -306.041304)
			(xy 91.991984 -306.045317) (xy 92.054774 -306.057295) (xy 92.115567 -306.077048) (xy 92.173406 -306.104265)
			(xy 92.227377 -306.138516) (xy 92.27663 -306.179261) (xy 92.320387 -306.225858) (xy 92.35796 -306.277573)
			(xy 92.388754 -306.333588) (xy 92.412286 -306.393021) (xy 92.428183 -306.454935) (xy 92.436194 -306.518353)
			(xy 92.436696 -306.550314) (xy 92.436194 -306.582275) (xy 92.428183 -306.645693) (xy 92.412286 -306.707607)
			(xy 92.40187 -306.733913) (xy 95.064828 -306.733913) (xy 95.064828 -306.669991) (xy 95.072839 -306.606573)
			(xy 95.088736 -306.544659) (xy 95.112268 -306.485226) (xy 95.143062 -306.429211) (xy 95.180635 -306.377496)
			(xy 95.224392 -306.330899) (xy 95.273645 -306.290154) (xy 95.327616 -306.255903) (xy 95.385455 -306.228686)
			(xy 95.446248 -306.208933) (xy 95.509038 -306.196955) (xy 95.572834 -306.192942) (xy 95.63663 -306.196955)
			(xy 95.69942 -306.208933) (xy 95.760213 -306.228686) (xy 95.818052 -306.255903) (xy 95.872023 -306.290154)
			(xy 95.921276 -306.330899) (xy 95.965033 -306.377496) (xy 96.002606 -306.429211) (xy 96.0334 -306.485226)
			(xy 96.056932 -306.544659) (xy 96.072829 -306.606573) (xy 96.08084 -306.669991) (xy 96.081342 -306.701952)
			(xy 96.08084 -306.733913) (xy 96.072829 -306.797331) (xy 96.056932 -306.859245) (xy 96.0334 -306.918678)
			(xy 96.002606 -306.974693) (xy 95.965033 -307.026408) (xy 95.921276 -307.073005) (xy 95.872023 -307.11375)
			(xy 95.818052 -307.148001) (xy 95.760213 -307.175218) (xy 95.69942 -307.194971) (xy 95.63663 -307.206949)
			(xy 95.572834 -307.210963) (xy 95.509038 -307.206949) (xy 95.446248 -307.194971) (xy 95.385455 -307.175218)
			(xy 95.327616 -307.148001) (xy 95.273645 -307.11375) (xy 95.224392 -307.073005) (xy 95.180635 -307.026408)
			(xy 95.143062 -306.974693) (xy 95.112268 -306.918678) (xy 95.088736 -306.859245) (xy 95.072839 -306.797331)
			(xy 95.064828 -306.733913) (xy 92.40187 -306.733913) (xy 92.388754 -306.76704) (xy 92.35796 -306.823055)
			(xy 92.320387 -306.87477) (xy 92.27663 -306.921367) (xy 92.227377 -306.962112) (xy 92.173406 -306.996363)
			(xy 92.115567 -307.02358) (xy 92.054774 -307.043333) (xy 91.991984 -307.055311) (xy 91.928188 -307.059325)
			(xy 91.864392 -307.055311) (xy 91.801602 -307.043333) (xy 91.740809 -307.02358) (xy 91.68297 -306.996363)
			(xy 91.628999 -306.962112) (xy 91.579746 -306.921367) (xy 91.535989 -306.87477) (xy 91.498416 -306.823055)
			(xy 91.467622 -306.76704) (xy 91.44409 -306.707607) (xy 91.428193 -306.645693) (xy 91.420182 -306.582275)
			(xy 90.833276 -306.582275) (xy 90.87342 -306.589933) (xy 90.934213 -306.609686) (xy 90.992052 -306.636903)
			(xy 91.046023 -306.671154) (xy 91.095276 -306.711899) (xy 91.139033 -306.758496) (xy 91.176606 -306.810211)
			(xy 91.2074 -306.866226) (xy 91.230932 -306.925659) (xy 91.246829 -306.987573) (xy 91.25484 -307.050991)
			(xy 91.255342 -307.082952) (xy 91.25484 -307.114913) (xy 91.246829 -307.178331) (xy 91.237536 -307.214524)
			(xy 93.048326 -307.214524) (xy 93.052397 -307.158902) (xy 93.064523 -307.104465) (xy 93.084446 -307.052374)
			(xy 93.111742 -307.003739) (xy 93.145828 -306.959596) (xy 93.185977 -306.920887) (xy 93.231335 -306.888436)
			(xy 93.280935 -306.862935) (xy 93.333719 -306.844928) (xy 93.388562 -306.834798) (xy 93.444296 -306.832761)
			(xy 93.499733 -306.838861) (xy 93.55369 -306.852967) (xy 93.605019 -306.874779) (xy 93.652625 -306.903833)
			(xy 93.695493 -306.939508) (xy 93.73271 -306.981045) (xy 93.763483 -307.027558) (xy 93.787155 -307.078055)
			(xy 93.803223 -307.131462) (xy 93.811343 -307.186638) (xy 93.811852 -307.214524) (xy 93.811343 -307.24241)
			(xy 93.803223 -307.297586) (xy 93.787155 -307.350993) (xy 93.763483 -307.40149) (xy 93.73271 -307.448003)
			(xy 93.695493 -307.48954) (xy 93.652625 -307.525215) (xy 93.605019 -307.554269) (xy 93.55369 -307.576081)
			(xy 93.499733 -307.590187) (xy 93.444296 -307.596287) (xy 93.388562 -307.59425) (xy 93.333719 -307.58412)
			(xy 93.280935 -307.566113) (xy 93.231335 -307.540612) (xy 93.185977 -307.508161) (xy 93.145828 -307.469452)
			(xy 93.111742 -307.425309) (xy 93.084446 -307.376674) (xy 93.064523 -307.324583) (xy 93.052397 -307.270146)
			(xy 93.048326 -307.214524) (xy 91.237536 -307.214524) (xy 91.230932 -307.240245) (xy 91.2074 -307.299678)
			(xy 91.176606 -307.355693) (xy 91.139033 -307.407408) (xy 91.095276 -307.454005) (xy 91.046023 -307.49475)
			(xy 90.992052 -307.529001) (xy 90.934213 -307.556218) (xy 90.87342 -307.575971) (xy 90.81063 -307.587949)
			(xy 90.746834 -307.591963) (xy 90.683038 -307.587949) (xy 90.620248 -307.575971) (xy 90.559455 -307.556218)
			(xy 90.501616 -307.529001) (xy 90.447645 -307.49475) (xy 90.398392 -307.454005) (xy 90.354635 -307.407408)
			(xy 90.317062 -307.355693) (xy 90.286268 -307.299678) (xy 90.262736 -307.240245) (xy 90.246839 -307.178331)
			(xy 90.238828 -307.114913) (xy 89.707611 -307.114913) (xy 89.719468 -307.136482) (xy 89.743 -307.195915)
			(xy 89.758897 -307.257829) (xy 89.766908 -307.321247) (xy 89.76741 -307.353208) (xy 89.766908 -307.385169)
			(xy 89.758897 -307.448587) (xy 89.743 -307.510501) (xy 89.719468 -307.569934) (xy 89.688674 -307.625949)
			(xy 89.651101 -307.677664) (xy 89.607344 -307.724261) (xy 89.558091 -307.765006) (xy 89.50412 -307.799257)
			(xy 89.446281 -307.826474) (xy 89.385488 -307.846227) (xy 89.322698 -307.858205) (xy 89.258902 -307.862219)
			(xy 89.195106 -307.858205) (xy 89.132316 -307.846227) (xy 89.071523 -307.826474) (xy 89.013684 -307.799257)
			(xy 88.959713 -307.765006) (xy 88.91046 -307.724261) (xy 88.866703 -307.677664) (xy 88.82913 -307.625949)
			(xy 88.798336 -307.569934) (xy 88.774804 -307.510501) (xy 88.758907 -307.448587) (xy 88.750896 -307.385169)
			(xy 72.882549 -307.385169) (xy 70.583732 -309.683986) (xy 78.652905 -309.683986) (xy 78.652905 -309.632014)
			(xy 78.661035 -309.580682) (xy 78.677095 -309.531254) (xy 78.700688 -309.484947) (xy 78.731235 -309.4429)
			(xy 78.767984 -309.40615) (xy 78.810028 -309.3756) (xy 78.856334 -309.352003) (xy 78.905761 -309.33594)
			(xy 78.957092 -309.327807) (xy 78.983078 -309.327296) (xy 78.999899 -309.32751) (xy 79.033366 -309.330946)
			(xy 79.04988 -309.334154) (xy 79.061407 -309.335998) (xy 79.083983 -309.330144) (xy 79.101664 -309.314933)
			(xy 79.106776 -309.304436) (xy 79.121518 -309.271638) (xy 79.158868 -309.210193) (xy 79.181198 -309.182008)
			(xy 79.186433 -309.175061) (xy 79.192281 -309.158695) (xy 79.192628 -309.150004) (xy 79.192628 -308.995826)
			(xy 79.192246 -308.987081) (xy 79.186421 -308.97059) (xy 79.181198 -308.963568) (xy 79.162531 -308.940162)
			(xy 79.130217 -308.889761) (xy 79.104057 -308.835909) (xy 79.084417 -308.779352) (xy 79.077566 -308.750208)
			(xy 79.074502 -308.738946) (xy 79.06001 -308.720689) (xy 79.038937 -308.710723) (xy 79.027274 -308.71033)
			(xy 79.023464 -308.71033) (xy 79.02321 -308.71033) (xy 78.997222 -308.709804) (xy 78.945886 -308.701674)
			(xy 78.896453 -308.685614) (xy 78.850141 -308.662018) (xy 78.808091 -308.631468) (xy 78.771338 -308.594716)
			(xy 78.740787 -308.552667) (xy 78.71719 -308.506356) (xy 78.701128 -308.456924) (xy 78.692997 -308.405588)
			(xy 78.692997 -308.353612) (xy 78.701128 -308.302276) (xy 78.71719 -308.252844) (xy 78.740787 -308.206533)
			(xy 78.771338 -308.164484) (xy 78.808091 -308.127732) (xy 78.850141 -308.097182) (xy 78.896453 -308.073586)
			(xy 78.945886 -308.057526) (xy 78.997222 -308.049396) (xy 79.02321 -308.048914) (xy 79.047989 -308.049367)
			(xy 79.096992 -308.056757) (xy 79.144345 -308.07137) (xy 79.188991 -308.092881) (xy 79.22993 -308.120807)
			(xy 79.266249 -308.154525) (xy 79.282036 -308.173628) (xy 79.289703 -308.182366) (xy 79.310676 -308.192336)
			(xy 79.333897 -308.192065) (xy 79.34452 -308.187344) (xy 79.371291 -308.174267) (xy 79.427222 -308.153727)
			(xy 79.485172 -308.139877) (xy 79.544345 -308.132906) (xy 79.574136 -308.13248) (xy 79.604867 -308.132922)
			(xy 79.665881 -308.140334) (xy 79.725557 -308.155046) (xy 79.783025 -308.176844) (xy 79.837446 -308.20541)
			(xy 79.888028 -308.240326) (xy 79.934032 -308.281085) (xy 79.974789 -308.327091) (xy 80.009703 -308.377674)
			(xy 80.038266 -308.432097) (xy 80.060061 -308.489566) (xy 80.062386 -308.499) (xy 88.375291 -308.499)
			(xy 88.379305 -308.435208) (xy 88.391281 -308.372422) (xy 88.411032 -308.311632) (xy 88.438245 -308.253797)
			(xy 88.472492 -308.199828) (xy 88.513233 -308.150577) (xy 88.559825 -308.106819) (xy 88.611534 -308.069246)
			(xy 88.667543 -308.03845) (xy 88.726971 -308.014916) (xy 88.78888 -307.999015) (xy 88.852293 -307.990999)
			(xy 88.884252 -307.990494) (xy 88.915807 -307.990985) (xy 88.978432 -307.998793) (xy 89.039608 -308.014296)
			(xy 89.098393 -308.037255) (xy 89.153883 -308.067316) (xy 89.205224 -308.104017) (xy 89.251626 -308.146792)
			(xy 89.272364 -308.17058) (xy 89.279033 -308.177673) (xy 89.296261 -308.186696) (xy 89.305892 -308.188106)
			(xy 89.386156 -308.196488) (xy 89.404698 -308.191154) (xy 89.412572 -308.185058) (xy 89.432771 -308.169776)
			(xy 89.476437 -308.144108) (xy 89.523118 -308.124452) (xy 89.571992 -308.111153) (xy 89.622197 -308.104446)
			(xy 89.647522 -308.104032) (xy 89.674775 -308.104439) (xy 89.728726 -308.112199) (xy 89.781024 -308.127558)
			(xy 89.830603 -308.150203) (xy 89.876456 -308.179673) (xy 89.917648 -308.215368) (xy 89.953341 -308.256562)
			(xy 89.982808 -308.302416) (xy 90.00545 -308.351997) (xy 90.020805 -308.404295) (xy 90.028562 -308.458247)
			(xy 90.028562 -308.512753) (xy 90.020805 -308.566705) (xy 90.00545 -308.619003) (xy 89.982808 -308.668584)
			(xy 89.953341 -308.714438) (xy 89.917648 -308.755632) (xy 89.876456 -308.791327) (xy 89.830603 -308.820797)
			(xy 89.781024 -308.843442) (xy 89.728726 -308.858801) (xy 89.674775 -308.866561) (xy 89.647522 -308.867048)
			(xy 89.617533 -308.866515) (xy 89.558297 -308.85712) (xy 89.501259 -308.838573) (xy 89.447825 -308.811331)
			(xy 89.42324 -308.79415) (xy 89.415112 -308.788308) (xy 89.396316 -308.783736) (xy 89.306908 -308.795928)
			(xy 89.290144 -308.80558) (xy 89.283794 -308.813454) (xy 89.263071 -308.838942) (xy 89.216142 -308.884911)
			(xy 89.163684 -308.924452) (xy 89.10657 -308.956907) (xy 89.045751 -308.981735) (xy 88.982241 -308.998523)
			(xy 88.917098 -309.006991) (xy 88.884252 -309.00751) (xy 88.852293 -309.007001) (xy 88.78888 -308.998985)
			(xy 88.726971 -308.983084) (xy 88.667543 -308.95955) (xy 88.611534 -308.928754) (xy 88.559825 -308.891181)
			(xy 88.513233 -308.847423) (xy 88.472492 -308.798172) (xy 88.438245 -308.744203) (xy 88.411032 -308.686368)
			(xy 88.391281 -308.625578) (xy 88.379305 -308.562792) (xy 88.375291 -308.499) (xy 80.062386 -308.499)
			(xy 80.07477 -308.549242) (xy 80.08218 -308.610257) (xy 80.082644 -308.640988) (xy 80.082051 -308.675953)
			(xy 80.072452 -308.745222) (xy 80.053446 -308.81252) (xy 80.025393 -308.876577) (xy 79.988823 -308.936184)
			(xy 79.967074 -308.963568) (xy 79.961814 -308.970574) (xy 79.955962 -308.987071) (xy 79.955644 -308.995826)
			(xy 79.955644 -309.14975) (xy 79.955977 -309.1585) (xy 79.961834 -309.174992) (xy 79.967074 -309.182008)
			(xy 79.988812 -309.209399) (xy 80.025366 -309.269012) (xy 80.053413 -309.333068) (xy 80.072425 -309.400362)
			(xy 80.082043 -309.469625) (xy 80.082644 -309.504588) (xy 80.082133 -309.535317) (xy 80.079424 -309.557631)
			(xy 85.733122 -309.557631) (xy 85.733122 -309.493709) (xy 85.741133 -309.430291) (xy 85.75703 -309.368377)
			(xy 85.780562 -309.308944) (xy 85.811356 -309.252929) (xy 85.848929 -309.201214) (xy 85.892686 -309.154617)
			(xy 85.941939 -309.113872) (xy 85.99591 -309.079621) (xy 86.053749 -309.052404) (xy 86.114542 -309.032651)
			(xy 86.177332 -309.020673) (xy 86.241128 -309.01666) (xy 86.304924 -309.020673) (xy 86.31448 -309.022496)
			(xy 93.06433 -309.022496) (xy 93.064781 -308.997717) (xy 93.07217 -308.948714) (xy 93.086784 -308.90136)
			(xy 93.108295 -308.856714) (xy 93.136221 -308.815775) (xy 93.16994 -308.779457) (xy 93.189044 -308.76367)
			(xy 93.197771 -308.75599) (xy 93.207755 -308.735026) (xy 93.207484 -308.711807) (xy 93.20276 -308.701186)
			(xy 93.189687 -308.674413) (xy 93.169146 -308.618484) (xy 93.155294 -308.560534) (xy 93.148322 -308.501361)
			(xy 93.147896 -308.47157) (xy 93.148328 -308.440838) (xy 93.15574 -308.379823) (xy 93.170452 -308.320146)
			(xy 93.19225 -308.262678) (xy 93.220816 -308.208256) (xy 93.255733 -308.157674) (xy 93.296493 -308.111669)
			(xy 93.3425 -308.070912) (xy 93.393085 -308.035998) (xy 93.447509 -308.007436) (xy 93.504979 -307.985642)
			(xy 93.564657 -307.970934) (xy 93.625672 -307.963526) (xy 93.656404 -307.963062) (xy 93.691359 -307.96365)
			(xy 93.760612 -307.973211) (xy 93.827902 -307.992167) (xy 93.891963 -308.020161) (xy 93.951585 -308.056664)
			(xy 93.978984 -308.078378) (xy 93.985926 -308.083618) (xy 94.002297 -308.089461) (xy 94.010988 -308.089808)
			(xy 94.16542 -308.089808) (xy 94.174105 -308.089439) (xy 94.190462 -308.083585) (xy 94.197424 -308.078378)
			(xy 94.224812 -308.056651) (xy 94.284441 -308.020156) (xy 94.348505 -307.992167) (xy 94.415796 -307.973209)
			(xy 94.485049 -307.963641) (xy 94.520004 -307.963062) (xy 94.550734 -307.963552) (xy 94.611746 -307.970961)
			(xy 94.67142 -307.985669) (xy 94.728886 -308.007462) (xy 94.783306 -308.036023) (xy 94.833887 -308.070936)
			(xy 94.879892 -308.11169) (xy 94.920648 -308.157692) (xy 94.955563 -308.208272) (xy 94.984127 -308.26269)
			(xy 95.005923 -308.320156) (xy 95.020635 -308.379829) (xy 95.028046 -308.44084) (xy 95.028512 -308.47157)
			(xy 95.027985 -308.50506) (xy 95.019202 -308.571463) (xy 95.001785 -308.636139) (xy 94.976033 -308.697971)
			(xy 94.942393 -308.755891) (xy 94.92234 -308.78272) (xy 94.915633 -308.792284) (xy 94.910912 -308.815137)
			(xy 94.916721 -308.837738) (xy 94.923864 -308.846982) (xy 94.938905 -308.865058) (xy 94.964266 -308.904657)
			(xy 94.98376 -308.947449) (xy 94.996992 -308.992573) (xy 95.003694 -309.039117) (xy 95.004128 -309.062628)
			(xy 95.003618 -309.088615) (xy 94.995488 -309.13995) (xy 94.979427 -309.18938) (xy 94.955831 -309.23569)
			(xy 94.925281 -309.277738) (xy 94.88853 -309.314489) (xy 94.846482 -309.345039) (xy 94.800172 -309.368635)
			(xy 94.750742 -309.384696) (xy 94.699407 -309.392826) (xy 94.647433 -309.392826) (xy 94.596098 -309.384696)
			(xy 94.546668 -309.368635) (xy 94.500358 -309.345039) (xy 94.45831 -309.314489) (xy 94.421559 -309.277738)
			(xy 94.391009 -309.23569) (xy 94.367413 -309.18938) (xy 94.351352 -309.13995) (xy 94.343222 -309.088615)
			(xy 94.342712 -309.062628) (xy 94.342928 -309.045807) (xy 94.346363 -309.01234) (xy 94.34957 -308.995826)
			(xy 94.351399 -308.984299) (xy 94.345549 -308.961725) (xy 94.330346 -308.944044) (xy 94.319852 -308.93893)
			(xy 94.287059 -308.924257) (xy 94.225612 -308.887035) (xy 94.197424 -308.864762) (xy 94.190476 -308.85953)
			(xy 94.17411 -308.853682) (xy 94.16542 -308.853332) (xy 94.010988 -308.853332) (xy 94.002303 -308.853696)
			(xy 93.985945 -308.859553) (xy 93.978984 -308.864762) (xy 93.955564 -308.883387) (xy 93.905149 -308.915622)
			(xy 93.851298 -308.941716) (xy 93.794756 -308.961308) (xy 93.765624 -308.96814) (xy 93.754345 -308.971151)
			(xy 93.736094 -308.985673) (xy 93.726136 -309.006763) (xy 93.725746 -309.018432) (xy 93.725746 -309.022242)
			(xy 93.725746 -309.022496) (xy 93.725236 -309.048483) (xy 93.717106 -309.099818) (xy 93.701045 -309.149248)
			(xy 93.677449 -309.195558) (xy 93.646899 -309.237606) (xy 93.610148 -309.274357) (xy 93.5681 -309.304907)
			(xy 93.52179 -309.328503) (xy 93.47236 -309.344564) (xy 93.421025 -309.352694) (xy 93.369051 -309.352694)
			(xy 93.317716 -309.344564) (xy 93.268286 -309.328503) (xy 93.221976 -309.304907) (xy 93.179928 -309.274357)
			(xy 93.143177 -309.237606) (xy 93.112627 -309.195558) (xy 93.089031 -309.149248) (xy 93.07297 -309.099818)
			(xy 93.06484 -309.048483) (xy 93.06433 -309.022496) (xy 86.31448 -309.022496) (xy 86.367714 -309.032651)
			(xy 86.428507 -309.052404) (xy 86.486346 -309.079621) (xy 86.540317 -309.113872) (xy 86.58957 -309.154617)
			(xy 86.633327 -309.201214) (xy 86.6709 -309.252929) (xy 86.701694 -309.308944) (xy 86.725226 -309.368377)
			(xy 86.741123 -309.430291) (xy 86.749134 -309.493709) (xy 86.749636 -309.52567) (xy 86.749134 -309.557631)
			(xy 86.741123 -309.621049) (xy 86.725226 -309.682963) (xy 86.701694 -309.742396) (xy 86.6709 -309.798411)
			(xy 86.633327 -309.850126) (xy 86.58957 -309.896723) (xy 86.540317 -309.937468) (xy 86.486346 -309.971719)
			(xy 86.428507 -309.998936) (xy 86.367714 -310.018689) (xy 86.304924 -310.030667) (xy 86.241128 -310.034681)
			(xy 86.177332 -310.030667) (xy 86.114542 -310.018689) (xy 86.053749 -309.998936) (xy 85.99591 -309.971719)
			(xy 85.941939 -309.937468) (xy 85.892686 -309.896723) (xy 85.848929 -309.850126) (xy 85.811356 -309.798411)
			(xy 85.780562 -309.742396) (xy 85.75703 -309.682963) (xy 85.741133 -309.621049) (xy 85.733122 -309.557631)
			(xy 80.079424 -309.557631) (xy 80.074726 -309.596328) (xy 80.06002 -309.656001) (xy 80.038229 -309.713467)
			(xy 80.009669 -309.767887) (xy 79.974759 -309.818468) (xy 79.934006 -309.864472) (xy 79.888006 -309.905229)
			(xy 79.837428 -309.940145) (xy 79.783011 -309.968709) (xy 79.725547 -309.990506) (xy 79.665875 -310.005218)
			(xy 79.604865 -310.01263) (xy 79.574136 -310.013096) (xy 79.540646 -310.012569) (xy 79.474243 -310.003787)
			(xy 79.409567 -309.986369) (xy 79.347734 -309.960618) (xy 79.289815 -309.926977) (xy 79.262986 -309.906924)
			(xy 79.253418 -309.900225) (xy 79.230568 -309.895504) (xy 79.207968 -309.901308) (xy 79.198724 -309.908448)
			(xy 79.180643 -309.923484) (xy 79.141047 -309.948846) (xy 79.098255 -309.968341) (xy 79.053132 -309.981574)
			(xy 79.006589 -309.988278) (xy 78.983078 -309.988712) (xy 78.957092 -309.988193) (xy 78.905761 -309.98006)
			(xy 78.856334 -309.963997) (xy 78.810028 -309.9404) (xy 78.767984 -309.90985) (xy 78.731235 -309.8731)
			(xy 78.700688 -309.831053) (xy 78.677095 -309.784746) (xy 78.661035 -309.735318) (xy 78.652905 -309.683986)
			(xy 70.583732 -309.683986) (xy 69.810122 -310.457596) (xy 95.560134 -310.457596) (xy 95.560638 -310.430439)
			(xy 95.569513 -310.376856) (xy 95.587025 -310.325444) (xy 95.612702 -310.277583) (xy 95.645854 -310.234562)
			(xy 95.68559 -310.197535) (xy 95.730842 -310.1675) (xy 95.780394 -310.145262) (xy 95.806514 -310.13781)
			(xy 95.81769 -310.135016) (xy 95.834962 -310.12003) (xy 95.876872 -310.026304) (xy 95.87611 -310.003444)
			(xy 95.870776 -309.99303) (xy 95.857253 -309.965923) (xy 95.836061 -309.90917) (xy 95.821766 -309.8503)
			(xy 95.81457 -309.790148) (xy 95.814134 -309.759858) (xy 95.814636 -309.727897) (xy 95.822647 -309.664479)
			(xy 95.838544 -309.602565) (xy 95.862076 -309.543132) (xy 95.89287 -309.487117) (xy 95.930443 -309.435402)
			(xy 95.9742 -309.388805) (xy 96.023453 -309.34806) (xy 96.077424 -309.313809) (xy 96.135263 -309.286592)
			(xy 96.196056 -309.266839) (xy 96.258846 -309.254861) (xy 96.322642 -309.250848) (xy 96.386438 -309.254861)
			(xy 96.449228 -309.266839) (xy 96.510021 -309.286592) (xy 96.56786 -309.313809) (xy 96.621831 -309.34806)
			(xy 96.671084 -309.388805) (xy 96.714841 -309.435402) (xy 96.752414 -309.487117) (xy 96.783208 -309.543132)
			(xy 96.80674 -309.602565) (xy 96.822637 -309.664479) (xy 96.830648 -309.727897) (xy 96.83115 -309.759858)
			(xy 96.831022 -309.776543) (xy 96.828861 -309.809844) (xy 96.826832 -309.826406) (xy 96.825922 -309.838178)
			(xy 96.833566 -309.860481) (xy 96.850359 -309.877031) (xy 96.861376 -309.88127) (xy 96.891489 -309.89168)
			(xy 96.949054 -309.918993) (xy 97.002753 -309.953287) (xy 97.051746 -309.994023) (xy 97.095262 -310.040563)
			(xy 97.132621 -310.092178) (xy 97.163235 -310.148057) (xy 97.186626 -310.207324) (xy 97.202425 -310.26905)
			(xy 97.210386 -310.332266) (xy 97.21088 -310.364124) (xy 97.210485 -310.394858) (xy 97.203073 -310.455877)
			(xy 97.18836 -310.515557) (xy 97.16656 -310.573029) (xy 97.137992 -310.627454) (xy 97.103072 -310.678039)
			(xy 97.06231 -310.724046) (xy 97.016298 -310.764804) (xy 96.989798 -310.783094) (xy 98.386037 -310.783094)
			(xy 98.386037 -310.731106) (xy 98.394171 -310.679758) (xy 98.410237 -310.630314) (xy 98.433841 -310.583993)
			(xy 98.464401 -310.541935) (xy 98.501164 -310.505176) (xy 98.543226 -310.474621) (xy 98.589549 -310.451023)
			(xy 98.638995 -310.434962) (xy 98.690344 -310.426834) (xy 98.716338 -310.426354) (xy 98.733159 -310.426574)
			(xy 98.766626 -310.430006) (xy 98.78314 -310.433212) (xy 98.794671 -310.434985) (xy 98.817233 -310.429154)
			(xy 98.834916 -310.413976) (xy 98.840036 -310.403494) (xy 98.854775 -310.370695) (xy 98.892127 -310.309251)
			(xy 98.914458 -310.281066) (xy 98.919717 -310.274136) (xy 98.925549 -310.257756) (xy 98.925888 -310.249062)
			(xy 98.925888 -310.094884) (xy 98.925533 -310.086136) (xy 98.919691 -310.069645) (xy 98.914458 -310.062626)
			(xy 98.895773 -310.039234) (xy 98.863464 -309.988828) (xy 98.837309 -309.934971) (xy 98.817674 -309.878411)
			(xy 98.810826 -309.849266) (xy 98.807821 -309.837984) (xy 98.793301 -309.819727) (xy 98.772205 -309.809772)
			(xy 98.760534 -309.809388) (xy 98.756724 -309.809388) (xy 98.75647 -309.809388) (xy 98.730483 -309.808916)
			(xy 98.679149 -309.800781) (xy 98.629719 -309.784717) (xy 98.583411 -309.761118) (xy 98.541365 -309.730566)
			(xy 98.504615 -309.693813) (xy 98.474066 -309.651763) (xy 98.450472 -309.605453) (xy 98.434412 -309.556022)
			(xy 98.426281 -309.504687) (xy 98.426281 -309.452713) (xy 98.434412 -309.401378) (xy 98.450472 -309.351947)
			(xy 98.474066 -309.305637) (xy 98.504615 -309.263587) (xy 98.541365 -309.226834) (xy 98.583411 -309.196282)
			(xy 98.629719 -309.172683) (xy 98.679149 -309.156619) (xy 98.730483 -309.148484) (xy 98.75647 -309.147972)
			(xy 98.781249 -309.148398) (xy 98.830253 -309.155796) (xy 98.877606 -309.170416) (xy 98.922251 -309.191931)
			(xy 98.96319 -309.219861) (xy 98.999509 -309.253582) (xy 99.015296 -309.272686) (xy 99.022997 -309.28139)
			(xy 99.043951 -309.291373) (xy 99.06716 -309.291115) (xy 99.07778 -309.286402) (xy 99.104543 -309.273308)
			(xy 99.160476 -309.252771) (xy 99.218429 -309.238925) (xy 99.277604 -309.23196) (xy 99.307396 -309.231538)
			(xy 99.33813 -309.231941) (xy 99.399149 -309.239351) (xy 99.458831 -309.254061) (xy 99.516303 -309.275859)
			(xy 99.57073 -309.304425) (xy 99.621315 -309.339344) (xy 99.667323 -309.380107) (xy 99.708081 -309.426118)
			(xy 99.742996 -309.476706) (xy 99.771559 -309.531135) (xy 99.793351 -309.58861) (xy 99.808057 -309.648292)
			(xy 99.815461 -309.709312) (xy 99.815904 -309.740046) (xy 99.815297 -309.775011) (xy 99.805702 -309.844279)
			(xy 99.7867 -309.911578) (xy 99.75865 -309.975635) (xy 99.722082 -310.035242) (xy 99.700334 -310.062626)
			(xy 99.695045 -310.069613) (xy 99.689211 -310.086125) (xy 99.688904 -310.094884) (xy 99.688904 -310.248808)
			(xy 99.689264 -310.257555) (xy 99.695103 -310.274046) (xy 99.700334 -310.281066) (xy 99.722061 -310.308465)
			(xy 99.758615 -310.368076) (xy 99.786664 -310.432131) (xy 99.805678 -310.499422) (xy 99.8153 -310.568683)
			(xy 99.815904 -310.603646) (xy 99.815488 -310.634378) (xy 99.808074 -310.695394) (xy 99.79336 -310.755071)
			(xy 99.77156 -310.81254) (xy 99.742993 -310.866962) (xy 99.708074 -310.917544) (xy 99.667313 -310.963548)
			(xy 99.621304 -311.004305) (xy 99.570719 -311.039219) (xy 99.516294 -311.067781) (xy 99.458823 -311.089575)
			(xy 99.399145 -311.104283) (xy 99.338128 -311.111691) (xy 99.307396 -311.112154) (xy 99.273905 -311.111637)
			(xy 99.207503 -311.102851) (xy 99.142827 -311.08543) (xy 99.080995 -311.059677) (xy 99.023075 -311.026035)
			(xy 98.996246 -311.005982) (xy 98.986703 -310.999238) (xy 98.963836 -310.994523) (xy 98.941226 -311.000351)
			(xy 98.931984 -311.007506) (xy 98.913926 -311.022569) (xy 98.874322 -311.047926) (xy 98.831524 -311.067414)
			(xy 98.786397 -311.080641) (xy 98.739851 -311.087339) (xy 98.716338 -311.08777) (xy 98.690344 -311.087366)
			(xy 98.638995 -311.079238) (xy 98.589549 -311.063177) (xy 98.543226 -311.039579) (xy 98.501164 -311.009024)
			(xy 98.464401 -310.972265) (xy 98.433841 -310.930207) (xy 98.410237 -310.883886) (xy 98.394171 -310.834442)
			(xy 98.386037 -310.783094) (xy 96.989798 -310.783094) (xy 96.96571 -310.799719) (xy 96.911282 -310.828282)
			(xy 96.853807 -310.850075) (xy 96.794125 -310.864782) (xy 96.733106 -310.872188) (xy 96.702372 -310.872632)
			(xy 96.669241 -310.872089) (xy 96.603542 -310.863473) (xy 96.539516 -310.846403) (xy 96.478248 -310.821168)
			(xy 96.420773 -310.788194) (xy 96.368063 -310.74804) (xy 96.321011 -310.701385) (xy 96.30029 -310.675528)
			(xy 96.293432 -310.666638) (xy 96.272858 -310.656224) (xy 96.171004 -310.653684) (xy 96.150176 -310.663082)
			(xy 96.14281 -310.671972) (xy 96.126999 -310.689866) (xy 96.091127 -310.721383) (xy 96.0511 -310.747419)
			(xy 96.007748 -310.767436) (xy 95.961971 -310.781018) (xy 95.914717 -310.787883) (xy 95.890842 -310.788304)
			(xy 95.864854 -310.787786) (xy 95.813516 -310.779661) (xy 95.764082 -310.763604) (xy 95.717769 -310.740011)
			(xy 95.675716 -310.709463) (xy 95.638961 -310.672713) (xy 95.608408 -310.630664) (xy 95.58481 -310.584353)
			(xy 95.568748 -310.534921) (xy 95.560617 -310.483584) (xy 95.560134 -310.457596) (xy 69.810122 -310.457596)
			(xy 65.090929 -315.176789) (xy 97.790756 -315.176789) (xy 97.790756 -315.124811) (xy 97.798886 -315.073473)
			(xy 97.814947 -315.024039) (xy 97.838543 -314.977726) (xy 97.869093 -314.935673) (xy 97.905844 -314.898917)
			(xy 97.947893 -314.868363) (xy 97.994204 -314.844762) (xy 98.043636 -314.828695) (xy 98.094973 -314.820559)
			(xy 98.120962 -314.820046) (xy 98.137783 -314.820263) (xy 98.17125 -314.823697) (xy 98.187764 -314.826904)
			(xy 98.199293 -314.828703) (xy 98.221859 -314.822862) (xy 98.239541 -314.807673) (xy 98.24466 -314.797186)
			(xy 98.259395 -314.764385) (xy 98.29675 -314.702942) (xy 98.319082 -314.674758) (xy 98.324305 -314.667804)
			(xy 98.330158 -314.651443) (xy 98.330512 -314.642754) (xy 98.330512 -314.488576) (xy 98.330156 -314.479828)
			(xy 98.324314 -314.463337) (xy 98.319082 -314.456318) (xy 98.300398 -314.432925) (xy 98.268088 -314.38252)
			(xy 98.241933 -314.328663) (xy 98.222298 -314.272103) (xy 98.21545 -314.242958) (xy 98.212428 -314.231682)
			(xy 98.197914 -314.213428) (xy 98.176827 -314.203469) (xy 98.165158 -314.20308) (xy 98.161348 -314.20308)
			(xy 98.161094 -314.20308) (xy 98.135105 -314.202626) (xy 98.083767 -314.194494) (xy 98.034333 -314.178431)
			(xy 97.98802 -314.154833) (xy 97.945969 -314.12428) (xy 97.909216 -314.087526) (xy 97.878664 -314.045475)
			(xy 97.855067 -313.999162) (xy 97.839005 -313.949727) (xy 97.830874 -313.898389) (xy 97.830874 -313.846411)
			(xy 97.839005 -313.795073) (xy 97.855067 -313.745638) (xy 97.878664 -313.699325) (xy 97.909216 -313.657274)
			(xy 97.945969 -313.62052) (xy 97.98802 -313.589967) (xy 98.034333 -313.566369) (xy 98.083767 -313.550306)
			(xy 98.135105 -313.542174) (xy 98.161094 -313.541664) (xy 98.185871 -313.542147) (xy 98.234872 -313.549533)
			(xy 98.282224 -313.564142) (xy 98.32687 -313.585647) (xy 98.36781 -313.613567) (xy 98.404131 -313.647278)
			(xy 98.41992 -313.666378) (xy 98.427604 -313.6751) (xy 98.448567 -313.68508) (xy 98.471783 -313.684814)
			(xy 98.482404 -313.680094) (xy 98.509163 -313.666991) (xy 98.565097 -313.646457) (xy 98.623051 -313.632613)
			(xy 98.682228 -313.625651) (xy 98.71202 -313.62523) (xy 98.742754 -313.625619) (xy 98.803774 -313.633031)
			(xy 98.863455 -313.647744) (xy 98.920927 -313.669543) (xy 98.975353 -313.698112) (xy 99.025938 -313.733032)
			(xy 99.071946 -313.773795) (xy 99.112704 -313.819807) (xy 99.147619 -313.870397) (xy 99.176181 -313.924826)
			(xy 99.197974 -313.982301) (xy 99.21268 -314.041984) (xy 99.220085 -314.103004) (xy 99.220528 -314.133738)
			(xy 99.219911 -314.168702) (xy 99.210318 -314.23797) (xy 99.191318 -314.305268) (xy 99.16327 -314.369326)
			(xy 99.126705 -314.428933) (xy 99.104958 -314.456318) (xy 99.099675 -314.463309) (xy 99.093837 -314.479818)
			(xy 99.093528 -314.488576) (xy 99.093528 -314.6425) (xy 99.093887 -314.651247) (xy 99.099726 -314.667739)
			(xy 99.104958 -314.674758) (xy 99.12667 -314.702169) (xy 99.163229 -314.761775) (xy 99.191282 -314.825827)
			(xy 99.210299 -314.893116) (xy 99.219924 -314.962376) (xy 99.220528 -314.997338) (xy 99.22008 -315.028069)
			(xy 99.212668 -315.089083) (xy 99.197955 -315.148758) (xy 99.176158 -315.206225) (xy 99.147593 -315.260646)
			(xy 99.112677 -315.311227) (xy 99.071919 -315.357232) (xy 99.025913 -315.397988) (xy 98.975331 -315.432902)
			(xy 98.920909 -315.461465) (xy 98.863441 -315.483261) (xy 98.803765 -315.497971) (xy 98.742751 -315.505381)
			(xy 98.71202 -315.505846) (xy 98.67853 -315.505318) (xy 98.612128 -315.496534) (xy 98.547452 -315.479116)
			(xy 98.485619 -315.453365) (xy 98.427699 -315.419726) (xy 98.40087 -315.399674) (xy 98.391313 -315.392954)
			(xy 98.368455 -315.388232) (xy 98.34585 -315.394049) (xy 98.336608 -315.401198) (xy 98.31854 -315.416249)
			(xy 98.278939 -315.441608) (xy 98.236144 -315.461099) (xy 98.191019 -315.474328) (xy 98.144474 -315.481029)
			(xy 98.120962 -315.481462) (xy 98.094973 -315.481041) (xy 98.043636 -315.472905) (xy 97.994204 -315.456838)
			(xy 97.947893 -315.433237) (xy 97.905844 -315.402683) (xy 97.869093 -315.365927) (xy 97.838543 -315.323874)
			(xy 97.814947 -315.277561) (xy 97.798886 -315.228127) (xy 97.790756 -315.176789) (xy 65.090929 -315.176789)
			(xy 60.130436 -320.137282) (xy 60.123035 -320.14412) (xy 60.104436 -320.151834) (xy 60.094368 -320.152268)
			(xy 24.032718 -320.152268) (xy 24.026709 -320.152439) (xy 24.01503 -320.155268) (xy 24.009604 -320.157856)
			(xy 24.00613 -320.159696) (xy 23.999753 -320.164291) (xy 23.996904 -320.167) (xy 22.634194 -321.52971)
			(xy 22.63149 -321.532563) (xy 22.626902 -321.538943) (xy 22.62505 -321.54241) (xy 22.622461 -321.547836)
			(xy 22.619627 -321.559515) (xy 22.619462 -321.565524) (xy 22.619462 -323.030342) (xy 67.354958 -323.030342)
			(xy 67.35539 -322.99962) (xy 67.362797 -322.938625) (xy 67.377496 -322.878965) (xy 67.399274 -322.821511)
			(xy 67.427813 -322.767097) (xy 67.444874 -322.741544) (xy 67.450234 -322.732841) (xy 67.45431 -322.712835)
			(xy 67.450261 -322.692823) (xy 67.444874 -322.68414) (xy 67.427854 -322.658562) (xy 67.399319 -322.604151)
			(xy 67.377545 -322.5467) (xy 67.362849 -322.487045) (xy 67.355445 -322.426054) (xy 67.355441 -322.364615)
			(xy 67.362837 -322.303623) (xy 67.377525 -322.243966) (xy 67.399291 -322.186512) (xy 67.427818 -322.132098)
			(xy 67.444874 -322.106544) (xy 67.450234 -322.097841) (xy 67.45431 -322.077835) (xy 67.450261 -322.057823)
			(xy 67.444874 -322.04914) (xy 67.427854 -322.023562) (xy 67.399319 -321.969151) (xy 67.377545 -321.9117)
			(xy 67.362849 -321.852045) (xy 67.355445 -321.791054) (xy 67.355441 -321.729615) (xy 67.362837 -321.668623)
			(xy 67.377525 -321.608966) (xy 67.399291 -321.551512) (xy 67.427818 -321.497098) (xy 67.444874 -321.471544)
			(xy 67.450234 -321.462841) (xy 67.45431 -321.442835) (xy 67.450261 -321.422823) (xy 67.444874 -321.41414)
			(xy 67.427854 -321.388562) (xy 67.399319 -321.334151) (xy 67.377545 -321.2767) (xy 67.362849 -321.217045)
			(xy 67.355445 -321.156054) (xy 67.355441 -321.094615) (xy 67.362837 -321.033623) (xy 67.377525 -320.973966)
			(xy 67.399291 -320.916512) (xy 67.427818 -320.862098) (xy 67.444874 -320.836544) (xy 67.450234 -320.827841)
			(xy 67.45431 -320.807835) (xy 67.450261 -320.787823) (xy 67.444874 -320.77914) (xy 67.427835 -320.753574)
			(xy 67.399299 -320.699163) (xy 67.377525 -320.641711) (xy 67.362828 -320.582054) (xy 67.355423 -320.521062)
			(xy 67.354958 -320.490342) (xy 67.355477 -320.459612) (xy 67.36288 -320.3986) (xy 67.377584 -320.338925)
			(xy 67.399373 -320.281457) (xy 67.427931 -320.227035) (xy 67.46284 -320.176452) (xy 67.503592 -320.130446)
			(xy 67.549592 -320.089687) (xy 67.60017 -320.05477) (xy 67.654588 -320.026204) (xy 67.712052 -320.004406)
			(xy 67.771725 -319.989694) (xy 67.832736 -319.982282) (xy 67.863466 -319.981834) (xy 67.882262 -319.982088)
			(xy 67.89293 -319.982596) (xy 67.91325 -319.974468) (xy 67.980814 -319.904872) (xy 67.98818 -319.884806)
			(xy 67.987418 -319.874138) (xy 67.986402 -319.840864) (xy 67.986822 -319.810132) (xy 67.994235 -319.749116)
			(xy 68.008948 -319.689439) (xy 68.030747 -319.63197) (xy 68.059314 -319.577547) (xy 68.094232 -319.526965)
			(xy 68.134993 -319.48096) (xy 68.181001 -319.440204) (xy 68.231587 -319.40529) (xy 68.286012 -319.376728)
			(xy 68.343483 -319.354934) (xy 68.403161 -319.340226) (xy 68.464178 -319.332819) (xy 68.49491 -319.332356)
			(xy 68.515992 -319.332864) (xy 68.516246 -319.332864) (xy 68.526679 -319.332722) (xy 68.546088 -319.325118)
			(xy 68.553838 -319.318132) (xy 68.607178 -319.264792) (xy 68.614181 -319.257054) (xy 68.621779 -319.237637)
			(xy 68.62191 -319.2272) (xy 68.62191 -319.226692) (xy 68.621402 -319.205864) (xy 68.621904 -319.173903)
			(xy 68.629915 -319.110485) (xy 68.645812 -319.048571) (xy 68.669344 -318.989138) (xy 68.700138 -318.933123)
			(xy 68.737711 -318.881408) (xy 68.781468 -318.834811) (xy 68.830721 -318.794066) (xy 68.884692 -318.759815)
			(xy 68.942531 -318.732598) (xy 69.003324 -318.712845) (xy 69.066114 -318.700867) (xy 69.12991 -318.696854)
			(xy 69.193706 -318.700867) (xy 69.256496 -318.712845) (xy 69.317289 -318.732598) (xy 69.375128 -318.759815)
			(xy 69.429099 -318.794066) (xy 69.478352 -318.834811) (xy 69.522109 -318.881408) (xy 69.559682 -318.933123)
			(xy 69.590476 -318.989138) (xy 69.614008 -319.048571) (xy 69.629905 -319.110485) (xy 69.637916 -319.173903)
			(xy 69.638418 -319.205864) (xy 69.637925 -319.236584) (xy 69.63053 -319.297576) (xy 69.615844 -319.357235)
			(xy 69.594081 -319.41469) (xy 69.565556 -319.469107) (xy 69.548502 -319.494662) (xy 69.543139 -319.503363)
			(xy 69.539067 -319.52337) (xy 69.543116 -319.543382) (xy 69.548502 -319.552066) (xy 69.565541 -319.577632)
			(xy 69.594077 -319.632043) (xy 69.615852 -319.689495) (xy 69.630549 -319.749152) (xy 69.637953 -319.810144)
			(xy 69.638418 -319.840864) (xy 69.638013 -319.869819) (xy 69.631415 -319.927353) (xy 69.618325 -319.983765)
			(xy 69.598911 -320.038324) (xy 69.573424 -320.090325) (xy 69.558154 -320.11493) (xy 69.553005 -320.123943)
			(xy 69.549624 -320.144398) (xy 69.554581 -320.16453) (xy 69.56044 -320.173096) (xy 69.579985 -320.199677)
			(xy 69.61272 -320.256965) (xy 69.637771 -320.318004) (xy 69.654719 -320.38177) (xy 69.663279 -320.447192)
			(xy 69.663818 -320.480182) (xy 69.663818 -320.480436) (xy 69.663361 -320.511157) (xy 69.655958 -320.572151)
			(xy 69.641264 -320.63181) (xy 69.619492 -320.689265) (xy 69.59096 -320.74368) (xy 69.573902 -320.769234)
			(xy 69.568478 -320.777902) (xy 69.564426 -320.79793) (xy 69.568501 -320.817953) (xy 69.573902 -320.826638)
			(xy 69.590994 -320.85217) (xy 69.619526 -320.906589) (xy 69.641295 -320.964047) (xy 69.655986 -321.02371)
			(xy 69.663383 -321.084707) (xy 69.663379 -321.146152) (xy 69.655975 -321.207149) (xy 69.641278 -321.266809)
			(xy 69.619501 -321.324266) (xy 69.590963 -321.378681) (xy 69.573902 -321.404234) (xy 69.568478 -321.412902)
			(xy 69.564426 -321.43293) (xy 69.568501 -321.452953) (xy 69.573902 -321.461638) (xy 69.590994 -321.48717)
			(xy 69.619526 -321.541589) (xy 69.641295 -321.599047) (xy 69.655986 -321.65871) (xy 69.663383 -321.719707)
			(xy 69.663379 -321.781152) (xy 69.655975 -321.842149) (xy 69.641278 -321.901809) (xy 69.619501 -321.959266)
			(xy 69.590963 -322.013681) (xy 69.573902 -322.039234) (xy 69.568478 -322.047902) (xy 69.564426 -322.06793)
			(xy 69.568501 -322.087953) (xy 69.573902 -322.096638) (xy 69.590972 -322.122184) (xy 69.619503 -322.176601)
			(xy 69.641272 -322.234058) (xy 69.655961 -322.293719) (xy 69.663358 -322.354715) (xy 69.663818 -322.385436)
			(xy 69.663818 -322.38569) (xy 69.663335 -322.418673) (xy 69.654825 -322.484087) (xy 69.637919 -322.547849)
			(xy 69.612903 -322.608886) (xy 69.580198 -322.666173) (xy 69.560694 -322.692776) (xy 69.554784 -322.701377)
			(xy 69.549864 -322.721639) (xy 69.553386 -322.74219) (xy 69.558662 -322.751196) (xy 69.574487 -322.776129)
			(xy 69.600945 -322.828926) (xy 69.621108 -322.884433) (xy 69.634703 -322.941903) (xy 69.641547 -323.00056)
			(xy 69.641974 -323.030088) (xy 69.641974 -323.030342) (xy 71.368158 -323.030342) (xy 71.368158 -323.030088)
			(xy 71.368688 -322.997107) (xy 71.377188 -322.931695) (xy 71.394083 -322.867934) (xy 71.419088 -322.806895)
			(xy 71.451783 -322.749607) (xy 71.471282 -322.723002) (xy 71.477122 -322.714362) (xy 71.482056 -322.694124)
			(xy 71.478568 -322.673588) (xy 71.473314 -322.664582) (xy 71.457477 -322.639656) (xy 71.431021 -322.586857)
			(xy 71.410862 -322.531348) (xy 71.39727 -322.473877) (xy 71.390428 -322.415218) (xy 71.390002 -322.38569)
			(xy 71.390002 -322.385436) (xy 71.390492 -322.354716) (xy 71.397886 -322.293723) (xy 71.412573 -322.234065)
			(xy 71.434338 -322.176609) (xy 71.462863 -322.122193) (xy 71.479918 -322.096638) (xy 71.485279 -322.087937)
			(xy 71.48935 -322.06793) (xy 71.485303 -322.047919) (xy 71.479918 -322.039234) (xy 71.462894 -322.013658)
			(xy 71.434363 -321.959247) (xy 71.412592 -321.901795) (xy 71.397898 -321.84214) (xy 71.390495 -321.781149)
			(xy 71.390492 -321.71971) (xy 71.397887 -321.658719) (xy 71.412574 -321.599062) (xy 71.434338 -321.541607)
			(xy 71.462863 -321.487192) (xy 71.479918 -321.461638) (xy 71.485279 -321.452937) (xy 71.48935 -321.43293)
			(xy 71.485303 -321.412919) (xy 71.479918 -321.404234) (xy 71.462894 -321.378658) (xy 71.434363 -321.324247)
			(xy 71.412592 -321.266795) (xy 71.397898 -321.20714) (xy 71.390495 -321.146149) (xy 71.390492 -321.08471)
			(xy 71.397887 -321.023719) (xy 71.412574 -320.964062) (xy 71.434338 -320.906607) (xy 71.462863 -320.852192)
			(xy 71.479918 -320.826638) (xy 71.485279 -320.817937) (xy 71.48935 -320.79793) (xy 71.485303 -320.777919)
			(xy 71.479918 -320.769234) (xy 71.462881 -320.743666) (xy 71.434344 -320.689256) (xy 71.412569 -320.631804)
			(xy 71.397871 -320.572148) (xy 71.390467 -320.511156) (xy 71.390002 -320.480436) (xy 71.390002 -320.480182)
			(xy 71.390471 -320.449243) (xy 71.397972 -320.38782) (xy 71.412872 -320.327762) (xy 71.434952 -320.269957)
			(xy 71.463885 -320.215259) (xy 71.481188 -320.189606) (xy 71.486635 -320.180837) (xy 71.490796 -320.160642)
			(xy 71.486668 -320.14044) (xy 71.481188 -320.131694) (xy 71.463891 -320.106037) (xy 71.434959 -320.051339)
			(xy 71.412877 -319.993535) (xy 71.397971 -319.933478) (xy 71.390461 -319.872057) (xy 71.390002 -319.841118)
			(xy 71.390002 -319.840864) (xy 71.390455 -319.810143) (xy 71.397859 -319.749149) (xy 71.412554 -319.68949)
			(xy 71.434326 -319.632035) (xy 71.462859 -319.57762) (xy 71.479918 -319.552066) (xy 71.48534 -319.543397)
			(xy 71.489391 -319.52337) (xy 71.485317 -319.503347) (xy 71.479918 -319.494662) (xy 71.462828 -319.469129)
			(xy 71.434301 -319.414709) (xy 71.412535 -319.357251) (xy 71.397847 -319.297589) (xy 71.390451 -319.236592)
			(xy 71.390455 -319.175149) (xy 71.397858 -319.114153) (xy 71.412553 -319.054493) (xy 71.434325 -318.997036)
			(xy 71.462859 -318.94262) (xy 71.479918 -318.917066) (xy 71.48534 -318.908397) (xy 71.489391 -318.88837)
			(xy 71.485317 -318.868347) (xy 71.479918 -318.859662) (xy 71.462828 -318.834129) (xy 71.434301 -318.779709)
			(xy 71.412535 -318.722251) (xy 71.397847 -318.662589) (xy 71.390451 -318.601592) (xy 71.390455 -318.540149)
			(xy 71.397858 -318.479153) (xy 71.412553 -318.419493) (xy 71.434325 -318.362036) (xy 71.462859 -318.30762)
			(xy 71.479918 -318.282066) (xy 71.48534 -318.273397) (xy 71.489391 -318.25337) (xy 71.485317 -318.233347)
			(xy 71.479918 -318.224662) (xy 71.462828 -318.199129) (xy 71.434301 -318.144709) (xy 71.412535 -318.087251)
			(xy 71.397847 -318.027589) (xy 71.390451 -317.966592) (xy 71.390455 -317.905149) (xy 71.397858 -317.844153)
			(xy 71.412553 -317.784493) (xy 71.434325 -317.727036) (xy 71.462859 -317.67262) (xy 71.479918 -317.647066)
			(xy 71.48534 -317.638397) (xy 71.489391 -317.61837) (xy 71.485317 -317.598347) (xy 71.479918 -317.589662)
			(xy 71.462828 -317.564129) (xy 71.434301 -317.509709) (xy 71.412535 -317.452251) (xy 71.397847 -317.392589)
			(xy 71.390451 -317.331592) (xy 71.390455 -317.270149) (xy 71.397858 -317.209153) (xy 71.412553 -317.149493)
			(xy 71.434325 -317.092036) (xy 71.462859 -317.03762) (xy 71.479918 -317.012066) (xy 71.48534 -317.003397)
			(xy 71.489391 -316.98337) (xy 71.485317 -316.963347) (xy 71.479918 -316.954662) (xy 71.46285 -316.929114)
			(xy 71.434318 -316.874698) (xy 71.412549 -316.817241) (xy 71.397859 -316.757581) (xy 71.390462 -316.696585)
			(xy 71.390002 -316.665864) (xy 71.390422 -316.635132) (xy 71.397835 -316.574116) (xy 71.412548 -316.514439)
			(xy 71.434347 -316.45697) (xy 71.462914 -316.402547) (xy 71.497832 -316.351965) (xy 71.538593 -316.30596)
			(xy 71.584601 -316.265204) (xy 71.635187 -316.23029) (xy 71.689612 -316.201728) (xy 71.747083 -316.179934)
			(xy 71.806761 -316.165226) (xy 71.867778 -316.157819) (xy 71.89851 -316.157356) (xy 71.929231 -316.157813)
			(xy 71.990226 -316.165214) (xy 72.049885 -316.179908) (xy 72.10734 -316.20168) (xy 72.161754 -316.230213)
			(xy 72.187308 -316.247272) (xy 72.195993 -316.252665) (xy 72.21601 -316.256726) (xy 72.236027 -316.252665)
			(xy 72.244712 -316.247272) (xy 72.270266 -316.230214) (xy 72.324681 -316.201683) (xy 72.382136 -316.179912)
			(xy 72.441795 -316.16522) (xy 72.502789 -316.15782) (xy 72.564231 -316.15782) (xy 72.625225 -316.16522)
			(xy 72.684884 -316.179912) (xy 72.742339 -316.201683) (xy 72.796754 -316.230214) (xy 72.822308 -316.247272)
			(xy 72.830993 -316.252665) (xy 72.85101 -316.256726) (xy 72.871027 -316.252665) (xy 72.879712 -316.247272)
			(xy 72.905263 -316.23021) (xy 72.959679 -316.201678) (xy 73.017135 -316.179908) (xy 73.076794 -316.165217)
			(xy 73.137789 -316.157818) (xy 73.16851 -316.157356) (xy 73.19924 -316.157847) (xy 73.260251 -316.165256)
			(xy 73.319925 -316.179964) (xy 73.377391 -316.201758) (xy 73.431811 -316.230319) (xy 73.482392 -316.265232)
			(xy 73.528396 -316.305986) (xy 73.569152 -316.351988) (xy 73.604067 -316.402567) (xy 73.632631 -316.456986)
			(xy 73.654428 -316.51445) (xy 73.66914 -316.574123) (xy 73.676552 -316.635134) (xy 73.677018 -316.665864)
			(xy 73.676525 -316.696584) (xy 73.66913 -316.757576) (xy 73.654444 -316.817235) (xy 73.632681 -316.87469)
			(xy 73.604156 -316.929107) (xy 73.587102 -316.954662) (xy 73.581739 -316.963363) (xy 73.577667 -316.98337)
			(xy 73.581716 -317.003382) (xy 73.587102 -317.012066) (xy 73.604128 -317.037641) (xy 73.632664 -317.092051)
			(xy 73.654439 -317.149503) (xy 73.669135 -317.209159) (xy 73.676539 -317.270151) (xy 73.676542 -317.33159)
			(xy 73.669145 -317.392583) (xy 73.654456 -317.452241) (xy 73.632689 -317.509695) (xy 73.604159 -317.564109)
			(xy 73.587102 -317.589662) (xy 73.581739 -317.598363) (xy 73.577667 -317.61837) (xy 73.581716 -317.638382)
			(xy 73.587102 -317.647066) (xy 73.604128 -317.672641) (xy 73.632664 -317.727051) (xy 73.654439 -317.784503)
			(xy 73.669135 -317.844159) (xy 73.676539 -317.905151) (xy 73.676542 -317.96659) (xy 73.669145 -318.027583)
			(xy 73.654456 -318.087241) (xy 73.632689 -318.144695) (xy 73.604159 -318.199109) (xy 73.587102 -318.224662)
			(xy 73.581739 -318.233363) (xy 73.577667 -318.25337) (xy 73.581716 -318.273382) (xy 73.587102 -318.282066)
			(xy 73.604128 -318.307641) (xy 73.632664 -318.362051) (xy 73.654439 -318.419503) (xy 73.669135 -318.479159)
			(xy 73.676539 -318.540151) (xy 73.676542 -318.60159) (xy 73.669145 -318.662583) (xy 73.654456 -318.722241)
			(xy 73.632689 -318.779695) (xy 73.604159 -318.834109) (xy 73.587102 -318.859662) (xy 73.581739 -318.868363)
			(xy 73.577667 -318.88837) (xy 73.581716 -318.908382) (xy 73.587102 -318.917066) (xy 73.604128 -318.942641)
			(xy 73.632664 -318.997051) (xy 73.654439 -319.054503) (xy 73.669135 -319.114159) (xy 73.676539 -319.175151)
			(xy 73.676542 -319.23659) (xy 73.669145 -319.297583) (xy 73.654456 -319.357241) (xy 73.632689 -319.414695)
			(xy 73.604159 -319.469109) (xy 73.587102 -319.494662) (xy 73.581739 -319.503363) (xy 73.577667 -319.52337)
			(xy 73.581716 -319.543382) (xy 73.587102 -319.552066) (xy 73.604128 -319.577641) (xy 73.632664 -319.632051)
			(xy 73.654439 -319.689503) (xy 73.669135 -319.749159) (xy 73.676539 -319.810151) (xy 73.676542 -319.87159)
			(xy 73.669145 -319.932583) (xy 73.654456 -319.992241) (xy 73.632689 -320.049695) (xy 73.604159 -320.104109)
			(xy 73.587102 -320.129662) (xy 73.581739 -320.138363) (xy 73.577667 -320.15837) (xy 73.581716 -320.178382)
			(xy 73.587102 -320.187066) (xy 73.604128 -320.212641) (xy 73.632664 -320.267051) (xy 73.654439 -320.324503)
			(xy 73.669135 -320.384159) (xy 73.676539 -320.445151) (xy 73.676542 -320.50659) (xy 73.669145 -320.567583)
			(xy 73.654456 -320.627241) (xy 73.632689 -320.684695) (xy 73.604159 -320.739109) (xy 73.587102 -320.764662)
			(xy 73.581739 -320.773363) (xy 73.577667 -320.79337) (xy 73.581716 -320.813382) (xy 73.587102 -320.822066)
			(xy 73.604128 -320.847641) (xy 73.632664 -320.902051) (xy 73.654439 -320.959503) (xy 73.669135 -321.019159)
			(xy 73.676539 -321.080151) (xy 73.676542 -321.14159) (xy 73.669145 -321.202583) (xy 73.654456 -321.262241)
			(xy 73.632689 -321.319695) (xy 73.604159 -321.374109) (xy 73.587102 -321.399662) (xy 73.581739 -321.408363)
			(xy 73.577667 -321.42837) (xy 73.581716 -321.448382) (xy 73.587102 -321.457066) (xy 73.604128 -321.482641)
			(xy 73.632664 -321.537051) (xy 73.654439 -321.594503) (xy 73.669135 -321.654159) (xy 73.676539 -321.715151)
			(xy 73.676542 -321.77659) (xy 73.669145 -321.837583) (xy 73.654456 -321.897241) (xy 73.632689 -321.954695)
			(xy 73.604159 -322.009109) (xy 73.587102 -322.034662) (xy 73.581739 -322.043363) (xy 73.577667 -322.06337)
			(xy 73.581716 -322.083382) (xy 73.587102 -322.092066) (xy 73.604141 -322.117632) (xy 73.632677 -322.172043)
			(xy 73.654452 -322.229495) (xy 73.669149 -322.289152) (xy 73.676553 -322.350144) (xy 73.676695 -322.359528)
			(xy 75.706986 -322.359528) (xy 75.706986 -322.359274) (xy 75.707447 -322.328553) (xy 75.714849 -322.267559)
			(xy 75.729542 -322.207901) (xy 75.751313 -322.150445) (xy 75.779844 -322.09603) (xy 75.796902 -322.070476)
			(xy 75.802317 -322.061803) (xy 75.806372 -322.041778) (xy 75.8023 -322.021757) (xy 75.796902 -322.013072)
			(xy 75.779819 -321.987534) (xy 75.751286 -321.933117) (xy 75.729516 -321.875659) (xy 75.714825 -321.815997)
			(xy 75.707427 -321.755001) (xy 75.707429 -321.693557) (xy 75.714832 -321.632561) (xy 75.729529 -321.5729)
			(xy 75.751304 -321.515444) (xy 75.779841 -321.461029) (xy 75.796902 -321.435476) (xy 75.802317 -321.426803)
			(xy 75.806372 -321.406778) (xy 75.8023 -321.386757) (xy 75.796902 -321.378072) (xy 75.779819 -321.352534)
			(xy 75.751286 -321.298117) (xy 75.729516 -321.240659) (xy 75.714825 -321.180997) (xy 75.707427 -321.120001)
			(xy 75.707429 -321.058557) (xy 75.714832 -320.997561) (xy 75.729529 -320.9379) (xy 75.751304 -320.880444)
			(xy 75.779841 -320.826029) (xy 75.796902 -320.800476) (xy 75.802317 -320.791803) (xy 75.806372 -320.771778)
			(xy 75.8023 -320.751757) (xy 75.796902 -320.743072) (xy 75.779819 -320.717534) (xy 75.751286 -320.663117)
			(xy 75.729516 -320.605659) (xy 75.714825 -320.545997) (xy 75.707427 -320.485001) (xy 75.707429 -320.423557)
			(xy 75.714832 -320.362561) (xy 75.729529 -320.3029) (xy 75.751304 -320.245444) (xy 75.779841 -320.191029)
			(xy 75.796902 -320.165476) (xy 75.802317 -320.156803) (xy 75.806372 -320.136778) (xy 75.8023 -320.116757)
			(xy 75.796902 -320.108072) (xy 75.779819 -320.082534) (xy 75.751286 -320.028117) (xy 75.729516 -319.970659)
			(xy 75.714825 -319.910997) (xy 75.707427 -319.850001) (xy 75.707429 -319.788557) (xy 75.714832 -319.727561)
			(xy 75.729529 -319.6679) (xy 75.751304 -319.610444) (xy 75.779841 -319.556029) (xy 75.796902 -319.530476)
			(xy 75.802317 -319.521803) (xy 75.806372 -319.501778) (xy 75.8023 -319.481757) (xy 75.796902 -319.473072)
			(xy 75.779819 -319.447534) (xy 75.751286 -319.393117) (xy 75.729516 -319.335659) (xy 75.714825 -319.275997)
			(xy 75.707427 -319.215001) (xy 75.707429 -319.153557) (xy 75.714832 -319.092561) (xy 75.729529 -319.0329)
			(xy 75.751304 -318.975444) (xy 75.779841 -318.921029) (xy 75.796902 -318.895476) (xy 75.802317 -318.886803)
			(xy 75.806372 -318.866778) (xy 75.8023 -318.846757) (xy 75.796902 -318.838072) (xy 75.779819 -318.812534)
			(xy 75.751286 -318.758117) (xy 75.729516 -318.700659) (xy 75.714825 -318.640997) (xy 75.707427 -318.580001)
			(xy 75.707429 -318.518557) (xy 75.714832 -318.457561) (xy 75.729529 -318.3979) (xy 75.751304 -318.340444)
			(xy 75.779841 -318.286029) (xy 75.796902 -318.260476) (xy 75.802317 -318.251803) (xy 75.806372 -318.231778)
			(xy 75.8023 -318.211757) (xy 75.796902 -318.203072) (xy 75.779819 -318.177534) (xy 75.751286 -318.123117)
			(xy 75.729516 -318.065659) (xy 75.714825 -318.005997) (xy 75.707427 -317.945001) (xy 75.707429 -317.883557)
			(xy 75.714832 -317.822561) (xy 75.729529 -317.7629) (xy 75.751304 -317.705444) (xy 75.779841 -317.651029)
			(xy 75.796902 -317.625476) (xy 75.802317 -317.616803) (xy 75.806372 -317.596778) (xy 75.8023 -317.576757)
			(xy 75.796902 -317.568072) (xy 75.779819 -317.542534) (xy 75.751286 -317.488117) (xy 75.729516 -317.430659)
			(xy 75.714825 -317.370997) (xy 75.707427 -317.310001) (xy 75.707429 -317.248557) (xy 75.714832 -317.187561)
			(xy 75.729529 -317.1279) (xy 75.751304 -317.070444) (xy 75.779841 -317.016029) (xy 75.796902 -316.990476)
			(xy 75.802317 -316.981803) (xy 75.806372 -316.961778) (xy 75.8023 -316.941757) (xy 75.796902 -316.933072)
			(xy 75.779836 -316.907523) (xy 75.751305 -316.853107) (xy 75.729535 -316.795651) (xy 75.714845 -316.73599)
			(xy 75.707447 -316.674995) (xy 75.706986 -316.644274) (xy 75.707432 -316.613543) (xy 75.714843 -316.552528)
			(xy 75.729554 -316.492852) (xy 75.751351 -316.435385) (xy 75.779916 -316.380963) (xy 75.814832 -316.330381)
			(xy 75.855591 -316.284377) (xy 75.901597 -316.24362) (xy 75.95218 -316.208706) (xy 76.006603 -316.180143)
			(xy 76.064072 -316.158348) (xy 76.123748 -316.143639) (xy 76.184763 -316.13623) (xy 76.215494 -316.135766)
			(xy 76.246214 -316.136247) (xy 76.307207 -316.143645) (xy 76.366866 -316.158334) (xy 76.424321 -316.1801)
			(xy 76.478737 -316.208627) (xy 76.504292 -316.225682) (xy 76.512977 -316.231075) (xy 76.532994 -316.235136)
			(xy 76.553011 -316.231075) (xy 76.561696 -316.225682) (xy 76.58725 -316.208624) (xy 76.641665 -316.180093)
			(xy 76.69912 -316.158322) (xy 76.758779 -316.14363) (xy 76.819773 -316.13623) (xy 76.881215 -316.13623)
			(xy 76.942209 -316.14363) (xy 77.001868 -316.158322) (xy 77.059323 -316.180093) (xy 77.113738 -316.208624)
			(xy 77.139292 -316.225682) (xy 77.147977 -316.231075) (xy 77.167994 -316.235136) (xy 77.188011 -316.231075)
			(xy 77.196696 -316.225682) (xy 77.222253 -316.208628) (xy 77.276667 -316.180095) (xy 77.334121 -316.158323)
			(xy 77.39378 -316.14363) (xy 77.454773 -316.136229) (xy 77.485494 -316.135766) (xy 77.516224 -316.136262)
			(xy 77.577236 -316.143669) (xy 77.63691 -316.158376) (xy 77.694376 -316.180169) (xy 77.748797 -316.208729)
			(xy 77.799378 -316.243641) (xy 77.845382 -316.284395) (xy 77.886139 -316.330397) (xy 77.921054 -316.380976)
			(xy 77.949618 -316.435395) (xy 77.971414 -316.49286) (xy 77.986125 -316.552533) (xy 77.993536 -316.613544)
			(xy 77.994002 -316.644274) (xy 77.993517 -316.674994) (xy 77.986121 -316.735987) (xy 77.971433 -316.795646)
			(xy 77.949668 -316.853101) (xy 77.921141 -316.907517) (xy 77.904086 -316.933072) (xy 77.898716 -316.941769)
			(xy 77.894648 -316.961778) (xy 77.898699 -316.981791) (xy 77.904086 -316.990476) (xy 77.921119 -317.016046)
			(xy 77.94965 -317.070459) (xy 77.97142 -317.127911) (xy 77.986112 -317.187568) (xy 77.993514 -317.248559)
			(xy 77.993517 -317.309998) (xy 77.98612 -317.37099) (xy 77.971432 -317.430648) (xy 77.949667 -317.488102)
			(xy 77.921141 -317.542518) (xy 77.904086 -317.568072) (xy 77.898716 -317.576769) (xy 77.894648 -317.596778)
			(xy 77.898699 -317.616791) (xy 77.904086 -317.625476) (xy 77.921119 -317.651046) (xy 77.94965 -317.705459)
			(xy 77.97142 -317.762911) (xy 77.986112 -317.822568) (xy 77.993514 -317.883559) (xy 77.993517 -317.944998)
			(xy 77.98612 -318.00599) (xy 77.971432 -318.065648) (xy 77.949667 -318.123102) (xy 77.921141 -318.177518)
			(xy 77.904086 -318.203072) (xy 77.898716 -318.211769) (xy 77.894648 -318.231778) (xy 77.898699 -318.251791)
			(xy 77.904086 -318.260476) (xy 77.921119 -318.286046) (xy 77.94965 -318.340459) (xy 77.97142 -318.397911)
			(xy 77.986112 -318.457568) (xy 77.993514 -318.518559) (xy 77.993517 -318.579998) (xy 77.98612 -318.64099)
			(xy 77.971432 -318.700648) (xy 77.949667 -318.758102) (xy 77.921141 -318.812518) (xy 77.904086 -318.838072)
			(xy 77.898716 -318.846769) (xy 77.894648 -318.866778) (xy 77.898699 -318.886791) (xy 77.904086 -318.895476)
			(xy 77.921119 -318.921046) (xy 77.94965 -318.975459) (xy 77.97142 -319.032911) (xy 77.986112 -319.092568)
			(xy 77.993514 -319.153559) (xy 77.993517 -319.214998) (xy 77.98612 -319.27599) (xy 77.971432 -319.335648)
			(xy 77.949667 -319.393102) (xy 77.921141 -319.447518) (xy 77.904086 -319.473072) (xy 77.898716 -319.481769)
			(xy 77.894648 -319.501778) (xy 77.898699 -319.521791) (xy 77.904086 -319.530476) (xy 77.921127 -319.556041)
			(xy 77.949664 -319.610452) (xy 77.971438 -319.667904) (xy 77.986134 -319.727561) (xy 77.993538 -319.788554)
			(xy 77.994002 -319.819274) (xy 77.993604 -319.848229) (xy 77.987005 -319.905764) (xy 77.973913 -319.962175)
			(xy 77.954497 -320.016735) (xy 77.929009 -320.068735) (xy 77.913738 -320.09334) (xy 77.90857 -320.102345)
			(xy 77.905186 -320.122807) (xy 77.910155 -320.142943) (xy 77.916024 -320.151506) (xy 77.935526 -320.178118)
			(xy 77.968268 -320.235396) (xy 77.993329 -320.296427) (xy 78.010287 -320.360187) (xy 78.018858 -320.425604)
			(xy 78.019402 -320.458592) (xy 78.019402 -320.458846) (xy 78.018953 -320.489567) (xy 78.011549 -320.550562)
			(xy 77.996853 -320.610221) (xy 77.975079 -320.667675) (xy 77.946545 -320.72209) (xy 77.929486 -320.747644)
			(xy 77.924055 -320.756308) (xy 77.920007 -320.776338) (xy 77.924085 -320.796363) (xy 77.929486 -320.805048)
			(xy 77.946585 -320.830575) (xy 77.975111 -320.884996) (xy 77.996876 -320.942456) (xy 78.011563 -321.002119)
			(xy 78.018958 -321.063116) (xy 78.018954 -321.12456) (xy 78.01155 -321.185556) (xy 77.996854 -321.245217)
			(xy 77.97508 -321.302673) (xy 77.946545 -321.35709) (xy 77.929486 -321.382644) (xy 77.924055 -321.391308)
			(xy 77.920007 -321.411338) (xy 77.924085 -321.431363) (xy 77.929486 -321.440048) (xy 77.946585 -321.465575)
			(xy 77.975111 -321.519996) (xy 77.996876 -321.577456) (xy 78.011563 -321.637119) (xy 78.018958 -321.698116)
			(xy 78.018954 -321.75956) (xy 78.01155 -321.820556) (xy 77.996854 -321.880217) (xy 77.97508 -321.937673)
			(xy 77.946545 -321.99209) (xy 77.929486 -322.017644) (xy 77.924055 -322.026308) (xy 77.920007 -322.046338)
			(xy 77.924085 -322.066363) (xy 77.929486 -322.075048) (xy 77.946559 -322.100593) (xy 77.97509 -322.15501)
			(xy 77.996858 -322.212467) (xy 78.011547 -322.272128) (xy 78.018942 -322.333125) (xy 78.019402 -322.363846)
			(xy 78.019402 -322.3641) (xy 78.018874 -322.397081) (xy 78.010374 -322.462493) (xy 77.99348 -322.526255)
			(xy 77.968474 -322.587293) (xy 77.935777 -322.644582) (xy 77.916278 -322.671186) (xy 77.91036 -322.679782)
			(xy 77.905444 -322.700047) (xy 77.90897 -322.7206) (xy 77.914246 -322.729606) (xy 77.930085 -322.754531)
			(xy 77.956539 -322.807331) (xy 77.976697 -322.86284) (xy 77.990289 -322.920311) (xy 77.997131 -322.97897)
			(xy 77.997558 -323.008498) (xy 77.997558 -323.008752) (xy 79.723742 -323.008752) (xy 79.723742 -323.008498)
			(xy 79.72428 -322.975517) (xy 79.732779 -322.910106) (xy 79.749672 -322.846345) (xy 79.774675 -322.785306)
			(xy 79.807369 -322.728017) (xy 79.826866 -322.701412) (xy 79.832783 -322.692817) (xy 79.837694 -322.672551)
			(xy 79.834171 -322.652) (xy 79.828898 -322.642992) (xy 79.813063 -322.618065) (xy 79.786608 -322.565266)
			(xy 79.766448 -322.509757) (xy 79.752855 -322.452287) (xy 79.746012 -322.393628) (xy 79.745586 -322.3641)
			(xy 79.745586 -322.363846) (xy 79.746033 -322.333125) (xy 79.753438 -322.27213) (xy 79.768135 -322.212471)
			(xy 79.789909 -322.155017) (xy 79.818443 -322.100602) (xy 79.835502 -322.075048) (xy 79.840856 -322.066342)
			(xy 79.844931 -322.046338) (xy 79.840886 -322.026328) (xy 79.835502 -322.017644) (xy 79.818485 -321.992064)
			(xy 79.789948 -321.937654) (xy 79.768173 -321.880203) (xy 79.753476 -321.820548) (xy 79.746071 -321.759557)
			(xy 79.746066 -321.698118) (xy 79.753462 -321.637126) (xy 79.76815 -321.577469) (xy 79.789917 -321.520015)
			(xy 79.818445 -321.465601) (xy 79.835502 -321.440048) (xy 79.840856 -321.431342) (xy 79.844931 -321.411338)
			(xy 79.840886 -321.391328) (xy 79.835502 -321.382644) (xy 79.818485 -321.357064) (xy 79.789948 -321.302654)
			(xy 79.768173 -321.245203) (xy 79.753476 -321.185548) (xy 79.746071 -321.124557) (xy 79.746066 -321.063118)
			(xy 79.753462 -321.002126) (xy 79.76815 -320.942469) (xy 79.789917 -320.885015) (xy 79.818445 -320.830601)
			(xy 79.835502 -320.805048) (xy 79.840856 -320.796342) (xy 79.844931 -320.776338) (xy 79.840886 -320.756328)
			(xy 79.835502 -320.747644) (xy 79.818424 -320.722103) (xy 79.789895 -320.667685) (xy 79.768128 -320.610226)
			(xy 79.75344 -320.550564) (xy 79.746045 -320.489568) (xy 79.745586 -320.458846) (xy 79.745586 -320.458592)
			(xy 79.746063 -320.427653) (xy 79.753562 -320.366231) (xy 79.768461 -320.306173) (xy 79.790539 -320.248368)
			(xy 79.81947 -320.193669) (xy 79.836772 -320.168016) (xy 79.842298 -320.159289) (xy 79.846434 -320.139067)
			(xy 79.842272 -320.11885) (xy 79.836772 -320.110104) (xy 79.819477 -320.084446) (xy 79.790545 -320.029748)
			(xy 79.768462 -319.971944) (xy 79.753556 -319.911888) (xy 79.746045 -319.850467) (xy 79.745586 -319.819528)
			(xy 79.745586 -319.819274) (xy 79.746047 -319.788553) (xy 79.753449 -319.727559) (xy 79.768142 -319.667901)
			(xy 79.789913 -319.610445) (xy 79.818444 -319.55603) (xy 79.835502 -319.530476) (xy 79.840917 -319.521803)
			(xy 79.844972 -319.501778) (xy 79.8409 -319.481757) (xy 79.835502 -319.473072) (xy 79.818419 -319.447534)
			(xy 79.789886 -319.393117) (xy 79.768116 -319.335659) (xy 79.753425 -319.275997) (xy 79.746027 -319.215001)
			(xy 79.746029 -319.153557) (xy 79.753432 -319.092561) (xy 79.768129 -319.0329) (xy 79.789904 -318.975444)
			(xy 79.818441 -318.921029) (xy 79.835502 -318.895476) (xy 79.840917 -318.886803) (xy 79.844972 -318.866778)
			(xy 79.8409 -318.846757) (xy 79.835502 -318.838072) (xy 79.818419 -318.812534) (xy 79.789886 -318.758117)
			(xy 79.768116 -318.700659) (xy 79.753425 -318.640997) (xy 79.746027 -318.580001) (xy 79.746029 -318.518557)
			(xy 79.753432 -318.457561) (xy 79.768129 -318.3979) (xy 79.789904 -318.340444) (xy 79.818441 -318.286029)
			(xy 79.835502 -318.260476) (xy 79.840917 -318.251803) (xy 79.844972 -318.231778) (xy 79.8409 -318.211757)
			(xy 79.835502 -318.203072) (xy 79.818419 -318.177534) (xy 79.789886 -318.123117) (xy 79.768116 -318.065659)
			(xy 79.753425 -318.005997) (xy 79.746027 -317.945001) (xy 79.746029 -317.883557) (xy 79.753432 -317.822561)
			(xy 79.768129 -317.7629) (xy 79.789904 -317.705444) (xy 79.818441 -317.651029) (xy 79.835502 -317.625476)
			(xy 79.840917 -317.616803) (xy 79.844972 -317.596778) (xy 79.8409 -317.576757) (xy 79.835502 -317.568072)
			(xy 79.818419 -317.542534) (xy 79.789886 -317.488117) (xy 79.768116 -317.430659) (xy 79.753425 -317.370997)
			(xy 79.746027 -317.310001) (xy 79.746029 -317.248557) (xy 79.753432 -317.187561) (xy 79.768129 -317.1279)
			(xy 79.789904 -317.070444) (xy 79.818441 -317.016029) (xy 79.835502 -316.990476) (xy 79.840917 -316.981803)
			(xy 79.844972 -316.961778) (xy 79.8409 -316.941757) (xy 79.835502 -316.933072) (xy 79.818436 -316.907523)
			(xy 79.789905 -316.853107) (xy 79.768135 -316.795651) (xy 79.753445 -316.73599) (xy 79.746047 -316.674995)
			(xy 79.745586 -316.644274) (xy 79.746032 -316.613543) (xy 79.753443 -316.552528) (xy 79.768154 -316.492852)
			(xy 79.789951 -316.435385) (xy 79.818516 -316.380963) (xy 79.853432 -316.330381) (xy 79.894191 -316.284377)
			(xy 79.940197 -316.24362) (xy 79.99078 -316.208706) (xy 80.045203 -316.180143) (xy 80.102672 -316.158348)
			(xy 80.162348 -316.143639) (xy 80.223363 -316.13623) (xy 80.254094 -316.135766) (xy 80.284814 -316.136247)
			(xy 80.345807 -316.143645) (xy 80.405466 -316.158334) (xy 80.462921 -316.1801) (xy 80.517337 -316.208627)
			(xy 80.542892 -316.225682) (xy 80.551577 -316.231075) (xy 80.571594 -316.235136) (xy 80.591611 -316.231075)
			(xy 80.600296 -316.225682) (xy 80.62585 -316.208624) (xy 80.680265 -316.180093) (xy 80.73772 -316.158322)
			(xy 80.797379 -316.14363) (xy 80.858373 -316.13623) (xy 80.919815 -316.13623) (xy 80.980809 -316.14363)
			(xy 81.040468 -316.158322) (xy 81.097923 -316.180093) (xy 81.152338 -316.208624) (xy 81.177892 -316.225682)
			(xy 81.186577 -316.231075) (xy 81.206594 -316.235136) (xy 81.226611 -316.231075) (xy 81.235296 -316.225682)
			(xy 81.260853 -316.208628) (xy 81.315267 -316.180095) (xy 81.372721 -316.158323) (xy 81.43238 -316.14363)
			(xy 81.493373 -316.136229) (xy 81.524094 -316.135766) (xy 81.554824 -316.136262) (xy 81.615836 -316.143669)
			(xy 81.67551 -316.158376) (xy 81.732976 -316.180169) (xy 81.787397 -316.208729) (xy 81.837978 -316.243641)
			(xy 81.883982 -316.284395) (xy 81.924739 -316.330397) (xy 81.959654 -316.380976) (xy 81.988218 -316.435395)
			(xy 82.010014 -316.49286) (xy 82.024725 -316.552533) (xy 82.032136 -316.613544) (xy 82.032602 -316.644274)
			(xy 82.032117 -316.674994) (xy 82.024721 -316.735987) (xy 82.010033 -316.795646) (xy 81.988268 -316.853101)
			(xy 81.959741 -316.907517) (xy 81.942686 -316.933072) (xy 81.937316 -316.941769) (xy 81.933248 -316.961778)
			(xy 81.937299 -316.981791) (xy 81.942686 -316.990476) (xy 81.959719 -317.016046) (xy 81.98825 -317.070459)
			(xy 82.01002 -317.127911) (xy 82.024712 -317.187568) (xy 82.032114 -317.248559) (xy 82.032117 -317.309998)
			(xy 82.02472 -317.37099) (xy 82.010032 -317.430648) (xy 81.988267 -317.488102) (xy 81.959741 -317.542518)
			(xy 81.942686 -317.568072) (xy 81.937316 -317.576769) (xy 81.933248 -317.596778) (xy 81.937299 -317.616791)
			(xy 81.942686 -317.625476) (xy 81.959719 -317.651046) (xy 81.98825 -317.705459) (xy 82.01002 -317.762911)
			(xy 82.024712 -317.822568) (xy 82.032114 -317.883559) (xy 82.032117 -317.944998) (xy 82.02472 -318.00599)
			(xy 82.010032 -318.065648) (xy 81.988267 -318.123102) (xy 81.959741 -318.177518) (xy 81.942686 -318.203072)
			(xy 81.937316 -318.211769) (xy 81.933248 -318.231778) (xy 81.937299 -318.251791) (xy 81.942686 -318.260476)
			(xy 81.959719 -318.286046) (xy 81.98825 -318.340459) (xy 82.01002 -318.397911) (xy 82.024712 -318.457568)
			(xy 82.032114 -318.518559) (xy 82.032117 -318.579998) (xy 82.02472 -318.64099) (xy 82.010032 -318.700648)
			(xy 81.988267 -318.758102) (xy 81.959741 -318.812518) (xy 81.942686 -318.838072) (xy 81.937316 -318.846769)
			(xy 81.933248 -318.866778) (xy 81.937299 -318.886791) (xy 81.942686 -318.895476) (xy 81.959719 -318.921046)
			(xy 81.98825 -318.975459) (xy 82.01002 -319.032911) (xy 82.024712 -319.092568) (xy 82.032114 -319.153559)
			(xy 82.032117 -319.214998) (xy 82.02472 -319.27599) (xy 82.010032 -319.335648) (xy 81.988267 -319.393102)
			(xy 81.959741 -319.447518) (xy 81.942686 -319.473072) (xy 81.937316 -319.481769) (xy 81.933248 -319.501778)
			(xy 81.937299 -319.521791) (xy 81.942686 -319.530476) (xy 81.959719 -319.556046) (xy 81.98825 -319.610459)
			(xy 82.01002 -319.667911) (xy 82.024712 -319.727568) (xy 82.032114 -319.788559) (xy 82.032117 -319.849998)
			(xy 82.02472 -319.91099) (xy 82.010032 -319.970648) (xy 81.988267 -320.028102) (xy 81.959741 -320.082518)
			(xy 81.942686 -320.108072) (xy 81.937316 -320.116769) (xy 81.933248 -320.136778) (xy 81.937299 -320.156791)
			(xy 81.942686 -320.165476) (xy 81.959719 -320.191046) (xy 81.98825 -320.245459) (xy 82.01002 -320.302911)
			(xy 82.024712 -320.362568) (xy 82.032114 -320.423559) (xy 82.032117 -320.484998) (xy 82.02472 -320.54599)
			(xy 82.010032 -320.605648) (xy 81.988267 -320.663102) (xy 81.959741 -320.717518) (xy 81.942686 -320.743072)
			(xy 81.937316 -320.751769) (xy 81.933248 -320.771778) (xy 81.937299 -320.791791) (xy 81.942686 -320.800476)
			(xy 81.959719 -320.826046) (xy 81.98825 -320.880459) (xy 82.01002 -320.937911) (xy 82.024712 -320.997568)
			(xy 82.032114 -321.058559) (xy 82.032117 -321.119998) (xy 82.02472 -321.18099) (xy 82.010032 -321.240648)
			(xy 81.988267 -321.298102) (xy 81.959741 -321.352518) (xy 81.942686 -321.378072) (xy 81.937316 -321.386769)
			(xy 81.933248 -321.406778) (xy 81.937299 -321.426791) (xy 81.942686 -321.435476) (xy 81.959719 -321.461046)
			(xy 81.98825 -321.515459) (xy 82.01002 -321.572911) (xy 82.024712 -321.632568) (xy 82.032114 -321.693559)
			(xy 82.032117 -321.754998) (xy 82.02472 -321.81599) (xy 82.010032 -321.875648) (xy 81.988267 -321.933102)
			(xy 81.959741 -321.987518) (xy 81.942686 -322.013072) (xy 81.937316 -322.021769) (xy 81.933248 -322.041778)
			(xy 81.937299 -322.061791) (xy 81.942686 -322.070476) (xy 81.959727 -322.096041) (xy 81.988264 -322.150452)
			(xy 82.010038 -322.207904) (xy 82.024734 -322.267561) (xy 82.032138 -322.328554) (xy 82.032602 -322.359274)
			(xy 82.032036 -322.392517) (xy 82.023356 -322.458436) (xy 82.006153 -322.522659) (xy 81.980722 -322.58409)
			(xy 81.947496 -322.64168) (xy 81.9277 -322.668392) (xy 81.921752 -322.67709) (xy 81.916824 -322.697554)
			(xy 81.920512 -322.718277) (xy 81.925922 -322.72732) (xy 81.942068 -322.752405) (xy 81.969026 -322.805626)
			(xy 81.989566 -322.861638) (xy 82.003404 -322.919669) (xy 82.01035 -322.978922) (xy 82.010758 -323.008752)
			(xy 84.063586 -323.008752) (xy 84.064036 -322.978031) (xy 84.07144 -322.917037) (xy 84.086136 -322.857378)
			(xy 84.10791 -322.799923) (xy 84.136443 -322.745508) (xy 84.153502 -322.719954) (xy 84.158936 -322.711291)
			(xy 84.162984 -322.69126) (xy 84.158905 -322.671235) (xy 84.153502 -322.66255) (xy 84.136399 -322.637025)
			(xy 84.107868 -322.582605) (xy 84.086099 -322.525145) (xy 84.071409 -322.465482) (xy 84.064013 -322.404483)
			(xy 84.064018 -322.343038) (xy 84.071423 -322.28204) (xy 84.086122 -322.222379) (xy 84.1079 -322.164923)
			(xy 84.13644 -322.110507) (xy 84.153502 -322.084954) (xy 84.158936 -322.076291) (xy 84.162984 -322.05626)
			(xy 84.158905 -322.036235) (xy 84.153502 -322.02755) (xy 84.136399 -322.002025) (xy 84.107868 -321.947605)
			(xy 84.086099 -321.890145) (xy 84.071409 -321.830482) (xy 84.064013 -321.769483) (xy 84.064018 -321.708038)
			(xy 84.071423 -321.64704) (xy 84.086122 -321.587379) (xy 84.1079 -321.529923) (xy 84.13644 -321.475507)
			(xy 84.153502 -321.449954) (xy 84.158936 -321.441291) (xy 84.162984 -321.42126) (xy 84.158905 -321.401235)
			(xy 84.153502 -321.39255) (xy 84.136399 -321.367025) (xy 84.107868 -321.312605) (xy 84.086099 -321.255145)
			(xy 84.071409 -321.195482) (xy 84.064013 -321.134483) (xy 84.064018 -321.073038) (xy 84.071423 -321.01204)
			(xy 84.086122 -320.952379) (xy 84.1079 -320.894923) (xy 84.13644 -320.840507) (xy 84.153502 -320.814954)
			(xy 84.158936 -320.806291) (xy 84.162984 -320.78626) (xy 84.158905 -320.766235) (xy 84.153502 -320.75755)
			(xy 84.136427 -320.732007) (xy 84.107897 -320.677589) (xy 84.086129 -320.620131) (xy 84.071441 -320.56047)
			(xy 84.064046 -320.499474) (xy 84.063586 -320.468752) (xy 84.063586 -320.468498) (xy 84.064065 -320.436929)
			(xy 84.071928 -320.374281) (xy 84.087483 -320.313089) (xy 84.110491 -320.254291) (xy 84.140598 -320.198792)
			(xy 84.158582 -320.172842) (xy 84.164278 -320.163981) (xy 84.16858 -320.143382) (xy 84.164263 -320.122786)
			(xy 84.158582 -320.113914) (xy 84.140777 -320.088004) (xy 84.110968 -320.032654) (xy 84.088202 -319.974053)
			(xy 84.072826 -319.913095) (xy 84.065074 -319.850708) (xy 84.064602 -319.819274) (xy 84.06506 -319.788553)
			(xy 84.072462 -319.727559) (xy 84.087156 -319.6679) (xy 84.108928 -319.610445) (xy 84.13746 -319.55603)
			(xy 84.154518 -319.530476) (xy 84.159932 -319.521803) (xy 84.163985 -319.501778) (xy 84.159915 -319.481757)
			(xy 84.154518 -319.473072) (xy 84.137438 -319.447533) (xy 84.10891 -319.393115) (xy 84.087143 -319.335657)
			(xy 84.072454 -319.275996) (xy 84.065057 -319.215) (xy 84.06506 -319.153557) (xy 84.072462 -319.092562)
			(xy 84.087156 -319.032902) (xy 84.108927 -318.975446) (xy 84.13746 -318.92103) (xy 84.154518 -318.895476)
			(xy 84.159932 -318.886803) (xy 84.163985 -318.866778) (xy 84.159915 -318.846757) (xy 84.154518 -318.838072)
			(xy 84.137438 -318.812533) (xy 84.10891 -318.758115) (xy 84.087143 -318.700657) (xy 84.072454 -318.640996)
			(xy 84.065057 -318.58) (xy 84.06506 -318.518557) (xy 84.072462 -318.457562) (xy 84.087156 -318.397902)
			(xy 84.108927 -318.340446) (xy 84.13746 -318.28603) (xy 84.154518 -318.260476) (xy 84.159932 -318.251803)
			(xy 84.163985 -318.231778) (xy 84.159915 -318.211757) (xy 84.154518 -318.203072) (xy 84.137438 -318.177533)
			(xy 84.10891 -318.123115) (xy 84.087143 -318.065657) (xy 84.072454 -318.005996) (xy 84.065057 -317.945)
			(xy 84.06506 -317.883557) (xy 84.072462 -317.822562) (xy 84.087156 -317.762902) (xy 84.108927 -317.705446)
			(xy 84.13746 -317.65103) (xy 84.154518 -317.625476) (xy 84.159932 -317.616803) (xy 84.163985 -317.596778)
			(xy 84.159915 -317.576757) (xy 84.154518 -317.568072) (xy 84.137438 -317.542533) (xy 84.10891 -317.488115)
			(xy 84.087143 -317.430657) (xy 84.072454 -317.370996) (xy 84.065057 -317.31) (xy 84.06506 -317.248557)
			(xy 84.072462 -317.187562) (xy 84.087156 -317.127902) (xy 84.108927 -317.070446) (xy 84.13746 -317.01603)
			(xy 84.154518 -316.990476) (xy 84.159932 -316.981803) (xy 84.163985 -316.961778) (xy 84.159915 -316.941757)
			(xy 84.154518 -316.933072) (xy 84.137454 -316.907522) (xy 84.108922 -316.853106) (xy 84.087152 -316.79565)
			(xy 84.072461 -316.73599) (xy 84.065063 -316.674995) (xy 84.064602 -316.644274) (xy 84.065032 -316.613542)
			(xy 84.072443 -316.552527) (xy 84.087155 -316.492849) (xy 84.108953 -316.435381) (xy 84.137519 -316.380958)
			(xy 84.172437 -316.330376) (xy 84.213196 -316.284371) (xy 84.259204 -316.243614) (xy 84.309789 -316.208701)
			(xy 84.364214 -316.180138) (xy 84.421684 -316.158345) (xy 84.481362 -316.143637) (xy 84.542378 -316.136229)
			(xy 84.57311 -316.135766) (xy 84.60383 -316.136238) (xy 84.664824 -316.143638) (xy 84.724482 -316.158329)
			(xy 84.781937 -316.180097) (xy 84.836353 -316.208626) (xy 84.861908 -316.225682) (xy 84.870593 -316.231075)
			(xy 84.89061 -316.235136) (xy 84.910627 -316.231075) (xy 84.919312 -316.225682) (xy 84.944866 -316.208624)
			(xy 84.999281 -316.180093) (xy 85.056736 -316.158322) (xy 85.116395 -316.14363) (xy 85.177389 -316.13623)
			(xy 85.238831 -316.13623) (xy 85.299825 -316.14363) (xy 85.359484 -316.158322) (xy 85.416939 -316.180093)
			(xy 85.471354 -316.208624) (xy 85.496908 -316.225682) (xy 85.505593 -316.231075) (xy 85.52561 -316.235136)
			(xy 85.545627 -316.231075) (xy 85.554312 -316.225682) (xy 85.579864 -316.208621) (xy 85.634279 -316.180089)
			(xy 85.691735 -316.158319) (xy 85.751394 -316.143627) (xy 85.812389 -316.136228) (xy 85.84311 -316.135766)
			(xy 85.87384 -316.136247) (xy 85.934852 -316.143656) (xy 85.994527 -316.158365) (xy 86.051993 -316.180159)
			(xy 86.106414 -316.208721) (xy 86.156995 -316.243634) (xy 86.202999 -316.284389) (xy 86.243756 -316.330392)
			(xy 86.278671 -316.380973) (xy 86.307234 -316.435392) (xy 86.329031 -316.492858) (xy 86.343741 -316.552532)
			(xy 86.351152 -316.613544) (xy 86.351618 -316.644274) (xy 86.35113 -316.674994) (xy 86.343734 -316.735987)
			(xy 86.329047 -316.795645) (xy 86.307282 -316.853101) (xy 86.278757 -316.907517) (xy 86.261702 -316.933072)
			(xy 86.256331 -316.941768) (xy 86.252261 -316.961778) (xy 86.256314 -316.981792) (xy 86.261702 -316.990476)
			(xy 86.278738 -317.016045) (xy 86.307273 -317.070456) (xy 86.329047 -317.127909) (xy 86.343742 -317.187566)
			(xy 86.351145 -317.248559) (xy 86.351147 -317.309999) (xy 86.34375 -317.370992) (xy 86.329059 -317.43065)
			(xy 86.30729 -317.488104) (xy 86.27876 -317.542519) (xy 86.261702 -317.568072) (xy 86.256331 -317.576768)
			(xy 86.252261 -317.596778) (xy 86.256314 -317.616792) (xy 86.261702 -317.625476) (xy 86.278738 -317.651045)
			(xy 86.307273 -317.705456) (xy 86.329047 -317.762909) (xy 86.343742 -317.822566) (xy 86.351145 -317.883559)
			(xy 86.351147 -317.944999) (xy 86.34375 -318.005992) (xy 86.329059 -318.06565) (xy 86.30729 -318.123104)
			(xy 86.27876 -318.177519) (xy 86.261702 -318.203072) (xy 86.256331 -318.211768) (xy 86.252261 -318.231778)
			(xy 86.256314 -318.251792) (xy 86.261702 -318.260476) (xy 86.278738 -318.286045) (xy 86.307273 -318.340456)
			(xy 86.329047 -318.397909) (xy 86.343742 -318.457566) (xy 86.351145 -318.518559) (xy 86.351147 -318.579999)
			(xy 86.34375 -318.640992) (xy 86.329059 -318.70065) (xy 86.30729 -318.758104) (xy 86.27876 -318.812519)
			(xy 86.261702 -318.838072) (xy 86.256331 -318.846768) (xy 86.252261 -318.866778) (xy 86.256314 -318.886792)
			(xy 86.261702 -318.895476) (xy 86.278738 -318.921045) (xy 86.307273 -318.975456) (xy 86.329047 -319.032909)
			(xy 86.343742 -319.092566) (xy 86.351145 -319.153559) (xy 86.351147 -319.214999) (xy 86.34375 -319.275992)
			(xy 86.329059 -319.33565) (xy 86.30729 -319.393104) (xy 86.27876 -319.447519) (xy 86.261702 -319.473072)
			(xy 86.256331 -319.481768) (xy 86.252261 -319.501778) (xy 86.256314 -319.521792) (xy 86.261702 -319.530476)
			(xy 86.278745 -319.556039) (xy 86.307281 -319.610451) (xy 86.329055 -319.667904) (xy 86.343751 -319.727561)
			(xy 86.351154 -319.788554) (xy 86.351618 -319.819274) (xy 86.351217 -319.848229) (xy 86.344619 -319.905763)
			(xy 86.331527 -319.962175) (xy 86.312112 -320.016735) (xy 86.286625 -320.068735) (xy 86.271354 -320.09334)
			(xy 86.266197 -320.102348) (xy 86.262818 -320.122807) (xy 86.267779 -320.14294) (xy 86.27364 -320.151506)
			(xy 86.293144 -320.178116) (xy 86.325886 -320.235395) (xy 86.350945 -320.296427) (xy 86.367903 -320.360187)
			(xy 86.376474 -320.425604) (xy 86.377018 -320.458592) (xy 86.377018 -320.458846) (xy 86.376567 -320.489567)
			(xy 86.369162 -320.550561) (xy 86.354467 -320.61022) (xy 86.332694 -320.667675) (xy 86.30416 -320.72209)
			(xy 86.287102 -320.747644) (xy 86.281669 -320.756308) (xy 86.27762 -320.776338) (xy 86.281699 -320.796363)
			(xy 86.287102 -320.805048) (xy 86.304203 -320.830574) (xy 86.332734 -320.884994) (xy 86.354503 -320.942454)
			(xy 86.369193 -321.002117) (xy 86.376589 -321.063115) (xy 86.376584 -321.12456) (xy 86.369179 -321.185558)
			(xy 86.354481 -321.245219) (xy 86.332703 -321.302675) (xy 86.304164 -321.357091) (xy 86.287102 -321.382644)
			(xy 86.281669 -321.391308) (xy 86.27762 -321.411338) (xy 86.281699 -321.431363) (xy 86.287102 -321.440048)
			(xy 86.304203 -321.465574) (xy 86.332734 -321.519994) (xy 86.354503 -321.577454) (xy 86.369193 -321.637117)
			(xy 86.376589 -321.698115) (xy 86.376584 -321.75956) (xy 86.369179 -321.820558) (xy 86.354481 -321.880219)
			(xy 86.332703 -321.937675) (xy 86.304164 -321.992091) (xy 86.287102 -322.017644) (xy 86.281669 -322.026308)
			(xy 86.27762 -322.046338) (xy 86.281699 -322.066363) (xy 86.287102 -322.075048) (xy 86.304177 -322.100591)
			(xy 86.332707 -322.155009) (xy 86.354474 -322.212467) (xy 86.369163 -322.272128) (xy 86.376558 -322.333124)
			(xy 86.377018 -322.363846) (xy 86.376482 -322.397208) (xy 86.36776 -322.463359) (xy 86.350471 -322.527804)
			(xy 86.324911 -322.589439) (xy 86.291519 -322.647206) (xy 86.271608 -322.67398) (xy 86.265601 -322.682573)
			(xy 86.260479 -322.702886) (xy 86.263842 -322.723563) (xy 86.269068 -322.732654) (xy 86.284604 -322.757378)
			(xy 86.310496 -322.809719) (xy 86.330218 -322.864682) (xy 86.34351 -322.921544) (xy 86.350197 -322.979555)
			(xy 86.350602 -323.008752) (xy 88.102186 -323.008752) (xy 88.102661 -322.977411) (xy 88.110367 -322.915203)
			(xy 88.125656 -322.854414) (xy 88.148297 -322.795963) (xy 88.177947 -322.740736) (xy 88.195658 -322.714874)
			(xy 88.201288 -322.706087) (xy 88.20552 -322.68567) (xy 88.201264 -322.665258) (xy 88.195658 -322.656454)
			(xy 88.178122 -322.630665) (xy 88.14877 -322.575639) (xy 88.12637 -322.517436) (xy 88.111257 -322.456929)
			(xy 88.10366 -322.395029) (xy 88.103202 -322.363846) (xy 88.103646 -322.333125) (xy 88.111052 -322.27213)
			(xy 88.125749 -322.212471) (xy 88.147523 -322.155016) (xy 88.176059 -322.100602) (xy 88.193118 -322.075048)
			(xy 88.198471 -322.066342) (xy 88.202544 -322.046338) (xy 88.1985 -322.026329) (xy 88.193118 -322.017644)
			(xy 88.176103 -321.992063) (xy 88.147571 -321.937652) (xy 88.1258 -321.880201) (xy 88.111105 -321.820547)
			(xy 88.103702 -321.759557) (xy 88.103697 -321.698119) (xy 88.111091 -321.637128) (xy 88.125777 -321.577471)
			(xy 88.14754 -321.520017) (xy 88.176064 -321.465602) (xy 88.193118 -321.440048) (xy 88.198471 -321.431342)
			(xy 88.202544 -321.411338) (xy 88.1985 -321.391329) (xy 88.193118 -321.382644) (xy 88.176103 -321.357063)
			(xy 88.147571 -321.302652) (xy 88.1258 -321.245201) (xy 88.111105 -321.185547) (xy 88.103702 -321.124557)
			(xy 88.103697 -321.063119) (xy 88.111091 -321.002128) (xy 88.125777 -320.942471) (xy 88.14754 -320.885017)
			(xy 88.176064 -320.830602) (xy 88.193118 -320.805048) (xy 88.198471 -320.796342) (xy 88.202544 -320.776338)
			(xy 88.1985 -320.756329) (xy 88.193118 -320.747644) (xy 88.176042 -320.722101) (xy 88.147512 -320.667684)
			(xy 88.125744 -320.610226) (xy 88.111056 -320.550564) (xy 88.103661 -320.489568) (xy 88.103202 -320.458846)
			(xy 88.103202 -320.458592) (xy 88.103676 -320.427653) (xy 88.111176 -320.36623) (xy 88.126075 -320.306173)
			(xy 88.148154 -320.248367) (xy 88.177086 -320.193669) (xy 88.194388 -320.168016) (xy 88.199912 -320.159288)
			(xy 88.204047 -320.139067) (xy 88.199886 -320.118851) (xy 88.194388 -320.110104) (xy 88.177096 -320.084444)
			(xy 88.148163 -320.029747) (xy 88.126079 -319.971943) (xy 88.111172 -319.911888) (xy 88.103662 -319.850467)
			(xy 88.103202 -319.819528) (xy 88.103202 -319.819274) (xy 88.10366 -319.788553) (xy 88.111062 -319.727559)
			(xy 88.125756 -319.6679) (xy 88.147528 -319.610445) (xy 88.17606 -319.55603) (xy 88.193118 -319.530476)
			(xy 88.198532 -319.521803) (xy 88.202585 -319.501778) (xy 88.198515 -319.481757) (xy 88.193118 -319.473072)
			(xy 88.176038 -319.447533) (xy 88.14751 -319.393115) (xy 88.125743 -319.335657) (xy 88.111054 -319.275996)
			(xy 88.103657 -319.215) (xy 88.10366 -319.153557) (xy 88.111062 -319.092562) (xy 88.125756 -319.032902)
			(xy 88.147527 -318.975446) (xy 88.17606 -318.92103) (xy 88.193118 -318.895476) (xy 88.198532 -318.886803)
			(xy 88.202585 -318.866778) (xy 88.198515 -318.846757) (xy 88.193118 -318.838072) (xy 88.176038 -318.812533)
			(xy 88.14751 -318.758115) (xy 88.125743 -318.700657) (xy 88.111054 -318.640996) (xy 88.103657 -318.58)
			(xy 88.10366 -318.518557) (xy 88.111062 -318.457562) (xy 88.125756 -318.397902) (xy 88.147527 -318.340446)
			(xy 88.17606 -318.28603) (xy 88.193118 -318.260476) (xy 88.198532 -318.251803) (xy 88.202585 -318.231778)
			(xy 88.198515 -318.211757) (xy 88.193118 -318.203072) (xy 88.176038 -318.177533) (xy 88.14751 -318.123115)
			(xy 88.125743 -318.065657) (xy 88.111054 -318.005996) (xy 88.103657 -317.945) (xy 88.10366 -317.883557)
			(xy 88.111062 -317.822562) (xy 88.125756 -317.762902) (xy 88.147527 -317.705446) (xy 88.17606 -317.65103)
			(xy 88.193118 -317.625476) (xy 88.198532 -317.616803) (xy 88.202585 -317.596778) (xy 88.198515 -317.576757)
			(xy 88.193118 -317.568072) (xy 88.176038 -317.542533) (xy 88.14751 -317.488115) (xy 88.125743 -317.430657)
			(xy 88.111054 -317.370996) (xy 88.103657 -317.31) (xy 88.10366 -317.248557) (xy 88.111062 -317.187562)
			(xy 88.125756 -317.127902) (xy 88.147527 -317.070446) (xy 88.17606 -317.01603) (xy 88.193118 -316.990476)
			(xy 88.198532 -316.981803) (xy 88.202585 -316.961778) (xy 88.198515 -316.941757) (xy 88.193118 -316.933072)
			(xy 88.176054 -316.907522) (xy 88.147522 -316.853106) (xy 88.125752 -316.79565) (xy 88.111061 -316.73599)
			(xy 88.103663 -316.674995) (xy 88.103202 -316.644274) (xy 88.103632 -316.613542) (xy 88.111043 -316.552527)
			(xy 88.125755 -316.492849) (xy 88.147553 -316.435381) (xy 88.176119 -316.380958) (xy 88.211037 -316.330376)
			(xy 88.251796 -316.284371) (xy 88.297804 -316.243614) (xy 88.348389 -316.208701) (xy 88.402814 -316.180138)
			(xy 88.460284 -316.158345) (xy 88.519962 -316.143637) (xy 88.580978 -316.136229) (xy 88.61171 -316.135766)
			(xy 88.64243 -316.136238) (xy 88.703424 -316.143638) (xy 88.763082 -316.158329) (xy 88.820537 -316.180097)
			(xy 88.874953 -316.208626) (xy 88.900508 -316.225682) (xy 88.909193 -316.231075) (xy 88.92921 -316.235136)
			(xy 88.949227 -316.231075) (xy 88.957912 -316.225682) (xy 88.983466 -316.208624) (xy 89.037881 -316.180093)
			(xy 89.095336 -316.158322) (xy 89.154995 -316.14363) (xy 89.215989 -316.13623) (xy 89.277431 -316.13623)
			(xy 89.338425 -316.14363) (xy 89.398084 -316.158322) (xy 89.455539 -316.180093) (xy 89.509954 -316.208624)
			(xy 89.535508 -316.225682) (xy 89.544193 -316.231075) (xy 89.56421 -316.235136) (xy 89.584227 -316.231075)
			(xy 89.592912 -316.225682) (xy 89.618464 -316.208621) (xy 89.672879 -316.180089) (xy 89.730335 -316.158319)
			(xy 89.789994 -316.143627) (xy 89.850989 -316.136228) (xy 89.88171 -316.135766) (xy 89.91244 -316.136247)
			(xy 89.973452 -316.143656) (xy 90.033127 -316.158365) (xy 90.090593 -316.180159) (xy 90.145014 -316.208721)
			(xy 90.195595 -316.243634) (xy 90.241599 -316.284389) (xy 90.282356 -316.330392) (xy 90.317271 -316.380973)
			(xy 90.345834 -316.435392) (xy 90.367631 -316.492858) (xy 90.382341 -316.552532) (xy 90.389752 -316.613544)
			(xy 90.390218 -316.644274) (xy 90.38973 -316.674994) (xy 90.382334 -316.735987) (xy 90.367647 -316.795645)
			(xy 90.345882 -316.853101) (xy 90.317357 -316.907517) (xy 90.300302 -316.933072) (xy 90.294931 -316.941768)
			(xy 90.290861 -316.961778) (xy 90.294914 -316.981792) (xy 90.300302 -316.990476) (xy 90.317338 -317.016045)
			(xy 90.345873 -317.070456) (xy 90.367647 -317.127909) (xy 90.382342 -317.187566) (xy 90.389745 -317.248559)
			(xy 90.389747 -317.309999) (xy 90.38235 -317.370992) (xy 90.367659 -317.43065) (xy 90.34589 -317.488104)
			(xy 90.31736 -317.542519) (xy 90.300302 -317.568072) (xy 90.294931 -317.576768) (xy 90.290861 -317.596778)
			(xy 90.294914 -317.616792) (xy 90.300302 -317.625476) (xy 90.317338 -317.651045) (xy 90.345873 -317.705456)
			(xy 90.367647 -317.762909) (xy 90.382342 -317.822566) (xy 90.389745 -317.883559) (xy 90.389747 -317.944999)
			(xy 90.38235 -318.005992) (xy 90.367659 -318.06565) (xy 90.34589 -318.123104) (xy 90.31736 -318.177519)
			(xy 90.300302 -318.203072) (xy 90.294931 -318.211768) (xy 90.290861 -318.231778) (xy 90.294914 -318.251792)
			(xy 90.300302 -318.260476) (xy 90.317338 -318.286045) (xy 90.345873 -318.340456) (xy 90.367647 -318.397909)
			(xy 90.382342 -318.457566) (xy 90.389745 -318.518559) (xy 90.389747 -318.579999) (xy 90.38235 -318.640992)
			(xy 90.367659 -318.70065) (xy 90.34589 -318.758104) (xy 90.31736 -318.812519) (xy 90.300302 -318.838072)
			(xy 90.294931 -318.846768) (xy 90.290861 -318.866778) (xy 90.294914 -318.886792) (xy 90.300302 -318.895476)
			(xy 90.317338 -318.921045) (xy 90.345873 -318.975456) (xy 90.367647 -319.032909) (xy 90.382342 -319.092566)
			(xy 90.389745 -319.153559) (xy 90.389747 -319.214999) (xy 90.38235 -319.275992) (xy 90.367659 -319.33565)
			(xy 90.34589 -319.393104) (xy 90.31736 -319.447519) (xy 90.300302 -319.473072) (xy 90.294931 -319.481768)
			(xy 90.290861 -319.501778) (xy 90.294914 -319.521792) (xy 90.300302 -319.530476) (xy 90.317338 -319.556045)
			(xy 90.345873 -319.610456) (xy 90.367647 -319.667909) (xy 90.382342 -319.727566) (xy 90.389745 -319.788559)
			(xy 90.389746 -319.833752) (xy 92.318586 -319.833752) (xy 92.319036 -319.803031) (xy 92.32644 -319.742037)
			(xy 92.341136 -319.682378) (xy 92.36291 -319.624923) (xy 92.391443 -319.570508) (xy 92.408502 -319.544954)
			(xy 92.413936 -319.536291) (xy 92.417984 -319.51626) (xy 92.413905 -319.496235) (xy 92.408502 -319.48755)
			(xy 92.391399 -319.462025) (xy 92.362868 -319.407605) (xy 92.341099 -319.350145) (xy 92.326409 -319.290482)
			(xy 92.319013 -319.229483) (xy 92.319018 -319.168038) (xy 92.326423 -319.10704) (xy 92.341122 -319.047379)
			(xy 92.3629 -318.989923) (xy 92.39144 -318.935507) (xy 92.408502 -318.909954) (xy 92.413936 -318.901291)
			(xy 92.417984 -318.88126) (xy 92.413905 -318.861235) (xy 92.408502 -318.85255) (xy 92.391399 -318.827025)
			(xy 92.362868 -318.772605) (xy 92.341099 -318.715145) (xy 92.326409 -318.655482) (xy 92.319013 -318.594483)
			(xy 92.319018 -318.533038) (xy 92.326423 -318.47204) (xy 92.341122 -318.412379) (xy 92.3629 -318.354923)
			(xy 92.39144 -318.300507) (xy 92.408502 -318.274954) (xy 92.413936 -318.266291) (xy 92.417984 -318.24626)
			(xy 92.413905 -318.226235) (xy 92.408502 -318.21755) (xy 92.391399 -318.192025) (xy 92.362868 -318.137605)
			(xy 92.341099 -318.080145) (xy 92.326409 -318.020482) (xy 92.319013 -317.959483) (xy 92.319018 -317.898038)
			(xy 92.326423 -317.83704) (xy 92.341122 -317.777379) (xy 92.3629 -317.719923) (xy 92.39144 -317.665507)
			(xy 92.408502 -317.639954) (xy 92.413936 -317.631291) (xy 92.417984 -317.61126) (xy 92.413905 -317.591235)
			(xy 92.408502 -317.58255) (xy 92.391399 -317.557025) (xy 92.362868 -317.502605) (xy 92.341099 -317.445145)
			(xy 92.326409 -317.385482) (xy 92.319013 -317.324483) (xy 92.319018 -317.263038) (xy 92.326423 -317.20204)
			(xy 92.341122 -317.142379) (xy 92.3629 -317.084923) (xy 92.39144 -317.030507) (xy 92.408502 -317.004954)
			(xy 92.413936 -316.996291) (xy 92.417984 -316.97626) (xy 92.413905 -316.956235) (xy 92.408502 -316.94755)
			(xy 92.391427 -316.922007) (xy 92.362897 -316.867589) (xy 92.341129 -316.810131) (xy 92.326441 -316.75047)
			(xy 92.319046 -316.689474) (xy 92.318586 -316.658752) (xy 92.31901 -316.62802) (xy 92.326424 -316.567005)
			(xy 92.341138 -316.507329) (xy 92.362938 -316.449861) (xy 92.391505 -316.395439) (xy 92.426423 -316.344857)
			(xy 92.467183 -316.298853) (xy 92.51319 -316.258097) (xy 92.563775 -316.223183) (xy 92.618199 -316.19462)
			(xy 92.675669 -316.172826) (xy 92.735347 -316.158117) (xy 92.796362 -316.150708) (xy 92.827094 -316.150244)
			(xy 92.857815 -316.150711) (xy 92.918809 -316.15811) (xy 92.978468 -316.172802) (xy 93.035923 -316.194571)
			(xy 93.090338 -316.223102) (xy 93.115892 -316.24016) (xy 93.124577 -316.245553) (xy 93.144594 -316.249614)
			(xy 93.164611 -316.245553) (xy 93.173296 -316.24016) (xy 93.19885 -316.223102) (xy 93.253265 -316.194571)
			(xy 93.31072 -316.1728) (xy 93.370379 -316.158108) (xy 93.431373 -316.150708) (xy 93.492815 -316.150708)
			(xy 93.553809 -316.158108) (xy 93.613468 -316.1728) (xy 93.670923 -316.194571) (xy 93.725338 -316.223102)
			(xy 93.750892 -316.24016) (xy 93.759577 -316.245553) (xy 93.779594 -316.249614) (xy 93.799611 -316.245553)
			(xy 93.808296 -316.24016) (xy 93.833851 -316.223103) (xy 93.888265 -316.194571) (xy 93.94572 -316.1728)
			(xy 94.005379 -316.158107) (xy 94.066373 -316.150707) (xy 94.097094 -316.150244) (xy 94.127823 -316.150762)
			(xy 94.188833 -316.158168) (xy 94.248506 -316.172875) (xy 94.305971 -316.194666) (xy 94.36039 -316.223225)
			(xy 94.410971 -316.258135) (xy 94.456975 -316.298887) (xy 94.497731 -316.344887) (xy 94.532647 -316.395464)
			(xy 94.561211 -316.44988) (xy 94.583009 -316.507343) (xy 94.597722 -316.567014) (xy 94.605135 -316.628023)
			(xy 94.605602 -316.658752) (xy 94.605156 -316.689473) (xy 94.597751 -316.750468) (xy 94.583054 -316.810127)
			(xy 94.56128 -316.867582) (xy 94.532745 -316.921996) (xy 94.515686 -316.94755) (xy 94.510335 -316.956257)
			(xy 94.506261 -316.97626) (xy 94.510304 -316.996269) (xy 94.515686 -317.004954) (xy 94.532699 -317.030537)
			(xy 94.561231 -317.084947) (xy 94.583002 -317.142398) (xy 94.597697 -317.202052) (xy 94.6051 -317.263042)
			(xy 94.605105 -317.324479) (xy 94.597711 -317.38547) (xy 94.583026 -317.445127) (xy 94.561263 -317.502581)
			(xy 94.53274 -317.556996) (xy 94.515686 -317.58255) (xy 94.510335 -317.591257) (xy 94.506261 -317.61126)
			(xy 94.510304 -317.631269) (xy 94.515686 -317.639954) (xy 94.532699 -317.665537) (xy 94.561231 -317.719947)
			(xy 94.583002 -317.777398) (xy 94.597697 -317.837052) (xy 94.6051 -317.898042) (xy 94.605105 -317.959479)
			(xy 94.597711 -318.02047) (xy 94.583026 -318.080127) (xy 94.561263 -318.137581) (xy 94.53274 -318.191996)
			(xy 94.515686 -318.21755) (xy 94.510335 -318.226257) (xy 94.506261 -318.24626) (xy 94.510304 -318.266269)
			(xy 94.515686 -318.274954) (xy 94.532699 -318.300537) (xy 94.561231 -318.354947) (xy 94.583002 -318.412398)
			(xy 94.597697 -318.472052) (xy 94.6051 -318.533042) (xy 94.605105 -318.594479) (xy 94.597711 -318.65547)
			(xy 94.583026 -318.715127) (xy 94.561263 -318.772581) (xy 94.53274 -318.826996) (xy 94.515686 -318.85255)
			(xy 94.510335 -318.861257) (xy 94.506261 -318.88126) (xy 94.510304 -318.901269) (xy 94.515686 -318.909954)
			(xy 94.532699 -318.935537) (xy 94.561231 -318.989947) (xy 94.583002 -319.047398) (xy 94.597697 -319.107052)
			(xy 94.6051 -319.168042) (xy 94.605105 -319.229479) (xy 94.597711 -319.29047) (xy 94.583026 -319.350127)
			(xy 94.561263 -319.407581) (xy 94.53274 -319.461996) (xy 94.515686 -319.48755) (xy 94.510335 -319.496257)
			(xy 94.506261 -319.51626) (xy 94.510304 -319.536269) (xy 94.515686 -319.544954) (xy 94.532761 -319.570497)
			(xy 94.561292 -319.624914) (xy 94.583059 -319.682372) (xy 94.597748 -319.742034) (xy 94.605142 -319.80303)
			(xy 94.605602 -319.833752) (xy 94.605193 -319.862707) (xy 94.598597 -319.920241) (xy 94.585508 -319.976653)
			(xy 94.566094 -320.031212) (xy 94.540608 -320.083213) (xy 94.525338 -320.107818) (xy 94.52019 -320.116832)
			(xy 94.516799 -320.137288) (xy 94.52176 -320.157421) (xy 94.527624 -320.165984) (xy 94.547161 -320.192571)
			(xy 94.579898 -320.249856) (xy 94.604951 -320.310894) (xy 94.621901 -320.374659) (xy 94.630463 -320.440081)
			(xy 94.631002 -320.47307) (xy 94.631002 -320.473324) (xy 94.630542 -320.504045) (xy 94.62314 -320.565039)
			(xy 94.608447 -320.624698) (xy 94.586676 -320.682153) (xy 94.558144 -320.736568) (xy 94.541086 -320.762122)
			(xy 94.535673 -320.770796) (xy 94.531619 -320.79082) (xy 94.535689 -320.810841) (xy 94.541086 -320.819526)
			(xy 94.558165 -320.845066) (xy 94.586692 -320.899484) (xy 94.608459 -320.956942) (xy 94.623148 -321.016603)
			(xy 94.630545 -321.077599) (xy 94.630542 -321.139041) (xy 94.623141 -321.200036) (xy 94.608447 -321.259696)
			(xy 94.586676 -321.317152) (xy 94.558144 -321.371568) (xy 94.541086 -321.397122) (xy 94.535673 -321.405796)
			(xy 94.531619 -321.42582) (xy 94.535689 -321.445841) (xy 94.541086 -321.454526) (xy 94.558165 -321.480066)
			(xy 94.586692 -321.534484) (xy 94.608459 -321.591942) (xy 94.623148 -321.651603) (xy 94.630545 -321.712599)
			(xy 94.630542 -321.774041) (xy 94.623141 -321.835036) (xy 94.608447 -321.894696) (xy 94.586676 -321.952152)
			(xy 94.558144 -322.006568) (xy 94.541086 -322.032122) (xy 94.535673 -322.040796) (xy 94.531619 -322.06082)
			(xy 94.535689 -322.080841) (xy 94.541086 -322.089526) (xy 94.558149 -322.115077) (xy 94.586682 -322.169492)
			(xy 94.608452 -322.226948) (xy 94.623143 -322.286608) (xy 94.630541 -322.347603) (xy 94.631002 -322.378324)
			(xy 94.630515 -322.410195) (xy 94.622544 -322.473437) (xy 94.606742 -322.535189) (xy 94.583357 -322.594487)
			(xy 94.552753 -322.650402) (xy 94.534482 -322.67652) (xy 94.528667 -322.685432) (xy 94.524278 -322.706231)
			(xy 94.528693 -322.727025) (xy 94.534482 -322.735956) (xy 94.55276 -322.762073) (xy 94.583398 -322.817973)
			(xy 94.606797 -322.877269) (xy 94.622589 -322.939028) (xy 94.630526 -323.002279) (xy 94.631002 -323.034152)
			(xy 96.357186 -323.034152) (xy 96.357663 -323.002281) (xy 96.365637 -322.939039) (xy 96.381441 -322.877286)
			(xy 96.404829 -322.817989) (xy 96.435434 -322.762074) (xy 96.453706 -322.735956) (xy 96.459455 -322.727008)
			(xy 96.463868 -322.706231) (xy 96.459481 -322.685449) (xy 96.453706 -322.67652) (xy 96.435416 -322.650412)
			(xy 96.40478 -322.594509) (xy 96.381384 -322.53521) (xy 96.365594 -322.473449) (xy 96.357661 -322.410198)
			(xy 96.357186 -322.378324) (xy 96.357672 -322.347604) (xy 96.365068 -322.286611) (xy 96.379756 -322.226953)
			(xy 96.401521 -322.169497) (xy 96.430047 -322.115081) (xy 96.447102 -322.089526) (xy 96.452475 -322.08083)
			(xy 96.456543 -322.06082) (xy 96.45249 -322.040806) (xy 96.447102 -322.032122) (xy 96.430065 -322.006555)
			(xy 96.401529 -321.952143) (xy 96.379755 -321.89469) (xy 96.36506 -321.835033) (xy 96.357657 -321.77404)
			(xy 96.357655 -321.7126) (xy 96.365053 -321.651606) (xy 96.379744 -321.591948) (xy 96.401513 -321.534493)
			(xy 96.430044 -321.480079) (xy 96.447102 -321.454526) (xy 96.452475 -321.44583) (xy 96.456543 -321.42582)
			(xy 96.45249 -321.405806) (xy 96.447102 -321.397122) (xy 96.430065 -321.371555) (xy 96.401529 -321.317143)
			(xy 96.379755 -321.25969) (xy 96.36506 -321.200033) (xy 96.357657 -321.13904) (xy 96.357655 -321.0776)
			(xy 96.365053 -321.016606) (xy 96.379744 -320.956948) (xy 96.401513 -320.899493) (xy 96.430044 -320.845079)
			(xy 96.447102 -320.819526) (xy 96.452475 -320.81083) (xy 96.456543 -320.79082) (xy 96.45249 -320.770806)
			(xy 96.447102 -320.762122) (xy 96.430058 -320.736559) (xy 96.401523 -320.682147) (xy 96.379749 -320.624694)
			(xy 96.365053 -320.565037) (xy 96.35765 -320.504044) (xy 96.357186 -320.473324) (xy 96.357186 -320.47307)
			(xy 96.357652 -320.44213) (xy 96.365154 -320.380708) (xy 96.380055 -320.32065) (xy 96.402136 -320.262845)
			(xy 96.431069 -320.208147) (xy 96.448372 -320.182494) (xy 96.453831 -320.173731) (xy 96.457989 -320.153532)
			(xy 96.453856 -320.133327) (xy 96.448372 -320.124582) (xy 96.431068 -320.09893) (xy 96.402137 -320.04423)
			(xy 96.380056 -319.986425) (xy 96.365152 -319.926368) (xy 96.357644 -319.864946) (xy 96.357186 -319.834006)
			(xy 96.357186 -319.833752) (xy 96.357636 -319.803031) (xy 96.36504 -319.742037) (xy 96.379736 -319.682378)
			(xy 96.40151 -319.624923) (xy 96.430043 -319.570508) (xy 96.447102 -319.544954) (xy 96.452536 -319.536291)
			(xy 96.456584 -319.51626) (xy 96.452505 -319.496235) (xy 96.447102 -319.48755) (xy 96.429999 -319.462025)
			(xy 96.401468 -319.407605) (xy 96.379699 -319.350145) (xy 96.365009 -319.290482) (xy 96.357613 -319.229483)
			(xy 96.357618 -319.168038) (xy 96.365023 -319.10704) (xy 96.379722 -319.047379) (xy 96.4015 -318.989923)
			(xy 96.43004 -318.935507) (xy 96.447102 -318.909954) (xy 96.452536 -318.901291) (xy 96.456584 -318.88126)
			(xy 96.452505 -318.861235) (xy 96.447102 -318.85255) (xy 96.429999 -318.827025) (xy 96.401468 -318.772605)
			(xy 96.379699 -318.715145) (xy 96.365009 -318.655482) (xy 96.357613 -318.594483) (xy 96.357618 -318.533038)
			(xy 96.365023 -318.47204) (xy 96.379722 -318.412379) (xy 96.4015 -318.354923) (xy 96.43004 -318.300507)
			(xy 96.447102 -318.274954) (xy 96.452536 -318.266291) (xy 96.456584 -318.24626) (xy 96.452505 -318.226235)
			(xy 96.447102 -318.21755) (xy 96.429999 -318.192025) (xy 96.401468 -318.137605) (xy 96.379699 -318.080145)
			(xy 96.365009 -318.020482) (xy 96.357613 -317.959483) (xy 96.357618 -317.898038) (xy 96.365023 -317.83704)
			(xy 96.379722 -317.777379) (xy 96.4015 -317.719923) (xy 96.43004 -317.665507) (xy 96.447102 -317.639954)
			(xy 96.452536 -317.631291) (xy 96.456584 -317.61126) (xy 96.452505 -317.591235) (xy 96.447102 -317.58255)
			(xy 96.429999 -317.557025) (xy 96.401468 -317.502605) (xy 96.379699 -317.445145) (xy 96.365009 -317.385482)
			(xy 96.357613 -317.324483) (xy 96.357618 -317.263038) (xy 96.365023 -317.20204) (xy 96.379722 -317.142379)
			(xy 96.4015 -317.084923) (xy 96.43004 -317.030507) (xy 96.447102 -317.004954) (xy 96.452536 -316.996291)
			(xy 96.456584 -316.97626) (xy 96.452505 -316.956235) (xy 96.447102 -316.94755) (xy 96.430027 -316.922007)
			(xy 96.401497 -316.867589) (xy 96.379729 -316.810131) (xy 96.365041 -316.75047) (xy 96.357646 -316.689474)
			(xy 96.357186 -316.658752) (xy 96.35761 -316.62802) (xy 96.365024 -316.567005) (xy 96.379738 -316.507329)
			(xy 96.401538 -316.449861) (xy 96.430105 -316.395439) (xy 96.465023 -316.344857) (xy 96.505783 -316.298853)
			(xy 96.55179 -316.258097) (xy 96.602375 -316.223183) (xy 96.656799 -316.19462) (xy 96.714269 -316.172826)
			(xy 96.773947 -316.158117) (xy 96.834962 -316.150708) (xy 96.865694 -316.150244) (xy 96.896415 -316.150711)
			(xy 96.957409 -316.15811) (xy 97.017068 -316.172802) (xy 97.074523 -316.194571) (xy 97.128938 -316.223102)
			(xy 97.154492 -316.24016) (xy 97.163177 -316.245553) (xy 97.183194 -316.249614) (xy 97.203211 -316.245553)
			(xy 97.211896 -316.24016) (xy 97.23745 -316.223102) (xy 97.291865 -316.194571) (xy 97.34932 -316.1728)
			(xy 97.408979 -316.158108) (xy 97.469973 -316.150708) (xy 97.531415 -316.150708) (xy 97.592409 -316.158108)
			(xy 97.652068 -316.1728) (xy 97.709523 -316.194571) (xy 97.763938 -316.223102) (xy 97.789492 -316.24016)
			(xy 97.798177 -316.245553) (xy 97.818194 -316.249614) (xy 97.838211 -316.245553) (xy 97.846896 -316.24016)
			(xy 97.872451 -316.223103) (xy 97.926865 -316.194571) (xy 97.98432 -316.1728) (xy 98.043979 -316.158107)
			(xy 98.104973 -316.150707) (xy 98.135694 -316.150244) (xy 98.166423 -316.150762) (xy 98.227433 -316.158168)
			(xy 98.287106 -316.172875) (xy 98.344571 -316.194666) (xy 98.39899 -316.223225) (xy 98.449571 -316.258135)
			(xy 98.495575 -316.298887) (xy 98.536331 -316.344887) (xy 98.571247 -316.395464) (xy 98.599811 -316.44988)
			(xy 98.621609 -316.507343) (xy 98.636322 -316.567014) (xy 98.643735 -316.628023) (xy 98.644202 -316.658752)
			(xy 98.643756 -316.689473) (xy 98.636351 -316.750468) (xy 98.621654 -316.810127) (xy 98.59988 -316.867582)
			(xy 98.571345 -316.921996) (xy 98.554286 -316.94755) (xy 98.548935 -316.956257) (xy 98.544861 -316.97626)
			(xy 98.548904 -316.996269) (xy 98.554286 -317.004954) (xy 98.571299 -317.030537) (xy 98.599831 -317.084947)
			(xy 98.621602 -317.142398) (xy 98.636297 -317.202052) (xy 98.6437 -317.263042) (xy 98.643705 -317.324479)
			(xy 98.636311 -317.38547) (xy 98.621626 -317.445127) (xy 98.599863 -317.502581) (xy 98.57134 -317.556996)
			(xy 98.554286 -317.58255) (xy 98.548935 -317.591257) (xy 98.544861 -317.61126) (xy 98.548904 -317.631269)
			(xy 98.554286 -317.639954) (xy 98.571299 -317.665537) (xy 98.599831 -317.719947) (xy 98.621602 -317.777398)
			(xy 98.636297 -317.837052) (xy 98.6437 -317.898042) (xy 98.643705 -317.959479) (xy 98.636311 -318.02047)
			(xy 98.621626 -318.080127) (xy 98.599863 -318.137581) (xy 98.57134 -318.191996) (xy 98.554286 -318.21755)
			(xy 98.548935 -318.226257) (xy 98.544861 -318.24626) (xy 98.548904 -318.266269) (xy 98.554286 -318.274954)
			(xy 98.571299 -318.300537) (xy 98.599831 -318.354947) (xy 98.621602 -318.412398) (xy 98.636297 -318.472052)
			(xy 98.6437 -318.533042) (xy 98.643705 -318.594479) (xy 98.636311 -318.65547) (xy 98.621626 -318.715127)
			(xy 98.599863 -318.772581) (xy 98.57134 -318.826996) (xy 98.554286 -318.85255) (xy 98.548935 -318.861257)
			(xy 98.544861 -318.88126) (xy 98.548904 -318.901269) (xy 98.554286 -318.909954) (xy 98.571299 -318.935537)
			(xy 98.599831 -318.989947) (xy 98.621602 -319.047398) (xy 98.636297 -319.107052) (xy 98.6437 -319.168042)
			(xy 98.643705 -319.229479) (xy 98.636311 -319.29047) (xy 98.621626 -319.350127) (xy 98.599863 -319.407581)
			(xy 98.57134 -319.461996) (xy 98.554286 -319.48755) (xy 98.548935 -319.496257) (xy 98.544861 -319.51626)
			(xy 98.548904 -319.536269) (xy 98.554286 -319.544954) (xy 98.571361 -319.570497) (xy 98.599892 -319.624914)
			(xy 98.621659 -319.682372) (xy 98.636348 -319.742034) (xy 98.643742 -319.80303) (xy 98.644202 -319.833752)
			(xy 98.64369 -319.865885) (xy 98.635551 -319.929636) (xy 98.619448 -319.991853) (xy 98.595636 -320.051546)
			(xy 98.564495 -320.107765) (xy 98.545904 -320.13398) (xy 98.540003 -320.142965) (xy 98.53551 -320.163961)
			(xy 98.539971 -320.184964) (xy 98.545904 -320.193924) (xy 98.564488 -320.220144) (xy 98.59564 -320.276357)
			(xy 98.619458 -320.336049) (xy 98.635562 -320.398267) (xy 98.643694 -320.462018) (xy 98.644202 -320.494152)
			(xy 98.643756 -320.524873) (xy 98.636351 -320.585868) (xy 98.621654 -320.645527) (xy 98.59988 -320.702982)
			(xy 98.571345 -320.757396) (xy 98.554286 -320.78295) (xy 98.548935 -320.791657) (xy 98.544861 -320.81166)
			(xy 98.548904 -320.831669) (xy 98.554286 -320.840354) (xy 98.571299 -320.865937) (xy 98.599831 -320.920347)
			(xy 98.621602 -320.977798) (xy 98.636297 -321.037452) (xy 98.6437 -321.098442) (xy 98.643705 -321.159879)
			(xy 98.636311 -321.22087) (xy 98.621626 -321.280527) (xy 98.599863 -321.337981) (xy 98.57134 -321.392396)
			(xy 98.554286 -321.41795) (xy 98.548935 -321.426657) (xy 98.544861 -321.44666) (xy 98.548904 -321.466669)
			(xy 98.554286 -321.475354) (xy 98.571299 -321.500937) (xy 98.599831 -321.555347) (xy 98.621602 -321.612798)
			(xy 98.636297 -321.672452) (xy 98.6437 -321.733442) (xy 98.643705 -321.794879) (xy 98.636311 -321.85587)
			(xy 98.621626 -321.915527) (xy 98.599863 -321.972981) (xy 98.57134 -322.027396) (xy 98.554286 -322.05295)
			(xy 98.548935 -322.061657) (xy 98.544861 -322.08166) (xy 98.548904 -322.101669) (xy 98.554286 -322.110354)
			(xy 98.571299 -322.135937) (xy 98.599831 -322.190347) (xy 98.621602 -322.247798) (xy 98.636297 -322.307452)
			(xy 98.6437 -322.368442) (xy 98.643705 -322.429879) (xy 98.636311 -322.49087) (xy 98.621626 -322.550527)
			(xy 98.599863 -322.607981) (xy 98.57134 -322.662396) (xy 98.554286 -322.68795) (xy 98.548935 -322.696657)
			(xy 98.544861 -322.71666) (xy 98.548904 -322.736669) (xy 98.554286 -322.745354) (xy 98.571361 -322.770897)
			(xy 98.599892 -322.825314) (xy 98.621659 -322.882772) (xy 98.636348 -322.942434) (xy 98.643742 -323.00343)
			(xy 98.644202 -323.034152) (xy 98.643717 -323.064883) (xy 98.636314 -323.125898) (xy 98.62161 -323.185576)
			(xy 98.599819 -323.243046) (xy 98.571259 -323.29747) (xy 98.536347 -323.348055) (xy 98.495592 -323.394062)
			(xy 98.449588 -323.434821) (xy 98.399006 -323.469737) (xy 98.344585 -323.498302) (xy 98.287116 -323.520097)
			(xy 98.22744 -323.534806) (xy 98.166425 -323.542215) (xy 98.135694 -323.54266) (xy 98.104973 -323.542198)
			(xy 98.043979 -323.534798) (xy 97.98432 -323.520105) (xy 97.926865 -323.498334) (xy 97.87245 -323.469802)
			(xy 97.846896 -323.452744) (xy 97.838211 -323.447351) (xy 97.818194 -323.44329) (xy 97.798177 -323.447351)
			(xy 97.789492 -323.452744) (xy 97.763938 -323.469802) (xy 97.709523 -323.498333) (xy 97.652068 -323.520104)
			(xy 97.592409 -323.534796) (xy 97.531415 -323.542196) (xy 97.469973 -323.542196) (xy 97.408979 -323.534796)
			(xy 97.34932 -323.520104) (xy 97.291865 -323.498333) (xy 97.23745 -323.469802) (xy 97.211896 -323.452744)
			(xy 97.203211 -323.447351) (xy 97.183194 -323.44329) (xy 97.163177 -323.447351) (xy 97.154492 -323.452744)
			(xy 97.128941 -323.469806) (xy 97.074525 -323.498337) (xy 97.017069 -323.520107) (xy 96.95741 -323.534799)
			(xy 96.896415 -323.542198) (xy 96.865694 -323.54266) (xy 96.83496 -323.542268) (xy 96.77394 -323.534858)
			(xy 96.714258 -323.520146) (xy 96.656785 -323.498347) (xy 96.602359 -323.469779) (xy 96.551773 -323.434859)
			(xy 96.505766 -323.394096) (xy 96.465007 -323.348084) (xy 96.430093 -323.297495) (xy 96.401531 -323.243065)
			(xy 96.379738 -323.18559) (xy 96.365033 -323.125907) (xy 96.357629 -323.064886) (xy 96.357186 -323.034152)
			(xy 94.631002 -323.034152) (xy 94.630517 -323.064883) (xy 94.623114 -323.125898) (xy 94.60841 -323.185576)
			(xy 94.586619 -323.243046) (xy 94.558059 -323.29747) (xy 94.523147 -323.348055) (xy 94.482392 -323.394062)
			(xy 94.436388 -323.434821) (xy 94.385806 -323.469737) (xy 94.331385 -323.498302) (xy 94.273916 -323.520097)
			(xy 94.21424 -323.534806) (xy 94.153225 -323.542215) (xy 94.122494 -323.54266) (xy 94.091773 -323.542198)
			(xy 94.030779 -323.534798) (xy 93.97112 -323.520105) (xy 93.913665 -323.498334) (xy 93.85925 -323.469802)
			(xy 93.833696 -323.452744) (xy 93.825011 -323.447351) (xy 93.804994 -323.44329) (xy 93.784977 -323.447351)
			(xy 93.776292 -323.452744) (xy 93.750738 -323.469802) (xy 93.696323 -323.498333) (xy 93.638868 -323.520104)
			(xy 93.579209 -323.534796) (xy 93.518215 -323.542196) (xy 93.456773 -323.542196) (xy 93.395779 -323.534796)
			(xy 93.33612 -323.520104) (xy 93.278665 -323.498333) (xy 93.22425 -323.469802) (xy 93.198696 -323.452744)
			(xy 93.190011 -323.447351) (xy 93.169994 -323.44329) (xy 93.149977 -323.447351) (xy 93.141292 -323.452744)
			(xy 93.115741 -323.469806) (xy 93.061325 -323.498337) (xy 93.003869 -323.520107) (xy 92.94421 -323.534799)
			(xy 92.883215 -323.542198) (xy 92.852494 -323.54266) (xy 92.82176 -323.542268) (xy 92.76074 -323.534858)
			(xy 92.701058 -323.520146) (xy 92.643585 -323.498347) (xy 92.589159 -323.469779) (xy 92.538573 -323.434859)
			(xy 92.492566 -323.394096) (xy 92.451807 -323.348084) (xy 92.416893 -323.297495) (xy 92.388331 -323.243065)
			(xy 92.366538 -323.18559) (xy 92.351833 -323.125907) (xy 92.344429 -323.064886) (xy 92.343986 -323.034152)
			(xy 92.344436 -323.003431) (xy 92.35184 -322.942437) (xy 92.366536 -322.882778) (xy 92.38831 -322.825323)
			(xy 92.416843 -322.770908) (xy 92.433902 -322.745354) (xy 92.439336 -322.736691) (xy 92.443384 -322.71666)
			(xy 92.439305 -322.696635) (xy 92.433902 -322.68795) (xy 92.416799 -322.662425) (xy 92.388268 -322.608005)
			(xy 92.366499 -322.550545) (xy 92.351809 -322.490882) (xy 92.344413 -322.429883) (xy 92.344418 -322.368438)
			(xy 92.351823 -322.30744) (xy 92.366522 -322.247779) (xy 92.3883 -322.190323) (xy 92.41684 -322.135907)
			(xy 92.433902 -322.110354) (xy 92.439336 -322.101691) (xy 92.443384 -322.08166) (xy 92.439305 -322.061635)
			(xy 92.433902 -322.05295) (xy 92.416799 -322.027425) (xy 92.388268 -321.973005) (xy 92.366499 -321.915545)
			(xy 92.351809 -321.855882) (xy 92.344413 -321.794883) (xy 92.344418 -321.733438) (xy 92.351823 -321.67244)
			(xy 92.366522 -321.612779) (xy 92.3883 -321.555323) (xy 92.41684 -321.500907) (xy 92.433902 -321.475354)
			(xy 92.439336 -321.466691) (xy 92.443384 -321.44666) (xy 92.439305 -321.426635) (xy 92.433902 -321.41795)
			(xy 92.416799 -321.392425) (xy 92.388268 -321.338005) (xy 92.366499 -321.280545) (xy 92.351809 -321.220882)
			(xy 92.344413 -321.159883) (xy 92.344418 -321.098438) (xy 92.351823 -321.03744) (xy 92.366522 -320.977779)
			(xy 92.3883 -320.920323) (xy 92.41684 -320.865907) (xy 92.433902 -320.840354) (xy 92.439336 -320.831691)
			(xy 92.443384 -320.81166) (xy 92.439305 -320.791635) (xy 92.433902 -320.78295) (xy 92.416827 -320.757407)
			(xy 92.388297 -320.702989) (xy 92.366529 -320.645531) (xy 92.351841 -320.58587) (xy 92.344446 -320.524874)
			(xy 92.343986 -320.494152) (xy 92.343986 -320.493644) (xy 92.344446 -320.4635) (xy 92.351614 -320.40364)
			(xy 92.365807 -320.345047) (xy 92.386826 -320.288542) (xy 92.414376 -320.234917) (xy 92.430854 -320.209672)
			(xy 92.436483 -320.200499) (xy 92.44015 -320.179308) (xy 92.434858 -320.158463) (xy 92.428568 -320.149728)
			(xy 92.407844 -320.122637) (xy 92.373019 -320.063991) (xy 92.346335 -320.00122) (xy 92.328268 -319.935449)
			(xy 92.319143 -319.867855) (xy 92.318586 -319.833752) (xy 90.389746 -319.833752) (xy 90.389747 -319.849999)
			(xy 90.38235 -319.910992) (xy 90.367659 -319.97065) (xy 90.34589 -320.028104) (xy 90.31736 -320.082519)
			(xy 90.300302 -320.108072) (xy 90.294931 -320.116768) (xy 90.290861 -320.136778) (xy 90.294914 -320.156792)
			(xy 90.300302 -320.165476) (xy 90.317338 -320.191045) (xy 90.345873 -320.245456) (xy 90.367647 -320.302909)
			(xy 90.382342 -320.362566) (xy 90.389745 -320.423559) (xy 90.389747 -320.484999) (xy 90.38235 -320.545992)
			(xy 90.367659 -320.60565) (xy 90.34589 -320.663104) (xy 90.31736 -320.717519) (xy 90.300302 -320.743072)
			(xy 90.294931 -320.751768) (xy 90.290861 -320.771778) (xy 90.294914 -320.791792) (xy 90.300302 -320.800476)
			(xy 90.317338 -320.826045) (xy 90.345873 -320.880456) (xy 90.367647 -320.937909) (xy 90.382342 -320.997566)
			(xy 90.389745 -321.058559) (xy 90.389747 -321.119999) (xy 90.38235 -321.180992) (xy 90.367659 -321.24065)
			(xy 90.34589 -321.298104) (xy 90.31736 -321.352519) (xy 90.300302 -321.378072) (xy 90.294931 -321.386768)
			(xy 90.290861 -321.406778) (xy 90.294914 -321.426792) (xy 90.300302 -321.435476) (xy 90.317338 -321.461045)
			(xy 90.345873 -321.515456) (xy 90.367647 -321.572909) (xy 90.382342 -321.632566) (xy 90.389745 -321.693559)
			(xy 90.389747 -321.754999) (xy 90.38235 -321.815992) (xy 90.367659 -321.87565) (xy 90.34589 -321.933104)
			(xy 90.31736 -321.987519) (xy 90.300302 -322.013072) (xy 90.294931 -322.021768) (xy 90.290861 -322.041778)
			(xy 90.294914 -322.061792) (xy 90.300302 -322.070476) (xy 90.317345 -322.096039) (xy 90.345881 -322.150451)
			(xy 90.367655 -322.207904) (xy 90.382351 -322.267561) (xy 90.389754 -322.328554) (xy 90.390218 -322.359274)
			(xy 90.390218 -322.359528) (xy 90.3897 -322.391096) (xy 90.381846 -322.453742) (xy 90.3663 -322.514934)
			(xy 90.343301 -322.573732) (xy 90.313202 -322.629232) (xy 90.295222 -322.655184) (xy 90.289504 -322.664032)
			(xy 90.285208 -322.68464) (xy 90.289535 -322.70524) (xy 90.295222 -322.714112) (xy 90.313026 -322.740022)
			(xy 90.342838 -322.795372) (xy 90.365606 -322.853972) (xy 90.380981 -322.91493) (xy 90.388731 -322.977318)
			(xy 90.389202 -323.008752) (xy 90.388717 -323.039483) (xy 90.381314 -323.100498) (xy 90.36661 -323.160176)
			(xy 90.344819 -323.217646) (xy 90.316259 -323.27207) (xy 90.281347 -323.322655) (xy 90.240592 -323.368662)
			(xy 90.194588 -323.409421) (xy 90.144006 -323.444337) (xy 90.089585 -323.472902) (xy 90.032116 -323.494697)
			(xy 89.97244 -323.509406) (xy 89.911425 -323.516815) (xy 89.880694 -323.51726) (xy 89.849973 -323.516798)
			(xy 89.788979 -323.509398) (xy 89.72932 -323.494705) (xy 89.671865 -323.472934) (xy 89.61745 -323.444402)
			(xy 89.591896 -323.427344) (xy 89.583211 -323.421951) (xy 89.563194 -323.41789) (xy 89.543177 -323.421951)
			(xy 89.534492 -323.427344) (xy 89.508938 -323.444402) (xy 89.454523 -323.472933) (xy 89.397068 -323.494704)
			(xy 89.337409 -323.509396) (xy 89.276415 -323.516796) (xy 89.214973 -323.516796) (xy 89.153979 -323.509396)
			(xy 89.09432 -323.494704) (xy 89.036865 -323.472933) (xy 88.98245 -323.444402) (xy 88.956896 -323.427344)
			(xy 88.948211 -323.421951) (xy 88.928194 -323.41789) (xy 88.908177 -323.421951) (xy 88.899492 -323.427344)
			(xy 88.873941 -323.444406) (xy 88.819525 -323.472937) (xy 88.762069 -323.494707) (xy 88.70241 -323.509399)
			(xy 88.641415 -323.516798) (xy 88.610694 -323.51726) (xy 88.57996 -323.516868) (xy 88.51894 -323.509458)
			(xy 88.459258 -323.494746) (xy 88.401785 -323.472947) (xy 88.347359 -323.444379) (xy 88.296773 -323.409459)
			(xy 88.250766 -323.368696) (xy 88.210007 -323.322684) (xy 88.175093 -323.272095) (xy 88.146531 -323.217665)
			(xy 88.124738 -323.16019) (xy 88.110033 -323.100507) (xy 88.102629 -323.039486) (xy 88.102186 -323.008752)
			(xy 86.350602 -323.008752) (xy 86.350117 -323.039483) (xy 86.342714 -323.100498) (xy 86.32801 -323.160176)
			(xy 86.306219 -323.217646) (xy 86.277659 -323.27207) (xy 86.242747 -323.322655) (xy 86.201992 -323.368662)
			(xy 86.155988 -323.409421) (xy 86.105406 -323.444337) (xy 86.050985 -323.472902) (xy 85.993516 -323.494697)
			(xy 85.93384 -323.509406) (xy 85.872825 -323.516815) (xy 85.842094 -323.51726) (xy 85.811373 -323.516798)
			(xy 85.750379 -323.509398) (xy 85.69072 -323.494705) (xy 85.633265 -323.472934) (xy 85.57885 -323.444402)
			(xy 85.553296 -323.427344) (xy 85.544611 -323.421951) (xy 85.524594 -323.41789) (xy 85.504577 -323.421951)
			(xy 85.495892 -323.427344) (xy 85.470338 -323.444402) (xy 85.415923 -323.472933) (xy 85.358468 -323.494704)
			(xy 85.298809 -323.509396) (xy 85.237815 -323.516796) (xy 85.176373 -323.516796) (xy 85.115379 -323.509396)
			(xy 85.05572 -323.494704) (xy 84.998265 -323.472933) (xy 84.94385 -323.444402) (xy 84.918296 -323.427344)
			(xy 84.909611 -323.421951) (xy 84.889594 -323.41789) (xy 84.869577 -323.421951) (xy 84.860892 -323.427344)
			(xy 84.835341 -323.444406) (xy 84.780925 -323.472937) (xy 84.723469 -323.494707) (xy 84.66381 -323.509399)
			(xy 84.602815 -323.516798) (xy 84.572094 -323.51726) (xy 84.54136 -323.516868) (xy 84.48034 -323.509458)
			(xy 84.420658 -323.494746) (xy 84.363185 -323.472947) (xy 84.308759 -323.444379) (xy 84.258173 -323.409459)
			(xy 84.212166 -323.368696) (xy 84.171407 -323.322684) (xy 84.136493 -323.272095) (xy 84.107931 -323.217665)
			(xy 84.086138 -323.16019) (xy 84.071433 -323.100507) (xy 84.064029 -323.039486) (xy 84.063586 -323.008752)
			(xy 82.010758 -323.008752) (xy 82.010199 -323.03948) (xy 82.002797 -323.100489) (xy 81.988095 -323.16016)
			(xy 81.966308 -323.217625) (xy 81.937753 -323.272044) (xy 81.902847 -323.322625) (xy 81.862099 -323.368629)
			(xy 81.816102 -323.409387) (xy 81.765528 -323.444303) (xy 81.711114 -323.472868) (xy 81.653654 -323.494666)
			(xy 81.593985 -323.509379) (xy 81.532978 -323.516793) (xy 81.50225 -323.51726) (xy 81.471529 -323.516821)
			(xy 81.410533 -323.509415) (xy 81.350874 -323.494717) (xy 81.293419 -323.472941) (xy 81.239005 -323.444404)
			(xy 81.213452 -323.427344) (xy 81.204767 -323.421951) (xy 81.18475 -323.41789) (xy 81.164733 -323.421951)
			(xy 81.156048 -323.427344) (xy 81.130494 -323.444402) (xy 81.076079 -323.472933) (xy 81.018624 -323.494704)
			(xy 80.958965 -323.509396) (xy 80.897971 -323.516796) (xy 80.836529 -323.516796) (xy 80.775535 -323.509396)
			(xy 80.715876 -323.494704) (xy 80.658421 -323.472933) (xy 80.604006 -323.444402) (xy 80.578452 -323.427344)
			(xy 80.569767 -323.421951) (xy 80.54975 -323.41789) (xy 80.529733 -323.421951) (xy 80.521048 -323.427344)
			(xy 80.495509 -323.444425) (xy 80.44109 -323.472953) (xy 80.383631 -323.494719) (xy 80.323969 -323.509406)
			(xy 80.262972 -323.5168) (xy 80.23225 -323.51726) (xy 80.201516 -323.516891) (xy 80.140497 -323.509476)
			(xy 80.080817 -323.49476) (xy 80.023345 -323.472958) (xy 79.968921 -323.444387) (xy 79.918337 -323.409464)
			(xy 79.872332 -323.368699) (xy 79.831575 -323.322686) (xy 79.796662 -323.272095) (xy 79.768102 -323.217665)
			(xy 79.746311 -323.16019) (xy 79.731606 -323.100506) (xy 79.724203 -323.039486) (xy 79.723742 -323.008752)
			(xy 77.997558 -323.008752) (xy 77.996999 -323.03948) (xy 77.989597 -323.100489) (xy 77.974895 -323.16016)
			(xy 77.953108 -323.217625) (xy 77.924553 -323.272044) (xy 77.889647 -323.322625) (xy 77.848899 -323.368629)
			(xy 77.802902 -323.409387) (xy 77.752328 -323.444303) (xy 77.697914 -323.472868) (xy 77.640454 -323.494666)
			(xy 77.580785 -323.509379) (xy 77.519778 -323.516793) (xy 77.48905 -323.51726) (xy 77.458329 -323.516821)
			(xy 77.397333 -323.509415) (xy 77.337674 -323.494717) (xy 77.280219 -323.472941) (xy 77.225805 -323.444404)
			(xy 77.200252 -323.427344) (xy 77.191567 -323.421951) (xy 77.17155 -323.41789) (xy 77.151533 -323.421951)
			(xy 77.142848 -323.427344) (xy 77.117294 -323.444402) (xy 77.062879 -323.472933) (xy 77.005424 -323.494704)
			(xy 76.945765 -323.509396) (xy 76.884771 -323.516796) (xy 76.823329 -323.516796) (xy 76.762335 -323.509396)
			(xy 76.702676 -323.494704) (xy 76.645221 -323.472933) (xy 76.590806 -323.444402) (xy 76.565252 -323.427344)
			(xy 76.556567 -323.421951) (xy 76.53655 -323.41789) (xy 76.516533 -323.421951) (xy 76.507848 -323.427344)
			(xy 76.482309 -323.444425) (xy 76.42789 -323.472953) (xy 76.370431 -323.494719) (xy 76.310769 -323.509406)
			(xy 76.249772 -323.5168) (xy 76.21905 -323.51726) (xy 76.188316 -323.516891) (xy 76.127297 -323.509476)
			(xy 76.067617 -323.49476) (xy 76.010145 -323.472958) (xy 75.955721 -323.444387) (xy 75.905137 -323.409464)
			(xy 75.859132 -323.368699) (xy 75.818375 -323.322686) (xy 75.783462 -323.272095) (xy 75.754902 -323.217665)
			(xy 75.733111 -323.16019) (xy 75.718406 -323.100506) (xy 75.711003 -323.039486) (xy 75.710542 -323.008752)
			(xy 75.711034 -322.977538) (xy 75.718673 -322.915578) (xy 75.73383 -322.855018) (xy 75.756279 -322.796765)
			(xy 75.785681 -322.741693) (xy 75.803252 -322.71589) (xy 75.808947 -322.706971) (xy 75.813191 -322.68626)
			(xy 75.808754 -322.665589) (xy 75.802998 -322.656708) (xy 75.784835 -322.630658) (xy 75.75441 -322.574914)
			(xy 75.731156 -322.515818) (xy 75.715436 -322.454288) (xy 75.707494 -322.391281) (xy 75.706986 -322.359528)
			(xy 73.676695 -322.359528) (xy 73.677018 -322.380864) (xy 73.676444 -322.414107) (xy 73.667765 -322.480025)
			(xy 73.650564 -322.544248) (xy 73.625134 -322.605679) (xy 73.591911 -322.663269) (xy 73.572116 -322.689982)
			(xy 73.566176 -322.698685) (xy 73.561244 -322.719146) (xy 73.564929 -322.739868) (xy 73.570338 -322.74891)
			(xy 73.58647 -322.774004) (xy 73.613433 -322.827222) (xy 73.633976 -322.883231) (xy 73.647817 -322.941261)
			(xy 73.654765 -323.000513) (xy 73.655174 -323.030342) (xy 73.654784 -323.061075) (xy 73.64737 -323.122093)
			(xy 73.632655 -323.181772) (xy 73.610854 -323.239243) (xy 73.582285 -323.293666) (xy 73.547364 -323.34425)
			(xy 73.506601 -323.390255) (xy 73.46059 -323.431011) (xy 73.410001 -323.465925) (xy 73.355573 -323.494486)
			(xy 73.2981 -323.516278) (xy 73.238418 -323.530984) (xy 73.177399 -323.538388) (xy 73.146666 -323.53885)
			(xy 73.115945 -323.538404) (xy 73.05495 -323.531) (xy 72.995291 -323.516304) (xy 72.937836 -323.49453)
			(xy 72.883421 -323.465994) (xy 72.857868 -323.448934) (xy 72.849183 -323.443541) (xy 72.829166 -323.43948)
			(xy 72.809149 -323.443541) (xy 72.800464 -323.448934) (xy 72.77491 -323.465992) (xy 72.720495 -323.494523)
			(xy 72.66304 -323.516294) (xy 72.603381 -323.530986) (xy 72.542387 -323.538386) (xy 72.480945 -323.538386)
			(xy 72.419951 -323.530986) (xy 72.360292 -323.516294) (xy 72.302837 -323.494523) (xy 72.248422 -323.465992)
			(xy 72.222868 -323.448934) (xy 72.214183 -323.443541) (xy 72.194166 -323.43948) (xy 72.174149 -323.443541)
			(xy 72.165464 -323.448934) (xy 72.13992 -323.466007) (xy 72.085502 -323.494537) (xy 72.028045 -323.516304)
			(xy 71.968383 -323.530993) (xy 71.907387 -323.538389) (xy 71.876666 -323.53885) (xy 71.845936 -323.538376)
			(xy 71.784924 -323.530965) (xy 71.72525 -323.516254) (xy 71.667785 -323.494458) (xy 71.613365 -323.465895)
			(xy 71.562784 -323.430981) (xy 71.516781 -323.390225) (xy 71.476024 -323.344222) (xy 71.441109 -323.293642)
			(xy 71.412545 -323.239223) (xy 71.390749 -323.181757) (xy 71.376037 -323.122084) (xy 71.368624 -323.061072)
			(xy 71.368158 -323.030342) (xy 69.641974 -323.030342) (xy 69.641584 -323.061075) (xy 69.63417 -323.122093)
			(xy 69.619455 -323.181772) (xy 69.597654 -323.239243) (xy 69.569085 -323.293666) (xy 69.534164 -323.34425)
			(xy 69.493401 -323.390255) (xy 69.44739 -323.431011) (xy 69.396801 -323.465925) (xy 69.342373 -323.494486)
			(xy 69.2849 -323.516278) (xy 69.225218 -323.530984) (xy 69.164199 -323.538388) (xy 69.133466 -323.53885)
			(xy 69.102745 -323.538404) (xy 69.04175 -323.531) (xy 68.982091 -323.516304) (xy 68.924636 -323.49453)
			(xy 68.870221 -323.465994) (xy 68.844668 -323.448934) (xy 68.835983 -323.443541) (xy 68.815966 -323.43948)
			(xy 68.795949 -323.443541) (xy 68.787264 -323.448934) (xy 68.76171 -323.465992) (xy 68.707295 -323.494523)
			(xy 68.64984 -323.516294) (xy 68.590181 -323.530986) (xy 68.529187 -323.538386) (xy 68.467745 -323.538386)
			(xy 68.406751 -323.530986) (xy 68.347092 -323.516294) (xy 68.289637 -323.494523) (xy 68.235222 -323.465992)
			(xy 68.209668 -323.448934) (xy 68.200983 -323.443541) (xy 68.180966 -323.43948) (xy 68.160949 -323.443541)
			(xy 68.152264 -323.448934) (xy 68.12672 -323.466007) (xy 68.072302 -323.494537) (xy 68.014845 -323.516304)
			(xy 67.955183 -323.530993) (xy 67.894187 -323.538389) (xy 67.863466 -323.53885) (xy 67.832736 -323.538376)
			(xy 67.771724 -323.530965) (xy 67.71205 -323.516254) (xy 67.654585 -323.494458) (xy 67.600165 -323.465895)
			(xy 67.549584 -323.430981) (xy 67.503581 -323.390225) (xy 67.462824 -323.344222) (xy 67.427909 -323.293642)
			(xy 67.399345 -323.239223) (xy 67.377549 -323.181757) (xy 67.362837 -323.122084) (xy 67.355424 -323.061072)
			(xy 67.354958 -323.030342) (xy 22.619462 -323.030342) (xy 22.619462 -324.647517) (xy 23.822654 -324.647517)
			(xy 23.822654 -324.583595) (xy 23.830665 -324.520177) (xy 23.846562 -324.458263) (xy 23.870094 -324.39883)
			(xy 23.900888 -324.342815) (xy 23.938461 -324.2911) (xy 23.982218 -324.244503) (xy 24.031471 -324.203758)
			(xy 24.085442 -324.169507) (xy 24.143281 -324.14229) (xy 24.204074 -324.122537) (xy 24.266864 -324.110559)
			(xy 24.33066 -324.106546) (xy 24.394456 -324.110559) (xy 24.457246 -324.122537) (xy 24.518039 -324.14229)
			(xy 24.575878 -324.169507) (xy 24.629849 -324.203758) (xy 24.679102 -324.244503) (xy 24.722859 -324.2911)
			(xy 24.760432 -324.342815) (xy 24.791226 -324.39883) (xy 24.814758 -324.458263) (xy 24.830655 -324.520177)
			(xy 24.832564 -324.53529) (xy 25.334225 -324.53529) (xy 25.338216 -324.446403) (xy 25.35016 -324.358232)
			(xy 25.369959 -324.271486) (xy 25.397454 -324.186865) (xy 25.432424 -324.105048) (xy 25.474587 -324.026696)
			(xy 25.523604 -323.952439) (xy 25.57908 -323.882874) (xy 25.640568 -323.818563) (xy 25.707574 -323.760022)
			(xy 25.779558 -323.707723) (xy 25.855939 -323.662087) (xy 25.936104 -323.623481) (xy 26.019407 -323.592217)
			(xy 26.105177 -323.568546) (xy 26.192724 -323.552659) (xy 26.281342 -323.544683) (xy 26.32583 -323.544184)
			(xy 28.07843 -323.544184) (xy 28.122918 -323.544679) (xy 28.211537 -323.552655) (xy 28.299084 -323.568542)
			(xy 28.384854 -323.592213) (xy 28.468157 -323.623478) (xy 28.548323 -323.662083) (xy 28.624705 -323.707719)
			(xy 28.696688 -323.760018) (xy 28.763694 -323.81856) (xy 28.825183 -323.882872) (xy 28.880659 -323.952437)
			(xy 28.929676 -324.026694) (xy 28.971839 -324.105047) (xy 29.006809 -324.186863) (xy 29.034305 -324.271485)
			(xy 29.054104 -324.358231) (xy 29.066048 -324.446403) (xy 29.07004 -324.53529) (xy 32.878025 -324.53529)
			(xy 32.882016 -324.446403) (xy 32.89396 -324.358232) (xy 32.913759 -324.271486) (xy 32.941254 -324.186865)
			(xy 32.976224 -324.105048) (xy 33.018387 -324.026696) (xy 33.067404 -323.952439) (xy 33.12288 -323.882874)
			(xy 33.184368 -323.818563) (xy 33.251374 -323.760022) (xy 33.323358 -323.707723) (xy 33.399739 -323.662087)
			(xy 33.479904 -323.623481) (xy 33.563207 -323.592217) (xy 33.648977 -323.568546) (xy 33.736524 -323.552659)
			(xy 33.825142 -323.544683) (xy 33.86963 -323.544184) (xy 35.62223 -323.544184) (xy 35.666718 -323.544679)
			(xy 35.755337 -323.552655) (xy 35.842884 -323.568542) (xy 35.928654 -323.592213) (xy 36.011957 -323.623478)
			(xy 36.092123 -323.662083) (xy 36.168505 -323.707719) (xy 36.240488 -323.760018) (xy 36.307494 -323.81856)
			(xy 36.368983 -323.882872) (xy 36.424459 -323.952437) (xy 36.473476 -324.026694) (xy 36.515639 -324.105047)
			(xy 36.550609 -324.186863) (xy 36.578105 -324.271485) (xy 36.597904 -324.358231) (xy 36.609848 -324.446403)
			(xy 36.61384 -324.53529) (xy 36.61384 -324.5353) (xy 40.422084 -324.5353) (xy 40.426076 -324.446413)
			(xy 40.43802 -324.358242) (xy 40.457819 -324.271496) (xy 40.485314 -324.186875) (xy 40.520283 -324.105058)
			(xy 40.562446 -324.026706) (xy 40.611462 -323.952448) (xy 40.666938 -323.882883) (xy 40.728426 -323.818571)
			(xy 40.795431 -323.760029) (xy 40.867414 -323.70773) (xy 40.943795 -323.662093) (xy 41.023959 -323.623487)
			(xy 41.107262 -323.592222) (xy 41.193031 -323.568549) (xy 41.280578 -323.552661) (xy 41.369196 -323.544684)
			(xy 41.413684 -323.544184) (xy 43.166284 -323.544184) (xy 43.210773 -323.544684) (xy 43.299393 -323.552658)
			(xy 43.386941 -323.568545) (xy 43.472713 -323.592215) (xy 43.556018 -323.623479) (xy 43.636185 -323.662084)
			(xy 43.712569 -323.70772) (xy 43.784554 -323.760019) (xy 43.851561 -323.818561) (xy 43.913051 -323.882873)
			(xy 43.968529 -323.952439) (xy 44.017547 -324.026697) (xy 44.059711 -324.105051) (xy 44.094682 -324.186868)
			(xy 44.122178 -324.271491) (xy 44.141978 -324.358239) (xy 44.153922 -324.446411) (xy 44.157914 -324.53529)
			(xy 47.966134 -324.53529) (xy 47.970126 -324.446403) (xy 47.98207 -324.358232) (xy 48.001869 -324.271487)
			(xy 48.029364 -324.186865) (xy 48.064334 -324.105049) (xy 48.106497 -324.026697) (xy 48.155514 -323.95244)
			(xy 48.21099 -323.882875) (xy 48.272478 -323.818563) (xy 48.339483 -323.760022) (xy 48.411466 -323.707723)
			(xy 48.487848 -323.662087) (xy 48.568013 -323.623482) (xy 48.651316 -323.592218) (xy 48.737085 -323.568547)
			(xy 48.824632 -323.552659) (xy 48.91325 -323.544683) (xy 48.957738 -323.544184) (xy 50.710338 -323.544184)
			(xy 50.754827 -323.544664) (xy 50.843447 -323.55264) (xy 50.930995 -323.568528) (xy 51.016767 -323.592199)
			(xy 51.100072 -323.623464) (xy 51.180238 -323.66207) (xy 51.256622 -323.707706) (xy 51.328607 -323.760006)
			(xy 51.395614 -323.818549) (xy 51.457103 -323.882861) (xy 51.51258 -323.952427) (xy 51.561598 -324.026686)
			(xy 51.603762 -324.10504) (xy 51.638733 -324.186858) (xy 51.666229 -324.271481) (xy 51.686028 -324.358228)
			(xy 51.697972 -324.446401) (xy 51.701964 -324.53529) (xy 51.701964 -324.5353) (xy 55.510184 -324.5353)
			(xy 55.514176 -324.446413) (xy 55.52612 -324.358241) (xy 55.545919 -324.271495) (xy 55.573414 -324.186873)
			(xy 55.608384 -324.105056) (xy 55.650547 -324.026703) (xy 55.699564 -323.952446) (xy 55.75504 -323.882881)
			(xy 55.816529 -323.818568) (xy 55.883534 -323.760027) (xy 55.955518 -323.707727) (xy 56.0319 -323.66209)
			(xy 56.112065 -323.623484) (xy 56.195368 -323.59222) (xy 56.281138 -323.568548) (xy 56.368685 -323.55266)
			(xy 56.457304 -323.544683) (xy 56.501792 -323.544184) (xy 58.254392 -323.544184) (xy 58.298881 -323.544684)
			(xy 58.3875 -323.552659) (xy 58.475048 -323.568546) (xy 58.560819 -323.592217) (xy 58.644124 -323.623481)
			(xy 58.72429 -323.662087) (xy 58.800673 -323.707723) (xy 58.872658 -323.760022) (xy 58.939664 -323.818564)
			(xy 59.001154 -323.882876) (xy 59.056631 -323.952441) (xy 59.105648 -324.0267) (xy 59.147812 -324.105053)
			(xy 59.182783 -324.18687) (xy 59.210279 -324.271493) (xy 59.230078 -324.35824) (xy 59.242022 -324.446412)
			(xy 59.246014 -324.5353) (xy 59.242022 -324.624188) (xy 59.230078 -324.71236) (xy 59.210279 -324.799107)
			(xy 59.182783 -324.88373) (xy 59.147812 -324.965547) (xy 59.105648 -325.0439) (xy 59.056631 -325.118159)
			(xy 59.001154 -325.187724) (xy 58.939664 -325.252036) (xy 58.872658 -325.310578) (xy 58.800673 -325.362877)
			(xy 58.72429 -325.408513) (xy 58.644124 -325.447119) (xy 58.560819 -325.478383) (xy 58.475048 -325.502054)
			(xy 58.3875 -325.517941) (xy 58.298881 -325.525916) (xy 58.254392 -325.5264) (xy 56.501792 -325.5264)
			(xy 56.457304 -325.525917) (xy 56.368685 -325.51794) (xy 56.281138 -325.502052) (xy 56.195368 -325.47838)
			(xy 56.112065 -325.447116) (xy 56.0319 -325.40851) (xy 55.955518 -325.362873) (xy 55.883534 -325.310573)
			(xy 55.816529 -325.252032) (xy 55.75504 -325.187719) (xy 55.699564 -325.118154) (xy 55.650547 -325.043897)
			(xy 55.608384 -324.965544) (xy 55.573414 -324.883727) (xy 55.545919 -324.799105) (xy 55.52612 -324.712359)
			(xy 55.514176 -324.624187) (xy 55.510184 -324.5353) (xy 51.701964 -324.5353) (xy 51.697972 -324.624179)
			(xy 51.686028 -324.712352) (xy 51.666229 -324.799099) (xy 51.638733 -324.883722) (xy 51.603762 -324.96554)
			(xy 51.561598 -325.043894) (xy 51.51258 -325.118153) (xy 51.457103 -325.187719) (xy 51.395614 -325.252031)
			(xy 51.328607 -325.310574) (xy 51.256622 -325.362874) (xy 51.180238 -325.40851) (xy 51.100072 -325.447116)
			(xy 51.016767 -325.478381) (xy 50.930995 -325.502052) (xy 50.843447 -325.51794) (xy 50.754827 -325.525916)
			(xy 50.710338 -325.5264) (xy 48.957738 -325.5264) (xy 48.91325 -325.525897) (xy 48.824632 -325.517921)
			(xy 48.737085 -325.502033) (xy 48.651316 -325.478362) (xy 48.568013 -325.447098) (xy 48.487848 -325.408493)
			(xy 48.411466 -325.362857) (xy 48.339483 -325.310558) (xy 48.272478 -325.252017) (xy 48.21099 -325.187705)
			(xy 48.155514 -325.11814) (xy 48.106497 -325.043883) (xy 48.064334 -324.965531) (xy 48.029364 -324.883715)
			(xy 48.001869 -324.799093) (xy 47.98207 -324.712348) (xy 47.970126 -324.624177) (xy 47.966134 -324.53529)
			(xy 44.157914 -324.53529) (xy 44.157914 -324.5353) (xy 44.153922 -324.624189) (xy 44.141978 -324.712361)
			(xy 44.122178 -324.799109) (xy 44.094682 -324.883732) (xy 44.059711 -324.965549) (xy 44.017547 -325.043903)
			(xy 43.968529 -325.118161) (xy 43.913051 -325.187727) (xy 43.851561 -325.252039) (xy 43.784554 -325.310581)
			(xy 43.712569 -325.36288) (xy 43.636185 -325.408516) (xy 43.556018 -325.447121) (xy 43.472713 -325.478385)
			(xy 43.386941 -325.502055) (xy 43.299393 -325.517942) (xy 43.210773 -325.525916) (xy 43.166284 -325.5264)
			(xy 41.413684 -325.5264) (xy 41.369196 -325.525916) (xy 41.280578 -325.517939) (xy 41.193031 -325.502051)
			(xy 41.107262 -325.478378) (xy 41.023959 -325.447113) (xy 40.943795 -325.408507) (xy 40.867414 -325.36287)
			(xy 40.795431 -325.310571) (xy 40.728426 -325.252029) (xy 40.666938 -325.187717) (xy 40.611462 -325.118152)
			(xy 40.562446 -325.043894) (xy 40.520283 -324.965542) (xy 40.485314 -324.883725) (xy 40.457819 -324.799104)
			(xy 40.43802 -324.712358) (xy 40.426076 -324.624187) (xy 40.422084 -324.5353) (xy 36.61384 -324.5353)
			(xy 36.609848 -324.624177) (xy 36.597904 -324.712349) (xy 36.578105 -324.799095) (xy 36.550609 -324.883717)
			(xy 36.515639 -324.965533) (xy 36.473476 -325.043886) (xy 36.424459 -325.118143) (xy 36.368983 -325.187708)
			(xy 36.307494 -325.25202) (xy 36.240488 -325.310562) (xy 36.168505 -325.362861) (xy 36.092123 -325.408497)
			(xy 36.011957 -325.447102) (xy 35.928654 -325.478367) (xy 35.842884 -325.502038) (xy 35.755337 -325.517925)
			(xy 35.666718 -325.525901) (xy 35.62223 -325.5264) (xy 33.86963 -325.5264) (xy 33.825142 -325.525897)
			(xy 33.736524 -325.517921) (xy 33.648977 -325.502034) (xy 33.563207 -325.478363) (xy 33.479904 -325.447099)
			(xy 33.399739 -325.408493) (xy 33.323358 -325.362857) (xy 33.251374 -325.310558) (xy 33.184368 -325.252017)
			(xy 33.12288 -325.187706) (xy 33.067404 -325.118141) (xy 33.018387 -325.043884) (xy 32.976224 -324.965532)
			(xy 32.941254 -324.883715) (xy 32.913759 -324.799094) (xy 32.89396 -324.712348) (xy 32.882016 -324.624177)
			(xy 32.878025 -324.53529) (xy 29.07004 -324.53529) (xy 29.066048 -324.624177) (xy 29.054104 -324.712349)
			(xy 29.034305 -324.799095) (xy 29.006809 -324.883717) (xy 28.971839 -324.965533) (xy 28.929676 -325.043886)
			(xy 28.880659 -325.118143) (xy 28.825183 -325.187708) (xy 28.763694 -325.25202) (xy 28.696688 -325.310562)
			(xy 28.624705 -325.362861) (xy 28.548323 -325.408497) (xy 28.468157 -325.447102) (xy 28.384854 -325.478367)
			(xy 28.299084 -325.502038) (xy 28.211537 -325.517925) (xy 28.122918 -325.525901) (xy 28.07843 -325.5264)
			(xy 26.32583 -325.5264) (xy 26.281342 -325.525897) (xy 26.192724 -325.517921) (xy 26.105177 -325.502034)
			(xy 26.019407 -325.478363) (xy 25.936104 -325.447099) (xy 25.855939 -325.408493) (xy 25.779558 -325.362857)
			(xy 25.707574 -325.310558) (xy 25.640568 -325.252017) (xy 25.57908 -325.187706) (xy 25.523604 -325.118141)
			(xy 25.474587 -325.043884) (xy 25.432424 -324.965532) (xy 25.397454 -324.883715) (xy 25.369959 -324.799094)
			(xy 25.35016 -324.712348) (xy 25.338216 -324.624177) (xy 25.334225 -324.53529) (xy 24.832564 -324.53529)
			(xy 24.838666 -324.583595) (xy 24.839168 -324.615556) (xy 24.838666 -324.647517) (xy 24.830655 -324.710935)
			(xy 24.814758 -324.772849) (xy 24.791226 -324.832282) (xy 24.760432 -324.888297) (xy 24.722859 -324.940012)
			(xy 24.679102 -324.986609) (xy 24.629849 -325.027354) (xy 24.575878 -325.061605) (xy 24.518039 -325.088822)
			(xy 24.457246 -325.108575) (xy 24.394456 -325.120553) (xy 24.33066 -325.124567) (xy 24.266864 -325.120553)
			(xy 24.204074 -325.108575) (xy 24.143281 -325.088822) (xy 24.085442 -325.061605) (xy 24.031471 -325.027354)
			(xy 23.982218 -324.986609) (xy 23.938461 -324.940012) (xy 23.900888 -324.888297) (xy 23.870094 -324.832282)
			(xy 23.846562 -324.772849) (xy 23.830665 -324.710935) (xy 23.822654 -324.647517) (xy 22.619462 -324.647517)
			(xy 22.619462 -332.7527) (xy 22.620478 -332.762352) (xy 22.622108 -332.769595) (xy 22.628954 -332.78276)
			(xy 22.63394 -332.78826) (xy 23.9522 -334.10652) (xy 58.664602 -334.10652) (xy 58.665083 -334.0758)
			(xy 58.67248 -334.014807) (xy 58.687169 -333.955148) (xy 58.708935 -333.897693) (xy 58.737462 -333.843277)
			(xy 58.754518 -333.817722) (xy 58.759893 -333.809028) (xy 58.763959 -333.789017) (xy 58.759906 -333.769003)
			(xy 58.754518 -333.760318) (xy 58.737479 -333.734752) (xy 58.708949 -333.680338) (xy 58.687179 -333.622885)
			(xy 58.672487 -333.563228) (xy 58.665086 -333.502236) (xy 58.665084 -333.440797) (xy 58.672481 -333.379804)
			(xy 58.687169 -333.320146) (xy 58.708935 -333.262692) (xy 58.737462 -333.208276) (xy 58.754518 -333.182722)
			(xy 58.759893 -333.174028) (xy 58.763959 -333.154017) (xy 58.759906 -333.134003) (xy 58.754518 -333.125318)
			(xy 58.737479 -333.099752) (xy 58.708949 -333.045338) (xy 58.687179 -332.987885) (xy 58.672487 -332.928228)
			(xy 58.665086 -332.867236) (xy 58.665084 -332.805797) (xy 58.672481 -332.744804) (xy 58.687169 -332.685146)
			(xy 58.708935 -332.627692) (xy 58.737462 -332.573276) (xy 58.754518 -332.547722) (xy 58.759893 -332.539028)
			(xy 58.763959 -332.519017) (xy 58.759906 -332.499003) (xy 58.754518 -332.490318) (xy 58.737479 -332.464752)
			(xy 58.708949 -332.410338) (xy 58.687179 -332.352885) (xy 58.672487 -332.293228) (xy 58.665086 -332.232236)
			(xy 58.665084 -332.170797) (xy 58.672481 -332.109804) (xy 58.687169 -332.050146) (xy 58.708935 -331.992692)
			(xy 58.737462 -331.938276) (xy 58.754518 -331.912722) (xy 58.759893 -331.904028) (xy 58.763959 -331.884017)
			(xy 58.759906 -331.864003) (xy 58.754518 -331.855318) (xy 58.737479 -331.829752) (xy 58.708949 -331.775338)
			(xy 58.687179 -331.717885) (xy 58.672487 -331.658228) (xy 58.665086 -331.597236) (xy 58.665084 -331.535797)
			(xy 58.672481 -331.474804) (xy 58.687169 -331.415146) (xy 58.708935 -331.357692) (xy 58.737462 -331.303276)
			(xy 58.754518 -331.277722) (xy 58.759893 -331.269028) (xy 58.763959 -331.249017) (xy 58.759906 -331.229003)
			(xy 58.754518 -331.220318) (xy 58.737479 -331.194752) (xy 58.708949 -331.140338) (xy 58.687179 -331.082885)
			(xy 58.672487 -331.023228) (xy 58.665086 -330.962236) (xy 58.665084 -330.900797) (xy 58.672481 -330.839804)
			(xy 58.687169 -330.780146) (xy 58.708935 -330.722692) (xy 58.737462 -330.668276) (xy 58.754518 -330.642722)
			(xy 58.759893 -330.634028) (xy 58.763959 -330.614017) (xy 58.759906 -330.594003) (xy 58.754518 -330.585318)
			(xy 58.737479 -330.559752) (xy 58.708949 -330.505338) (xy 58.687179 -330.447885) (xy 58.672487 -330.388228)
			(xy 58.665086 -330.327236) (xy 58.665084 -330.265797) (xy 58.672481 -330.204804) (xy 58.687169 -330.145146)
			(xy 58.708935 -330.087692) (xy 58.737462 -330.033276) (xy 58.754518 -330.007722) (xy 58.759893 -329.999028)
			(xy 58.763959 -329.979017) (xy 58.759906 -329.959003) (xy 58.754518 -329.950318) (xy 58.737474 -329.924755)
			(xy 58.708939 -329.870343) (xy 58.687164 -329.81289) (xy 58.672469 -329.753233) (xy 58.665066 -329.69224)
			(xy 58.664602 -329.66152) (xy 58.665056 -329.630788) (xy 58.672463 -329.569772) (xy 58.687171 -329.510093)
			(xy 58.708965 -329.452623) (xy 58.737527 -329.398198) (xy 58.772442 -329.347614) (xy 58.8132 -329.301607)
			(xy 58.859206 -329.260848) (xy 58.90979 -329.225932) (xy 58.964214 -329.197369) (xy 59.021684 -329.175574)
			(xy 59.081362 -329.160865) (xy 59.142378 -329.153457) (xy 59.17311 -329.153012) (xy 59.203831 -329.153476)
			(xy 59.264825 -329.160877) (xy 59.324483 -329.175569) (xy 59.381939 -329.197339) (xy 59.436354 -329.22587)
			(xy 59.461908 -329.242928) (xy 59.470593 -329.248321) (xy 59.49061 -329.252382) (xy 59.510627 -329.248321)
			(xy 59.519312 -329.242928) (xy 59.544866 -329.22587) (xy 59.599281 -329.197339) (xy 59.656736 -329.175568)
			(xy 59.716395 -329.160876) (xy 59.777389 -329.153476) (xy 59.838831 -329.153476) (xy 59.899825 -329.160876)
			(xy 59.959484 -329.175568) (xy 60.016939 -329.197339) (xy 60.071354 -329.22587) (xy 60.096908 -329.242928)
			(xy 60.105593 -329.248321) (xy 60.12561 -329.252382) (xy 60.145627 -329.248321) (xy 60.154312 -329.242928)
			(xy 60.179868 -329.225873) (xy 60.234282 -329.197338) (xy 60.291736 -329.175567) (xy 60.351395 -329.160874)
			(xy 60.412389 -329.153474) (xy 60.44311 -329.153012) (xy 60.473843 -329.153428) (xy 60.534861 -329.160838)
			(xy 60.594541 -329.17555) (xy 60.652012 -329.197347) (xy 60.706437 -329.225913) (xy 60.757022 -329.260832)
			(xy 60.803029 -329.301593) (xy 60.843787 -329.347602) (xy 60.878702 -329.398189) (xy 60.907265 -329.452615)
			(xy 60.929059 -329.510088) (xy 60.943767 -329.569769) (xy 60.951174 -329.630787) (xy 60.951618 -329.66152)
			(xy 60.951153 -329.692241) (xy 60.943752 -329.753234) (xy 60.929059 -329.812893) (xy 60.90729 -329.870348)
			(xy 60.878759 -329.924764) (xy 60.861702 -329.950318) (xy 60.856291 -329.958993) (xy 60.852235 -329.979017)
			(xy 60.856304 -329.999037) (xy 60.861702 -330.007722) (xy 60.878779 -330.033264) (xy 60.907312 -330.08768)
			(xy 60.929083 -330.145137) (xy 60.943774 -330.204799) (xy 60.951173 -330.265795) (xy 60.951171 -330.327238)
			(xy 60.943768 -330.388234) (xy 60.929073 -330.447894) (xy 60.907299 -330.50535) (xy 60.878762 -330.559765)
			(xy 60.861702 -330.585318) (xy 60.856291 -330.593993) (xy 60.852235 -330.614017) (xy 60.856304 -330.634037)
			(xy 60.861702 -330.642722) (xy 60.878779 -330.668264) (xy 60.907312 -330.72268) (xy 60.929083 -330.780137)
			(xy 60.943774 -330.839799) (xy 60.951173 -330.900795) (xy 60.951171 -330.962238) (xy 60.943768 -331.023234)
			(xy 60.929073 -331.082894) (xy 60.907299 -331.14035) (xy 60.878762 -331.194765) (xy 60.861702 -331.220318)
			(xy 60.856291 -331.228993) (xy 60.852235 -331.249017) (xy 60.856304 -331.269037) (xy 60.861702 -331.277722)
			(xy 60.878779 -331.303264) (xy 60.907312 -331.35768) (xy 60.929083 -331.415137) (xy 60.943774 -331.474799)
			(xy 60.951173 -331.535795) (xy 60.951171 -331.597238) (xy 60.943768 -331.658234) (xy 60.929073 -331.717894)
			(xy 60.907299 -331.77535) (xy 60.878762 -331.829765) (xy 60.861702 -331.855318) (xy 60.856291 -331.863993)
			(xy 60.852235 -331.884017) (xy 60.856304 -331.904037) (xy 60.861702 -331.912722) (xy 60.878779 -331.938264)
			(xy 60.907312 -331.99268) (xy 60.929083 -332.050137) (xy 60.943774 -332.109799) (xy 60.951173 -332.170795)
			(xy 60.951171 -332.232238) (xy 60.943768 -332.293234) (xy 60.929073 -332.352894) (xy 60.907299 -332.41035)
			(xy 60.878762 -332.464765) (xy 60.861702 -332.490318) (xy 60.856291 -332.498993) (xy 60.852235 -332.519017)
			(xy 60.856304 -332.539037) (xy 60.861702 -332.547722) (xy 60.878779 -332.573264) (xy 60.907312 -332.62768)
			(xy 60.929083 -332.685137) (xy 60.943774 -332.744799) (xy 60.951173 -332.805795) (xy 60.951171 -332.867238)
			(xy 60.943768 -332.928234) (xy 60.929073 -332.987894) (xy 60.907299 -333.04535) (xy 60.878762 -333.099765)
			(xy 60.861702 -333.125318) (xy 60.856291 -333.133993) (xy 60.852235 -333.154017) (xy 60.856304 -333.174037)
			(xy 60.861702 -333.182722) (xy 60.878779 -333.208264) (xy 60.907312 -333.26268) (xy 60.929083 -333.320137)
			(xy 60.943774 -333.379799) (xy 60.951173 -333.440795) (xy 60.951171 -333.502238) (xy 60.943768 -333.563234)
			(xy 60.929073 -333.622894) (xy 60.907299 -333.68035) (xy 60.878762 -333.734765) (xy 60.861702 -333.760318)
			(xy 60.856291 -333.768993) (xy 60.852235 -333.789017) (xy 60.856304 -333.809037) (xy 60.861702 -333.817722)
			(xy 60.878765 -333.843273) (xy 60.907297 -333.897688) (xy 60.929067 -333.955144) (xy 60.943758 -334.014804)
			(xy 60.951157 -334.075799) (xy 60.951618 -334.10652) (xy 60.951163 -334.137251) (xy 60.943752 -334.198265)
			(xy 60.929042 -334.25794) (xy 60.907245 -334.315408) (xy 60.878681 -334.369829) (xy 60.843766 -334.420411)
			(xy 60.803009 -334.466416) (xy 60.757003 -334.507172) (xy 60.706421 -334.542086) (xy 60.651999 -334.570649)
			(xy 60.594531 -334.592445) (xy 60.534855 -334.607154) (xy 60.473841 -334.614563) (xy 60.44311 -334.615028)
			(xy 60.41239 -334.614546) (xy 60.351397 -334.607149) (xy 60.291738 -334.59246) (xy 60.234283 -334.570694)
			(xy 60.179867 -334.542167) (xy 60.154312 -334.525112) (xy 60.145627 -334.519719) (xy 60.12561 -334.515658)
			(xy 60.105593 -334.519719) (xy 60.096908 -334.525112) (xy 60.071354 -334.54217) (xy 60.016939 -334.570701)
			(xy 59.959484 -334.592472) (xy 59.899825 -334.607164) (xy 59.838831 -334.614564) (xy 59.777389 -334.614564)
			(xy 59.716395 -334.607164) (xy 59.656736 -334.592472) (xy 59.599281 -334.570701) (xy 59.544866 -334.54217)
			(xy 59.519312 -334.525112) (xy 59.510627 -334.519719) (xy 59.49061 -334.515658) (xy 59.470593 -334.519719)
			(xy 59.461908 -334.525112) (xy 59.43635 -334.542164) (xy 59.381936 -334.570697) (xy 59.324482 -334.59247)
			(xy 59.264824 -334.607163) (xy 59.203831 -334.614565) (xy 59.17311 -334.615028) (xy 59.14238 -334.614535)
			(xy 59.081368 -334.607128) (xy 59.021693 -334.592421) (xy 58.964227 -334.570628) (xy 58.909806 -334.542068)
			(xy 58.859224 -334.507156) (xy 58.81322 -334.466401) (xy 58.772463 -334.420399) (xy 58.737548 -334.36982)
			(xy 58.708984 -334.315401) (xy 58.687188 -334.257935) (xy 58.672478 -334.198262) (xy 58.665067 -334.13725)
			(xy 58.664602 -334.10652) (xy 23.9522 -334.10652) (xy 24.758142 -334.912462) (xy 24.763644 -334.917443)
			(xy 24.776813 -334.924275) (xy 24.78405 -334.925924) (xy 24.793702 -334.92694) (xy 25.066498 -334.92694)
			(xy 25.076567 -334.927364) (xy 25.095169 -334.935082) (xy 25.102566 -334.941926) (xy 25.181306 -335.020666)
			(xy 25.186807 -335.025651) (xy 25.199974 -335.032491) (xy 25.207214 -335.034128) (xy 25.216866 -335.035144)
			(xy 62.176914 -335.035144)
		)
		(stroke
			(width 0)
			(type solid)
		)
		(fill yes)
		(layer "In13.Cu")
		(net "PVDDIO_P1")
	)
	(gr_poly
		(pts
			(xy 97.299018 -251.206254) (xy 97.311265 -251.205526) (xy 97.333008 -251.194244) (xy 97.340674 -251.184664)
			(xy 97.395538 -251.105924) (xy 97.39884 -251.081286) (xy 97.394522 -251.069602) (xy 97.385777 -251.044196)
			(xy 97.376321 -250.991308) (xy 97.375726 -250.964446) (xy 97.376248 -250.939191) (xy 97.384561 -250.889369)
			(xy 97.400962 -250.841595) (xy 97.425003 -250.797172) (xy 97.456027 -250.757312) (xy 97.493189 -250.723102)
			(xy 97.535475 -250.695476) (xy 97.581731 -250.675186) (xy 97.630696 -250.662786) (xy 97.681034 -250.658615)
			(xy 97.731372 -250.662786) (xy 97.780337 -250.675186) (xy 97.826593 -250.695476) (xy 97.868879 -250.723102)
			(xy 97.906041 -250.757312) (xy 97.937065 -250.797172) (xy 97.961106 -250.841595) (xy 97.977507 -250.889369)
			(xy 97.98582 -250.939191) (xy 97.986342 -250.964446) (xy 97.98576 -250.99131) (xy 97.976315 -251.044203)
			(xy 97.967546 -251.069602) (xy 97.963228 -251.081286) (xy 97.96653 -251.105924) (xy 98.021394 -251.184664)
			(xy 98.029018 -251.194289) (xy 98.050789 -251.205561) (xy 98.06305 -251.206254) (xy 98.239072 -251.206254)
			(xy 98.251324 -251.205536) (xy 98.273084 -251.194265) (xy 98.280728 -251.184664) (xy 98.335592 -251.105924)
			(xy 98.338894 -251.081286) (xy 98.334576 -251.069602) (xy 98.32583 -251.044196) (xy 98.316372 -250.991308)
			(xy 98.31578 -250.964446) (xy 98.316302 -250.939191) (xy 98.324615 -250.889369) (xy 98.341016 -250.841595)
			(xy 98.365057 -250.797172) (xy 98.396081 -250.757312) (xy 98.433243 -250.723102) (xy 98.475529 -250.695476)
			(xy 98.521785 -250.675186) (xy 98.57075 -250.662786) (xy 98.621088 -250.658615) (xy 98.671426 -250.662786)
			(xy 98.720391 -250.675186) (xy 98.766647 -250.695476) (xy 98.808933 -250.723102) (xy 98.846095 -250.757312)
			(xy 98.877119 -250.797172) (xy 98.90116 -250.841595) (xy 98.917561 -250.889369) (xy 98.925874 -250.939191)
			(xy 98.926396 -250.964446) (xy 98.925814 -250.99131) (xy 98.916367 -251.044202) (xy 98.9076 -251.069602)
			(xy 98.903282 -251.081286) (xy 98.906584 -251.105924) (xy 98.961448 -251.184664) (xy 98.969069 -251.194297)
			(xy 98.990839 -251.205588) (xy 99.003104 -251.206254) (xy 99.179126 -251.206254) (xy 99.191372 -251.205524)
			(xy 99.213113 -251.194241) (xy 99.220782 -251.184664) (xy 99.275646 -251.105924) (xy 99.278948 -251.081286)
			(xy 99.27463 -251.069602) (xy 99.265885 -251.044196) (xy 99.256429 -250.991308) (xy 99.255834 -250.964446)
			(xy 99.256356 -250.939191) (xy 99.264669 -250.889369) (xy 99.28107 -250.841595) (xy 99.305111 -250.797172)
			(xy 99.336135 -250.757312) (xy 99.373297 -250.723102) (xy 99.415583 -250.695476) (xy 99.461839 -250.675186)
			(xy 99.510804 -250.662786) (xy 99.561142 -250.658615) (xy 99.61148 -250.662786) (xy 99.660445 -250.675186)
			(xy 99.706701 -250.695476) (xy 99.748987 -250.723102) (xy 99.786149 -250.757312) (xy 99.817173 -250.797172)
			(xy 99.841214 -250.841595) (xy 99.857615 -250.889369) (xy 99.865928 -250.939191) (xy 99.86645 -250.964446)
			(xy 99.865868 -250.99131) (xy 99.856423 -251.044203) (xy 99.847654 -251.069602) (xy 99.843336 -251.081286)
			(xy 99.846638 -251.105924) (xy 99.901502 -251.184664) (xy 99.909127 -251.194288) (xy 99.930897 -251.205556)
			(xy 99.943158 -251.206254) (xy 100.118926 -251.206254) (xy 100.131172 -251.205524) (xy 100.152913 -251.194241)
			(xy 100.160582 -251.184664) (xy 100.215446 -251.105924) (xy 100.218748 -251.081286) (xy 100.21443 -251.069602)
			(xy 100.205685 -251.044196) (xy 100.196229 -250.991308) (xy 100.195634 -250.964446) (xy 100.196156 -250.939191)
			(xy 100.204469 -250.889369) (xy 100.22087 -250.841595) (xy 100.244911 -250.797172) (xy 100.275935 -250.757312)
			(xy 100.313097 -250.723102) (xy 100.355383 -250.695476) (xy 100.401639 -250.675186) (xy 100.450604 -250.662786)
			(xy 100.500942 -250.658615) (xy 100.55128 -250.662786) (xy 100.600245 -250.675186) (xy 100.646501 -250.695476)
			(xy 100.688787 -250.723102) (xy 100.725949 -250.757312) (xy 100.756973 -250.797172) (xy 100.781014 -250.841595)
			(xy 100.797415 -250.889369) (xy 100.805728 -250.939191) (xy 100.80625 -250.964446) (xy 100.805668 -250.99131)
			(xy 100.796223 -251.044203) (xy 100.787454 -251.069602) (xy 100.783136 -251.081286) (xy 100.786438 -251.105924)
			(xy 100.841302 -251.184664) (xy 100.848927 -251.194288) (xy 100.870697 -251.205556) (xy 100.882958 -251.206254)
			(xy 101.05898 -251.206254) (xy 101.071231 -251.205534) (xy 101.092988 -251.194261) (xy 101.100636 -251.184664)
			(xy 101.1555 -251.105924) (xy 101.158802 -251.081286) (xy 101.154484 -251.069602) (xy 101.145737 -251.044196)
			(xy 101.13628 -250.991309) (xy 101.135688 -250.964446) (xy 101.13621 -250.939191) (xy 101.144523 -250.889369)
			(xy 101.160924 -250.841595) (xy 101.184965 -250.797172) (xy 101.215989 -250.757312) (xy 101.253151 -250.723102)
			(xy 101.295437 -250.695476) (xy 101.341693 -250.675186) (xy 101.390658 -250.662786) (xy 101.440996 -250.658615)
			(xy 101.491334 -250.662786) (xy 101.540299 -250.675186) (xy 101.586555 -250.695476) (xy 101.628841 -250.723102)
			(xy 101.666003 -250.757312) (xy 101.697027 -250.797172) (xy 101.721068 -250.841595) (xy 101.737469 -250.889369)
			(xy 101.745782 -250.939191) (xy 101.746304 -250.964446) (xy 101.745722 -250.99131) (xy 101.736275 -251.044202)
			(xy 101.727508 -251.069602) (xy 101.72319 -251.081286) (xy 101.726492 -251.105924) (xy 101.781356 -251.184664)
			(xy 101.788978 -251.194296) (xy 101.810748 -251.205583) (xy 101.823012 -251.206254) (xy 102.939088 -251.206254)
			(xy 102.951338 -251.205532) (xy 102.973093 -251.194258) (xy 102.980744 -251.184664) (xy 103.035608 -251.105924)
			(xy 103.03891 -251.081286) (xy 103.034592 -251.069602) (xy 103.025846 -251.044196) (xy 103.016388 -250.991309)
			(xy 103.015796 -250.964446) (xy 103.016318 -250.939191) (xy 103.024631 -250.889369) (xy 103.041032 -250.841595)
			(xy 103.065073 -250.797172) (xy 103.096097 -250.757312) (xy 103.133259 -250.723102) (xy 103.175545 -250.695476)
			(xy 103.221801 -250.675186) (xy 103.270766 -250.662786) (xy 103.321104 -250.658615) (xy 103.371442 -250.662786)
			(xy 103.420407 -250.675186) (xy 103.466663 -250.695476) (xy 103.508949 -250.723102) (xy 103.546111 -250.757312)
			(xy 103.577135 -250.797172) (xy 103.601176 -250.841595) (xy 103.617577 -250.889369) (xy 103.62589 -250.939191)
			(xy 103.626412 -250.964446) (xy 103.62583 -250.99131) (xy 103.616384 -251.044202) (xy 103.607616 -251.069602)
			(xy 103.603298 -251.081286) (xy 103.6066 -251.105924) (xy 103.661464 -251.184664) (xy 103.669086 -251.194295)
			(xy 103.690857 -251.205579) (xy 103.70312 -251.206254) (xy 104.818942 -251.206254) (xy 104.831197 -251.205542)
			(xy 104.852969 -251.194279) (xy 104.860598 -251.184664) (xy 104.915462 -251.105924) (xy 104.918764 -251.081286)
			(xy 104.914446 -251.069602) (xy 104.9057 -251.044196) (xy 104.896244 -250.991308) (xy 104.89565 -250.964446)
			(xy 104.896172 -250.939191) (xy 104.904485 -250.889369) (xy 104.920886 -250.841595) (xy 104.944927 -250.797172)
			(xy 104.975951 -250.757312) (xy 105.013113 -250.723102) (xy 105.055399 -250.695476) (xy 105.101655 -250.675186)
			(xy 105.15062 -250.662786) (xy 105.200958 -250.658615) (xy 105.251296 -250.662786) (xy 105.300261 -250.675186)
			(xy 105.346517 -250.695476) (xy 105.388803 -250.723102) (xy 105.425965 -250.757312) (xy 105.456989 -250.797172)
			(xy 105.48103 -250.841595) (xy 105.497431 -250.889369) (xy 105.505744 -250.939191) (xy 105.506266 -250.964446)
			(xy 105.505684 -250.99131) (xy 105.496239 -251.044203) (xy 105.48747 -251.069602) (xy 105.483152 -251.081286)
			(xy 105.486454 -251.105924) (xy 105.541318 -251.184664) (xy 105.548944 -251.194286) (xy 105.570715 -251.205547)
			(xy 105.582974 -251.206254) (xy 106.69905 -251.206254) (xy 106.711305 -251.20554) (xy 106.733073 -251.194275)
			(xy 106.740706 -251.184664) (xy 106.79557 -251.105924) (xy 106.798872 -251.081286) (xy 106.794554 -251.069602)
			(xy 106.785808 -251.044196) (xy 106.776352 -250.991308) (xy 106.775758 -250.964446) (xy 106.77628 -250.939191)
			(xy 106.784593 -250.889369) (xy 106.800994 -250.841595) (xy 106.825035 -250.797172) (xy 106.856059 -250.757312)
			(xy 106.893221 -250.723102) (xy 106.935507 -250.695476) (xy 106.981763 -250.675186) (xy 107.030728 -250.662786)
			(xy 107.081066 -250.658615) (xy 107.131404 -250.662786) (xy 107.180369 -250.675186) (xy 107.226625 -250.695476)
			(xy 107.268911 -250.723102) (xy 107.306073 -250.757312) (xy 107.337097 -250.797172) (xy 107.361138 -250.841595)
			(xy 107.377539 -250.889369) (xy 107.385852 -250.939191) (xy 107.386374 -250.964446) (xy 107.385792 -250.99131)
			(xy 107.376348 -251.044203) (xy 107.367578 -251.069602) (xy 107.36326 -251.081286) (xy 107.366562 -251.105924)
			(xy 107.421426 -251.184664) (xy 107.429046 -251.194301) (xy 107.450816 -251.205601) (xy 107.463082 -251.206254)
			(xy 108.579158 -251.206254) (xy 108.591412 -251.205539) (xy 108.613177 -251.194271) (xy 108.620814 -251.184664)
			(xy 108.675678 -251.105924) (xy 108.67898 -251.081286) (xy 108.674662 -251.069602) (xy 108.665916 -251.044196)
			(xy 108.656459 -250.991308) (xy 108.655866 -250.964446) (xy 108.656388 -250.939191) (xy 108.664701 -250.889369)
			(xy 108.681102 -250.841595) (xy 108.705143 -250.797172) (xy 108.736167 -250.757312) (xy 108.773329 -250.723102)
			(xy 108.815615 -250.695476) (xy 108.861871 -250.675186) (xy 108.910836 -250.662786) (xy 108.961174 -250.658615)
			(xy 109.011512 -250.662786) (xy 109.060477 -250.675186) (xy 109.106733 -250.695476) (xy 109.149019 -250.723102)
			(xy 109.186181 -250.757312) (xy 109.217205 -250.797172) (xy 109.241246 -250.841595) (xy 109.257647 -250.889369)
			(xy 109.26596 -250.939191) (xy 109.266482 -250.964446) (xy 109.265901 -250.99131) (xy 109.256456 -251.044203)
			(xy 109.247686 -251.069602) (xy 109.243368 -251.081286) (xy 109.24667 -251.105924) (xy 109.301534 -251.184664)
			(xy 109.309154 -251.1943) (xy 109.330924 -251.205597) (xy 109.34319 -251.206254) (xy 109.518958 -251.206254)
			(xy 109.531212 -251.205539) (xy 109.552977 -251.194271) (xy 109.560614 -251.184664) (xy 109.615478 -251.105924)
			(xy 109.61878 -251.081286) (xy 109.614462 -251.069602) (xy 109.605716 -251.044196) (xy 109.596259 -250.991308)
			(xy 109.595666 -250.964446) (xy 109.596188 -250.939191) (xy 109.604501 -250.889369) (xy 109.620902 -250.841595)
			(xy 109.644943 -250.797172) (xy 109.675967 -250.757312) (xy 109.713129 -250.723102) (xy 109.755415 -250.695476)
			(xy 109.801671 -250.675186) (xy 109.850636 -250.662786) (xy 109.900974 -250.658615) (xy 109.951312 -250.662786)
			(xy 110.000277 -250.675186) (xy 110.046533 -250.695476) (xy 110.088819 -250.723102) (xy 110.125981 -250.757312)
			(xy 110.157005 -250.797172) (xy 110.181046 -250.841595) (xy 110.197447 -250.889369) (xy 110.20576 -250.939191)
			(xy 110.206282 -250.964446) (xy 110.205701 -250.99131) (xy 110.196256 -251.044203) (xy 110.187486 -251.069602)
			(xy 110.183168 -251.081286) (xy 110.18647 -251.105924) (xy 110.241334 -251.184664) (xy 110.248954 -251.1943)
			(xy 110.270724 -251.205597) (xy 110.28299 -251.206254) (xy 111.041688 -251.206254) (xy 111.047477 -251.206129)
			(xy 111.058768 -251.203569) (xy 111.06404 -251.201174) (xy 111.092742 -251.187204) (xy 111.0996 -251.179076)
			(xy 111.11752 -251.158608) (xy 111.158686 -251.123049) (xy 111.204945 -251.094425) (xy 111.255137 -251.073452)
			(xy 111.308008 -251.060655) (xy 111.362236 -251.056354) (xy 111.416464 -251.060655) (xy 111.469335 -251.073452)
			(xy 111.519527 -251.094425) (xy 111.565786 -251.123049) (xy 111.606952 -251.158608) (xy 111.624872 -251.179076)
			(xy 111.63173 -251.187204) (xy 111.660432 -251.201174) (xy 111.66571 -251.203555) (xy 111.676996 -251.206129)
			(xy 111.682784 -251.206254) (xy 111.956088 -251.206254) (xy 111.961877 -251.206129) (xy 111.973168 -251.203569)
			(xy 111.97844 -251.201174) (xy 112.007142 -251.187204) (xy 112.014 -251.179076) (xy 112.03192 -251.158608)
			(xy 112.073086 -251.123049) (xy 112.119345 -251.094425) (xy 112.169537 -251.073452) (xy 112.222408 -251.060655)
			(xy 112.276636 -251.056354) (xy 112.330864 -251.060655) (xy 112.383735 -251.073452) (xy 112.433927 -251.094425)
			(xy 112.480186 -251.123049) (xy 112.521352 -251.158608) (xy 112.539272 -251.179076) (xy 112.54613 -251.187204)
			(xy 112.574832 -251.201174) (xy 112.58011 -251.203555) (xy 112.591396 -251.206129) (xy 112.597184 -251.206254)
			(xy 113.272824 -251.206254) (xy 113.28507 -251.205525) (xy 113.306812 -251.194241) (xy 113.31448 -251.184664)
			(xy 113.369344 -251.105924) (xy 113.372646 -251.081286) (xy 113.368328 -251.069602) (xy 113.359583 -251.044196)
			(xy 113.350127 -250.991308) (xy 113.349532 -250.964446) (xy 113.350054 -250.939191) (xy 113.358367 -250.889369)
			(xy 113.374768 -250.841595) (xy 113.398809 -250.797172) (xy 113.429833 -250.757312) (xy 113.466995 -250.723102)
			(xy 113.509281 -250.695476) (xy 113.555537 -250.675186) (xy 113.604502 -250.662786) (xy 113.65484 -250.658615)
			(xy 113.705178 -250.662786) (xy 113.754143 -250.675186) (xy 113.800399 -250.695476) (xy 113.842685 -250.723102)
			(xy 113.879847 -250.757312) (xy 113.910871 -250.797172) (xy 113.934912 -250.841595) (xy 113.951313 -250.889369)
			(xy 113.959626 -250.939191) (xy 113.960148 -250.964446) (xy 113.959566 -250.99131) (xy 113.950121 -251.044203)
			(xy 113.941352 -251.069602) (xy 113.937034 -251.081286) (xy 113.940336 -251.105924) (xy 113.9952 -251.184664)
			(xy 114.002825 -251.194289) (xy 114.024595 -251.205557) (xy 114.036856 -251.206254) (xy 114.212624 -251.206254)
			(xy 114.22487 -251.205525) (xy 114.246612 -251.194241) (xy 114.25428 -251.184664) (xy 114.309144 -251.105924)
			(xy 114.312446 -251.081286) (xy 114.308128 -251.069602) (xy 114.299383 -251.044196) (xy 114.289927 -250.991308)
			(xy 114.289332 -250.964446) (xy 114.289854 -250.939191) (xy 114.298167 -250.889369) (xy 114.314568 -250.841595)
			(xy 114.338609 -250.797172) (xy 114.369633 -250.757312) (xy 114.406795 -250.723102) (xy 114.449081 -250.695476)
			(xy 114.495337 -250.675186) (xy 114.544302 -250.662786) (xy 114.59464 -250.658615) (xy 114.644978 -250.662786)
			(xy 114.693943 -250.675186) (xy 114.740199 -250.695476) (xy 114.782485 -250.723102) (xy 114.819647 -250.757312)
			(xy 114.850671 -250.797172) (xy 114.874712 -250.841595) (xy 114.891113 -250.889369) (xy 114.899426 -250.939191)
			(xy 114.899948 -250.964446) (xy 114.899366 -250.99131) (xy 114.889921 -251.044203) (xy 114.881152 -251.069602)
			(xy 114.876834 -251.081286) (xy 114.880136 -251.105924) (xy 114.935 -251.184664) (xy 114.942625 -251.194289)
			(xy 114.964395 -251.205557) (xy 114.976656 -251.206254) (xy 115.152678 -251.206254) (xy 115.164929 -251.205534)
			(xy 115.186687 -251.194262) (xy 115.194334 -251.184664) (xy 115.249198 -251.105924) (xy 115.2525 -251.081286)
			(xy 115.248182 -251.069602) (xy 115.239435 -251.044196) (xy 115.229978 -250.991309) (xy 115.229386 -250.964446)
			(xy 115.229908 -250.939191) (xy 115.238221 -250.889369) (xy 115.254622 -250.841595) (xy 115.278663 -250.797172)
			(xy 115.309687 -250.757312) (xy 115.346849 -250.723102) (xy 115.389135 -250.695476) (xy 115.435391 -250.675186)
			(xy 115.484356 -250.662786) (xy 115.534694 -250.658615) (xy 115.585032 -250.662786) (xy 115.633997 -250.675186)
			(xy 115.680253 -250.695476) (xy 115.722539 -250.723102) (xy 115.759701 -250.757312) (xy 115.790725 -250.797172)
			(xy 115.814766 -250.841595) (xy 115.831167 -250.889369) (xy 115.83948 -250.939191) (xy 115.840002 -250.964446)
			(xy 115.83942 -250.99131) (xy 115.829973 -251.044202) (xy 115.821206 -251.069602) (xy 115.816888 -251.081286)
			(xy 115.82019 -251.105924) (xy 115.875054 -251.184664) (xy 115.882676 -251.194296) (xy 115.904446 -251.205584)
			(xy 115.91671 -251.206254) (xy 117.032786 -251.206254) (xy 117.045036 -251.205533) (xy 117.066792 -251.194259)
			(xy 117.074442 -251.184664) (xy 117.129306 -251.105924) (xy 117.132608 -251.081286) (xy 117.12829 -251.069602)
			(xy 117.119544 -251.044196) (xy 117.110086 -250.991309) (xy 117.109494 -250.964446) (xy 117.110016 -250.939191)
			(xy 117.118329 -250.889369) (xy 117.13473 -250.841595) (xy 117.158771 -250.797172) (xy 117.189795 -250.757312)
			(xy 117.226957 -250.723102) (xy 117.269243 -250.695476) (xy 117.315499 -250.675186) (xy 117.364464 -250.662786)
			(xy 117.414802 -250.658615) (xy 117.46514 -250.662786) (xy 117.514105 -250.675186) (xy 117.560361 -250.695476)
			(xy 117.602647 -250.723102) (xy 117.639809 -250.757312) (xy 117.670833 -250.797172) (xy 117.694874 -250.841595)
			(xy 117.711275 -250.889369) (xy 117.719588 -250.939191) (xy 117.72011 -250.964446) (xy 117.719528 -250.99131)
			(xy 117.710081 -251.044202) (xy 117.701314 -251.069602) (xy 117.696996 -251.081286) (xy 117.700298 -251.105924)
			(xy 117.755162 -251.184664) (xy 117.762784 -251.194295) (xy 117.784554 -251.20558) (xy 117.796818 -251.206254)
			(xy 117.97284 -251.206254) (xy 117.985096 -251.205543) (xy 118.006868 -251.19428) (xy 118.014496 -251.184664)
			(xy 118.06936 -251.105924) (xy 118.072662 -251.081286) (xy 118.068344 -251.069602) (xy 118.059598 -251.044196)
			(xy 118.050142 -250.991308) (xy 118.049548 -250.964446) (xy 118.05007 -250.939191) (xy 118.058383 -250.889369)
			(xy 118.074784 -250.841595) (xy 118.098825 -250.797172) (xy 118.129849 -250.757312) (xy 118.167011 -250.723102)
			(xy 118.209297 -250.695476) (xy 118.255553 -250.675186) (xy 118.304518 -250.662786) (xy 118.354856 -250.658615)
			(xy 118.405194 -250.662786) (xy 118.454159 -250.675186) (xy 118.500415 -250.695476) (xy 118.542701 -250.723102)
			(xy 118.579863 -250.757312) (xy 118.610887 -250.797172) (xy 118.634928 -250.841595) (xy 118.651329 -250.889369)
			(xy 118.659642 -250.939191) (xy 118.660164 -250.964446) (xy 118.659582 -250.99131) (xy 118.650137 -251.044203)
			(xy 118.641368 -251.069602) (xy 118.63705 -251.081286) (xy 118.640352 -251.105924) (xy 118.695216 -251.184664)
			(xy 118.702842 -251.194286) (xy 118.724612 -251.205548) (xy 118.736872 -251.206254) (xy 118.91264 -251.206254)
			(xy 118.924896 -251.205543) (xy 118.946668 -251.19428) (xy 118.954296 -251.184664) (xy 119.00916 -251.105924)
			(xy 119.012462 -251.081286) (xy 119.008144 -251.069602) (xy 118.999398 -251.044196) (xy 118.989942 -250.991308)
			(xy 118.989348 -250.964446) (xy 118.98987 -250.939191) (xy 118.998183 -250.889369) (xy 119.014584 -250.841595)
			(xy 119.038625 -250.797172) (xy 119.069649 -250.757312) (xy 119.106811 -250.723102) (xy 119.149097 -250.695476)
			(xy 119.195353 -250.675186) (xy 119.244318 -250.662786) (xy 119.294656 -250.658615) (xy 119.344994 -250.662786)
			(xy 119.393959 -250.675186) (xy 119.440215 -250.695476) (xy 119.482501 -250.723102) (xy 119.519663 -250.757312)
			(xy 119.550687 -250.797172) (xy 119.574728 -250.841595) (xy 119.591129 -250.889369) (xy 119.599442 -250.939191)
			(xy 119.599964 -250.964446) (xy 119.599382 -250.99131) (xy 119.589937 -251.044203) (xy 119.581168 -251.069602)
			(xy 119.57685 -251.081286) (xy 119.580152 -251.105924) (xy 119.635016 -251.184664) (xy 119.642642 -251.194286)
			(xy 119.664412 -251.205548) (xy 119.676672 -251.206254) (xy 120.792748 -251.206254) (xy 120.805003 -251.205541)
			(xy 120.826772 -251.194276) (xy 120.834404 -251.184664) (xy 120.889268 -251.105924) (xy 120.89257 -251.081286)
			(xy 120.888252 -251.069602) (xy 120.879506 -251.044196) (xy 120.87005 -250.991308) (xy 120.869456 -250.964446)
			(xy 120.869978 -250.939191) (xy 120.878291 -250.889369) (xy 120.894692 -250.841595) (xy 120.918733 -250.797172)
			(xy 120.949757 -250.757312) (xy 120.986919 -250.723102) (xy 121.029205 -250.695476) (xy 121.075461 -250.675186)
			(xy 121.124426 -250.662786) (xy 121.174764 -250.658615) (xy 121.225102 -250.662786) (xy 121.274067 -250.675186)
			(xy 121.320323 -250.695476) (xy 121.362609 -250.723102) (xy 121.399771 -250.757312) (xy 121.430795 -250.797172)
			(xy 121.454836 -250.841595) (xy 121.471237 -250.889369) (xy 121.47955 -250.939191) (xy 121.480072 -250.964446)
			(xy 121.47949 -250.99131) (xy 121.470046 -251.044203) (xy 121.461276 -251.069602) (xy 121.456958 -251.081286)
			(xy 121.46026 -251.105924) (xy 121.515124 -251.184664) (xy 121.522744 -251.194302) (xy 121.544513 -251.205602)
			(xy 121.55678 -251.206254) (xy 121.732802 -251.206254) (xy 121.74505 -251.205529) (xy 121.7668 -251.194251)
			(xy 121.774458 -251.184664) (xy 121.829322 -251.105924) (xy 121.832624 -251.081286) (xy 121.828306 -251.069602)
			(xy 121.819559 -251.044196) (xy 121.810101 -250.991309) (xy 121.80951 -250.964446) (xy 121.810032 -250.939191)
			(xy 121.818345 -250.889369) (xy 121.834746 -250.841595) (xy 121.858787 -250.797172) (xy 121.889811 -250.757312)
			(xy 121.926973 -250.723102) (xy 121.969259 -250.695476) (xy 122.015515 -250.675186) (xy 122.06448 -250.662786)
			(xy 122.114818 -250.658615) (xy 122.165156 -250.662786) (xy 122.214121 -250.675186) (xy 122.260377 -250.695476)
			(xy 122.302663 -250.723102) (xy 122.339825 -250.757312) (xy 122.370849 -250.797172) (xy 122.39489 -250.841595)
			(xy 122.411291 -250.889369) (xy 122.419604 -250.939191) (xy 122.420126 -250.964446) (xy 122.419544 -250.99131)
			(xy 122.410098 -251.044203) (xy 122.40133 -251.069602) (xy 122.397012 -251.081286) (xy 122.400314 -251.105924)
			(xy 122.455178 -251.184664) (xy 122.462801 -251.194292) (xy 122.484572 -251.20557) (xy 122.496834 -251.206254)
			(xy 122.672602 -251.206254) (xy 122.68485 -251.205529) (xy 122.7066 -251.194251) (xy 122.714258 -251.184664)
			(xy 122.769122 -251.105924) (xy 122.772424 -251.081286) (xy 122.768106 -251.069602) (xy 122.759359 -251.044196)
			(xy 122.749901 -250.991309) (xy 122.74931 -250.964446) (xy 122.749832 -250.939191) (xy 122.758145 -250.889369)
			(xy 122.774546 -250.841595) (xy 122.798587 -250.797172) (xy 122.829611 -250.757312) (xy 122.866773 -250.723102)
			(xy 122.909059 -250.695476) (xy 122.955315 -250.675186) (xy 123.00428 -250.662786) (xy 123.054618 -250.658615)
			(xy 123.104956 -250.662786) (xy 123.153921 -250.675186) (xy 123.200177 -250.695476) (xy 123.242463 -250.723102)
			(xy 123.279625 -250.757312) (xy 123.310649 -250.797172) (xy 123.33469 -250.841595) (xy 123.351091 -250.889369)
			(xy 123.359404 -250.939191) (xy 123.359926 -250.964446) (xy 123.359344 -250.99131) (xy 123.349898 -251.044203)
			(xy 123.34113 -251.069602) (xy 123.336812 -251.081286) (xy 123.340114 -251.105924) (xy 123.394978 -251.184664)
			(xy 123.402601 -251.194292) (xy 123.424372 -251.20557) (xy 123.436634 -251.206254) (xy 124.55271 -251.206254)
			(xy 124.564957 -251.205528) (xy 124.586704 -251.194248) (xy 124.594366 -251.184664) (xy 124.64923 -251.105924)
			(xy 124.652532 -251.081286) (xy 124.648214 -251.069602) (xy 124.639467 -251.044196) (xy 124.630009 -250.991309)
			(xy 124.629418 -250.964446) (xy 124.62994 -250.939191) (xy 124.638253 -250.889369) (xy 124.654654 -250.841595)
			(xy 124.678695 -250.797172) (xy 124.709719 -250.757312) (xy 124.746881 -250.723102) (xy 124.789167 -250.695476)
			(xy 124.835423 -250.675186) (xy 124.884388 -250.662786) (xy 124.934726 -250.658615) (xy 124.985064 -250.662786)
			(xy 125.034029 -250.675186) (xy 125.080285 -250.695476) (xy 125.122571 -250.723102) (xy 125.159733 -250.757312)
			(xy 125.190757 -250.797172) (xy 125.214798 -250.841595) (xy 125.231199 -250.889369) (xy 125.239512 -250.939191)
			(xy 125.240034 -250.964446) (xy 125.239452 -250.99131) (xy 125.230006 -251.044203) (xy 125.221238 -251.069602)
			(xy 125.21692 -251.081286) (xy 125.220222 -251.105924) (xy 125.275086 -251.184664) (xy 125.28271 -251.194291)
			(xy 125.30448 -251.205565) (xy 125.316742 -251.206254) (xy 125.492764 -251.206254) (xy 125.505017 -251.205537)
			(xy 125.52678 -251.194269) (xy 125.53442 -251.184664) (xy 125.589284 -251.105924) (xy 125.592586 -251.081286)
			(xy 125.588268 -251.069602) (xy 125.579522 -251.044196) (xy 125.570065 -250.991308) (xy 125.569472 -250.964446)
			(xy 125.569915 -250.94045) (xy 125.577416 -250.893048) (xy 125.59224 -250.847403) (xy 125.614022 -250.804639)
			(xy 125.642227 -250.765809) (xy 125.676159 -250.73187) (xy 125.714982 -250.703657) (xy 125.757742 -250.681865)
			(xy 125.803383 -250.667031) (xy 125.850784 -250.65952) (xy 125.87478 -250.659138) (xy 125.887543 -250.659278)
			(xy 125.912976 -250.661444) (xy 125.92558 -250.663456) (xy 125.92558 -250.663202) (xy 125.950442 -250.667894)
			(xy 125.998264 -250.684404) (xy 126.042714 -250.708566) (xy 126.082576 -250.73972) (xy 126.116763 -250.777014)
			(xy 126.14434 -250.81943) (xy 126.164553 -250.865809) (xy 126.176852 -250.914883) (xy 126.179326 -250.940062)
			(xy 126.179326 -250.940824) (xy 126.180449 -250.950515) (xy 126.188961 -250.968052) (xy 126.20338 -250.981168)
			(xy 126.212346 -250.98502) (xy 126.298706 -251.017024) (xy 126.307941 -251.020031) (xy 126.327342 -251.019589)
			(xy 126.345176 -251.011939) (xy 126.3523 -251.00534) (xy 126.553722 -250.803918) (xy 126.560326 -250.796044)
			(xy 126.576836 -250.773184) (xy 126.57709 -250.77293) (xy 126.580646 -250.768358) (xy 126.58598 -250.762008)
			(xy 126.595378 -250.73737) (xy 126.596919 -250.733022) (xy 126.598576 -250.723948) (xy 126.59868 -250.719336)
			(xy 126.59868 -250.531884) (xy 126.598026 -250.519382) (xy 126.586298 -250.497295) (xy 126.576328 -250.48972)
			(xy 126.49581 -250.435364) (xy 126.470918 -250.432824) (xy 126.45898 -250.43765) (xy 126.431544 -250.447983)
			(xy 126.373991 -250.45912) (xy 126.34468 -250.459748) (xy 126.319422 -250.459225) (xy 126.269597 -250.450907)
			(xy 126.22182 -250.434503) (xy 126.177394 -250.410458) (xy 126.137531 -250.379429) (xy 126.10332 -250.342263)
			(xy 126.075691 -250.299973) (xy 126.055401 -250.253712) (xy 126.043 -250.204743) (xy 126.038829 -250.1544)
			(xy 126.043 -250.104057) (xy 126.055401 -250.055088) (xy 126.075691 -250.008827) (xy 126.10332 -249.966537)
			(xy 126.137531 -249.929371) (xy 126.177394 -249.898342) (xy 126.221819 -249.874297) (xy 126.269597 -249.857893)
			(xy 126.319422 -249.849575) (xy 126.34468 -249.849132) (xy 126.373989 -249.849778) (xy 126.43154 -249.86091)
			(xy 126.45898 -249.87123) (xy 126.470918 -249.876056) (xy 126.49581 -249.873516) (xy 126.576328 -249.81916)
			(xy 126.586348 -249.811632) (xy 126.598068 -249.789514) (xy 126.59868 -249.776996) (xy 126.59868 -249.589544)
			(xy 126.598575 -249.584933) (xy 126.596907 -249.575862) (xy 126.595378 -249.57151) (xy 126.58598 -249.546872)
			(xy 126.580646 -249.540268) (xy 126.565832 -249.521847) (xy 126.541475 -249.481336) (xy 126.523649 -249.437557)
			(xy 126.512778 -249.391554) (xy 126.509123 -249.344426) (xy 126.51277 -249.297298) (xy 126.523633 -249.251293)
			(xy 126.541452 -249.207511) (xy 126.565802 -249.166996) (xy 126.580646 -249.1486) (xy 126.58598 -249.141996)
			(xy 126.595378 -249.117358) (xy 126.596918 -249.11301) (xy 126.598573 -249.103936) (xy 126.59868 -249.099324)
			(xy 126.59868 -247.969532) (xy 126.598574 -247.964921) (xy 126.596904 -247.955851) (xy 126.595378 -247.951498)
			(xy 126.58598 -247.92686) (xy 126.580646 -247.920256) (xy 126.565833 -247.901835) (xy 126.541478 -247.861324)
			(xy 126.523653 -247.817545) (xy 126.512785 -247.771544) (xy 126.509131 -247.724417) (xy 126.512779 -247.67729)
			(xy 126.523643 -247.631287) (xy 126.541463 -247.587506) (xy 126.565813 -247.546993) (xy 126.580646 -247.528588)
			(xy 126.58598 -247.521984) (xy 126.595378 -247.497346) (xy 126.596917 -247.492998) (xy 126.59857 -247.483924)
			(xy 126.59868 -247.479312) (xy 126.59868 -247.29186) (xy 126.598043 -247.279348) (xy 126.586333 -247.257233)
			(xy 126.576328 -247.249696) (xy 126.49581 -247.19534) (xy 126.470918 -247.1928) (xy 126.45898 -247.197626)
			(xy 126.431543 -247.207957) (xy 126.37399 -247.219091) (xy 126.34468 -247.219724) (xy 126.319424 -247.219201)
			(xy 126.269603 -247.210884) (xy 126.221829 -247.194481) (xy 126.177407 -247.170438) (xy 126.137548 -247.139412)
			(xy 126.103339 -247.102248) (xy 126.075713 -247.059962) (xy 126.055423 -247.013704) (xy 126.043024 -246.964739)
			(xy 126.038853 -246.9144) (xy 126.043024 -246.864061) (xy 126.055423 -246.815096) (xy 126.075713 -246.768838)
			(xy 126.103339 -246.726552) (xy 126.137548 -246.689388) (xy 126.177407 -246.658362) (xy 126.221829 -246.634319)
			(xy 126.269603 -246.617916) (xy 126.319424 -246.609599) (xy 126.34468 -246.609108) (xy 126.373989 -246.609754)
			(xy 126.43154 -246.620885) (xy 126.45898 -246.631206) (xy 126.470918 -246.636032) (xy 126.49581 -246.633492)
			(xy 126.576328 -246.579136) (xy 126.586344 -246.571606) (xy 126.598054 -246.549488) (xy 126.59868 -246.536972)
			(xy 126.59868 -246.34952) (xy 126.598582 -246.344907) (xy 126.596927 -246.335832) (xy 126.595378 -246.331486)
			(xy 126.58598 -246.306848) (xy 126.580646 -246.300244) (xy 126.565834 -246.281823) (xy 126.541481 -246.241312)
			(xy 126.523658 -246.197534) (xy 126.512791 -246.151533) (xy 126.509138 -246.104408) (xy 126.512788 -246.057282)
			(xy 126.523653 -246.01128) (xy 126.541474 -245.967501) (xy 126.565825 -245.92699) (xy 126.580646 -245.908576)
			(xy 126.58598 -245.901972) (xy 126.595378 -245.877334) (xy 126.596924 -245.872987) (xy 126.598593 -245.863913)
			(xy 126.59868 -245.8593) (xy 126.59868 -244.729508) (xy 126.598581 -244.724896) (xy 126.596924 -244.715821)
			(xy 126.595378 -244.711474) (xy 126.58598 -244.686836) (xy 126.580646 -244.680232) (xy 126.564041 -244.659453)
			(xy 126.53752 -244.613352) (xy 126.51936 -244.563364) (xy 126.510106 -244.51099) (xy 126.509526 -244.484398)
			(xy 126.510046 -244.459432) (xy 126.518208 -244.41017) (xy 126.534265 -244.362888) (xy 126.545594 -244.340634)
			(xy 126.553468 -244.325902) (xy 126.548388 -244.292628) (xy 126.252986 -243.997226) (xy 126.245874 -243.98986)
			(xy 126.227078 -243.98224) (xy 116.121688 -243.98224) (xy 116.116734 -243.98212) (xy 116.107013 -243.980201)
			(xy 116.102384 -243.97843) (xy 116.096796 -243.976144) (xy 116.089871 -243.973534) (xy 116.075158 -243.971987)
			(xy 116.06784 -243.973096) (xy 116.061744 -243.974366) (xy 116.047654 -243.976872) (xy 116.019158 -243.97954)
			(xy 116.004848 -243.9797) (xy 116.002816 -243.9797) (xy 115.979028 -243.97909) (xy 115.932072 -243.971403)
			(xy 115.886876 -243.956525) (xy 115.844535 -243.934814) (xy 115.806076 -243.906798) (xy 115.772428 -243.873155)
			(xy 115.744407 -243.834699) (xy 115.722691 -243.792362) (xy 115.707806 -243.747168) (xy 115.700113 -243.700212)
			(xy 115.69954 -243.676424) (xy 115.69954 -243.674392) (xy 115.699716 -243.660146) (xy 115.702385 -243.631778)
			(xy 115.704874 -243.61775) (xy 115.70716 -243.605304) (xy 115.703604 -243.593366) (xy 115.70158 -243.587481)
			(xy 115.69516 -243.576824) (xy 115.690904 -243.572284) (xy 114.751358 -242.632738) (xy 114.744796 -242.626609)
			(xy 114.728526 -242.619043) (xy 114.719608 -242.618006) (xy 114.703565 -242.616518) (xy 114.671668 -242.611946)
			(xy 114.655854 -242.608862) (xy 114.617246 -242.599718) (xy 114.610642 -242.59794) (xy 114.578892 -242.59794)
			(xy 114.572288 -242.599718) (xy 114.535607 -242.609137) (xy 114.460548 -242.619207) (xy 114.422682 -242.619784)
			(xy 114.12474 -242.619784) (xy 114.086876 -242.619168) (xy 114.01182 -242.609107) (xy 113.975134 -242.599718)
			(xy 113.96853 -242.59794) (xy 113.155222 -242.59794) (xy 113.145159 -242.597501) (xy 113.126581 -242.58976)
			(xy 113.119154 -242.582954) (xy 111.053626 -240.517426) (xy 111.046788 -240.510025) (xy 111.039077 -240.491426)
			(xy 111.03864 -240.481358) (xy 111.03864 -213.274402) (xy 111.039064 -213.264333) (xy 111.046782 -213.245731)
			(xy 111.053626 -213.238334) (xy 122.159014 -202.132946) (xy 122.159522 -202.132438) (xy 122.166106 -202.125058)
			(xy 122.173558 -202.106758) (xy 122.174 -202.096878) (xy 122.174 -190.272162) (xy 122.17357 -190.262095)
			(xy 122.165846 -190.243501) (xy 122.159014 -190.236094) (xy 121.633996 -189.711076) (xy 121.626884 -189.70371)
			(xy 121.608088 -189.69609) (xy 114.497612 -189.69609) (xy 114.487541 -189.695669) (xy 114.468934 -189.687956)
			(xy 114.461544 -189.681104) (xy 114.435382 -189.654942) (xy 114.42827 -189.647576) (xy 114.409474 -189.639956)
			(xy 105.532174 -189.639956) (xy 105.522107 -189.640385) (xy 105.503515 -189.648113) (xy 105.496106 -189.654942)
			(xy 104.386634 -190.764414) (xy 104.379236 -190.771259) (xy 104.360637 -190.778983) (xy 104.350566 -190.7794)
			(xy 78.187296 -190.7794) (xy 78.177226 -190.778976) (xy 78.158623 -190.771261) (xy 78.151228 -190.764414)
			(xy 71.464424 -184.07761) (xy 71.45782 -184.072022) (xy 71.457566 -184.072022) (xy 71.45044 -184.067341)
			(xy 71.434078 -184.062586) (xy 71.417064 -184.063515) (xy 71.409052 -184.066434) (xy 71.322438 -184.102248)
			(xy 71.31338 -184.10649) (xy 71.299199 -184.120566) (xy 71.29148 -184.138996) (xy 71.290942 -184.148984)
			(xy 71.290321 -184.176144) (xy 71.282337 -184.229878) (xy 71.266811 -184.281937) (xy 71.244058 -184.331268)
			(xy 71.214538 -184.376872) (xy 71.178848 -184.417829) (xy 71.13771 -184.453309) (xy 71.091955 -184.482595)
			(xy 71.042509 -184.505096) (xy 70.990371 -184.520355) (xy 70.936596 -184.528065) (xy 70.909434 -184.52846)
			(xy 70.882181 -184.527999) (xy 70.828229 -184.520246) (xy 70.77593 -184.504892) (xy 70.726348 -184.482251)
			(xy 70.680494 -184.452783) (xy 70.639301 -184.417089) (xy 70.603609 -184.375895) (xy 70.574142 -184.330039)
			(xy 70.551503 -184.280457) (xy 70.536151 -184.228158) (xy 70.5284 -184.174205) (xy 70.527926 -184.146952)
			(xy 70.528276 -184.123858) (xy 70.533876 -184.07801) (xy 70.539102 -184.055512) (xy 70.54215 -184.043066)
			(xy 70.536054 -184.018682) (xy 70.47103 -183.9468) (xy 70.462195 -183.937976) (xy 70.438761 -183.929433)
			(xy 70.426326 -183.930544) (xy 70.425564 -183.930544) (xy 70.412867 -183.932247) (xy 70.387319 -183.934153)
			(xy 70.37451 -183.934354) (xy 70.370446 -183.934354) (xy 70.343269 -183.933762) (xy 70.289492 -183.925826)
			(xy 70.237387 -183.910336) (xy 70.188008 -183.887606) (xy 70.142356 -183.858097) (xy 70.101356 -183.822405)
			(xy 70.065838 -183.781255) (xy 70.036521 -183.735479) (xy 70.014 -183.686005) (xy 69.99873 -183.633835)
			(xy 69.99102 -183.580026) (xy 69.990462 -183.552846) (xy 69.990965 -183.525086) (xy 69.99902 -183.470154)
			(xy 70.014951 -183.416969) (xy 70.038423 -183.366654) (xy 70.068939 -183.320273) (xy 70.105856 -183.278805)
			(xy 70.148392 -183.243125) (xy 70.195651 -183.213987) (xy 70.246635 -183.192006) (xy 70.300265 -183.177646)
			(xy 70.327774 -183.173878) (xy 70.342506 -183.1721) (xy 70.365112 -183.154066) (xy 70.39991 -183.053736)
			(xy 70.402675 -183.044631) (xy 70.401968 -183.025629) (xy 70.394382 -183.008192) (xy 70.387972 -183.001158)
			(xy 67.747134 -180.36032) (xy 67.740022 -180.352954) (xy 67.721226 -180.345334) (xy 62.487302 -180.345334)
			(xy 62.477232 -180.345757) (xy 62.45863 -180.353475) (xy 62.451234 -180.36032) (xy 61.996066 -180.815488)
			(xy 61.9887 -180.8226) (xy 61.98108 -180.841396) (xy 61.98108 -190.677038) (xy 61.981543 -190.686914)
			(xy 61.988989 -190.705209) (xy 61.995558 -190.712598) (xy 61.995812 -190.712852) (xy 67.183254 -195.900294)
			(xy 67.190106 -195.90769) (xy 67.19785 -195.926288) (xy 67.19824 -195.936362) (xy 67.19824 -198.838058)
			(xy 67.198706 -198.847933) (xy 67.206153 -198.866227) (xy 67.212718 -198.873618) (xy 67.212972 -198.873872)
			(xy 67.284092 -198.944992) (xy 67.815206 -198.944992) (xy 67.815694 -198.913616) (xy 67.823405 -198.851339)
			(xy 67.838722 -198.790484) (xy 67.86141 -198.731976) (xy 67.891126 -198.676706) (xy 67.927418 -198.625512)
			(xy 67.969733 -198.579173) (xy 68.01743 -198.538394) (xy 68.069782 -198.503795) (xy 68.125994 -198.4759)
			(xy 68.185212 -198.455135) (xy 68.246534 -198.441816) (xy 68.27774 -198.438516) (xy 68.288154 -198.4375)
			(xy 68.305934 -198.428102) (xy 68.365116 -198.355712) (xy 68.370704 -198.336408) (xy 68.369434 -198.325994)
			(xy 68.367984 -198.311879) (xy 68.366457 -198.283541) (xy 68.366386 -198.269352) (xy 68.366888 -198.237391)
			(xy 68.374899 -198.173973) (xy 68.390796 -198.112059) (xy 68.414328 -198.052626) (xy 68.445122 -197.996611)
			(xy 68.482695 -197.944896) (xy 68.526452 -197.898299) (xy 68.575705 -197.857554) (xy 68.629676 -197.823303)
			(xy 68.687515 -197.796086) (xy 68.748308 -197.776333) (xy 68.811098 -197.764355) (xy 68.874894 -197.760342)
			(xy 68.93869 -197.764355) (xy 69.00148 -197.776333) (xy 69.062273 -197.796086) (xy 69.120112 -197.823303)
			(xy 69.174083 -197.857554) (xy 69.223336 -197.898299) (xy 69.267093 -197.944896) (xy 69.304666 -197.996611)
			(xy 69.33546 -198.052626) (xy 69.358992 -198.112059) (xy 69.374889 -198.173973) (xy 69.3829 -198.237391)
			(xy 69.383402 -198.269352) (xy 69.382947 -198.300729) (xy 69.375231 -198.363007) (xy 69.35991 -198.423862)
			(xy 69.337218 -198.482369) (xy 69.307498 -198.53764) (xy 69.271203 -198.588833) (xy 69.228885 -198.635171)
			(xy 69.181186 -198.67595) (xy 69.128832 -198.710549) (xy 69.072618 -198.738443) (xy 69.013399 -198.759208)
			(xy 68.952074 -198.772528) (xy 68.920868 -198.775828) (xy 68.910454 -198.776844) (xy 68.892674 -198.786242)
			(xy 68.833492 -198.858632) (xy 68.827904 -198.877936) (xy 68.829174 -198.88835) (xy 68.830952 -198.90867)
			(xy 68.831714 -198.918068) (xy 68.83908 -198.934578) (xy 68.900294 -198.994776) (xy 68.916804 -199.002142)
			(xy 68.926202 -199.00265) (xy 68.95695 -199.00494) (xy 69.017608 -199.016005) (xy 69.076483 -199.034324)
			(xy 69.132711 -199.059626) (xy 69.185467 -199.091542) (xy 69.233977 -199.129603) (xy 69.277529 -199.173249)
			(xy 69.315484 -199.221842) (xy 69.347286 -199.274667) (xy 69.360288 -199.302624) (xy 69.364352 -199.311514)
			(xy 69.378068 -199.324976) (xy 69.460364 -199.359266) (xy 69.479668 -199.35952) (xy 69.488812 -199.356218)
			(xy 69.517481 -199.345901) (xy 69.576668 -199.331429) (xy 69.637162 -199.324149) (xy 69.667628 -199.323706)
			(xy 69.699589 -199.324182) (xy 69.763006 -199.332196) (xy 69.824919 -199.348096) (xy 69.88435 -199.371629)
			(xy 69.940364 -199.402426) (xy 69.992077 -199.44) (xy 70.038672 -199.483759) (xy 70.079416 -199.533012)
			(xy 70.113666 -199.586983) (xy 70.140881 -199.644822) (xy 70.160634 -199.705615) (xy 70.172611 -199.768405)
			(xy 70.176625 -199.8322) (xy 70.172611 -199.895995) (xy 70.160634 -199.958785) (xy 70.140881 -200.019578)
			(xy 70.113666 -200.077417) (xy 70.079416 -200.131388) (xy 70.038672 -200.180641) (xy 69.992077 -200.2244)
			(xy 69.940364 -200.261974) (xy 69.88435 -200.292771) (xy 69.824919 -200.316304) (xy 69.763006 -200.332204)
			(xy 69.699589 -200.340218) (xy 69.667628 -200.340722) (xy 69.635136 -200.340226) (xy 69.570683 -200.331927)
			(xy 69.507812 -200.315487) (xy 69.447548 -200.291173) (xy 69.390871 -200.259381) (xy 69.338704 -200.220629)
			(xy 69.291899 -200.175549) (xy 69.251216 -200.124874) (xy 69.217319 -200.069431) (xy 69.20357 -200.039986)
			(xy 69.199506 -200.031096) (xy 69.18579 -200.017634) (xy 69.103494 -199.983344) (xy 69.08419 -199.98309)
			(xy 69.075046 -199.986392) (xy 69.046372 -199.996694) (xy 68.987187 -200.011171) (xy 68.926695 -200.018458)
			(xy 68.89623 -200.018904) (xy 68.864451 -200.018418) (xy 68.801388 -200.010501) (xy 68.739803 -199.994786)
			(xy 68.680656 -199.97152) (xy 68.624871 -199.941063) (xy 68.573315 -199.903892) (xy 68.526794 -199.860585)
			(xy 68.486033 -199.811819) (xy 68.451667 -199.758353) (xy 68.424232 -199.701021) (xy 68.404156 -199.640717)
			(xy 68.391751 -199.578381) (xy 68.388992 -199.546718) (xy 68.38823 -199.53732) (xy 68.380864 -199.52081)
			(xy 68.31965 -199.460612) (xy 68.30314 -199.453246) (xy 68.293742 -199.452738) (xy 68.261772 -199.450425)
			(xy 68.198767 -199.438625) (xy 68.137744 -199.419003) (xy 68.07967 -199.391867) (xy 68.025466 -199.35765)
			(xy 67.975991 -199.316893) (xy 67.93203 -199.270242) (xy 67.894279 -199.218436) (xy 67.863338 -199.162298)
			(xy 67.839695 -199.102717) (xy 67.823727 -199.040637) (xy 67.815686 -198.977042) (xy 67.815206 -198.944992)
			(xy 67.284092 -198.944992) (xy 70.235318 -201.896218) (xy 71.201534 -201.896218) (xy 71.201955 -201.865485)
			(xy 71.209362 -201.804466) (xy 71.224071 -201.744785) (xy 71.245867 -201.687313) (xy 71.274432 -201.632887)
			(xy 71.309349 -201.582301) (xy 71.35011 -201.536293) (xy 71.39612 -201.495535) (xy 71.446707 -201.460619)
			(xy 71.501135 -201.432057) (xy 71.558608 -201.410264) (xy 71.61829 -201.395558) (xy 71.679309 -201.388153)
			(xy 71.710042 -201.38771) (xy 71.74174 -201.388232) (xy 71.804641 -201.396129) (xy 71.866074 -201.411783)
			(xy 71.925084 -201.434952) (xy 71.980757 -201.465275) (xy 72.03223 -201.502282) (xy 72.078704 -201.545401)
			(xy 72.119458 -201.593961) (xy 72.15386 -201.64721) (xy 72.181377 -201.704322) (xy 72.201583 -201.764411)
			(xy 72.214163 -201.826546) (xy 72.217026 -201.858118) (xy 72.218417 -201.868883) (xy 72.228879 -201.887879)
			(xy 72.24619 -201.900941) (xy 72.25665 -201.903838) (xy 72.28698 -201.911152) (xy 72.34571 -201.932207)
			(xy 72.401423 -201.960289) (xy 72.453282 -201.994978) (xy 72.500507 -202.03575) (xy 72.542389 -202.081994)
			(xy 72.578298 -202.133015) (xy 72.607695 -202.188046) (xy 72.630138 -202.24626) (xy 72.645291 -202.306783)
			(xy 72.652924 -202.368705) (xy 72.653398 -202.3999) (xy 72.653031 -202.427104) (xy 72.647173 -202.481197)
			(xy 72.641714 -202.50785) (xy 72.639981 -202.5192) (xy 72.645353 -202.541488) (xy 72.659815 -202.559276)
			(xy 72.669908 -202.564746) (xy 72.698806 -202.578704) (xy 72.753136 -202.612864) (xy 72.802736 -202.65359)
			(xy 72.846816 -202.700233) (xy 72.884677 -202.752054) (xy 72.915715 -202.808226) (xy 72.939437 -202.867858)
			(xy 72.955466 -202.930001) (xy 72.963548 -202.993667) (xy 72.96404 -203.025756) (xy 72.963538 -203.057717)
			(xy 72.955527 -203.121135) (xy 72.93963 -203.183049) (xy 72.916098 -203.242482) (xy 72.885304 -203.298497)
			(xy 72.847731 -203.350212) (xy 72.803974 -203.396809) (xy 72.754721 -203.437554) (xy 72.70075 -203.471805)
			(xy 72.642911 -203.499022) (xy 72.582118 -203.518775) (xy 72.519328 -203.530753) (xy 72.455532 -203.534767)
			(xy 72.391736 -203.530753) (xy 72.328946 -203.518775) (xy 72.268153 -203.499022) (xy 72.210314 -203.471805)
			(xy 72.156343 -203.437554) (xy 72.10709 -203.396809) (xy 72.063333 -203.350212) (xy 72.02576 -203.298497)
			(xy 71.994966 -203.242482) (xy 71.971434 -203.183049) (xy 71.955537 -203.121135) (xy 71.947526 -203.057717)
			(xy 71.947024 -203.025756) (xy 71.947401 -202.998552) (xy 71.953252 -202.94446) (xy 71.958708 -202.917806)
			(xy 71.960468 -202.906459) (xy 71.955081 -202.884169) (xy 71.94061 -202.86638) (xy 71.930514 -202.86091)
			(xy 71.900176 -202.8462) (xy 71.843333 -202.809938) (xy 71.791782 -202.766481) (xy 71.746428 -202.716591)
			(xy 71.708065 -202.661145) (xy 71.677368 -202.601114) (xy 71.654874 -202.537553) (xy 71.640979 -202.471576)
			(xy 71.637906 -202.438) (xy 71.636551 -202.427226) (xy 71.62608 -202.408224) (xy 71.60875 -202.395168)
			(xy 71.598282 -202.39228) (xy 71.567962 -202.384927) (xy 71.509233 -202.363877) (xy 71.45352 -202.335799)
			(xy 71.401661 -202.301115) (xy 71.354435 -202.260347) (xy 71.312553 -202.214107) (xy 71.276642 -202.16309)
			(xy 71.247244 -202.108062) (xy 71.224799 -202.049851) (xy 71.209645 -201.989331) (xy 71.202009 -201.927412)
			(xy 71.201534 -201.896218) (xy 70.235318 -201.896218) (xy 72.47763 -204.13853) (xy 72.482059 -204.143313)
			(xy 88.816428 -204.143313) (xy 88.816428 -204.079391) (xy 88.824439 -204.015973) (xy 88.840336 -203.954059)
			(xy 88.863868 -203.894626) (xy 88.894662 -203.838611) (xy 88.932235 -203.786896) (xy 88.975992 -203.740299)
			(xy 89.025245 -203.699554) (xy 89.079216 -203.665303) (xy 89.137055 -203.638086) (xy 89.197848 -203.618333)
			(xy 89.260638 -203.606355) (xy 89.324434 -203.602342) (xy 89.38823 -203.606355) (xy 89.45102 -203.618333)
			(xy 89.511813 -203.638086) (xy 89.569652 -203.665303) (xy 89.623623 -203.699554) (xy 89.672876 -203.740299)
			(xy 89.716633 -203.786896) (xy 89.754206 -203.838611) (xy 89.785 -203.894626) (xy 89.808532 -203.954059)
			(xy 89.824429 -204.015973) (xy 89.83244 -204.079391) (xy 89.832942 -204.111352) (xy 89.83244 -204.143313)
			(xy 90.086428 -204.143313) (xy 90.086428 -204.079391) (xy 90.094439 -204.015973) (xy 90.110336 -203.954059)
			(xy 90.133868 -203.894626) (xy 90.164662 -203.838611) (xy 90.202235 -203.786896) (xy 90.245992 -203.740299)
			(xy 90.295245 -203.699554) (xy 90.349216 -203.665303) (xy 90.407055 -203.638086) (xy 90.467848 -203.618333)
			(xy 90.530638 -203.606355) (xy 90.594434 -203.602342) (xy 90.65823 -203.606355) (xy 90.72102 -203.618333)
			(xy 90.781813 -203.638086) (xy 90.839652 -203.665303) (xy 90.893623 -203.699554) (xy 90.942876 -203.740299)
			(xy 90.986633 -203.786896) (xy 91.024206 -203.838611) (xy 91.055 -203.894626) (xy 91.078532 -203.954059)
			(xy 91.094429 -204.015973) (xy 91.10244 -204.079391) (xy 91.102942 -204.111352) (xy 91.10244 -204.143313)
			(xy 91.356428 -204.143313) (xy 91.356428 -204.079391) (xy 91.364439 -204.015973) (xy 91.380336 -203.954059)
			(xy 91.403868 -203.894626) (xy 91.434662 -203.838611) (xy 91.472235 -203.786896) (xy 91.515992 -203.740299)
			(xy 91.565245 -203.699554) (xy 91.619216 -203.665303) (xy 91.677055 -203.638086) (xy 91.737848 -203.618333)
			(xy 91.800638 -203.606355) (xy 91.864434 -203.602342) (xy 91.92823 -203.606355) (xy 91.99102 -203.618333)
			(xy 92.051813 -203.638086) (xy 92.109652 -203.665303) (xy 92.163623 -203.699554) (xy 92.212876 -203.740299)
			(xy 92.256633 -203.786896) (xy 92.294206 -203.838611) (xy 92.325 -203.894626) (xy 92.348532 -203.954059)
			(xy 92.364429 -204.015973) (xy 92.37244 -204.079391) (xy 92.372942 -204.111352) (xy 92.37244 -204.143313)
			(xy 92.626428 -204.143313) (xy 92.626428 -204.079391) (xy 92.634439 -204.015973) (xy 92.650336 -203.954059)
			(xy 92.673868 -203.894626) (xy 92.704662 -203.838611) (xy 92.742235 -203.786896) (xy 92.785992 -203.740299)
			(xy 92.835245 -203.699554) (xy 92.889216 -203.665303) (xy 92.947055 -203.638086) (xy 93.007848 -203.618333)
			(xy 93.070638 -203.606355) (xy 93.134434 -203.602342) (xy 93.19823 -203.606355) (xy 93.26102 -203.618333)
			(xy 93.321813 -203.638086) (xy 93.379652 -203.665303) (xy 93.433623 -203.699554) (xy 93.482876 -203.740299)
			(xy 93.526633 -203.786896) (xy 93.564206 -203.838611) (xy 93.595 -203.894626) (xy 93.618532 -203.954059)
			(xy 93.634429 -204.015973) (xy 93.64244 -204.079391) (xy 93.642942 -204.111352) (xy 93.64244 -204.143313)
			(xy 93.896428 -204.143313) (xy 93.896428 -204.079391) (xy 93.904439 -204.015973) (xy 93.920336 -203.954059)
			(xy 93.943868 -203.894626) (xy 93.974662 -203.838611) (xy 94.012235 -203.786896) (xy 94.055992 -203.740299)
			(xy 94.105245 -203.699554) (xy 94.159216 -203.665303) (xy 94.217055 -203.638086) (xy 94.277848 -203.618333)
			(xy 94.340638 -203.606355) (xy 94.404434 -203.602342) (xy 94.46823 -203.606355) (xy 94.53102 -203.618333)
			(xy 94.591813 -203.638086) (xy 94.649652 -203.665303) (xy 94.703623 -203.699554) (xy 94.752876 -203.740299)
			(xy 94.796633 -203.786896) (xy 94.834206 -203.838611) (xy 94.865 -203.894626) (xy 94.888532 -203.954059)
			(xy 94.904429 -204.015973) (xy 94.91244 -204.079391) (xy 94.912942 -204.111352) (xy 94.91244 -204.143313)
			(xy 95.166428 -204.143313) (xy 95.166428 -204.079391) (xy 95.174439 -204.015973) (xy 95.190336 -203.954059)
			(xy 95.213868 -203.894626) (xy 95.244662 -203.838611) (xy 95.282235 -203.786896) (xy 95.325992 -203.740299)
			(xy 95.375245 -203.699554) (xy 95.429216 -203.665303) (xy 95.487055 -203.638086) (xy 95.547848 -203.618333)
			(xy 95.610638 -203.606355) (xy 95.674434 -203.602342) (xy 95.73823 -203.606355) (xy 95.80102 -203.618333)
			(xy 95.861813 -203.638086) (xy 95.919652 -203.665303) (xy 95.973623 -203.699554) (xy 96.022876 -203.740299)
			(xy 96.066633 -203.786896) (xy 96.104206 -203.838611) (xy 96.135 -203.894626) (xy 96.158532 -203.954059)
			(xy 96.174429 -204.015973) (xy 96.18244 -204.079391) (xy 96.182942 -204.111352) (xy 96.18244 -204.143313)
			(xy 96.174429 -204.206731) (xy 96.158532 -204.268645) (xy 96.135 -204.328078) (xy 96.104206 -204.384093)
			(xy 96.066633 -204.435808) (xy 96.022876 -204.482405) (xy 95.973623 -204.52315) (xy 95.919652 -204.557401)
			(xy 95.861813 -204.584618) (xy 95.80102 -204.604371) (xy 95.73823 -204.616349) (xy 95.674434 -204.620363)
			(xy 95.610638 -204.616349) (xy 95.547848 -204.604371) (xy 95.487055 -204.584618) (xy 95.429216 -204.557401)
			(xy 95.375245 -204.52315) (xy 95.325992 -204.482405) (xy 95.282235 -204.435808) (xy 95.244662 -204.384093)
			(xy 95.213868 -204.328078) (xy 95.190336 -204.268645) (xy 95.174439 -204.206731) (xy 95.166428 -204.143313)
			(xy 94.91244 -204.143313) (xy 94.904429 -204.206731) (xy 94.888532 -204.268645) (xy 94.865 -204.328078)
			(xy 94.834206 -204.384093) (xy 94.796633 -204.435808) (xy 94.752876 -204.482405) (xy 94.703623 -204.52315)
			(xy 94.649652 -204.557401) (xy 94.591813 -204.584618) (xy 94.53102 -204.604371) (xy 94.46823 -204.616349)
			(xy 94.404434 -204.620363) (xy 94.340638 -204.616349) (xy 94.277848 -204.604371) (xy 94.217055 -204.584618)
			(xy 94.159216 -204.557401) (xy 94.105245 -204.52315) (xy 94.055992 -204.482405) (xy 94.012235 -204.435808)
			(xy 93.974662 -204.384093) (xy 93.943868 -204.328078) (xy 93.920336 -204.268645) (xy 93.904439 -204.206731)
			(xy 93.896428 -204.143313) (xy 93.64244 -204.143313) (xy 93.634429 -204.206731) (xy 93.618532 -204.268645)
			(xy 93.595 -204.328078) (xy 93.564206 -204.384093) (xy 93.526633 -204.435808) (xy 93.482876 -204.482405)
			(xy 93.433623 -204.52315) (xy 93.379652 -204.557401) (xy 93.321813 -204.584618) (xy 93.26102 -204.604371)
			(xy 93.19823 -204.616349) (xy 93.134434 -204.620363) (xy 93.070638 -204.616349) (xy 93.007848 -204.604371)
			(xy 92.947055 -204.584618) (xy 92.889216 -204.557401) (xy 92.835245 -204.52315) (xy 92.785992 -204.482405)
			(xy 92.742235 -204.435808) (xy 92.704662 -204.384093) (xy 92.673868 -204.328078) (xy 92.650336 -204.268645)
			(xy 92.634439 -204.206731) (xy 92.626428 -204.143313) (xy 92.37244 -204.143313) (xy 92.364429 -204.206731)
			(xy 92.348532 -204.268645) (xy 92.325 -204.328078) (xy 92.294206 -204.384093) (xy 92.256633 -204.435808)
			(xy 92.212876 -204.482405) (xy 92.163623 -204.52315) (xy 92.109652 -204.557401) (xy 92.051813 -204.584618)
			(xy 91.99102 -204.604371) (xy 91.92823 -204.616349) (xy 91.864434 -204.620363) (xy 91.800638 -204.616349)
			(xy 91.737848 -204.604371) (xy 91.677055 -204.584618) (xy 91.619216 -204.557401) (xy 91.565245 -204.52315)
			(xy 91.515992 -204.482405) (xy 91.472235 -204.435808) (xy 91.434662 -204.384093) (xy 91.403868 -204.328078)
			(xy 91.380336 -204.268645) (xy 91.364439 -204.206731) (xy 91.356428 -204.143313) (xy 91.10244 -204.143313)
			(xy 91.094429 -204.206731) (xy 91.078532 -204.268645) (xy 91.055 -204.328078) (xy 91.024206 -204.384093)
			(xy 90.986633 -204.435808) (xy 90.942876 -204.482405) (xy 90.893623 -204.52315) (xy 90.839652 -204.557401)
			(xy 90.781813 -204.584618) (xy 90.72102 -204.604371) (xy 90.65823 -204.616349) (xy 90.594434 -204.620363)
			(xy 90.530638 -204.616349) (xy 90.467848 -204.604371) (xy 90.407055 -204.584618) (xy 90.349216 -204.557401)
			(xy 90.295245 -204.52315) (xy 90.245992 -204.482405) (xy 90.202235 -204.435808) (xy 90.164662 -204.384093)
			(xy 90.133868 -204.328078) (xy 90.110336 -204.268645) (xy 90.094439 -204.206731) (xy 90.086428 -204.143313)
			(xy 89.83244 -204.143313) (xy 89.824429 -204.206731) (xy 89.808532 -204.268645) (xy 89.785 -204.328078)
			(xy 89.754206 -204.384093) (xy 89.716633 -204.435808) (xy 89.672876 -204.482405) (xy 89.623623 -204.52315)
			(xy 89.569652 -204.557401) (xy 89.511813 -204.584618) (xy 89.45102 -204.604371) (xy 89.38823 -204.616349)
			(xy 89.324434 -204.620363) (xy 89.260638 -204.616349) (xy 89.197848 -204.604371) (xy 89.137055 -204.584618)
			(xy 89.079216 -204.557401) (xy 89.025245 -204.52315) (xy 88.975992 -204.482405) (xy 88.932235 -204.435808)
			(xy 88.894662 -204.384093) (xy 88.863868 -204.328078) (xy 88.840336 -204.268645) (xy 88.824439 -204.206731)
			(xy 88.816428 -204.143313) (xy 72.482059 -204.143313) (xy 72.484479 -204.145927) (xy 72.492214 -204.164526)
			(xy 72.492616 -204.174598) (xy 72.492616 -205.701138) (xy 72.493021 -205.710656) (xy 72.499948 -205.728388)
			(xy 72.506078 -205.735682) (xy 72.527198 -205.759234) (xy 72.564052 -205.810653) (xy 72.594243 -205.866247)
			(xy 72.617305 -205.925157) (xy 72.632881 -205.986472) (xy 72.640731 -206.049245) (xy 72.640734 -206.112508)
			(xy 72.63289 -206.175282) (xy 72.617319 -206.236599) (xy 72.594263 -206.29551) (xy 72.594106 -206.2958)
			(xy 89.10542 -206.2958) (xy 89.109435 -206.231995) (xy 89.121414 -206.169197) (xy 89.14117 -206.108395)
			(xy 89.168391 -206.050549) (xy 89.202647 -205.99657) (xy 89.243398 -205.94731) (xy 89.290001 -205.903547)
			(xy 89.341723 -205.865969) (xy 89.397746 -205.83517) (xy 89.457187 -205.811636) (xy 89.51911 -205.795737)
			(xy 89.582537 -205.787725) (xy 89.614502 -205.787244) (xy 89.644167 -205.787692) (xy 89.703096 -205.794586)
			(xy 89.760822 -205.808293) (xy 89.81656 -205.828625) (xy 89.869553 -205.855307) (xy 89.91908 -205.887976)
			(xy 89.964467 -205.926187) (xy 89.985088 -205.947518) (xy 89.9922 -205.955138) (xy 90.011504 -205.96352)
			(xy 90.1065 -205.96352) (xy 90.125804 -205.955138) (xy 90.132916 -205.947518) (xy 90.15516 -205.924578)
			(xy 90.204406 -205.883862) (xy 90.258365 -205.849635) (xy 90.316188 -205.822439) (xy 90.376961 -205.802701)
			(xy 90.439729 -205.790732) (xy 90.503502 -205.786722) (xy 90.567275 -205.790732) (xy 90.630043 -205.802701)
			(xy 90.690816 -205.822439) (xy 90.748639 -205.849635) (xy 90.802598 -205.883862) (xy 90.851844 -205.924578)
			(xy 90.874088 -205.947518) (xy 90.8812 -205.955138) (xy 90.900504 -205.96352) (xy 90.9955 -205.96352)
			(xy 91.014804 -205.955138) (xy 91.021916 -205.947518) (xy 91.04252 -205.92617) (xy 91.087913 -205.887962)
			(xy 91.137444 -205.855295) (xy 91.190439 -205.828612) (xy 91.246178 -205.808277) (xy 91.303905 -205.794564)
			(xy 91.362835 -205.787661) (xy 91.392502 -205.787244) (xy 91.425903 -205.787747) (xy 91.492129 -205.796489)
			(xy 91.556639 -205.813834) (xy 91.61832 -205.839483) (xy 91.676108 -205.872994) (xy 91.729005 -205.913789)
			(xy 91.752928 -205.937104) (xy 91.760548 -205.944724) (xy 91.779852 -205.952344) (xy 91.875102 -205.949804)
			(xy 91.894152 -205.940914) (xy 91.90101 -205.93304) (xy 91.921747 -205.910372) (xy 91.967736 -205.869637)
			(xy 92.0183 -205.834742) (xy 92.0727 -205.806195) (xy 92.130145 -205.784412) (xy 92.189796 -205.769712)
			(xy 92.250784 -205.762307) (xy 92.281502 -205.761844) (xy 92.31346 -205.762442) (xy 92.376872 -205.770453)
			(xy 92.43878 -205.786348) (xy 92.498207 -205.809878) (xy 92.554217 -205.840669) (xy 92.605926 -205.878238)
			(xy 92.652518 -205.921992) (xy 92.69326 -205.97124) (xy 92.727508 -206.025206) (xy 92.754722 -206.083039)
			(xy 92.774473 -206.143826) (xy 92.786449 -206.20661) (xy 92.790463 -206.2704) (xy 92.786449 -206.33419)
			(xy 92.774473 -206.396974) (xy 92.754722 -206.457761) (xy 92.727508 -206.515594) (xy 92.69326 -206.56956)
			(xy 92.652518 -206.618808) (xy 92.605926 -206.662562) (xy 92.554217 -206.700131) (xy 92.498207 -206.730922)
			(xy 92.43878 -206.754452) (xy 92.376872 -206.770347) (xy 92.31346 -206.778358) (xy 92.281502 -206.77886)
			(xy 92.248101 -206.778353) (xy 92.181875 -206.769612) (xy 92.117365 -206.752268) (xy 92.055684 -206.726619)
			(xy 91.997897 -206.693109) (xy 91.944999 -206.652314) (xy 91.921076 -206.629) (xy 91.913456 -206.62138)
			(xy 91.894152 -206.61376) (xy 91.798902 -206.6163) (xy 91.779852 -206.62519) (xy 91.772994 -206.633064)
			(xy 91.752256 -206.65573) (xy 91.706267 -206.696465) (xy 91.655704 -206.731361) (xy 91.601303 -206.759908)
			(xy 91.543859 -206.781691) (xy 91.484208 -206.796392) (xy 91.42322 -206.803796) (xy 91.392502 -206.80426)
			(xy 91.362835 -206.80384) (xy 91.303904 -206.796944) (xy 91.246177 -206.783235) (xy 91.190438 -206.762899)
			(xy 91.137445 -206.736212) (xy 91.08792 -206.703538) (xy 91.042535 -206.66532) (xy 91.021916 -206.643986)
			(xy 91.014804 -206.636366) (xy 90.9955 -206.627984) (xy 90.900504 -206.627984) (xy 90.8812 -206.636366)
			(xy 90.874088 -206.643986) (xy 90.851844 -206.666926) (xy 90.802598 -206.707642) (xy 90.748639 -206.741869)
			(xy 90.690816 -206.769065) (xy 90.630043 -206.788803) (xy 90.567275 -206.800772) (xy 90.503502 -206.804782)
			(xy 90.439729 -206.800772) (xy 90.376961 -206.788803) (xy 90.316188 -206.769065) (xy 90.258365 -206.741869)
			(xy 90.204406 -206.707642) (xy 90.15516 -206.666926) (xy 90.132916 -206.643986) (xy 90.125804 -206.636366)
			(xy 90.1065 -206.627984) (xy 90.011504 -206.627984) (xy 89.9922 -206.636366) (xy 89.985088 -206.643986)
			(xy 89.964483 -206.665333) (xy 89.91909 -206.703541) (xy 89.869559 -206.736208) (xy 89.816564 -206.762891)
			(xy 89.760825 -206.783226) (xy 89.703099 -206.796939) (xy 89.644168 -206.803842) (xy 89.614502 -206.80426)
			(xy 89.582537 -206.803875) (xy 89.51911 -206.795863) (xy 89.457187 -206.779964) (xy 89.397746 -206.75643)
			(xy 89.341723 -206.725631) (xy 89.290001 -206.688053) (xy 89.243398 -206.64429) (xy 89.202647 -206.59503)
			(xy 89.168391 -206.541051) (xy 89.14117 -206.483205) (xy 89.121414 -206.422403) (xy 89.109435 -206.359605)
			(xy 89.10542 -206.2958) (xy 72.594106 -206.2958) (xy 72.564077 -206.351107) (xy 72.527228 -206.402529)
			(xy 72.506078 -206.426054) (xy 72.499898 -206.433315) (xy 72.492992 -206.45107) (xy 72.492616 -206.460598)
			(xy 72.492616 -208.635092) (xy 72.49309 -208.644963) (xy 72.500554 -208.663241) (xy 72.507094 -208.670652)
			(xy 72.507348 -208.670906) (xy 72.8599 -209.023458) (xy 93.979238 -209.023458) (xy 93.97981 -208.988503)
			(xy 93.989376 -208.919249) (xy 94.008336 -208.851959) (xy 94.036333 -208.787899) (xy 94.072839 -208.728276)
			(xy 94.094554 -208.700878) (xy 94.09984 -208.693889) (xy 94.105676 -208.677378) (xy 94.105984 -208.66862)
			(xy 94.105984 -208.514696) (xy 94.105625 -208.505949) (xy 94.099785 -208.489457) (xy 94.094554 -208.482438)
			(xy 94.072852 -208.455031) (xy 94.036354 -208.395407) (xy 94.00836 -208.331348) (xy 93.989396 -208.264061)
			(xy 93.979821 -208.194812) (xy 93.979238 -208.159858) (xy 93.97975 -208.129142) (xy 93.987155 -208.068157)
			(xy 94.001851 -208.008509) (xy 94.023626 -207.951065) (xy 94.052161 -207.896662) (xy 94.087042 -207.846092)
			(xy 94.12776 -207.800092) (xy 94.150434 -207.779366) (xy 94.156916 -207.773119) (xy 94.165377 -207.757243)
			(xy 94.166944 -207.748378) (xy 94.171262 -207.718406) (xy 94.172141 -207.709549) (xy 94.168494 -207.692139)
			(xy 94.16415 -207.68437) (xy 94.1505 -207.661604) (xy 94.128962 -207.613087) (xy 94.114357 -207.562054)
			(xy 94.106966 -207.509489) (xy 94.106492 -207.482948) (xy 94.106978 -207.455697) (xy 94.114734 -207.401749)
			(xy 94.130089 -207.349454) (xy 94.152731 -207.299877) (xy 94.182197 -207.254027) (xy 94.217888 -207.212836)
			(xy 94.259079 -207.177145) (xy 94.304929 -207.147679) (xy 94.354506 -207.125037) (xy 94.406801 -207.109682)
			(xy 94.460749 -207.101926) (xy 94.515251 -207.101926) (xy 94.569199 -207.109682) (xy 94.621494 -207.125037)
			(xy 94.671071 -207.147679) (xy 94.716921 -207.177145) (xy 94.758112 -207.212836) (xy 94.793803 -207.254027)
			(xy 94.823269 -207.299877) (xy 94.845911 -207.349454) (xy 94.861266 -207.401749) (xy 94.869022 -207.455697)
			(xy 94.869508 -207.482948) (xy 94.869044 -207.50952) (xy 94.861673 -207.562152) (xy 94.847066 -207.61325)
			(xy 94.825507 -207.661825) (xy 94.81185 -207.684624) (xy 94.807429 -207.692367) (xy 94.803667 -207.709781)
			(xy 94.804484 -207.71866) (xy 94.808802 -207.748632) (xy 94.810378 -207.757493) (xy 94.818841 -207.773365)
			(xy 94.825312 -207.77962) (xy 94.847959 -207.80034) (xy 94.888629 -207.846318) (xy 94.923468 -207.896857)
			(xy 94.951968 -207.951224) (xy 94.973716 -208.008626) (xy 94.988394 -208.068229) (xy 94.99579 -208.129166)
			(xy 94.996254 -208.159858) (xy 94.995693 -208.194814) (xy 94.988767 -208.244948) (xy 97.281238 -208.244948)
			(xy 97.281647 -208.219369) (xy 97.288495 -208.168671) (xy 97.302049 -208.119341) (xy 97.322067 -208.072262)
			(xy 97.348189 -208.028275) (xy 97.379948 -207.988169) (xy 97.398078 -207.97012) (xy 97.40519 -207.963516)
			(xy 97.413064 -207.945736) (xy 97.417128 -207.856582) (xy 97.411032 -207.838294) (xy 97.404682 -207.830928)
			(xy 97.385401 -207.807813) (xy 97.351816 -207.757857) (xy 97.324364 -207.704285) (xy 97.30343 -207.647846)
			(xy 97.289307 -207.58933) (xy 97.282193 -207.529556) (xy 97.281746 -207.499458) (xy 97.282316 -207.464502)
			(xy 97.291882 -207.395249) (xy 97.310843 -207.327958) (xy 97.33884 -207.263898) (xy 97.375347 -207.204276)
			(xy 97.397062 -207.176878) (xy 97.402349 -207.16989) (xy 97.408184 -207.153379) (xy 97.408492 -207.14462)
			(xy 97.408492 -206.990696) (xy 97.408131 -206.981949) (xy 97.402293 -206.965458) (xy 97.397062 -206.958438)
			(xy 97.375361 -206.93103) (xy 97.338863 -206.871406) (xy 97.310868 -206.807348) (xy 97.291905 -206.740061)
			(xy 97.282329 -206.670812) (xy 97.281746 -206.635858) (xy 97.282315 -206.601743) (xy 97.291451 -206.534126)
			(xy 97.309553 -206.468341) (xy 97.336295 -206.405569) (xy 97.371197 -206.34694) (xy 97.391982 -206.319882)
			(xy 97.397395 -206.312399) (xy 97.403011 -206.294825) (xy 97.402904 -206.285592) (xy 97.401126 -206.255112)
			(xy 97.400279 -206.24608) (xy 97.393134 -206.229422) (xy 97.387156 -206.2226) (xy 97.367459 -206.201149)
			(xy 97.334103 -206.153415) (xy 97.308382 -206.101169) (xy 97.290894 -206.045622) (xy 97.282044 -205.988065)
			(xy 97.281492 -205.958948) (xy 97.281978 -205.931697) (xy 97.289734 -205.877749) (xy 97.305089 -205.825454)
			(xy 97.327731 -205.775877) (xy 97.357197 -205.730027) (xy 97.392888 -205.688836) (xy 97.434079 -205.653145)
			(xy 97.479929 -205.623679) (xy 97.529506 -205.601037) (xy 97.581801 -205.585682) (xy 97.635749 -205.577926)
			(xy 97.690251 -205.577926) (xy 97.744199 -205.585682) (xy 97.796494 -205.601037) (xy 97.846071 -205.623679)
			(xy 97.891921 -205.653145) (xy 97.933112 -205.688836) (xy 97.968803 -205.730027) (xy 97.998269 -205.775877)
			(xy 98.020911 -205.825454) (xy 98.036266 -205.877749) (xy 98.044022 -205.931697) (xy 98.044508 -205.958948)
			(xy 98.044149 -205.983841) (xy 98.037726 -206.033211) (xy 98.024918 -206.081321) (xy 98.015806 -206.10449)
			(xy 98.012658 -206.112988) (xy 98.012021 -206.131088) (xy 98.014536 -206.139796) (xy 98.024188 -206.168752)
			(xy 98.027484 -206.177358) (xy 98.039062 -206.191678) (xy 98.046794 -206.196692) (xy 98.075146 -206.213851)
			(xy 98.12753 -206.254443) (xy 98.1742 -206.301495) (xy 98.214363 -206.354209) (xy 98.24734 -206.411693)
			(xy 98.272573 -206.472973) (xy 98.289633 -206.537011) (xy 98.298232 -206.602722) (xy 98.298762 -206.635858)
			(xy 98.298199 -206.670814) (xy 98.288631 -206.740067) (xy 98.269669 -206.807358) (xy 98.24167 -206.871418)
			(xy 98.205162 -206.93104) (xy 98.183446 -206.958438) (xy 98.178195 -206.96545) (xy 98.172338 -206.981943)
			(xy 98.172016 -206.990696) (xy 98.172016 -207.14462) (xy 98.172368 -207.153368) (xy 98.178212 -207.169859)
			(xy 98.183446 -207.176878) (xy 98.205156 -207.20428) (xy 98.241652 -207.263905) (xy 98.269645 -207.327965)
			(xy 98.288607 -207.395253) (xy 98.29818 -207.464504) (xy 98.298762 -207.499458) (xy 98.298214 -207.532801)
			(xy 98.289498 -207.598915) (xy 98.272211 -207.663321) (xy 98.246649 -207.724913) (xy 98.213251 -207.782633)
			(xy 98.172591 -207.835489) (xy 98.125368 -207.882574) (xy 98.072393 -207.923078) (xy 98.043746 -207.940148)
			(xy 98.035364 -207.944974) (xy 98.023426 -207.960214) (xy 97.997772 -208.045812) (xy 97.999296 -208.065116)
			(xy 98.003614 -208.073752) (xy 98.016405 -208.100459) (xy 98.034492 -208.156843) (xy 98.043672 -208.215341)
			(xy 98.044254 -208.244948) (xy 98.043768 -208.272199) (xy 98.036012 -208.326147) (xy 98.020657 -208.378442)
			(xy 97.998015 -208.428019) (xy 97.968549 -208.473869) (xy 97.932858 -208.51506) (xy 97.891667 -208.550751)
			(xy 97.845817 -208.580217) (xy 97.79624 -208.602859) (xy 97.743945 -208.618214) (xy 97.689997 -208.62597)
			(xy 97.635495 -208.62597) (xy 97.581547 -208.618214) (xy 97.529252 -208.602859) (xy 97.479675 -208.580217)
			(xy 97.433825 -208.550751) (xy 97.392634 -208.51506) (xy 97.356943 -208.473869) (xy 97.327477 -208.428019)
			(xy 97.304835 -208.378442) (xy 97.28948 -208.326147) (xy 97.281724 -208.272199) (xy 97.281238 -208.244948)
			(xy 94.988767 -208.244948) (xy 94.986125 -208.264068) (xy 94.967162 -208.331358) (xy 94.939163 -208.395418)
			(xy 94.902654 -208.45504) (xy 94.880938 -208.482438) (xy 94.875686 -208.489449) (xy 94.86983 -208.505943)
			(xy 94.869508 -208.514696) (xy 94.869508 -208.66862) (xy 94.869862 -208.677368) (xy 94.875705 -208.693859)
			(xy 94.880938 -208.700878) (xy 94.902646 -208.72828) (xy 94.939144 -208.787906) (xy 94.967137 -208.851965)
			(xy 94.986098 -208.919254) (xy 94.995672 -208.988504) (xy 94.996254 -209.023458) (xy 94.995779 -209.05547)
			(xy 94.987735 -209.118988) (xy 94.971783 -209.180994) (xy 94.948175 -209.240507) (xy 94.917283 -209.296587)
			(xy 94.879597 -209.348345) (xy 94.835712 -209.394964) (xy 94.786323 -209.435706) (xy 94.759526 -209.453226)
			(xy 94.749366 -209.459576) (xy 94.73692 -209.479896) (xy 94.727776 -209.584036) (xy 94.736412 -209.606134)
			(xy 94.745302 -209.614262) (xy 94.764477 -209.632439) (xy 94.7982 -209.67311) (xy 94.825988 -209.718045)
			(xy 94.847311 -209.766385) (xy 94.861758 -209.817204) (xy 94.869056 -209.869531) (xy 94.869508 -209.895948)
			(xy 94.869009 -209.923317) (xy 94.861199 -209.977495) (xy 94.845718 -210.029997) (xy 94.822883 -210.079745)
			(xy 94.793166 -210.125713) (xy 94.775528 -210.146646) (xy 94.769432 -210.153758) (xy 94.763082 -210.170776)
			(xy 94.763082 -210.25612) (xy 94.769432 -210.273138) (xy 94.775528 -210.28025) (xy 94.793161 -210.301187)
			(xy 94.822873 -210.347159) (xy 94.84571 -210.396905) (xy 94.861202 -210.449404) (xy 94.869033 -210.503579)
			(xy 94.869508 -210.530948) (xy 94.868932 -210.560386) (xy 94.859883 -210.618562) (xy 94.842009 -210.674659)
			(xy 94.815733 -210.727345) (xy 94.79915 -210.751674) (xy 94.793562 -210.759548) (xy 94.78899 -210.77809)
			(xy 94.799912 -210.865212) (xy 94.809056 -210.881976) (xy 94.816422 -210.888072) (xy 94.840181 -210.908866)
			(xy 94.88296 -210.955304) (xy 94.919665 -211.006678) (xy 94.949731 -211.062198) (xy 94.972696 -211.121012)
			(xy 94.988208 -211.182216) (xy 94.996028 -211.244869) (xy 94.996508 -211.276438) (xy 94.995946 -211.311394)
			(xy 94.986379 -211.380648) (xy 94.967418 -211.447939) (xy 94.939418 -211.511999) (xy 94.902909 -211.571621)
			(xy 94.881192 -211.599018) (xy 94.875889 -211.606013) (xy 94.869918 -211.622507) (xy 94.869508 -211.631276)
			(xy 94.869508 -211.7852) (xy 94.869867 -211.793977) (xy 94.875854 -211.81048) (xy 94.881192 -211.817458)
			(xy 94.902884 -211.844873) (xy 94.939386 -211.904494) (xy 94.967382 -211.96855) (xy 94.986348 -212.035836)
			(xy 94.995925 -212.105084) (xy 94.996508 -212.140038) (xy 94.996078 -212.170748) (xy 94.988691 -212.231722)
			(xy 94.974016 -212.291363) (xy 94.952266 -212.348804) (xy 94.923759 -212.403207) (xy 94.88891 -212.453783)
			(xy 94.848224 -212.499795) (xy 94.825566 -212.52053) (xy 94.819023 -212.526678) (xy 94.810439 -212.542435)
			(xy 94.808802 -212.551264) (xy 94.804738 -212.58149) (xy 94.803916 -212.590286) (xy 94.807541 -212.607561)
			(xy 94.81185 -212.615272) (xy 94.825492 -212.63808) (xy 94.847052 -212.686653) (xy 94.861664 -212.737748)
			(xy 94.869045 -212.790376) (xy 94.869508 -212.816948) (xy 94.869009 -212.844317) (xy 94.861199 -212.898495)
			(xy 94.845718 -212.950997) (xy 94.822883 -213.000745) (xy 94.793166 -213.046713) (xy 94.775528 -213.067646)
			(xy 94.769432 -213.074758) (xy 94.763082 -213.091776) (xy 94.763082 -213.17712) (xy 94.769432 -213.194138)
			(xy 94.775528 -213.20125) (xy 94.793161 -213.222187) (xy 94.822873 -213.268159) (xy 94.84571 -213.317905)
			(xy 94.861202 -213.370404) (xy 94.869033 -213.424579) (xy 94.869508 -213.451948) (xy 94.869044 -213.47852)
			(xy 94.861673 -213.531152) (xy 94.847066 -213.58225) (xy 94.825507 -213.630825) (xy 94.81185 -213.653624)
			(xy 94.807517 -213.661329) (xy 94.803874 -213.67861) (xy 94.804738 -213.687406) (xy 94.808802 -213.717632)
			(xy 94.810551 -213.726422) (xy 94.819116 -213.742146) (xy 94.825566 -213.748366) (xy 94.848248 -213.769077)
			(xy 94.888946 -213.815083) (xy 94.923802 -213.865659) (xy 94.952308 -213.920067) (xy 94.974048 -213.977515)
			(xy 94.988706 -214.037165) (xy 94.996066 -214.098146) (xy 94.996508 -214.128858) (xy 94.995958 -214.163814)
			(xy 94.986388 -214.233069) (xy 94.967424 -214.30036) (xy 94.939422 -214.36442) (xy 94.90291 -214.424041)
			(xy 94.881192 -214.451438) (xy 94.875881 -214.458428) (xy 94.869914 -214.474926) (xy 94.869508 -214.483696)
			(xy 94.869508 -214.63762) (xy 94.869858 -214.646398) (xy 94.875851 -214.662901) (xy 94.881192 -214.669878)
			(xy 94.902894 -214.697286) (xy 94.939393 -214.756909) (xy 94.967388 -214.820967) (xy 94.986352 -214.888254)
			(xy 94.995926 -214.957504) (xy 94.996508 -214.992458) (xy 94.996038 -215.02403) (xy 94.988228 -215.086688)
			(xy 94.972724 -215.147898) (xy 94.949764 -215.206718) (xy 94.9197 -215.262245) (xy 94.882995 -215.313624)
			(xy 94.840214 -215.360065) (xy 94.816422 -215.380824) (xy 94.809056 -215.38692) (xy 94.799912 -215.403684)
			(xy 94.78899 -215.490806) (xy 94.793562 -215.509348) (xy 94.79915 -215.517222) (xy 94.81575 -215.541542)
			(xy 94.842041 -215.594226) (xy 94.859921 -215.650326) (xy 94.868965 -215.708508) (xy 94.869508 -215.737948)
			(xy 94.869022 -215.765199) (xy 94.861266 -215.819147) (xy 94.845911 -215.871442) (xy 94.823269 -215.921019)
			(xy 94.793803 -215.966869) (xy 94.758112 -216.00806) (xy 94.716921 -216.043751) (xy 94.671071 -216.073217)
			(xy 94.621494 -216.095859) (xy 94.569199 -216.111214) (xy 94.515251 -216.11897) (xy 94.460749 -216.11897)
			(xy 94.406801 -216.111214) (xy 94.354506 -216.095859) (xy 94.304929 -216.073217) (xy 94.259079 -216.043751)
			(xy 94.217888 -216.00806) (xy 94.182197 -215.966869) (xy 94.152731 -215.921019) (xy 94.130089 -215.871442)
			(xy 94.114734 -215.819147) (xy 94.106978 -215.765199) (xy 94.106492 -215.737948) (xy 94.107066 -215.70851)
			(xy 94.116115 -215.650334) (xy 94.13399 -215.594237) (xy 94.160267 -215.541551) (xy 94.17685 -215.517222)
			(xy 94.182438 -215.509348) (xy 94.18701 -215.490806) (xy 94.176088 -215.403684) (xy 94.166944 -215.38692)
			(xy 94.159578 -215.380824) (xy 94.135817 -215.360032) (xy 94.093038 -215.313594) (xy 94.056334 -215.26222)
			(xy 94.026268 -215.206699) (xy 94.003303 -215.147884) (xy 93.987791 -215.08668) (xy 93.979972 -215.024027)
			(xy 93.979492 -214.992458) (xy 93.980052 -214.957502) (xy 93.989619 -214.888248) (xy 94.008581 -214.820957)
			(xy 94.036581 -214.756897) (xy 94.073091 -214.697275) (xy 94.094808 -214.669878) (xy 94.100113 -214.662884)
			(xy 94.106083 -214.646389) (xy 94.106492 -214.63762) (xy 94.106492 -214.483696) (xy 94.106135 -214.474918)
			(xy 94.100147 -214.458416) (xy 94.094808 -214.451438) (xy 94.073114 -214.424025) (xy 94.036613 -214.364403)
			(xy 94.008616 -214.300346) (xy 93.989651 -214.23306) (xy 93.980075 -214.163812) (xy 93.979492 -214.128858)
			(xy 93.979919 -214.098148) (xy 93.987307 -214.037174) (xy 94.001983 -213.977532) (xy 94.023732 -213.920092)
			(xy 94.05224 -213.865688) (xy 94.08709 -213.815113) (xy 94.127776 -213.769101) (xy 94.150434 -213.748366)
			(xy 94.156978 -213.742219) (xy 94.165561 -213.726461) (xy 94.167198 -213.717632) (xy 94.171262 -213.687406)
			(xy 94.172086 -213.67861) (xy 94.16846 -213.661335) (xy 94.16415 -213.653624) (xy 94.150507 -213.630817)
			(xy 94.128947 -213.582244) (xy 94.114335 -213.531148) (xy 94.106954 -213.47852) (xy 94.106492 -213.451948)
			(xy 94.106988 -213.424579) (xy 94.114799 -213.370401) (xy 94.130281 -213.317898) (xy 94.153116 -213.268151)
			(xy 94.182834 -213.222183) (xy 94.200472 -213.20125) (xy 94.206568 -213.194138) (xy 94.212918 -213.17712)
			(xy 94.212918 -213.091776) (xy 94.206568 -213.074758) (xy 94.200472 -213.067646) (xy 94.182837 -213.046711)
			(xy 94.153125 -213.000739) (xy 94.130289 -212.950992) (xy 94.114797 -212.898492) (xy 94.106967 -212.844317)
			(xy 94.106492 -212.816948) (xy 94.106954 -212.790375) (xy 94.114326 -212.737744) (xy 94.128933 -212.686646)
			(xy 94.150493 -212.638071) (xy 94.16415 -212.615272) (xy 94.168485 -212.607569) (xy 94.172127 -212.590287)
			(xy 94.171262 -212.58149) (xy 94.167198 -212.551264) (xy 94.165451 -212.542474) (xy 94.156885 -212.52675)
			(xy 94.150434 -212.52053) (xy 94.12775 -212.499821) (xy 94.087052 -212.453815) (xy 94.052196 -212.403239)
			(xy 94.02369 -212.34883) (xy 94.001951 -212.291381) (xy 93.987294 -212.231732) (xy 93.979934 -212.17075)
			(xy 93.979492 -212.140038) (xy 93.98004 -212.105082) (xy 93.98961 -212.035827) (xy 94.008575 -211.968536)
			(xy 94.036578 -211.904476) (xy 94.07309 -211.844855) (xy 94.094808 -211.817458) (xy 94.10008 -211.810442)
			(xy 94.10607 -211.793964) (xy 94.106492 -211.7852) (xy 94.106492 -211.631276) (xy 94.106144 -211.622497)
			(xy 94.10015 -211.605995) (xy 94.094808 -211.599018) (xy 94.073105 -211.571612) (xy 94.036605 -211.511988)
			(xy 94.008611 -211.447929) (xy 93.989648 -211.380642) (xy 93.980073 -211.311392) (xy 93.979492 -211.276438)
			(xy 93.979959 -211.244866) (xy 93.987769 -211.182208) (xy 94.003274 -211.120998) (xy 94.026235 -211.062178)
			(xy 94.056299 -211.006651) (xy 94.093004 -210.955272) (xy 94.135786 -210.908831) (xy 94.159578 -210.888072)
			(xy 94.166944 -210.881976) (xy 94.176088 -210.865212) (xy 94.18701 -210.77809) (xy 94.182438 -210.759548)
			(xy 94.17685 -210.751674) (xy 94.160248 -210.727355) (xy 94.133958 -210.67467) (xy 94.116078 -210.61857)
			(xy 94.107035 -210.560388) (xy 94.106492 -210.530948) (xy 94.106988 -210.503579) (xy 94.114799 -210.449401)
			(xy 94.130281 -210.396898) (xy 94.153116 -210.347151) (xy 94.182834 -210.301183) (xy 94.200472 -210.28025)
			(xy 94.206568 -210.273138) (xy 94.212918 -210.25612) (xy 94.212918 -210.170776) (xy 94.206568 -210.153758)
			(xy 94.200472 -210.146646) (xy 94.182837 -210.125711) (xy 94.153125 -210.079739) (xy 94.130289 -210.029992)
			(xy 94.114797 -209.977492) (xy 94.106967 -209.923317) (xy 94.106492 -209.895948) (xy 94.106969 -209.869531)
			(xy 94.114253 -209.817201) (xy 94.12869 -209.766377) (xy 94.150002 -209.718032) (xy 94.177781 -209.67309)
			(xy 94.211497 -209.632411) (xy 94.230698 -209.614262) (xy 94.239334 -209.606388) (xy 94.24797 -209.58429)
			(xy 94.238826 -209.48015) (xy 94.22638 -209.45983) (xy 94.21622 -209.45348) (xy 94.189395 -209.435959)
			(xy 94.139949 -209.39521) (xy 94.096014 -209.348572) (xy 94.058285 -209.296785) (xy 94.027359 -209.240669)
			(xy 94.003728 -209.181113) (xy 93.987764 -209.119061) (xy 93.979721 -209.055495) (xy 93.979238 -209.023458)
			(xy 72.8599 -209.023458) (xy 76.816712 -212.98027) (xy 78.812394 -212.98027) (xy 78.816423 -212.837949)
			(xy 78.828498 -212.696084) (xy 78.848579 -212.55513) (xy 78.876602 -212.415537) (xy 78.912478 -212.277753)
			(xy 78.956092 -212.14222) (xy 79.007304 -212.009371) (xy 79.06595 -211.879632) (xy 79.131841 -211.753419)
			(xy 79.204768 -211.631136) (xy 79.284496 -211.513174) (xy 79.37077 -211.399912) (xy 79.463314 -211.291713)
			(xy 79.56183 -211.188922) (xy 79.666005 -211.09187) (xy 79.775503 -211.000866) (xy 79.889974 -210.916204)
			(xy 80.009052 -210.838153) (xy 80.132355 -210.766964) (xy 80.259488 -210.702865) (xy 80.390044 -210.646061)
			(xy 80.523604 -210.596735) (xy 80.659741 -210.555043) (xy 80.798019 -210.52112) (xy 80.937994 -210.495075)
			(xy 81.079219 -210.47699) (xy 81.22124 -210.466925) (xy 81.363604 -210.46491) (xy 81.505854 -210.470953)
			(xy 81.647534 -210.485033) (xy 81.78819 -210.507107) (xy 81.927372 -210.537103) (xy 82.064634 -210.574925)
			(xy 82.199537 -210.620453) (xy 82.331648 -210.673539) (xy 82.460544 -210.734015) (xy 82.585812 -210.801686)
			(xy 82.707051 -210.876336) (xy 82.823872 -210.957725) (xy 82.935902 -211.045593) (xy 83.042781 -211.139659)
			(xy 83.144167 -211.23962) (xy 83.239736 -211.345158) (xy 83.329181 -211.455933) (xy 83.412215 -211.571591)
			(xy 83.488573 -211.691761) (xy 83.55801 -211.816059) (xy 83.620303 -211.944086) (xy 83.675254 -212.075433)
			(xy 83.722686 -212.209678) (xy 83.762447 -212.346391) (xy 83.794409 -212.485135) (xy 83.818471 -212.625465)
			(xy 83.834555 -212.766931) (xy 83.842611 -212.909081) (xy 83.843114 -212.98027) (xy 83.842611 -213.051459)
			(xy 83.834555 -213.193609) (xy 83.818471 -213.335075) (xy 83.794409 -213.475405) (xy 83.762447 -213.614149)
			(xy 83.722686 -213.750862) (xy 83.675254 -213.885107) (xy 83.620303 -214.016454) (xy 83.55801 -214.144481)
			(xy 83.488573 -214.268779) (xy 83.412215 -214.388949) (xy 83.329181 -214.504607) (xy 83.239736 -214.615382)
			(xy 83.144167 -214.72092) (xy 83.042781 -214.820881) (xy 82.935902 -214.914947) (xy 82.823872 -215.002815)
			(xy 82.707051 -215.084204) (xy 82.585812 -215.158854) (xy 82.460544 -215.226525) (xy 82.331648 -215.287001)
			(xy 82.199537 -215.340087) (xy 82.064634 -215.385615) (xy 81.927372 -215.423437) (xy 81.78819 -215.453433)
			(xy 81.647534 -215.475507) (xy 81.505854 -215.489587) (xy 81.363604 -215.49563) (xy 81.22124 -215.493615)
			(xy 81.079219 -215.48355) (xy 80.937994 -215.465465) (xy 80.798019 -215.43942) (xy 80.659741 -215.405497)
			(xy 80.523604 -215.363805) (xy 80.390044 -215.314479) (xy 80.259488 -215.257675) (xy 80.132355 -215.193576)
			(xy 80.009052 -215.122387) (xy 79.889974 -215.044336) (xy 79.775503 -214.959674) (xy 79.666005 -214.86867)
			(xy 79.56183 -214.771618) (xy 79.463314 -214.668827) (xy 79.37077 -214.560628) (xy 79.284496 -214.447366)
			(xy 79.204768 -214.329404) (xy 79.131841 -214.207121) (xy 79.06595 -214.080908) (xy 79.007304 -213.951169)
			(xy 78.956092 -213.81832) (xy 78.912478 -213.682787) (xy 78.876602 -213.545003) (xy 78.848579 -213.40541)
			(xy 78.828498 -213.264456) (xy 78.816423 -213.122591) (xy 78.812394 -212.98027) (xy 76.816712 -212.98027)
			(xy 79.694235 -215.857793) (xy 90.051884 -215.857793) (xy 90.051884 -215.793871) (xy 90.059895 -215.730453)
			(xy 90.075792 -215.668539) (xy 90.099324 -215.609106) (xy 90.130118 -215.553091) (xy 90.167691 -215.501376)
			(xy 90.211448 -215.454779) (xy 90.260701 -215.414034) (xy 90.314672 -215.379783) (xy 90.372511 -215.352566)
			(xy 90.433304 -215.332813) (xy 90.496094 -215.320835) (xy 90.55989 -215.316822) (xy 90.623686 -215.320835)
			(xy 90.686476 -215.332813) (xy 90.747269 -215.352566) (xy 90.805108 -215.379783) (xy 90.859079 -215.414034)
			(xy 90.908332 -215.454779) (xy 90.952089 -215.501376) (xy 90.989662 -215.553091) (xy 91.020456 -215.609106)
			(xy 91.043988 -215.668539) (xy 91.059885 -215.730453) (xy 91.067896 -215.793871) (xy 91.068398 -215.825832)
			(xy 91.067896 -215.857793) (xy 91.059885 -215.921211) (xy 91.043988 -215.983125) (xy 91.020456 -216.042558)
			(xy 90.989662 -216.098573) (xy 90.952089 -216.150288) (xy 90.908332 -216.196885) (xy 90.859079 -216.23763)
			(xy 90.805108 -216.271881) (xy 90.747269 -216.299098) (xy 90.686476 -216.318851) (xy 90.623686 -216.330829)
			(xy 90.55989 -216.334843) (xy 90.496094 -216.330829) (xy 90.433304 -216.318851) (xy 90.372511 -216.299098)
			(xy 90.314672 -216.271881) (xy 90.260701 -216.23763) (xy 90.211448 -216.196885) (xy 90.167691 -216.150288)
			(xy 90.130118 -216.098573) (xy 90.099324 -216.042558) (xy 90.075792 -215.983125) (xy 90.059895 -215.921211)
			(xy 90.051884 -215.857793) (xy 79.694235 -215.857793) (xy 80.419659 -216.583217) (xy 92.175832 -216.583217)
			(xy 92.175832 -216.519295) (xy 92.183843 -216.455877) (xy 92.19974 -216.393963) (xy 92.223272 -216.33453)
			(xy 92.254066 -216.278515) (xy 92.291639 -216.2268) (xy 92.335396 -216.180203) (xy 92.384649 -216.139458)
			(xy 92.43862 -216.105207) (xy 92.496459 -216.07799) (xy 92.557252 -216.058237) (xy 92.620042 -216.046259)
			(xy 92.683838 -216.042246) (xy 92.747634 -216.046259) (xy 92.810424 -216.058237) (xy 92.871217 -216.07799)
			(xy 92.929056 -216.105207) (xy 92.983027 -216.139458) (xy 93.03228 -216.180203) (xy 93.076037 -216.2268)
			(xy 93.11361 -216.278515) (xy 93.144404 -216.33453) (xy 93.167936 -216.393963) (xy 93.183833 -216.455877)
			(xy 93.191844 -216.519295) (xy 93.192346 -216.551256) (xy 93.191844 -216.583217) (xy 93.183833 -216.646635)
			(xy 93.167936 -216.708549) (xy 93.144404 -216.767982) (xy 93.11361 -216.823997) (xy 93.076037 -216.875712)
			(xy 93.03228 -216.922309) (xy 92.983027 -216.963054) (xy 92.929056 -216.997305) (xy 92.871217 -217.024522)
			(xy 92.810424 -217.044275) (xy 92.747634 -217.056253) (xy 92.683838 -217.060267) (xy 92.620042 -217.056253)
			(xy 92.557252 -217.044275) (xy 92.496459 -217.024522) (xy 92.43862 -216.997305) (xy 92.384649 -216.963054)
			(xy 92.335396 -216.922309) (xy 92.291639 -216.875712) (xy 92.254066 -216.823997) (xy 92.223272 -216.767982)
			(xy 92.19974 -216.708549) (xy 92.183843 -216.646635) (xy 92.175832 -216.583217) (xy 80.419659 -216.583217)
			(xy 82.179942 -218.3435) (xy 89.224369 -218.3435) (xy 89.228383 -218.279704) (xy 89.240361 -218.216913)
			(xy 89.260113 -218.156119) (xy 89.287329 -218.09828) (xy 89.32158 -218.044308) (xy 89.362324 -217.995054)
			(xy 89.408921 -217.951295) (xy 89.460634 -217.91372) (xy 89.516648 -217.882923) (xy 89.576081 -217.85939)
			(xy 89.637995 -217.84349) (xy 89.701413 -217.835476) (xy 89.733374 -217.834972) (xy 89.766077 -217.835474)
			(xy 89.830943 -217.843873) (xy 89.894195 -217.860522) (xy 89.95479 -217.885147) (xy 90.011725 -217.917341)
			(xy 90.064061 -217.956572) (xy 90.110933 -218.002191) (xy 90.131646 -218.027504) (xy 90.138758 -218.03614)
			(xy 90.158062 -218.046046) (xy 90.256614 -218.050618) (xy 90.276934 -218.042744) (xy 90.284554 -218.034616)
			(xy 90.310893 -218.008173) (xy 90.369936 -217.962521) (xy 90.402156 -217.943684) (xy 90.412824 -217.937588)
			(xy 90.426032 -217.91803) (xy 90.440002 -217.813382) (xy 90.432382 -217.79103) (xy 90.423492 -217.782394)
			(xy 90.399788 -217.758434) (xy 90.358333 -217.70529) (xy 90.324264 -217.647135) (xy 90.298177 -217.584988)
			(xy 90.280531 -217.519939) (xy 90.271635 -217.453128) (xy 90.271092 -217.419428) (xy 90.271594 -217.387467)
			(xy 90.279605 -217.324049) (xy 90.295502 -217.262135) (xy 90.319034 -217.202702) (xy 90.349828 -217.146687)
			(xy 90.387401 -217.094972) (xy 90.431158 -217.048375) (xy 90.480411 -217.00763) (xy 90.534382 -216.973379)
			(xy 90.592221 -216.946162) (xy 90.653014 -216.926409) (xy 90.715804 -216.914431) (xy 90.7796 -216.910418)
			(xy 90.843396 -216.914431) (xy 90.906186 -216.926409) (xy 90.966979 -216.946162) (xy 91.024818 -216.973379)
			(xy 91.078789 -217.00763) (xy 91.128042 -217.048375) (xy 91.171799 -217.094972) (xy 91.209372 -217.146687)
			(xy 91.240166 -217.202702) (xy 91.263698 -217.262135) (xy 91.279595 -217.324049) (xy 91.287606 -217.387467)
			(xy 91.288108 -217.419428) (xy 91.287576 -217.453085) (xy 91.27868 -217.51981) (xy 91.26106 -217.584777)
			(xy 91.235024 -217.646853) (xy 91.201028 -217.704952) (xy 91.159664 -217.758059) (xy 91.137792 -217.779557)
			(xy 92.67545 -217.779557) (xy 92.67545 -217.715635) (xy 92.683461 -217.652217) (xy 92.699358 -217.590303)
			(xy 92.72289 -217.53087) (xy 92.753684 -217.474855) (xy 92.791257 -217.42314) (xy 92.835014 -217.376543)
			(xy 92.884267 -217.335798) (xy 92.938238 -217.301547) (xy 92.996077 -217.27433) (xy 93.05687 -217.254577)
			(xy 93.11966 -217.242599) (xy 93.183456 -217.238586) (xy 93.247252 -217.242599) (xy 93.310042 -217.254577)
			(xy 93.370835 -217.27433) (xy 93.428674 -217.301547) (xy 93.482645 -217.335798) (xy 93.531898 -217.376543)
			(xy 93.575655 -217.42314) (xy 93.613228 -217.474855) (xy 93.644022 -217.53087) (xy 93.667554 -217.590303)
			(xy 93.683451 -217.652217) (xy 93.691462 -217.715635) (xy 93.691964 -217.747596) (xy 93.691462 -217.779557)
			(xy 93.683451 -217.842975) (xy 93.667554 -217.904889) (xy 93.644022 -217.964322) (xy 93.613228 -218.020337)
			(xy 93.575655 -218.072052) (xy 93.531898 -218.118649) (xy 93.482645 -218.159394) (xy 93.428674 -218.193645)
			(xy 93.370835 -218.220862) (xy 93.310042 -218.240615) (xy 93.247252 -218.252593) (xy 93.183456 -218.256607)
			(xy 93.11966 -218.252593) (xy 93.05687 -218.240615) (xy 92.996077 -218.220862) (xy 92.938238 -218.193645)
			(xy 92.884267 -218.159394) (xy 92.835014 -218.118649) (xy 92.791257 -218.072052) (xy 92.753684 -218.020337)
			(xy 92.72289 -217.964322) (xy 92.699358 -217.904889) (xy 92.683461 -217.842975) (xy 92.67545 -217.779557)
			(xy 91.137792 -217.779557) (xy 91.111657 -217.805246) (xy 91.057845 -217.845688) (xy 91.028774 -217.862658)
			(xy 91.018106 -217.868754) (xy 91.004898 -217.888312) (xy 90.990928 -217.99296) (xy 90.998548 -218.015312)
			(xy 91.007438 -218.023948) (xy 91.031101 -218.047947) (xy 91.072563 -218.101081) (xy 91.106639 -218.159227)
			(xy 91.132733 -218.221367) (xy 91.150387 -218.28641) (xy 91.159291 -218.353216) (xy 91.159838 -218.386914)
			(xy 91.159357 -218.417644) (xy 91.151948 -218.478656) (xy 91.137238 -218.53833) (xy 91.115444 -218.595797)
			(xy 91.086882 -218.650217) (xy 91.051969 -218.700798) (xy 91.011213 -218.746802) (xy 90.965211 -218.787559)
			(xy 90.914631 -218.822473) (xy 90.860211 -218.851037) (xy 90.802746 -218.872834) (xy 90.743072 -218.887545)
			(xy 90.68206 -218.894956) (xy 90.65133 -218.895422) (xy 90.618627 -218.894919) (xy 90.553761 -218.886521)
			(xy 90.490508 -218.869872) (xy 90.429914 -218.845247) (xy 90.372978 -218.813053) (xy 90.320643 -218.773822)
			(xy 90.273771 -218.728203) (xy 90.253058 -218.70289) (xy 90.245946 -218.694254) (xy 90.226642 -218.684348)
			(xy 90.12809 -218.679776) (xy 90.10777 -218.68765) (xy 90.10015 -218.695778) (xy 90.076081 -218.720011)
			(xy 90.022594 -218.762486) (xy 89.963904 -218.79742) (xy 89.901066 -218.824185) (xy 89.835211 -218.8423)
			(xy 89.767524 -218.851437) (xy 89.733374 -218.851988) (xy 89.701413 -218.851524) (xy 89.637995 -218.84351)
			(xy 89.576081 -218.82761) (xy 89.516648 -218.804077) (xy 89.460634 -218.77328) (xy 89.408921 -218.735705)
			(xy 89.362324 -218.691946) (xy 89.32158 -218.642692) (xy 89.287329 -218.58872) (xy 89.260113 -218.530881)
			(xy 89.240361 -218.470087) (xy 89.228383 -218.407296) (xy 89.224369 -218.3435) (xy 82.179942 -218.3435)
			(xy 82.778811 -218.942369) (xy 92.156528 -218.942369) (xy 92.156528 -218.878447) (xy 92.164539 -218.815029)
			(xy 92.180436 -218.753115) (xy 92.203968 -218.693682) (xy 92.234762 -218.637667) (xy 92.272335 -218.585952)
			(xy 92.316092 -218.539355) (xy 92.365345 -218.49861) (xy 92.419316 -218.464359) (xy 92.477155 -218.437142)
			(xy 92.537948 -218.417389) (xy 92.600738 -218.405411) (xy 92.664534 -218.401398) (xy 92.72833 -218.405411)
			(xy 92.79112 -218.417389) (xy 92.851913 -218.437142) (xy 92.909752 -218.464359) (xy 92.963723 -218.49861)
			(xy 93.012976 -218.539355) (xy 93.056733 -218.585952) (xy 93.094306 -218.637667) (xy 93.103328 -218.654079)
			(xy 93.376998 -218.654079) (xy 93.376998 -218.590157) (xy 93.385009 -218.526739) (xy 93.400906 -218.464825)
			(xy 93.424438 -218.405392) (xy 93.455232 -218.349377) (xy 93.492805 -218.297662) (xy 93.536562 -218.251065)
			(xy 93.585815 -218.21032) (xy 93.639786 -218.176069) (xy 93.697625 -218.148852) (xy 93.758418 -218.129099)
			(xy 93.821208 -218.117121) (xy 93.885004 -218.113108) (xy 93.9488 -218.117121) (xy 94.01159 -218.129099)
			(xy 94.072383 -218.148852) (xy 94.130222 -218.176069) (xy 94.184193 -218.21032) (xy 94.233446 -218.251065)
			(xy 94.277203 -218.297662) (xy 94.314776 -218.349377) (xy 94.34557 -218.405392) (xy 94.369102 -218.464825)
			(xy 94.384999 -218.526739) (xy 94.39301 -218.590157) (xy 94.393512 -218.622118) (xy 94.39301 -218.654079)
			(xy 94.384999 -218.717497) (xy 94.369102 -218.779411) (xy 94.34557 -218.838844) (xy 94.314776 -218.894859)
			(xy 94.277203 -218.946574) (xy 94.233446 -218.993171) (xy 94.184193 -219.033916) (xy 94.130222 -219.068167)
			(xy 94.072383 -219.095384) (xy 94.01159 -219.115137) (xy 93.9488 -219.127115) (xy 93.885004 -219.131129)
			(xy 93.821208 -219.127115) (xy 93.758418 -219.115137) (xy 93.697625 -219.095384) (xy 93.639786 -219.068167)
			(xy 93.585815 -219.033916) (xy 93.536562 -218.993171) (xy 93.492805 -218.946574) (xy 93.455232 -218.894859)
			(xy 93.424438 -218.838844) (xy 93.400906 -218.779411) (xy 93.385009 -218.717497) (xy 93.376998 -218.654079)
			(xy 93.103328 -218.654079) (xy 93.1251 -218.693682) (xy 93.148632 -218.753115) (xy 93.164529 -218.815029)
			(xy 93.17254 -218.878447) (xy 93.173042 -218.910408) (xy 93.17254 -218.942369) (xy 93.164529 -219.005787)
			(xy 93.148632 -219.067701) (xy 93.1251 -219.127134) (xy 93.094306 -219.183149) (xy 93.056733 -219.234864)
			(xy 93.012976 -219.281461) (xy 92.963723 -219.322206) (xy 92.909752 -219.356457) (xy 92.851913 -219.383674)
			(xy 92.79112 -219.403427) (xy 92.72833 -219.415405) (xy 92.664534 -219.419419) (xy 92.600738 -219.415405)
			(xy 92.537948 -219.403427) (xy 92.477155 -219.383674) (xy 92.419316 -219.356457) (xy 92.365345 -219.322206)
			(xy 92.316092 -219.281461) (xy 92.272335 -219.234864) (xy 92.234762 -219.183149) (xy 92.203968 -219.127134)
			(xy 92.180436 -219.067701) (xy 92.164539 -219.005787) (xy 92.156528 -218.942369) (xy 82.778811 -218.942369)
			(xy 85.034882 -221.19844) (xy 85.047328 -221.205298) (xy 85.05444 -221.206822) (xy 85.078429 -221.212665)
			(xy 85.124254 -221.231038) (xy 85.166526 -221.256544) (xy 85.204143 -221.28852) (xy 85.236125 -221.326132)
			(xy 85.261639 -221.368399) (xy 85.280019 -221.414221) (xy 85.285834 -221.438216) (xy 85.287358 -221.445328)
			(xy 85.294216 -221.457774) (xy 85.341206 -221.504764) (xy 90.322158 -221.504764) (xy 90.326118 -221.45571)
			(xy 90.337895 -221.407926) (xy 90.357186 -221.36265) (xy 90.383489 -221.321054) (xy 90.416124 -221.284217)
			(xy 90.454245 -221.253092) (xy 90.496866 -221.228485) (xy 90.542882 -221.211033) (xy 90.591101 -221.201189)
			(xy 90.640276 -221.199208) (xy 90.689131 -221.20514) (xy 90.736402 -221.218832) (xy 90.780864 -221.23993)
			(xy 90.821367 -221.267886) (xy 90.85686 -221.301978) (xy 90.886425 -221.341322) (xy 90.909296 -221.384899)
			(xy 90.92488 -221.43158) (xy 90.932775 -221.480157) (xy 90.93327 -221.504764) (xy 90.932775 -221.529371)
			(xy 90.92488 -221.577948) (xy 90.909296 -221.624629) (xy 90.886425 -221.668206) (xy 90.85686 -221.70755)
			(xy 90.821367 -221.741642) (xy 90.780864 -221.769598) (xy 90.736402 -221.790696) (xy 90.689131 -221.804388)
			(xy 90.68834 -221.804484) (xy 93.615268 -221.804484) (xy 93.619228 -221.75543) (xy 93.631005 -221.707646)
			(xy 93.650296 -221.66237) (xy 93.676599 -221.620774) (xy 93.709234 -221.583937) (xy 93.747355 -221.552812)
			(xy 93.789976 -221.528205) (xy 93.835992 -221.510753) (xy 93.884211 -221.500909) (xy 93.933386 -221.498928)
			(xy 93.982241 -221.50486) (xy 94.029512 -221.518552) (xy 94.073974 -221.53965) (xy 94.114477 -221.567606)
			(xy 94.14997 -221.601698) (xy 94.179535 -221.641042) (xy 94.202406 -221.684619) (xy 94.21799 -221.7313)
			(xy 94.225885 -221.779877) (xy 94.22638 -221.804484) (xy 94.555322 -221.804484) (xy 94.559282 -221.75543)
			(xy 94.571059 -221.707646) (xy 94.59035 -221.66237) (xy 94.616653 -221.620774) (xy 94.649288 -221.583937)
			(xy 94.687409 -221.552812) (xy 94.73003 -221.528205) (xy 94.776046 -221.510753) (xy 94.824265 -221.500909)
			(xy 94.87344 -221.498928) (xy 94.922295 -221.50486) (xy 94.969566 -221.518552) (xy 95.014028 -221.53965)
			(xy 95.054531 -221.567606) (xy 95.090024 -221.601698) (xy 95.119589 -221.641042) (xy 95.14246 -221.684619)
			(xy 95.158044 -221.7313) (xy 95.165939 -221.779877) (xy 95.166434 -221.804484) (xy 95.495122 -221.804484)
			(xy 95.499082 -221.75543) (xy 95.510859 -221.707646) (xy 95.53015 -221.66237) (xy 95.556453 -221.620774)
			(xy 95.589088 -221.583937) (xy 95.627209 -221.552812) (xy 95.66983 -221.528205) (xy 95.715846 -221.510753)
			(xy 95.764065 -221.500909) (xy 95.81324 -221.498928) (xy 95.862095 -221.50486) (xy 95.909366 -221.518552)
			(xy 95.953828 -221.53965) (xy 95.994331 -221.567606) (xy 96.029824 -221.601698) (xy 96.059389 -221.641042)
			(xy 96.08226 -221.684619) (xy 96.097844 -221.7313) (xy 96.105739 -221.779877) (xy 96.106234 -221.804484)
			(xy 96.435176 -221.804484) (xy 96.439136 -221.75543) (xy 96.450913 -221.707646) (xy 96.470204 -221.66237)
			(xy 96.496507 -221.620774) (xy 96.529142 -221.583937) (xy 96.567263 -221.552812) (xy 96.609884 -221.528205)
			(xy 96.6559 -221.510753) (xy 96.704119 -221.500909) (xy 96.753294 -221.498928) (xy 96.802149 -221.50486)
			(xy 96.84942 -221.518552) (xy 96.893882 -221.53965) (xy 96.934385 -221.567606) (xy 96.969878 -221.601698)
			(xy 96.999443 -221.641042) (xy 97.022314 -221.684619) (xy 97.037898 -221.7313) (xy 97.045793 -221.779877)
			(xy 97.046288 -221.804484) (xy 97.37523 -221.804484) (xy 97.37919 -221.75543) (xy 97.390967 -221.707646)
			(xy 97.410258 -221.66237) (xy 97.436561 -221.620774) (xy 97.469196 -221.583937) (xy 97.507317 -221.552812)
			(xy 97.549938 -221.528205) (xy 97.595954 -221.510753) (xy 97.644173 -221.500909) (xy 97.693348 -221.498928)
			(xy 97.742203 -221.50486) (xy 97.789474 -221.518552) (xy 97.833936 -221.53965) (xy 97.874439 -221.567606)
			(xy 97.909932 -221.601698) (xy 97.939497 -221.641042) (xy 97.962368 -221.684619) (xy 97.977952 -221.7313)
			(xy 97.985847 -221.779877) (xy 97.986342 -221.804484) (xy 99.255338 -221.804484) (xy 99.259298 -221.75543)
			(xy 99.271075 -221.707646) (xy 99.290366 -221.66237) (xy 99.316669 -221.620774) (xy 99.349304 -221.583937)
			(xy 99.387425 -221.552812) (xy 99.430046 -221.528205) (xy 99.476062 -221.510753) (xy 99.524281 -221.500909)
			(xy 99.573456 -221.498928) (xy 99.622311 -221.50486) (xy 99.669582 -221.518552) (xy 99.714044 -221.53965)
			(xy 99.754547 -221.567606) (xy 99.79004 -221.601698) (xy 99.819605 -221.641042) (xy 99.842476 -221.684619)
			(xy 99.85806 -221.7313) (xy 99.865955 -221.779877) (xy 99.86645 -221.804484) (xy 100.195138 -221.804484)
			(xy 100.199098 -221.75543) (xy 100.210875 -221.707646) (xy 100.230166 -221.66237) (xy 100.256469 -221.620774)
			(xy 100.289104 -221.583937) (xy 100.327225 -221.552812) (xy 100.369846 -221.528205) (xy 100.415862 -221.510753)
			(xy 100.464081 -221.500909) (xy 100.513256 -221.498928) (xy 100.562111 -221.50486) (xy 100.609382 -221.518552)
			(xy 100.653844 -221.53965) (xy 100.694347 -221.567606) (xy 100.72984 -221.601698) (xy 100.759405 -221.641042)
			(xy 100.782276 -221.684619) (xy 100.79786 -221.7313) (xy 100.805755 -221.779877) (xy 100.80625 -221.804484)
			(xy 101.135192 -221.804484) (xy 101.139152 -221.75543) (xy 101.150929 -221.707646) (xy 101.17022 -221.66237)
			(xy 101.196523 -221.620774) (xy 101.229158 -221.583937) (xy 101.267279 -221.552812) (xy 101.3099 -221.528205)
			(xy 101.355916 -221.510753) (xy 101.404135 -221.500909) (xy 101.45331 -221.498928) (xy 101.502165 -221.50486)
			(xy 101.549436 -221.518552) (xy 101.593898 -221.53965) (xy 101.634401 -221.567606) (xy 101.669894 -221.601698)
			(xy 101.699459 -221.641042) (xy 101.72233 -221.684619) (xy 101.737914 -221.7313) (xy 101.745809 -221.779877)
			(xy 101.746304 -221.804484) (xy 102.075246 -221.804484) (xy 102.079206 -221.75543) (xy 102.090983 -221.707646)
			(xy 102.110274 -221.66237) (xy 102.136577 -221.620774) (xy 102.169212 -221.583937) (xy 102.207333 -221.552812)
			(xy 102.249954 -221.528205) (xy 102.29597 -221.510753) (xy 102.344189 -221.500909) (xy 102.393364 -221.498928)
			(xy 102.442219 -221.50486) (xy 102.48949 -221.518552) (xy 102.533952 -221.53965) (xy 102.574455 -221.567606)
			(xy 102.609948 -221.601698) (xy 102.639513 -221.641042) (xy 102.662384 -221.684619) (xy 102.677968 -221.7313)
			(xy 102.685863 -221.779877) (xy 102.686358 -221.804484) (xy 103.955354 -221.804484) (xy 103.959314 -221.75543)
			(xy 103.971091 -221.707646) (xy 103.990382 -221.66237) (xy 104.016685 -221.620774) (xy 104.04932 -221.583937)
			(xy 104.087441 -221.552812) (xy 104.130062 -221.528205) (xy 104.176078 -221.510753) (xy 104.224297 -221.500909)
			(xy 104.273472 -221.498928) (xy 104.322327 -221.50486) (xy 104.369598 -221.518552) (xy 104.41406 -221.53965)
			(xy 104.454563 -221.567606) (xy 104.490056 -221.601698) (xy 104.519621 -221.641042) (xy 104.542492 -221.684619)
			(xy 104.558076 -221.7313) (xy 104.565971 -221.779877) (xy 104.566466 -221.804484) (xy 104.895154 -221.804484)
			(xy 104.899114 -221.75543) (xy 104.910891 -221.707646) (xy 104.930182 -221.66237) (xy 104.956485 -221.620774)
			(xy 104.98912 -221.583937) (xy 105.027241 -221.552812) (xy 105.069862 -221.528205) (xy 105.115878 -221.510753)
			(xy 105.164097 -221.500909) (xy 105.213272 -221.498928) (xy 105.262127 -221.50486) (xy 105.309398 -221.518552)
			(xy 105.35386 -221.53965) (xy 105.394363 -221.567606) (xy 105.429856 -221.601698) (xy 105.459421 -221.641042)
			(xy 105.482292 -221.684619) (xy 105.497876 -221.7313) (xy 105.505771 -221.779877) (xy 105.506266 -221.804484)
			(xy 106.775262 -221.804484) (xy 106.779222 -221.75543) (xy 106.790999 -221.707646) (xy 106.81029 -221.66237)
			(xy 106.836593 -221.620774) (xy 106.869228 -221.583937) (xy 106.907349 -221.552812) (xy 106.94997 -221.528205)
			(xy 106.995986 -221.510753) (xy 107.044205 -221.500909) (xy 107.09338 -221.498928) (xy 107.142235 -221.50486)
			(xy 107.189506 -221.518552) (xy 107.233968 -221.53965) (xy 107.274471 -221.567606) (xy 107.309964 -221.601698)
			(xy 107.339529 -221.641042) (xy 107.3624 -221.684619) (xy 107.377984 -221.7313) (xy 107.385879 -221.779877)
			(xy 107.386374 -221.804484) (xy 107.385879 -221.829091) (xy 107.377984 -221.877668) (xy 107.3624 -221.924349)
			(xy 107.339529 -221.967926) (xy 107.309964 -222.00727) (xy 107.274471 -222.041362) (xy 107.233968 -222.069318)
			(xy 107.189506 -222.090416) (xy 107.142235 -222.104108) (xy 107.09338 -222.11004) (xy 107.044205 -222.108059)
			(xy 106.995986 -222.098215) (xy 106.94997 -222.080763) (xy 106.907349 -222.056156) (xy 106.869228 -222.025031)
			(xy 106.836593 -221.988194) (xy 106.81029 -221.946598) (xy 106.790999 -221.901322) (xy 106.779222 -221.853538)
			(xy 106.775262 -221.804484) (xy 105.506266 -221.804484) (xy 105.505771 -221.829091) (xy 105.497876 -221.877668)
			(xy 105.482292 -221.924349) (xy 105.459421 -221.967926) (xy 105.429856 -222.00727) (xy 105.394363 -222.041362)
			(xy 105.35386 -222.069318) (xy 105.309398 -222.090416) (xy 105.262127 -222.104108) (xy 105.213272 -222.11004)
			(xy 105.164097 -222.108059) (xy 105.115878 -222.098215) (xy 105.069862 -222.080763) (xy 105.027241 -222.056156)
			(xy 104.98912 -222.025031) (xy 104.956485 -221.988194) (xy 104.930182 -221.946598) (xy 104.910891 -221.901322)
			(xy 104.899114 -221.853538) (xy 104.895154 -221.804484) (xy 104.566466 -221.804484) (xy 104.565971 -221.829091)
			(xy 104.558076 -221.877668) (xy 104.542492 -221.924349) (xy 104.519621 -221.967926) (xy 104.490056 -222.00727)
			(xy 104.454563 -222.041362) (xy 104.41406 -222.069318) (xy 104.369598 -222.090416) (xy 104.322327 -222.104108)
			(xy 104.273472 -222.11004) (xy 104.224297 -222.108059) (xy 104.176078 -222.098215) (xy 104.130062 -222.080763)
			(xy 104.087441 -222.056156) (xy 104.04932 -222.025031) (xy 104.016685 -221.988194) (xy 103.990382 -221.946598)
			(xy 103.971091 -221.901322) (xy 103.959314 -221.853538) (xy 103.955354 -221.804484) (xy 102.686358 -221.804484)
			(xy 102.685863 -221.829091) (xy 102.677968 -221.877668) (xy 102.662384 -221.924349) (xy 102.639513 -221.967926)
			(xy 102.609948 -222.00727) (xy 102.574455 -222.041362) (xy 102.533952 -222.069318) (xy 102.48949 -222.090416)
			(xy 102.442219 -222.104108) (xy 102.393364 -222.11004) (xy 102.344189 -222.108059) (xy 102.29597 -222.098215)
			(xy 102.249954 -222.080763) (xy 102.207333 -222.056156) (xy 102.169212 -222.025031) (xy 102.136577 -221.988194)
			(xy 102.110274 -221.946598) (xy 102.090983 -221.901322) (xy 102.079206 -221.853538) (xy 102.075246 -221.804484)
			(xy 101.746304 -221.804484) (xy 101.745809 -221.829091) (xy 101.737914 -221.877668) (xy 101.72233 -221.924349)
			(xy 101.699459 -221.967926) (xy 101.669894 -222.00727) (xy 101.634401 -222.041362) (xy 101.593898 -222.069318)
			(xy 101.549436 -222.090416) (xy 101.502165 -222.104108) (xy 101.45331 -222.11004) (xy 101.404135 -222.108059)
			(xy 101.355916 -222.098215) (xy 101.3099 -222.080763) (xy 101.267279 -222.056156) (xy 101.229158 -222.025031)
			(xy 101.196523 -221.988194) (xy 101.17022 -221.946598) (xy 101.150929 -221.901322) (xy 101.139152 -221.853538)
			(xy 101.135192 -221.804484) (xy 100.80625 -221.804484) (xy 100.805755 -221.829091) (xy 100.79786 -221.877668)
			(xy 100.782276 -221.924349) (xy 100.759405 -221.967926) (xy 100.72984 -222.00727) (xy 100.694347 -222.041362)
			(xy 100.653844 -222.069318) (xy 100.609382 -222.090416) (xy 100.562111 -222.104108) (xy 100.513256 -222.11004)
			(xy 100.464081 -222.108059) (xy 100.415862 -222.098215) (xy 100.369846 -222.080763) (xy 100.327225 -222.056156)
			(xy 100.289104 -222.025031) (xy 100.256469 -221.988194) (xy 100.230166 -221.946598) (xy 100.210875 -221.901322)
			(xy 100.199098 -221.853538) (xy 100.195138 -221.804484) (xy 99.86645 -221.804484) (xy 99.865955 -221.829091)
			(xy 99.85806 -221.877668) (xy 99.842476 -221.924349) (xy 99.819605 -221.967926) (xy 99.79004 -222.00727)
			(xy 99.754547 -222.041362) (xy 99.714044 -222.069318) (xy 99.669582 -222.090416) (xy 99.622311 -222.104108)
			(xy 99.573456 -222.11004) (xy 99.524281 -222.108059) (xy 99.476062 -222.098215) (xy 99.430046 -222.080763)
			(xy 99.387425 -222.056156) (xy 99.349304 -222.025031) (xy 99.316669 -221.988194) (xy 99.290366 -221.946598)
			(xy 99.271075 -221.901322) (xy 99.259298 -221.853538) (xy 99.255338 -221.804484) (xy 97.986342 -221.804484)
			(xy 97.985847 -221.829091) (xy 97.977952 -221.877668) (xy 97.962368 -221.924349) (xy 97.939497 -221.967926)
			(xy 97.909932 -222.00727) (xy 97.874439 -222.041362) (xy 97.833936 -222.069318) (xy 97.789474 -222.090416)
			(xy 97.742203 -222.104108) (xy 97.693348 -222.11004) (xy 97.644173 -222.108059) (xy 97.595954 -222.098215)
			(xy 97.549938 -222.080763) (xy 97.507317 -222.056156) (xy 97.469196 -222.025031) (xy 97.436561 -221.988194)
			(xy 97.410258 -221.946598) (xy 97.390967 -221.901322) (xy 97.37919 -221.853538) (xy 97.37523 -221.804484)
			(xy 97.046288 -221.804484) (xy 97.045793 -221.829091) (xy 97.037898 -221.877668) (xy 97.022314 -221.924349)
			(xy 96.999443 -221.967926) (xy 96.969878 -222.00727) (xy 96.934385 -222.041362) (xy 96.893882 -222.069318)
			(xy 96.84942 -222.090416) (xy 96.802149 -222.104108) (xy 96.753294 -222.11004) (xy 96.704119 -222.108059)
			(xy 96.6559 -222.098215) (xy 96.609884 -222.080763) (xy 96.567263 -222.056156) (xy 96.529142 -222.025031)
			(xy 96.496507 -221.988194) (xy 96.470204 -221.946598) (xy 96.450913 -221.901322) (xy 96.439136 -221.853538)
			(xy 96.435176 -221.804484) (xy 96.106234 -221.804484) (xy 96.105739 -221.829091) (xy 96.097844 -221.877668)
			(xy 96.08226 -221.924349) (xy 96.059389 -221.967926) (xy 96.029824 -222.00727) (xy 95.994331 -222.041362)
			(xy 95.953828 -222.069318) (xy 95.909366 -222.090416) (xy 95.862095 -222.104108) (xy 95.81324 -222.11004)
			(xy 95.764065 -222.108059) (xy 95.715846 -222.098215) (xy 95.66983 -222.080763) (xy 95.627209 -222.056156)
			(xy 95.589088 -222.025031) (xy 95.556453 -221.988194) (xy 95.53015 -221.946598) (xy 95.510859 -221.901322)
			(xy 95.499082 -221.853538) (xy 95.495122 -221.804484) (xy 95.166434 -221.804484) (xy 95.165939 -221.829091)
			(xy 95.158044 -221.877668) (xy 95.14246 -221.924349) (xy 95.119589 -221.967926) (xy 95.090024 -222.00727)
			(xy 95.054531 -222.041362) (xy 95.014028 -222.069318) (xy 94.969566 -222.090416) (xy 94.922295 -222.104108)
			(xy 94.87344 -222.11004) (xy 94.824265 -222.108059) (xy 94.776046 -222.098215) (xy 94.73003 -222.080763)
			(xy 94.687409 -222.056156) (xy 94.649288 -222.025031) (xy 94.616653 -221.988194) (xy 94.59035 -221.946598)
			(xy 94.571059 -221.901322) (xy 94.559282 -221.853538) (xy 94.555322 -221.804484) (xy 94.22638 -221.804484)
			(xy 94.225885 -221.829091) (xy 94.21799 -221.877668) (xy 94.202406 -221.924349) (xy 94.179535 -221.967926)
			(xy 94.14997 -222.00727) (xy 94.114477 -222.041362) (xy 94.073974 -222.069318) (xy 94.029512 -222.090416)
			(xy 93.982241 -222.104108) (xy 93.933386 -222.11004) (xy 93.884211 -222.108059) (xy 93.835992 -222.098215)
			(xy 93.789976 -222.080763) (xy 93.747355 -222.056156) (xy 93.709234 -222.025031) (xy 93.676599 -221.988194)
			(xy 93.650296 -221.946598) (xy 93.631005 -221.901322) (xy 93.619228 -221.853538) (xy 93.615268 -221.804484)
			(xy 90.68834 -221.804484) (xy 90.640276 -221.81032) (xy 90.591101 -221.808339) (xy 90.542882 -221.798495)
			(xy 90.496866 -221.781043) (xy 90.454245 -221.756436) (xy 90.416124 -221.725311) (xy 90.383489 -221.688474)
			(xy 90.357186 -221.646878) (xy 90.337895 -221.601602) (xy 90.326118 -221.553818) (xy 90.322158 -221.504764)
			(xy 85.341206 -221.504764) (xy 86.450932 -222.61449) (xy 91.26526 -222.61449) (xy 91.26922 -222.565436)
			(xy 91.280997 -222.517652) (xy 91.300288 -222.472376) (xy 91.326591 -222.43078) (xy 91.359226 -222.393943)
			(xy 91.397347 -222.362818) (xy 91.439968 -222.338211) (xy 91.485984 -222.320759) (xy 91.534203 -222.310915)
			(xy 91.583378 -222.308934) (xy 91.632233 -222.314866) (xy 91.679504 -222.328558) (xy 91.723966 -222.349656)
			(xy 91.764469 -222.377612) (xy 91.799962 -222.411704) (xy 91.829527 -222.451048) (xy 91.852398 -222.494625)
			(xy 91.867982 -222.541306) (xy 91.875877 -222.589883) (xy 91.876372 -222.61449) (xy 92.205314 -222.61449)
			(xy 92.209274 -222.565436) (xy 92.221051 -222.517652) (xy 92.240342 -222.472376) (xy 92.266645 -222.43078)
			(xy 92.29928 -222.393943) (xy 92.337401 -222.362818) (xy 92.380022 -222.338211) (xy 92.426038 -222.320759)
			(xy 92.474257 -222.310915) (xy 92.523432 -222.308934) (xy 92.572287 -222.314866) (xy 92.619558 -222.328558)
			(xy 92.66402 -222.349656) (xy 92.704523 -222.377612) (xy 92.740016 -222.411704) (xy 92.769581 -222.451048)
			(xy 92.792452 -222.494625) (xy 92.808036 -222.541306) (xy 92.815931 -222.589883) (xy 92.816426 -222.61449)
			(xy 95.025222 -222.61449) (xy 95.029182 -222.565436) (xy 95.040959 -222.517652) (xy 95.06025 -222.472376)
			(xy 95.086553 -222.43078) (xy 95.119188 -222.393943) (xy 95.157309 -222.362818) (xy 95.19993 -222.338211)
			(xy 95.245946 -222.320759) (xy 95.294165 -222.310915) (xy 95.34334 -222.308934) (xy 95.392195 -222.314866)
			(xy 95.439466 -222.328558) (xy 95.483928 -222.349656) (xy 95.524431 -222.377612) (xy 95.559924 -222.411704)
			(xy 95.589489 -222.451048) (xy 95.61236 -222.494625) (xy 95.627944 -222.541306) (xy 95.635839 -222.589883)
			(xy 95.636334 -222.61449) (xy 97.84513 -222.61449) (xy 97.84909 -222.565436) (xy 97.860867 -222.517652)
			(xy 97.880158 -222.472376) (xy 97.906461 -222.43078) (xy 97.939096 -222.393943) (xy 97.977217 -222.362818)
			(xy 98.019838 -222.338211) (xy 98.065854 -222.320759) (xy 98.114073 -222.310915) (xy 98.163248 -222.308934)
			(xy 98.212103 -222.314866) (xy 98.259374 -222.328558) (xy 98.303836 -222.349656) (xy 98.344339 -222.377612)
			(xy 98.379832 -222.411704) (xy 98.409397 -222.451048) (xy 98.432268 -222.494625) (xy 98.447852 -222.541306)
			(xy 98.455747 -222.589883) (xy 98.456242 -222.61449) (xy 100.665292 -222.61449) (xy 100.669252 -222.565436)
			(xy 100.681029 -222.517652) (xy 100.70032 -222.472376) (xy 100.726623 -222.43078) (xy 100.759258 -222.393943)
			(xy 100.797379 -222.362818) (xy 100.84 -222.338211) (xy 100.886016 -222.320759) (xy 100.934235 -222.310915)
			(xy 100.98341 -222.308934) (xy 101.032265 -222.314866) (xy 101.079536 -222.328558) (xy 101.123998 -222.349656)
			(xy 101.164501 -222.377612) (xy 101.199994 -222.411704) (xy 101.229559 -222.451048) (xy 101.25243 -222.494625)
			(xy 101.268014 -222.541306) (xy 101.275909 -222.589883) (xy 101.276404 -222.61449) (xy 110.065324 -222.61449)
			(xy 110.069284 -222.565436) (xy 110.081061 -222.517652) (xy 110.100352 -222.472376) (xy 110.126655 -222.43078)
			(xy 110.15929 -222.393943) (xy 110.197411 -222.362818) (xy 110.240032 -222.338211) (xy 110.286048 -222.320759)
			(xy 110.334267 -222.310915) (xy 110.383442 -222.308934) (xy 110.432297 -222.314866) (xy 110.479568 -222.328558)
			(xy 110.52403 -222.349656) (xy 110.564533 -222.377612) (xy 110.600026 -222.411704) (xy 110.629591 -222.451048)
			(xy 110.652462 -222.494625) (xy 110.668046 -222.541306) (xy 110.675941 -222.589883) (xy 110.676436 -222.61449)
			(xy 110.675941 -222.639097) (xy 110.668046 -222.687674) (xy 110.652462 -222.734355) (xy 110.629591 -222.777932)
			(xy 110.600026 -222.817276) (xy 110.564533 -222.851368) (xy 110.52403 -222.879324) (xy 110.479568 -222.900422)
			(xy 110.432297 -222.914114) (xy 110.383442 -222.920046) (xy 110.334267 -222.918065) (xy 110.286048 -222.908221)
			(xy 110.240032 -222.890769) (xy 110.197411 -222.866162) (xy 110.15929 -222.835037) (xy 110.126655 -222.7982)
			(xy 110.100352 -222.756604) (xy 110.081061 -222.711328) (xy 110.069284 -222.663544) (xy 110.065324 -222.61449)
			(xy 101.276404 -222.61449) (xy 101.275909 -222.639097) (xy 101.268014 -222.687674) (xy 101.25243 -222.734355)
			(xy 101.229559 -222.777932) (xy 101.199994 -222.817276) (xy 101.164501 -222.851368) (xy 101.123998 -222.879324)
			(xy 101.079536 -222.900422) (xy 101.032265 -222.914114) (xy 100.98341 -222.920046) (xy 100.934235 -222.918065)
			(xy 100.886016 -222.908221) (xy 100.84 -222.890769) (xy 100.797379 -222.866162) (xy 100.759258 -222.835037)
			(xy 100.726623 -222.7982) (xy 100.70032 -222.756604) (xy 100.681029 -222.711328) (xy 100.669252 -222.663544)
			(xy 100.665292 -222.61449) (xy 98.456242 -222.61449) (xy 98.455747 -222.639097) (xy 98.447852 -222.687674)
			(xy 98.432268 -222.734355) (xy 98.409397 -222.777932) (xy 98.379832 -222.817276) (xy 98.344339 -222.851368)
			(xy 98.303836 -222.879324) (xy 98.259374 -222.900422) (xy 98.212103 -222.914114) (xy 98.163248 -222.920046)
			(xy 98.114073 -222.918065) (xy 98.065854 -222.908221) (xy 98.019838 -222.890769) (xy 97.977217 -222.866162)
			(xy 97.939096 -222.835037) (xy 97.906461 -222.7982) (xy 97.880158 -222.756604) (xy 97.860867 -222.711328)
			(xy 97.84909 -222.663544) (xy 97.84513 -222.61449) (xy 95.636334 -222.61449) (xy 95.635839 -222.639097)
			(xy 95.627944 -222.687674) (xy 95.61236 -222.734355) (xy 95.589489 -222.777932) (xy 95.559924 -222.817276)
			(xy 95.524431 -222.851368) (xy 95.483928 -222.879324) (xy 95.439466 -222.900422) (xy 95.392195 -222.914114)
			(xy 95.34334 -222.920046) (xy 95.294165 -222.918065) (xy 95.245946 -222.908221) (xy 95.19993 -222.890769)
			(xy 95.157309 -222.866162) (xy 95.119188 -222.835037) (xy 95.086553 -222.7982) (xy 95.06025 -222.756604)
			(xy 95.040959 -222.711328) (xy 95.029182 -222.663544) (xy 95.025222 -222.61449) (xy 92.816426 -222.61449)
			(xy 92.815931 -222.639097) (xy 92.808036 -222.687674) (xy 92.792452 -222.734355) (xy 92.769581 -222.777932)
			(xy 92.740016 -222.817276) (xy 92.704523 -222.851368) (xy 92.66402 -222.879324) (xy 92.619558 -222.900422)
			(xy 92.572287 -222.914114) (xy 92.523432 -222.920046) (xy 92.474257 -222.918065) (xy 92.426038 -222.908221)
			(xy 92.380022 -222.890769) (xy 92.337401 -222.866162) (xy 92.29928 -222.835037) (xy 92.266645 -222.7982)
			(xy 92.240342 -222.756604) (xy 92.221051 -222.711328) (xy 92.209274 -222.663544) (xy 92.205314 -222.61449)
			(xy 91.876372 -222.61449) (xy 91.875877 -222.639097) (xy 91.867982 -222.687674) (xy 91.852398 -222.734355)
			(xy 91.829527 -222.777932) (xy 91.799962 -222.817276) (xy 91.764469 -222.851368) (xy 91.723966 -222.879324)
			(xy 91.679504 -222.900422) (xy 91.632233 -222.914114) (xy 91.583378 -222.920046) (xy 91.534203 -222.918065)
			(xy 91.485984 -222.908221) (xy 91.439968 -222.890769) (xy 91.397347 -222.866162) (xy 91.359226 -222.835037)
			(xy 91.326591 -222.7982) (xy 91.300288 -222.756604) (xy 91.280997 -222.711328) (xy 91.26922 -222.663544)
			(xy 91.26526 -222.61449) (xy 86.450932 -222.61449) (xy 87.049102 -223.21266) (xy 87.056468 -223.2195)
			(xy 87.075001 -223.227242) (xy 87.095085 -223.227242) (xy 87.113618 -223.2195) (xy 87.120984 -223.21266)
			(xy 87.121492 -223.212152) (xy 87.121746 -223.211898) (xy 87.139134 -223.19469) (xy 87.178373 -223.16548)
			(xy 87.221763 -223.142891) (xy 87.268197 -223.127501) (xy 87.316489 -223.119703) (xy 87.340948 -223.119188)
			(xy 87.364937 -223.119662) (xy 87.412323 -223.127174) (xy 87.457951 -223.142006) (xy 87.500697 -223.163792)
			(xy 87.53951 -223.191996) (xy 87.573433 -223.225924) (xy 87.601631 -223.26474) (xy 87.623411 -223.30749)
			(xy 87.638236 -223.35312) (xy 87.645741 -223.400507) (xy 87.645951 -223.410272) (xy 88.915506 -223.410272)
			(xy 88.919466 -223.361218) (xy 88.931243 -223.313434) (xy 88.950534 -223.268158) (xy 88.976837 -223.226562)
			(xy 89.009472 -223.189725) (xy 89.047593 -223.1586) (xy 89.090214 -223.133993) (xy 89.13623 -223.116541)
			(xy 89.184449 -223.106697) (xy 89.233624 -223.104716) (xy 89.282479 -223.110648) (xy 89.32975 -223.12434)
			(xy 89.374212 -223.145438) (xy 89.414715 -223.173394) (xy 89.450208 -223.207486) (xy 89.479773 -223.24683)
			(xy 89.502644 -223.290407) (xy 89.518228 -223.337088) (xy 89.526123 -223.385665) (xy 89.526618 -223.410272)
			(xy 89.526332 -223.424496) (xy 89.855306 -223.424496) (xy 89.859266 -223.375442) (xy 89.871043 -223.327658)
			(xy 89.890334 -223.282382) (xy 89.916637 -223.240786) (xy 89.949272 -223.203949) (xy 89.987393 -223.172824)
			(xy 90.030014 -223.148217) (xy 90.07603 -223.130765) (xy 90.124249 -223.120921) (xy 90.173424 -223.11894)
			(xy 90.222279 -223.124872) (xy 90.26955 -223.138564) (xy 90.314012 -223.159662) (xy 90.354515 -223.187618)
			(xy 90.390008 -223.22171) (xy 90.419573 -223.261054) (xy 90.442444 -223.304631) (xy 90.458028 -223.351312)
			(xy 90.465923 -223.399889) (xy 90.466418 -223.424496) (xy 90.795106 -223.424496) (xy 90.799066 -223.375442)
			(xy 90.810843 -223.327658) (xy 90.830134 -223.282382) (xy 90.856437 -223.240786) (xy 90.889072 -223.203949)
			(xy 90.927193 -223.172824) (xy 90.969814 -223.148217) (xy 91.01583 -223.130765) (xy 91.064049 -223.120921)
			(xy 91.113224 -223.11894) (xy 91.162079 -223.124872) (xy 91.20935 -223.138564) (xy 91.253812 -223.159662)
			(xy 91.294315 -223.187618) (xy 91.329808 -223.22171) (xy 91.359373 -223.261054) (xy 91.382244 -223.304631)
			(xy 91.397828 -223.351312) (xy 91.405723 -223.399889) (xy 91.406218 -223.424496) (xy 93.615268 -223.424496)
			(xy 93.619228 -223.375442) (xy 93.631005 -223.327658) (xy 93.650296 -223.282382) (xy 93.676599 -223.240786)
			(xy 93.709234 -223.203949) (xy 93.747355 -223.172824) (xy 93.789976 -223.148217) (xy 93.835992 -223.130765)
			(xy 93.884211 -223.120921) (xy 93.933386 -223.11894) (xy 93.982241 -223.124872) (xy 94.029512 -223.138564)
			(xy 94.073974 -223.159662) (xy 94.114477 -223.187618) (xy 94.14997 -223.22171) (xy 94.179535 -223.261054)
			(xy 94.202406 -223.304631) (xy 94.21799 -223.351312) (xy 94.225885 -223.399889) (xy 94.22638 -223.424496)
			(xy 94.555322 -223.424496) (xy 94.559282 -223.375442) (xy 94.571059 -223.327658) (xy 94.59035 -223.282382)
			(xy 94.616653 -223.240786) (xy 94.649288 -223.203949) (xy 94.687409 -223.172824) (xy 94.73003 -223.148217)
			(xy 94.776046 -223.130765) (xy 94.824265 -223.120921) (xy 94.87344 -223.11894) (xy 94.922295 -223.124872)
			(xy 94.969566 -223.138564) (xy 95.014028 -223.159662) (xy 95.054531 -223.187618) (xy 95.090024 -223.22171)
			(xy 95.119589 -223.261054) (xy 95.14246 -223.304631) (xy 95.158044 -223.351312) (xy 95.165939 -223.399889)
			(xy 95.166434 -223.424496) (xy 95.495122 -223.424496) (xy 95.499082 -223.375442) (xy 95.510859 -223.327658)
			(xy 95.53015 -223.282382) (xy 95.556453 -223.240786) (xy 95.589088 -223.203949) (xy 95.627209 -223.172824)
			(xy 95.66983 -223.148217) (xy 95.715846 -223.130765) (xy 95.764065 -223.120921) (xy 95.81324 -223.11894)
			(xy 95.862095 -223.124872) (xy 95.909366 -223.138564) (xy 95.953828 -223.159662) (xy 95.994331 -223.187618)
			(xy 96.029824 -223.22171) (xy 96.059389 -223.261054) (xy 96.08226 -223.304631) (xy 96.097844 -223.351312)
			(xy 96.105739 -223.399889) (xy 96.106234 -223.424496) (xy 96.435176 -223.424496) (xy 96.439136 -223.375442)
			(xy 96.450913 -223.327658) (xy 96.470204 -223.282382) (xy 96.496507 -223.240786) (xy 96.529142 -223.203949)
			(xy 96.567263 -223.172824) (xy 96.609884 -223.148217) (xy 96.6559 -223.130765) (xy 96.704119 -223.120921)
			(xy 96.753294 -223.11894) (xy 96.802149 -223.124872) (xy 96.84942 -223.138564) (xy 96.893882 -223.159662)
			(xy 96.934385 -223.187618) (xy 96.969878 -223.22171) (xy 96.999443 -223.261054) (xy 97.022314 -223.304631)
			(xy 97.037898 -223.351312) (xy 97.045793 -223.399889) (xy 97.046288 -223.424496) (xy 97.37523 -223.424496)
			(xy 97.37919 -223.375442) (xy 97.390967 -223.327658) (xy 97.410258 -223.282382) (xy 97.436561 -223.240786)
			(xy 97.469196 -223.203949) (xy 97.507317 -223.172824) (xy 97.549938 -223.148217) (xy 97.595954 -223.130765)
			(xy 97.644173 -223.120921) (xy 97.693348 -223.11894) (xy 97.742203 -223.124872) (xy 97.789474 -223.138564)
			(xy 97.833936 -223.159662) (xy 97.874439 -223.187618) (xy 97.909932 -223.22171) (xy 97.939497 -223.261054)
			(xy 97.962368 -223.304631) (xy 97.977952 -223.351312) (xy 97.985847 -223.399889) (xy 97.986342 -223.424496)
			(xy 98.315284 -223.424496) (xy 98.319244 -223.375442) (xy 98.331021 -223.327658) (xy 98.350312 -223.282382)
			(xy 98.376615 -223.240786) (xy 98.40925 -223.203949) (xy 98.447371 -223.172824) (xy 98.489992 -223.148217)
			(xy 98.536008 -223.130765) (xy 98.584227 -223.120921) (xy 98.633402 -223.11894) (xy 98.682257 -223.124872)
			(xy 98.729528 -223.138564) (xy 98.77399 -223.159662) (xy 98.814493 -223.187618) (xy 98.849986 -223.22171)
			(xy 98.879551 -223.261054) (xy 98.902422 -223.304631) (xy 98.918006 -223.351312) (xy 98.925901 -223.399889)
			(xy 98.926396 -223.424496) (xy 99.255338 -223.424496) (xy 99.259298 -223.375442) (xy 99.271075 -223.327658)
			(xy 99.290366 -223.282382) (xy 99.316669 -223.240786) (xy 99.349304 -223.203949) (xy 99.387425 -223.172824)
			(xy 99.430046 -223.148217) (xy 99.476062 -223.130765) (xy 99.524281 -223.120921) (xy 99.573456 -223.11894)
			(xy 99.622311 -223.124872) (xy 99.669582 -223.138564) (xy 99.714044 -223.159662) (xy 99.754547 -223.187618)
			(xy 99.79004 -223.22171) (xy 99.819605 -223.261054) (xy 99.842476 -223.304631) (xy 99.85806 -223.351312)
			(xy 99.865955 -223.399889) (xy 99.86645 -223.424496) (xy 100.195138 -223.424496) (xy 100.199098 -223.375442)
			(xy 100.210875 -223.327658) (xy 100.230166 -223.282382) (xy 100.256469 -223.240786) (xy 100.289104 -223.203949)
			(xy 100.327225 -223.172824) (xy 100.369846 -223.148217) (xy 100.415862 -223.130765) (xy 100.464081 -223.120921)
			(xy 100.513256 -223.11894) (xy 100.562111 -223.124872) (xy 100.609382 -223.138564) (xy 100.653844 -223.159662)
			(xy 100.694347 -223.187618) (xy 100.72984 -223.22171) (xy 100.759405 -223.261054) (xy 100.782276 -223.304631)
			(xy 100.79786 -223.351312) (xy 100.805755 -223.399889) (xy 100.80625 -223.424496) (xy 101.135192 -223.424496)
			(xy 101.139152 -223.375442) (xy 101.150929 -223.327658) (xy 101.17022 -223.282382) (xy 101.196523 -223.240786)
			(xy 101.229158 -223.203949) (xy 101.267279 -223.172824) (xy 101.3099 -223.148217) (xy 101.355916 -223.130765)
			(xy 101.404135 -223.120921) (xy 101.45331 -223.11894) (xy 101.502165 -223.124872) (xy 101.549436 -223.138564)
			(xy 101.593898 -223.159662) (xy 101.634401 -223.187618) (xy 101.669894 -223.22171) (xy 101.699459 -223.261054)
			(xy 101.72233 -223.304631) (xy 101.737914 -223.351312) (xy 101.745809 -223.399889) (xy 101.746304 -223.424496)
			(xy 102.075246 -223.424496) (xy 102.079206 -223.375442) (xy 102.090983 -223.327658) (xy 102.110274 -223.282382)
			(xy 102.136577 -223.240786) (xy 102.169212 -223.203949) (xy 102.207333 -223.172824) (xy 102.249954 -223.148217)
			(xy 102.29597 -223.130765) (xy 102.344189 -223.120921) (xy 102.393364 -223.11894) (xy 102.442219 -223.124872)
			(xy 102.48949 -223.138564) (xy 102.533952 -223.159662) (xy 102.574455 -223.187618) (xy 102.609948 -223.22171)
			(xy 102.639513 -223.261054) (xy 102.662384 -223.304631) (xy 102.677968 -223.351312) (xy 102.685863 -223.399889)
			(xy 102.686358 -223.424496) (xy 103.0153 -223.424496) (xy 103.01926 -223.375442) (xy 103.031037 -223.327658)
			(xy 103.050328 -223.282382) (xy 103.076631 -223.240786) (xy 103.109266 -223.203949) (xy 103.147387 -223.172824)
			(xy 103.190008 -223.148217) (xy 103.236024 -223.130765) (xy 103.284243 -223.120921) (xy 103.333418 -223.11894)
			(xy 103.382273 -223.124872) (xy 103.429544 -223.138564) (xy 103.474006 -223.159662) (xy 103.514509 -223.187618)
			(xy 103.550002 -223.22171) (xy 103.579567 -223.261054) (xy 103.602438 -223.304631) (xy 103.618022 -223.351312)
			(xy 103.625917 -223.399889) (xy 103.626412 -223.424496) (xy 109.59517 -223.424496) (xy 109.59913 -223.375442)
			(xy 109.610907 -223.327658) (xy 109.630198 -223.282382) (xy 109.656501 -223.240786) (xy 109.689136 -223.203949)
			(xy 109.727257 -223.172824) (xy 109.769878 -223.148217) (xy 109.815894 -223.130765) (xy 109.864113 -223.120921)
			(xy 109.913288 -223.11894) (xy 109.962143 -223.124872) (xy 110.009414 -223.138564) (xy 110.053876 -223.159662)
			(xy 110.094379 -223.187618) (xy 110.129872 -223.22171) (xy 110.159437 -223.261054) (xy 110.182308 -223.304631)
			(xy 110.197892 -223.351312) (xy 110.205787 -223.399889) (xy 110.206282 -223.424496) (xy 110.205787 -223.449103)
			(xy 110.197892 -223.49768) (xy 110.182308 -223.544361) (xy 110.159437 -223.587938) (xy 110.129872 -223.627282)
			(xy 110.094379 -223.661374) (xy 110.053876 -223.68933) (xy 110.009414 -223.710428) (xy 109.962143 -223.72412)
			(xy 109.913288 -223.730052) (xy 109.864113 -223.728071) (xy 109.815894 -223.718227) (xy 109.769878 -223.700775)
			(xy 109.727257 -223.676168) (xy 109.689136 -223.645043) (xy 109.656501 -223.608206) (xy 109.630198 -223.56661)
			(xy 109.610907 -223.521334) (xy 109.59913 -223.47355) (xy 109.59517 -223.424496) (xy 103.626412 -223.424496)
			(xy 103.625917 -223.449103) (xy 103.618022 -223.49768) (xy 103.602438 -223.544361) (xy 103.579567 -223.587938)
			(xy 103.550002 -223.627282) (xy 103.514509 -223.661374) (xy 103.474006 -223.68933) (xy 103.429544 -223.710428)
			(xy 103.382273 -223.72412) (xy 103.333418 -223.730052) (xy 103.284243 -223.728071) (xy 103.236024 -223.718227)
			(xy 103.190008 -223.700775) (xy 103.147387 -223.676168) (xy 103.109266 -223.645043) (xy 103.076631 -223.608206)
			(xy 103.050328 -223.56661) (xy 103.031037 -223.521334) (xy 103.01926 -223.47355) (xy 103.0153 -223.424496)
			(xy 102.686358 -223.424496) (xy 102.685863 -223.449103) (xy 102.677968 -223.49768) (xy 102.662384 -223.544361)
			(xy 102.639513 -223.587938) (xy 102.609948 -223.627282) (xy 102.574455 -223.661374) (xy 102.533952 -223.68933)
			(xy 102.48949 -223.710428) (xy 102.442219 -223.72412) (xy 102.393364 -223.730052) (xy 102.344189 -223.728071)
			(xy 102.29597 -223.718227) (xy 102.249954 -223.700775) (xy 102.207333 -223.676168) (xy 102.169212 -223.645043)
			(xy 102.136577 -223.608206) (xy 102.110274 -223.56661) (xy 102.090983 -223.521334) (xy 102.079206 -223.47355)
			(xy 102.075246 -223.424496) (xy 101.746304 -223.424496) (xy 101.745809 -223.449103) (xy 101.737914 -223.49768)
			(xy 101.72233 -223.544361) (xy 101.699459 -223.587938) (xy 101.669894 -223.627282) (xy 101.634401 -223.661374)
			(xy 101.593898 -223.68933) (xy 101.549436 -223.710428) (xy 101.502165 -223.72412) (xy 101.45331 -223.730052)
			(xy 101.404135 -223.728071) (xy 101.355916 -223.718227) (xy 101.3099 -223.700775) (xy 101.267279 -223.676168)
			(xy 101.229158 -223.645043) (xy 101.196523 -223.608206) (xy 101.17022 -223.56661) (xy 101.150929 -223.521334)
			(xy 101.139152 -223.47355) (xy 101.135192 -223.424496) (xy 100.80625 -223.424496) (xy 100.805755 -223.449103)
			(xy 100.79786 -223.49768) (xy 100.782276 -223.544361) (xy 100.759405 -223.587938) (xy 100.72984 -223.627282)
			(xy 100.694347 -223.661374) (xy 100.653844 -223.68933) (xy 100.609382 -223.710428) (xy 100.562111 -223.72412)
			(xy 100.513256 -223.730052) (xy 100.464081 -223.728071) (xy 100.415862 -223.718227) (xy 100.369846 -223.700775)
			(xy 100.327225 -223.676168) (xy 100.289104 -223.645043) (xy 100.256469 -223.608206) (xy 100.230166 -223.56661)
			(xy 100.210875 -223.521334) (xy 100.199098 -223.47355) (xy 100.195138 -223.424496) (xy 99.86645 -223.424496)
			(xy 99.865955 -223.449103) (xy 99.85806 -223.49768) (xy 99.842476 -223.544361) (xy 99.819605 -223.587938)
			(xy 99.79004 -223.627282) (xy 99.754547 -223.661374) (xy 99.714044 -223.68933) (xy 99.669582 -223.710428)
			(xy 99.622311 -223.72412) (xy 99.573456 -223.730052) (xy 99.524281 -223.728071) (xy 99.476062 -223.718227)
			(xy 99.430046 -223.700775) (xy 99.387425 -223.676168) (xy 99.349304 -223.645043) (xy 99.316669 -223.608206)
			(xy 99.290366 -223.56661) (xy 99.271075 -223.521334) (xy 99.259298 -223.47355) (xy 99.255338 -223.424496)
			(xy 98.926396 -223.424496) (xy 98.925901 -223.449103) (xy 98.918006 -223.49768) (xy 98.902422 -223.544361)
			(xy 98.879551 -223.587938) (xy 98.849986 -223.627282) (xy 98.814493 -223.661374) (xy 98.77399 -223.68933)
			(xy 98.729528 -223.710428) (xy 98.682257 -223.72412) (xy 98.633402 -223.730052) (xy 98.584227 -223.728071)
			(xy 98.536008 -223.718227) (xy 98.489992 -223.700775) (xy 98.447371 -223.676168) (xy 98.40925 -223.645043)
			(xy 98.376615 -223.608206) (xy 98.350312 -223.56661) (xy 98.331021 -223.521334) (xy 98.319244 -223.47355)
			(xy 98.315284 -223.424496) (xy 97.986342 -223.424496) (xy 97.985847 -223.449103) (xy 97.977952 -223.49768)
			(xy 97.962368 -223.544361) (xy 97.939497 -223.587938) (xy 97.909932 -223.627282) (xy 97.874439 -223.661374)
			(xy 97.833936 -223.68933) (xy 97.789474 -223.710428) (xy 97.742203 -223.72412) (xy 97.693348 -223.730052)
			(xy 97.644173 -223.728071) (xy 97.595954 -223.718227) (xy 97.549938 -223.700775) (xy 97.507317 -223.676168)
			(xy 97.469196 -223.645043) (xy 97.436561 -223.608206) (xy 97.410258 -223.56661) (xy 97.390967 -223.521334)
			(xy 97.37919 -223.47355) (xy 97.37523 -223.424496) (xy 97.046288 -223.424496) (xy 97.045793 -223.449103)
			(xy 97.037898 -223.49768) (xy 97.022314 -223.544361) (xy 96.999443 -223.587938) (xy 96.969878 -223.627282)
			(xy 96.934385 -223.661374) (xy 96.893882 -223.68933) (xy 96.84942 -223.710428) (xy 96.802149 -223.72412)
			(xy 96.753294 -223.730052) (xy 96.704119 -223.728071) (xy 96.6559 -223.718227) (xy 96.609884 -223.700775)
			(xy 96.567263 -223.676168) (xy 96.529142 -223.645043) (xy 96.496507 -223.608206) (xy 96.470204 -223.56661)
			(xy 96.450913 -223.521334) (xy 96.439136 -223.47355) (xy 96.435176 -223.424496) (xy 96.106234 -223.424496)
			(xy 96.105739 -223.449103) (xy 96.097844 -223.49768) (xy 96.08226 -223.544361) (xy 96.059389 -223.587938)
			(xy 96.029824 -223.627282) (xy 95.994331 -223.661374) (xy 95.953828 -223.68933) (xy 95.909366 -223.710428)
			(xy 95.862095 -223.72412) (xy 95.81324 -223.730052) (xy 95.764065 -223.728071) (xy 95.715846 -223.718227)
			(xy 95.66983 -223.700775) (xy 95.627209 -223.676168) (xy 95.589088 -223.645043) (xy 95.556453 -223.608206)
			(xy 95.53015 -223.56661) (xy 95.510859 -223.521334) (xy 95.499082 -223.47355) (xy 95.495122 -223.424496)
			(xy 95.166434 -223.424496) (xy 95.165939 -223.449103) (xy 95.158044 -223.49768) (xy 95.14246 -223.544361)
			(xy 95.119589 -223.587938) (xy 95.090024 -223.627282) (xy 95.054531 -223.661374) (xy 95.014028 -223.68933)
			(xy 94.969566 -223.710428) (xy 94.922295 -223.72412) (xy 94.87344 -223.730052) (xy 94.824265 -223.728071)
			(xy 94.776046 -223.718227) (xy 94.73003 -223.700775) (xy 94.687409 -223.676168) (xy 94.649288 -223.645043)
			(xy 94.616653 -223.608206) (xy 94.59035 -223.56661) (xy 94.571059 -223.521334) (xy 94.559282 -223.47355)
			(xy 94.555322 -223.424496) (xy 94.22638 -223.424496) (xy 94.225885 -223.449103) (xy 94.21799 -223.49768)
			(xy 94.202406 -223.544361) (xy 94.179535 -223.587938) (xy 94.14997 -223.627282) (xy 94.114477 -223.661374)
			(xy 94.073974 -223.68933) (xy 94.029512 -223.710428) (xy 93.982241 -223.72412) (xy 93.933386 -223.730052)
			(xy 93.884211 -223.728071) (xy 93.835992 -223.718227) (xy 93.789976 -223.700775) (xy 93.747355 -223.676168)
			(xy 93.709234 -223.645043) (xy 93.676599 -223.608206) (xy 93.650296 -223.56661) (xy 93.631005 -223.521334)
			(xy 93.619228 -223.47355) (xy 93.615268 -223.424496) (xy 91.406218 -223.424496) (xy 91.405723 -223.449103)
			(xy 91.397828 -223.49768) (xy 91.382244 -223.544361) (xy 91.359373 -223.587938) (xy 91.329808 -223.627282)
			(xy 91.294315 -223.661374) (xy 91.253812 -223.68933) (xy 91.20935 -223.710428) (xy 91.162079 -223.72412)
			(xy 91.113224 -223.730052) (xy 91.064049 -223.728071) (xy 91.01583 -223.718227) (xy 90.969814 -223.700775)
			(xy 90.927193 -223.676168) (xy 90.889072 -223.645043) (xy 90.856437 -223.608206) (xy 90.830134 -223.56661)
			(xy 90.810843 -223.521334) (xy 90.799066 -223.47355) (xy 90.795106 -223.424496) (xy 90.466418 -223.424496)
			(xy 90.465923 -223.449103) (xy 90.458028 -223.49768) (xy 90.442444 -223.544361) (xy 90.419573 -223.587938)
			(xy 90.390008 -223.627282) (xy 90.354515 -223.661374) (xy 90.314012 -223.68933) (xy 90.26955 -223.710428)
			(xy 90.222279 -223.72412) (xy 90.173424 -223.730052) (xy 90.124249 -223.728071) (xy 90.07603 -223.718227)
			(xy 90.030014 -223.700775) (xy 89.987393 -223.676168) (xy 89.949272 -223.645043) (xy 89.916637 -223.608206)
			(xy 89.890334 -223.56661) (xy 89.871043 -223.521334) (xy 89.859266 -223.47355) (xy 89.855306 -223.424496)
			(xy 89.526332 -223.424496) (xy 89.526123 -223.434879) (xy 89.518228 -223.483456) (xy 89.502644 -223.530137)
			(xy 89.479773 -223.573714) (xy 89.450208 -223.613058) (xy 89.414715 -223.64715) (xy 89.374212 -223.675106)
			(xy 89.32975 -223.696204) (xy 89.282479 -223.709896) (xy 89.233624 -223.715828) (xy 89.184449 -223.713847)
			(xy 89.13623 -223.704003) (xy 89.090214 -223.686551) (xy 89.047593 -223.661944) (xy 89.009472 -223.630819)
			(xy 88.976837 -223.593982) (xy 88.950534 -223.552386) (xy 88.931243 -223.50711) (xy 88.919466 -223.459326)
			(xy 88.915506 -223.410272) (xy 87.645951 -223.410272) (xy 87.646256 -223.424496) (xy 87.645845 -223.447119)
			(xy 87.639163 -223.491868) (xy 87.625944 -223.535139) (xy 87.606479 -223.575983) (xy 87.581195 -223.613504)
			(xy 87.566246 -223.63049) (xy 87.559896 -223.637602) (xy 87.553038 -223.65462) (xy 87.552784 -223.694752)
			(xy 87.553092 -223.703716) (xy 87.559062 -223.720615) (xy 87.564468 -223.727772) (xy 87.565992 -223.72955)
			(xy 87.759286 -223.922844) (xy 87.77986 -223.930718) (xy 87.790782 -223.929956) (xy 87.811102 -223.929194)
			(xy 87.835093 -223.929665) (xy 87.882484 -223.937171) (xy 87.928118 -223.951999) (xy 87.97087 -223.973782)
			(xy 88.009688 -224.001986) (xy 88.043617 -224.035915) (xy 88.07182 -224.074733) (xy 88.093603 -224.117486)
			(xy 88.10843 -224.163119) (xy 88.115936 -224.210511) (xy 88.11641 -224.234502) (xy 89.385152 -224.234502)
			(xy 89.389112 -224.185448) (xy 89.400889 -224.137664) (xy 89.42018 -224.092388) (xy 89.446483 -224.050792)
			(xy 89.479118 -224.013955) (xy 89.517239 -223.98283) (xy 89.55986 -223.958223) (xy 89.605876 -223.940771)
			(xy 89.654095 -223.930927) (xy 89.70327 -223.928946) (xy 89.752125 -223.934878) (xy 89.799396 -223.94857)
			(xy 89.843858 -223.969668) (xy 89.884361 -223.997624) (xy 89.919854 -224.031716) (xy 89.949419 -224.07106)
			(xy 89.97229 -224.114637) (xy 89.987874 -224.161318) (xy 89.995769 -224.209895) (xy 89.996264 -224.234502)
			(xy 90.325206 -224.234502) (xy 90.329166 -224.185448) (xy 90.340943 -224.137664) (xy 90.360234 -224.092388)
			(xy 90.386537 -224.050792) (xy 90.419172 -224.013955) (xy 90.457293 -223.98283) (xy 90.499914 -223.958223)
			(xy 90.54593 -223.940771) (xy 90.594149 -223.930927) (xy 90.643324 -223.928946) (xy 90.692179 -223.934878)
			(xy 90.73945 -223.94857) (xy 90.783912 -223.969668) (xy 90.824415 -223.997624) (xy 90.859908 -224.031716)
			(xy 90.889473 -224.07106) (xy 90.912344 -224.114637) (xy 90.927928 -224.161318) (xy 90.935823 -224.209895)
			(xy 90.936318 -224.234502) (xy 91.26526 -224.234502) (xy 91.26922 -224.185448) (xy 91.280997 -224.137664)
			(xy 91.300288 -224.092388) (xy 91.326591 -224.050792) (xy 91.359226 -224.013955) (xy 91.397347 -223.98283)
			(xy 91.439968 -223.958223) (xy 91.485984 -223.940771) (xy 91.534203 -223.930927) (xy 91.583378 -223.928946)
			(xy 91.632233 -223.934878) (xy 91.679504 -223.94857) (xy 91.723966 -223.969668) (xy 91.764469 -223.997624)
			(xy 91.799962 -224.031716) (xy 91.829527 -224.07106) (xy 91.852398 -224.114637) (xy 91.867982 -224.161318)
			(xy 91.875877 -224.209895) (xy 91.876372 -224.234502) (xy 93.145114 -224.234502) (xy 93.149074 -224.185448)
			(xy 93.160851 -224.137664) (xy 93.180142 -224.092388) (xy 93.206445 -224.050792) (xy 93.23908 -224.013955)
			(xy 93.277201 -223.98283) (xy 93.319822 -223.958223) (xy 93.365838 -223.940771) (xy 93.414057 -223.930927)
			(xy 93.463232 -223.928946) (xy 93.512087 -223.934878) (xy 93.559358 -223.94857) (xy 93.60382 -223.969668)
			(xy 93.644323 -223.997624) (xy 93.679816 -224.031716) (xy 93.709381 -224.07106) (xy 93.732252 -224.114637)
			(xy 93.747836 -224.161318) (xy 93.755731 -224.209895) (xy 93.756226 -224.234502) (xy 95.965276 -224.234502)
			(xy 95.969236 -224.185448) (xy 95.981013 -224.137664) (xy 96.000304 -224.092388) (xy 96.026607 -224.050792)
			(xy 96.059242 -224.013955) (xy 96.097363 -223.98283) (xy 96.139984 -223.958223) (xy 96.186 -223.940771)
			(xy 96.234219 -223.930927) (xy 96.283394 -223.928946) (xy 96.332249 -223.934878) (xy 96.37952 -223.94857)
			(xy 96.423982 -223.969668) (xy 96.464485 -223.997624) (xy 96.499978 -224.031716) (xy 96.529543 -224.07106)
			(xy 96.552414 -224.114637) (xy 96.567998 -224.161318) (xy 96.575893 -224.209895) (xy 96.576388 -224.234502)
			(xy 96.90533 -224.234502) (xy 96.90929 -224.185448) (xy 96.921067 -224.137664) (xy 96.940358 -224.092388)
			(xy 96.966661 -224.050792) (xy 96.999296 -224.013955) (xy 97.037417 -223.98283) (xy 97.080038 -223.958223)
			(xy 97.126054 -223.940771) (xy 97.174273 -223.930927) (xy 97.223448 -223.928946) (xy 97.272303 -223.934878)
			(xy 97.319574 -223.94857) (xy 97.364036 -223.969668) (xy 97.404539 -223.997624) (xy 97.440032 -224.031716)
			(xy 97.469597 -224.07106) (xy 97.492468 -224.114637) (xy 97.508052 -224.161318) (xy 97.515947 -224.209895)
			(xy 97.516442 -224.234502) (xy 97.84513 -224.234502) (xy 97.84909 -224.185448) (xy 97.860867 -224.137664)
			(xy 97.880158 -224.092388) (xy 97.906461 -224.050792) (xy 97.939096 -224.013955) (xy 97.977217 -223.98283)
			(xy 98.019838 -223.958223) (xy 98.065854 -223.940771) (xy 98.114073 -223.930927) (xy 98.163248 -223.928946)
			(xy 98.212103 -223.934878) (xy 98.259374 -223.94857) (xy 98.303836 -223.969668) (xy 98.344339 -223.997624)
			(xy 98.379832 -224.031716) (xy 98.409397 -224.07106) (xy 98.432268 -224.114637) (xy 98.447852 -224.161318)
			(xy 98.455747 -224.209895) (xy 98.456242 -224.234502) (xy 98.785184 -224.234502) (xy 98.789144 -224.185448)
			(xy 98.800921 -224.137664) (xy 98.820212 -224.092388) (xy 98.846515 -224.050792) (xy 98.87915 -224.013955)
			(xy 98.917271 -223.98283) (xy 98.959892 -223.958223) (xy 99.005908 -223.940771) (xy 99.054127 -223.930927)
			(xy 99.103302 -223.928946) (xy 99.152157 -223.934878) (xy 99.199428 -223.94857) (xy 99.24389 -223.969668)
			(xy 99.284393 -223.997624) (xy 99.319886 -224.031716) (xy 99.349451 -224.07106) (xy 99.372322 -224.114637)
			(xy 99.387906 -224.161318) (xy 99.395801 -224.209895) (xy 99.396296 -224.234502) (xy 99.725238 -224.234502)
			(xy 99.729198 -224.185448) (xy 99.740975 -224.137664) (xy 99.760266 -224.092388) (xy 99.786569 -224.050792)
			(xy 99.819204 -224.013955) (xy 99.857325 -223.98283) (xy 99.899946 -223.958223) (xy 99.945962 -223.940771)
			(xy 99.994181 -223.930927) (xy 100.043356 -223.928946) (xy 100.092211 -223.934878) (xy 100.139482 -223.94857)
			(xy 100.183944 -223.969668) (xy 100.224447 -223.997624) (xy 100.25994 -224.031716) (xy 100.289505 -224.07106)
			(xy 100.312376 -224.114637) (xy 100.32796 -224.161318) (xy 100.335855 -224.209895) (xy 100.33635 -224.234502)
			(xy 100.665292 -224.234502) (xy 100.669252 -224.185448) (xy 100.681029 -224.137664) (xy 100.70032 -224.092388)
			(xy 100.726623 -224.050792) (xy 100.759258 -224.013955) (xy 100.797379 -223.98283) (xy 100.84 -223.958223)
			(xy 100.886016 -223.940771) (xy 100.934235 -223.930927) (xy 100.98341 -223.928946) (xy 101.032265 -223.934878)
			(xy 101.079536 -223.94857) (xy 101.123998 -223.969668) (xy 101.164501 -223.997624) (xy 101.199994 -224.031716)
			(xy 101.229559 -224.07106) (xy 101.25243 -224.114637) (xy 101.268014 -224.161318) (xy 101.275909 -224.209895)
			(xy 101.276404 -224.234502) (xy 101.605346 -224.234502) (xy 101.609306 -224.185448) (xy 101.621083 -224.137664)
			(xy 101.640374 -224.092388) (xy 101.666677 -224.050792) (xy 101.699312 -224.013955) (xy 101.737433 -223.98283)
			(xy 101.780054 -223.958223) (xy 101.82607 -223.940771) (xy 101.874289 -223.930927) (xy 101.923464 -223.928946)
			(xy 101.972319 -223.934878) (xy 102.01959 -223.94857) (xy 102.064052 -223.969668) (xy 102.104555 -223.997624)
			(xy 102.140048 -224.031716) (xy 102.169613 -224.07106) (xy 102.192484 -224.114637) (xy 102.208068 -224.161318)
			(xy 102.215963 -224.209895) (xy 102.216458 -224.234502) (xy 102.545146 -224.234502) (xy 102.549106 -224.185448)
			(xy 102.560883 -224.137664) (xy 102.580174 -224.092388) (xy 102.606477 -224.050792) (xy 102.639112 -224.013955)
			(xy 102.677233 -223.98283) (xy 102.719854 -223.958223) (xy 102.76587 -223.940771) (xy 102.814089 -223.930927)
			(xy 102.863264 -223.928946) (xy 102.912119 -223.934878) (xy 102.95939 -223.94857) (xy 103.003852 -223.969668)
			(xy 103.044355 -223.997624) (xy 103.079848 -224.031716) (xy 103.109413 -224.07106) (xy 103.132284 -224.114637)
			(xy 103.147868 -224.161318) (xy 103.155763 -224.209895) (xy 103.156258 -224.234502) (xy 103.4852 -224.234502)
			(xy 103.48916 -224.185448) (xy 103.500937 -224.137664) (xy 103.520228 -224.092388) (xy 103.546531 -224.050792)
			(xy 103.579166 -224.013955) (xy 103.617287 -223.98283) (xy 103.659908 -223.958223) (xy 103.705924 -223.940771)
			(xy 103.754143 -223.930927) (xy 103.803318 -223.928946) (xy 103.852173 -223.934878) (xy 103.899444 -223.94857)
			(xy 103.943906 -223.969668) (xy 103.984409 -223.997624) (xy 104.019902 -224.031716) (xy 104.049467 -224.07106)
			(xy 104.072338 -224.114637) (xy 104.087922 -224.161318) (xy 104.095817 -224.209895) (xy 104.096312 -224.234502)
			(xy 104.425254 -224.234502) (xy 104.429214 -224.185448) (xy 104.440991 -224.137664) (xy 104.460282 -224.092388)
			(xy 104.486585 -224.050792) (xy 104.51922 -224.013955) (xy 104.557341 -223.98283) (xy 104.599962 -223.958223)
			(xy 104.645978 -223.940771) (xy 104.694197 -223.930927) (xy 104.743372 -223.928946) (xy 104.792227 -223.934878)
			(xy 104.839498 -223.94857) (xy 104.88396 -223.969668) (xy 104.924463 -223.997624) (xy 104.959956 -224.031716)
			(xy 104.989521 -224.07106) (xy 105.012392 -224.114637) (xy 105.027976 -224.161318) (xy 105.035871 -224.209895)
			(xy 105.036366 -224.234502) (xy 105.365308 -224.234502) (xy 105.369268 -224.185448) (xy 105.381045 -224.137664)
			(xy 105.400336 -224.092388) (xy 105.426639 -224.050792) (xy 105.459274 -224.013955) (xy 105.497395 -223.98283)
			(xy 105.540016 -223.958223) (xy 105.586032 -223.940771) (xy 105.634251 -223.930927) (xy 105.683426 -223.928946)
			(xy 105.732281 -223.934878) (xy 105.779552 -223.94857) (xy 105.824014 -223.969668) (xy 105.864517 -223.997624)
			(xy 105.90001 -224.031716) (xy 105.929575 -224.07106) (xy 105.952446 -224.114637) (xy 105.96803 -224.161318)
			(xy 105.975925 -224.209895) (xy 105.97642 -224.234502) (xy 106.305362 -224.234502) (xy 106.309322 -224.185448)
			(xy 106.321099 -224.137664) (xy 106.34039 -224.092388) (xy 106.366693 -224.050792) (xy 106.399328 -224.013955)
			(xy 106.437449 -223.98283) (xy 106.48007 -223.958223) (xy 106.526086 -223.940771) (xy 106.574305 -223.930927)
			(xy 106.62348 -223.928946) (xy 106.672335 -223.934878) (xy 106.719606 -223.94857) (xy 106.764068 -223.969668)
			(xy 106.804571 -223.997624) (xy 106.840064 -224.031716) (xy 106.869629 -224.07106) (xy 106.8925 -224.114637)
			(xy 106.908084 -224.161318) (xy 106.915979 -224.209895) (xy 106.916474 -224.234502) (xy 108.185216 -224.234502)
			(xy 108.189176 -224.185448) (xy 108.200953 -224.137664) (xy 108.220244 -224.092388) (xy 108.246547 -224.050792)
			(xy 108.279182 -224.013955) (xy 108.317303 -223.98283) (xy 108.359924 -223.958223) (xy 108.40594 -223.940771)
			(xy 108.454159 -223.930927) (xy 108.503334 -223.928946) (xy 108.552189 -223.934878) (xy 108.59946 -223.94857)
			(xy 108.643922 -223.969668) (xy 108.684425 -223.997624) (xy 108.719918 -224.031716) (xy 108.749483 -224.07106)
			(xy 108.772354 -224.114637) (xy 108.787938 -224.161318) (xy 108.795833 -224.209895) (xy 108.796328 -224.234502)
			(xy 109.12527 -224.234502) (xy 109.12923 -224.185448) (xy 109.141007 -224.137664) (xy 109.160298 -224.092388)
			(xy 109.186601 -224.050792) (xy 109.219236 -224.013955) (xy 109.257357 -223.98283) (xy 109.299978 -223.958223)
			(xy 109.345994 -223.940771) (xy 109.394213 -223.930927) (xy 109.443388 -223.928946) (xy 109.492243 -223.934878)
			(xy 109.539514 -223.94857) (xy 109.583976 -223.969668) (xy 109.624479 -223.997624) (xy 109.659972 -224.031716)
			(xy 109.689537 -224.07106) (xy 109.712408 -224.114637) (xy 109.727992 -224.161318) (xy 109.735887 -224.209895)
			(xy 109.736382 -224.234502) (xy 109.735887 -224.259109) (xy 109.727992 -224.307686) (xy 109.712408 -224.354367)
			(xy 109.689537 -224.397944) (xy 109.659972 -224.437288) (xy 109.624479 -224.47138) (xy 109.583976 -224.499336)
			(xy 109.539514 -224.520434) (xy 109.492243 -224.534126) (xy 109.443388 -224.540058) (xy 109.394213 -224.538077)
			(xy 109.345994 -224.528233) (xy 109.299978 -224.510781) (xy 109.257357 -224.486174) (xy 109.219236 -224.455049)
			(xy 109.186601 -224.418212) (xy 109.160298 -224.376616) (xy 109.141007 -224.33134) (xy 109.12923 -224.283556)
			(xy 109.12527 -224.234502) (xy 108.796328 -224.234502) (xy 108.795833 -224.259109) (xy 108.787938 -224.307686)
			(xy 108.772354 -224.354367) (xy 108.749483 -224.397944) (xy 108.719918 -224.437288) (xy 108.684425 -224.47138)
			(xy 108.643922 -224.499336) (xy 108.59946 -224.520434) (xy 108.552189 -224.534126) (xy 108.503334 -224.540058)
			(xy 108.454159 -224.538077) (xy 108.40594 -224.528233) (xy 108.359924 -224.510781) (xy 108.317303 -224.486174)
			(xy 108.279182 -224.455049) (xy 108.246547 -224.418212) (xy 108.220244 -224.376616) (xy 108.200953 -224.33134)
			(xy 108.189176 -224.283556) (xy 108.185216 -224.234502) (xy 106.916474 -224.234502) (xy 106.915979 -224.259109)
			(xy 106.908084 -224.307686) (xy 106.8925 -224.354367) (xy 106.869629 -224.397944) (xy 106.840064 -224.437288)
			(xy 106.804571 -224.47138) (xy 106.764068 -224.499336) (xy 106.719606 -224.520434) (xy 106.672335 -224.534126)
			(xy 106.62348 -224.540058) (xy 106.574305 -224.538077) (xy 106.526086 -224.528233) (xy 106.48007 -224.510781)
			(xy 106.437449 -224.486174) (xy 106.399328 -224.455049) (xy 106.366693 -224.418212) (xy 106.34039 -224.376616)
			(xy 106.321099 -224.33134) (xy 106.309322 -224.283556) (xy 106.305362 -224.234502) (xy 105.97642 -224.234502)
			(xy 105.975925 -224.259109) (xy 105.96803 -224.307686) (xy 105.952446 -224.354367) (xy 105.929575 -224.397944)
			(xy 105.90001 -224.437288) (xy 105.864517 -224.47138) (xy 105.824014 -224.499336) (xy 105.779552 -224.520434)
			(xy 105.732281 -224.534126) (xy 105.683426 -224.540058) (xy 105.634251 -224.538077) (xy 105.586032 -224.528233)
			(xy 105.540016 -224.510781) (xy 105.497395 -224.486174) (xy 105.459274 -224.455049) (xy 105.426639 -224.418212)
			(xy 105.400336 -224.376616) (xy 105.381045 -224.33134) (xy 105.369268 -224.283556) (xy 105.365308 -224.234502)
			(xy 105.036366 -224.234502) (xy 105.035871 -224.259109) (xy 105.027976 -224.307686) (xy 105.012392 -224.354367)
			(xy 104.989521 -224.397944) (xy 104.959956 -224.437288) (xy 104.924463 -224.47138) (xy 104.88396 -224.499336)
			(xy 104.839498 -224.520434) (xy 104.792227 -224.534126) (xy 104.743372 -224.540058) (xy 104.694197 -224.538077)
			(xy 104.645978 -224.528233) (xy 104.599962 -224.510781) (xy 104.557341 -224.486174) (xy 104.51922 -224.455049)
			(xy 104.486585 -224.418212) (xy 104.460282 -224.376616) (xy 104.440991 -224.33134) (xy 104.429214 -224.283556)
			(xy 104.425254 -224.234502) (xy 104.096312 -224.234502) (xy 104.095817 -224.259109) (xy 104.087922 -224.307686)
			(xy 104.072338 -224.354367) (xy 104.049467 -224.397944) (xy 104.019902 -224.437288) (xy 103.984409 -224.47138)
			(xy 103.943906 -224.499336) (xy 103.899444 -224.520434) (xy 103.852173 -224.534126) (xy 103.803318 -224.540058)
			(xy 103.754143 -224.538077) (xy 103.705924 -224.528233) (xy 103.659908 -224.510781) (xy 103.617287 -224.486174)
			(xy 103.579166 -224.455049) (xy 103.546531 -224.418212) (xy 103.520228 -224.376616) (xy 103.500937 -224.33134)
			(xy 103.48916 -224.283556) (xy 103.4852 -224.234502) (xy 103.156258 -224.234502) (xy 103.155763 -224.259109)
			(xy 103.147868 -224.307686) (xy 103.132284 -224.354367) (xy 103.109413 -224.397944) (xy 103.079848 -224.437288)
			(xy 103.044355 -224.47138) (xy 103.003852 -224.499336) (xy 102.95939 -224.520434) (xy 102.912119 -224.534126)
			(xy 102.863264 -224.540058) (xy 102.814089 -224.538077) (xy 102.76587 -224.528233) (xy 102.719854 -224.510781)
			(xy 102.677233 -224.486174) (xy 102.639112 -224.455049) (xy 102.606477 -224.418212) (xy 102.580174 -224.376616)
			(xy 102.560883 -224.33134) (xy 102.549106 -224.283556) (xy 102.545146 -224.234502) (xy 102.216458 -224.234502)
			(xy 102.215963 -224.259109) (xy 102.208068 -224.307686) (xy 102.192484 -224.354367) (xy 102.169613 -224.397944)
			(xy 102.140048 -224.437288) (xy 102.104555 -224.47138) (xy 102.064052 -224.499336) (xy 102.01959 -224.520434)
			(xy 101.972319 -224.534126) (xy 101.923464 -224.540058) (xy 101.874289 -224.538077) (xy 101.82607 -224.528233)
			(xy 101.780054 -224.510781) (xy 101.737433 -224.486174) (xy 101.699312 -224.455049) (xy 101.666677 -224.418212)
			(xy 101.640374 -224.376616) (xy 101.621083 -224.33134) (xy 101.609306 -224.283556) (xy 101.605346 -224.234502)
			(xy 101.276404 -224.234502) (xy 101.275909 -224.259109) (xy 101.268014 -224.307686) (xy 101.25243 -224.354367)
			(xy 101.229559 -224.397944) (xy 101.199994 -224.437288) (xy 101.164501 -224.47138) (xy 101.123998 -224.499336)
			(xy 101.079536 -224.520434) (xy 101.032265 -224.534126) (xy 100.98341 -224.540058) (xy 100.934235 -224.538077)
			(xy 100.886016 -224.528233) (xy 100.84 -224.510781) (xy 100.797379 -224.486174) (xy 100.759258 -224.455049)
			(xy 100.726623 -224.418212) (xy 100.70032 -224.376616) (xy 100.681029 -224.33134) (xy 100.669252 -224.283556)
			(xy 100.665292 -224.234502) (xy 100.33635 -224.234502) (xy 100.335855 -224.259109) (xy 100.32796 -224.307686)
			(xy 100.312376 -224.354367) (xy 100.289505 -224.397944) (xy 100.25994 -224.437288) (xy 100.224447 -224.47138)
			(xy 100.183944 -224.499336) (xy 100.139482 -224.520434) (xy 100.092211 -224.534126) (xy 100.043356 -224.540058)
			(xy 99.994181 -224.538077) (xy 99.945962 -224.528233) (xy 99.899946 -224.510781) (xy 99.857325 -224.486174)
			(xy 99.819204 -224.455049) (xy 99.786569 -224.418212) (xy 99.760266 -224.376616) (xy 99.740975 -224.33134)
			(xy 99.729198 -224.283556) (xy 99.725238 -224.234502) (xy 99.396296 -224.234502) (xy 99.395801 -224.259109)
			(xy 99.387906 -224.307686) (xy 99.372322 -224.354367) (xy 99.349451 -224.397944) (xy 99.319886 -224.437288)
			(xy 99.284393 -224.47138) (xy 99.24389 -224.499336) (xy 99.199428 -224.520434) (xy 99.152157 -224.534126)
			(xy 99.103302 -224.540058) (xy 99.054127 -224.538077) (xy 99.005908 -224.528233) (xy 98.959892 -224.510781)
			(xy 98.917271 -224.486174) (xy 98.87915 -224.455049) (xy 98.846515 -224.418212) (xy 98.820212 -224.376616)
			(xy 98.800921 -224.33134) (xy 98.789144 -224.283556) (xy 98.785184 -224.234502) (xy 98.456242 -224.234502)
			(xy 98.455747 -224.259109) (xy 98.447852 -224.307686) (xy 98.432268 -224.354367) (xy 98.409397 -224.397944)
			(xy 98.379832 -224.437288) (xy 98.344339 -224.47138) (xy 98.303836 -224.499336) (xy 98.259374 -224.520434)
			(xy 98.212103 -224.534126) (xy 98.163248 -224.540058) (xy 98.114073 -224.538077) (xy 98.065854 -224.528233)
			(xy 98.019838 -224.510781) (xy 97.977217 -224.486174) (xy 97.939096 -224.455049) (xy 97.906461 -224.418212)
			(xy 97.880158 -224.376616) (xy 97.860867 -224.33134) (xy 97.84909 -224.283556) (xy 97.84513 -224.234502)
			(xy 97.516442 -224.234502) (xy 97.515947 -224.259109) (xy 97.508052 -224.307686) (xy 97.492468 -224.354367)
			(xy 97.469597 -224.397944) (xy 97.440032 -224.437288) (xy 97.404539 -224.47138) (xy 97.364036 -224.499336)
			(xy 97.319574 -224.520434) (xy 97.272303 -224.534126) (xy 97.223448 -224.540058) (xy 97.174273 -224.538077)
			(xy 97.126054 -224.528233) (xy 97.080038 -224.510781) (xy 97.037417 -224.486174) (xy 96.999296 -224.455049)
			(xy 96.966661 -224.418212) (xy 96.940358 -224.376616) (xy 96.921067 -224.33134) (xy 96.90929 -224.283556)
			(xy 96.90533 -224.234502) (xy 96.576388 -224.234502) (xy 96.575893 -224.259109) (xy 96.567998 -224.307686)
			(xy 96.552414 -224.354367) (xy 96.529543 -224.397944) (xy 96.499978 -224.437288) (xy 96.464485 -224.47138)
			(xy 96.423982 -224.499336) (xy 96.37952 -224.520434) (xy 96.332249 -224.534126) (xy 96.283394 -224.540058)
			(xy 96.234219 -224.538077) (xy 96.186 -224.528233) (xy 96.139984 -224.510781) (xy 96.097363 -224.486174)
			(xy 96.059242 -224.455049) (xy 96.026607 -224.418212) (xy 96.000304 -224.376616) (xy 95.981013 -224.33134)
			(xy 95.969236 -224.283556) (xy 95.965276 -224.234502) (xy 93.756226 -224.234502) (xy 93.755731 -224.259109)
			(xy 93.747836 -224.307686) (xy 93.732252 -224.354367) (xy 93.709381 -224.397944) (xy 93.679816 -224.437288)
			(xy 93.644323 -224.47138) (xy 93.60382 -224.499336) (xy 93.559358 -224.520434) (xy 93.512087 -224.534126)
			(xy 93.463232 -224.540058) (xy 93.414057 -224.538077) (xy 93.365838 -224.528233) (xy 93.319822 -224.510781)
			(xy 93.277201 -224.486174) (xy 93.23908 -224.455049) (xy 93.206445 -224.418212) (xy 93.180142 -224.376616)
			(xy 93.160851 -224.33134) (xy 93.149074 -224.283556) (xy 93.145114 -224.234502) (xy 91.876372 -224.234502)
			(xy 91.875877 -224.259109) (xy 91.867982 -224.307686) (xy 91.852398 -224.354367) (xy 91.829527 -224.397944)
			(xy 91.799962 -224.437288) (xy 91.764469 -224.47138) (xy 91.723966 -224.499336) (xy 91.679504 -224.520434)
			(xy 91.632233 -224.534126) (xy 91.583378 -224.540058) (xy 91.534203 -224.538077) (xy 91.485984 -224.528233)
			(xy 91.439968 -224.510781) (xy 91.397347 -224.486174) (xy 91.359226 -224.455049) (xy 91.326591 -224.418212)
			(xy 91.300288 -224.376616) (xy 91.280997 -224.33134) (xy 91.26922 -224.283556) (xy 91.26526 -224.234502)
			(xy 90.936318 -224.234502) (xy 90.935823 -224.259109) (xy 90.927928 -224.307686) (xy 90.912344 -224.354367)
			(xy 90.889473 -224.397944) (xy 90.859908 -224.437288) (xy 90.824415 -224.47138) (xy 90.783912 -224.499336)
			(xy 90.73945 -224.520434) (xy 90.692179 -224.534126) (xy 90.643324 -224.540058) (xy 90.594149 -224.538077)
			(xy 90.54593 -224.528233) (xy 90.499914 -224.510781) (xy 90.457293 -224.486174) (xy 90.419172 -224.455049)
			(xy 90.386537 -224.418212) (xy 90.360234 -224.376616) (xy 90.340943 -224.33134) (xy 90.329166 -224.283556)
			(xy 90.325206 -224.234502) (xy 89.996264 -224.234502) (xy 89.995769 -224.259109) (xy 89.987874 -224.307686)
			(xy 89.97229 -224.354367) (xy 89.949419 -224.397944) (xy 89.919854 -224.437288) (xy 89.884361 -224.47138)
			(xy 89.843858 -224.499336) (xy 89.799396 -224.520434) (xy 89.752125 -224.534126) (xy 89.70327 -224.540058)
			(xy 89.654095 -224.538077) (xy 89.605876 -224.528233) (xy 89.55986 -224.510781) (xy 89.517239 -224.486174)
			(xy 89.479118 -224.455049) (xy 89.446483 -224.418212) (xy 89.42018 -224.376616) (xy 89.400889 -224.33134)
			(xy 89.389112 -224.283556) (xy 89.385152 -224.234502) (xy 88.11641 -224.234502) (xy 88.115648 -224.254822)
			(xy 88.114886 -224.265744) (xy 88.12276 -224.286318) (xy 88.78062 -224.944178) (xy 88.789745 -224.952258)
			(xy 88.812962 -224.959548) (xy 88.82507 -224.958148) (xy 88.907112 -224.943924) (xy 88.919099 -224.94106)
			(xy 88.938618 -224.926076) (xy 88.94445 -224.915222) (xy 88.955359 -224.893016) (xy 88.983262 -224.852164)
			(xy 89.017387 -224.816346) (xy 89.056841 -224.7865) (xy 89.100592 -224.763405) (xy 89.147494 -224.747668)
			(xy 89.19632 -224.7397) (xy 89.221056 -224.7392) (xy 89.245051 -224.739643) (xy 89.292452 -224.747144)
			(xy 89.338095 -224.761969) (xy 89.380856 -224.783752) (xy 89.419683 -224.811957) (xy 89.453619 -224.845889)
			(xy 89.481829 -224.884713) (xy 89.503617 -224.927472) (xy 89.518447 -224.973113) (xy 89.525954 -225.020513)
			(xy 89.526364 -225.044508) (xy 89.855306 -225.044508) (xy 89.859266 -224.995454) (xy 89.871043 -224.94767)
			(xy 89.890334 -224.902394) (xy 89.916637 -224.860798) (xy 89.949272 -224.823961) (xy 89.987393 -224.792836)
			(xy 90.030014 -224.768229) (xy 90.07603 -224.750777) (xy 90.124249 -224.740933) (xy 90.173424 -224.738952)
			(xy 90.222279 -224.744884) (xy 90.26955 -224.758576) (xy 90.314012 -224.779674) (xy 90.354515 -224.80763)
			(xy 90.390008 -224.841722) (xy 90.419573 -224.881066) (xy 90.442444 -224.924643) (xy 90.458028 -224.971324)
			(xy 90.465923 -225.019901) (xy 90.466418 -225.044508) (xy 90.784675 -225.044508) (xy 90.78877 -224.99378)
			(xy 90.800949 -224.944366) (xy 90.820897 -224.897546) (xy 90.848098 -224.854532) (xy 90.881846 -224.816438)
			(xy 90.921268 -224.784251) (xy 90.965342 -224.758805) (xy 91.012928 -224.740758) (xy 91.062792 -224.730578)
			(xy 91.113644 -224.728529) (xy 91.164165 -224.734663) (xy 91.213049 -224.748823) (xy 91.259028 -224.77064)
			(xy 91.300912 -224.79955) (xy 91.337616 -224.834805) (xy 91.368189 -224.875491) (xy 91.39184 -224.920554)
			(xy 91.407956 -224.968828) (xy 91.41612 -225.019062) (xy 91.416632 -225.044508) (xy 91.73516 -225.044508)
			(xy 91.73912 -224.995454) (xy 91.750897 -224.94767) (xy 91.770188 -224.902394) (xy 91.796491 -224.860798)
			(xy 91.829126 -224.823961) (xy 91.867247 -224.792836) (xy 91.909868 -224.768229) (xy 91.955884 -224.750777)
			(xy 92.004103 -224.740933) (xy 92.053278 -224.738952) (xy 92.102133 -224.744884) (xy 92.149404 -224.758576)
			(xy 92.193866 -224.779674) (xy 92.234369 -224.80763) (xy 92.269862 -224.841722) (xy 92.299427 -224.881066)
			(xy 92.322298 -224.924643) (xy 92.337882 -224.971324) (xy 92.345777 -225.019901) (xy 92.346272 -225.044508)
			(xy 92.675214 -225.044508) (xy 92.679174 -224.995454) (xy 92.690951 -224.94767) (xy 92.710242 -224.902394)
			(xy 92.736545 -224.860798) (xy 92.76918 -224.823961) (xy 92.807301 -224.792836) (xy 92.849922 -224.768229)
			(xy 92.895938 -224.750777) (xy 92.944157 -224.740933) (xy 92.993332 -224.738952) (xy 93.042187 -224.744884)
			(xy 93.089458 -224.758576) (xy 93.13392 -224.779674) (xy 93.174423 -224.80763) (xy 93.209916 -224.841722)
			(xy 93.239481 -224.881066) (xy 93.262352 -224.924643) (xy 93.277936 -224.971324) (xy 93.285831 -225.019901)
			(xy 93.286326 -225.044508) (xy 93.604837 -225.044508) (xy 93.608932 -224.99378) (xy 93.621111 -224.944366)
			(xy 93.641059 -224.897546) (xy 93.66826 -224.854532) (xy 93.702008 -224.816438) (xy 93.74143 -224.784251)
			(xy 93.785504 -224.758805) (xy 93.83309 -224.740758) (xy 93.882954 -224.730578) (xy 93.933806 -224.728529)
			(xy 93.984327 -224.734663) (xy 94.033211 -224.748823) (xy 94.07919 -224.77064) (xy 94.121074 -224.79955)
			(xy 94.157778 -224.834805) (xy 94.188351 -224.875491) (xy 94.212002 -224.920554) (xy 94.228118 -224.968828)
			(xy 94.236282 -225.019062) (xy 94.236794 -225.044508) (xy 94.555322 -225.044508) (xy 94.559282 -224.995454)
			(xy 94.571059 -224.94767) (xy 94.59035 -224.902394) (xy 94.616653 -224.860798) (xy 94.649288 -224.823961)
			(xy 94.687409 -224.792836) (xy 94.73003 -224.768229) (xy 94.776046 -224.750777) (xy 94.824265 -224.740933)
			(xy 94.87344 -224.738952) (xy 94.922295 -224.744884) (xy 94.969566 -224.758576) (xy 95.014028 -224.779674)
			(xy 95.054531 -224.80763) (xy 95.090024 -224.841722) (xy 95.119589 -224.881066) (xy 95.14246 -224.924643)
			(xy 95.158044 -224.971324) (xy 95.165939 -225.019901) (xy 95.166434 -225.044508) (xy 95.495122 -225.044508)
			(xy 95.499082 -224.995454) (xy 95.510859 -224.94767) (xy 95.53015 -224.902394) (xy 95.556453 -224.860798)
			(xy 95.589088 -224.823961) (xy 95.627209 -224.792836) (xy 95.66983 -224.768229) (xy 95.715846 -224.750777)
			(xy 95.764065 -224.740933) (xy 95.81324 -224.738952) (xy 95.862095 -224.744884) (xy 95.909366 -224.758576)
			(xy 95.953828 -224.779674) (xy 95.994331 -224.80763) (xy 96.029824 -224.841722) (xy 96.059389 -224.881066)
			(xy 96.08226 -224.924643) (xy 96.097844 -224.971324) (xy 96.105739 -225.019901) (xy 96.106234 -225.044508)
			(xy 97.37523 -225.044508) (xy 97.37919 -224.995454) (xy 97.390967 -224.94767) (xy 97.410258 -224.902394)
			(xy 97.436561 -224.860798) (xy 97.469196 -224.823961) (xy 97.507317 -224.792836) (xy 97.549938 -224.768229)
			(xy 97.595954 -224.750777) (xy 97.644173 -224.740933) (xy 97.693348 -224.738952) (xy 97.742203 -224.744884)
			(xy 97.789474 -224.758576) (xy 97.833936 -224.779674) (xy 97.874439 -224.80763) (xy 97.909932 -224.841722)
			(xy 97.939497 -224.881066) (xy 97.962368 -224.924643) (xy 97.977952 -224.971324) (xy 97.985847 -225.019901)
			(xy 97.986342 -225.044508) (xy 98.315284 -225.044508) (xy 98.319244 -224.995454) (xy 98.331021 -224.94767)
			(xy 98.350312 -224.902394) (xy 98.376615 -224.860798) (xy 98.40925 -224.823961) (xy 98.447371 -224.792836)
			(xy 98.489992 -224.768229) (xy 98.536008 -224.750777) (xy 98.584227 -224.740933) (xy 98.633402 -224.738952)
			(xy 98.682257 -224.744884) (xy 98.729528 -224.758576) (xy 98.77399 -224.779674) (xy 98.814493 -224.80763)
			(xy 98.849986 -224.841722) (xy 98.879551 -224.881066) (xy 98.902422 -224.924643) (xy 98.918006 -224.971324)
			(xy 98.925901 -225.019901) (xy 98.926396 -225.044508) (xy 100.195138 -225.044508) (xy 100.199098 -224.995454)
			(xy 100.210875 -224.94767) (xy 100.230166 -224.902394) (xy 100.256469 -224.860798) (xy 100.289104 -224.823961)
			(xy 100.327225 -224.792836) (xy 100.369846 -224.768229) (xy 100.415862 -224.750777) (xy 100.464081 -224.740933)
			(xy 100.513256 -224.738952) (xy 100.562111 -224.744884) (xy 100.609382 -224.758576) (xy 100.653844 -224.779674)
			(xy 100.694347 -224.80763) (xy 100.72984 -224.841722) (xy 100.759405 -224.881066) (xy 100.782276 -224.924643)
			(xy 100.79786 -224.971324) (xy 100.805755 -225.019901) (xy 100.80625 -225.044508) (xy 101.135192 -225.044508)
			(xy 101.139152 -224.995454) (xy 101.150929 -224.94767) (xy 101.17022 -224.902394) (xy 101.196523 -224.860798)
			(xy 101.229158 -224.823961) (xy 101.267279 -224.792836) (xy 101.3099 -224.768229) (xy 101.355916 -224.750777)
			(xy 101.404135 -224.740933) (xy 101.45331 -224.738952) (xy 101.502165 -224.744884) (xy 101.549436 -224.758576)
			(xy 101.593898 -224.779674) (xy 101.634401 -224.80763) (xy 101.669894 -224.841722) (xy 101.699459 -224.881066)
			(xy 101.72233 -224.924643) (xy 101.737914 -224.971324) (xy 101.745809 -225.019901) (xy 101.746304 -225.044508)
			(xy 103.0153 -225.044508) (xy 103.01926 -224.995454) (xy 103.031037 -224.94767) (xy 103.050328 -224.902394)
			(xy 103.076631 -224.860798) (xy 103.109266 -224.823961) (xy 103.147387 -224.792836) (xy 103.190008 -224.768229)
			(xy 103.236024 -224.750777) (xy 103.284243 -224.740933) (xy 103.333418 -224.738952) (xy 103.382273 -224.744884)
			(xy 103.429544 -224.758576) (xy 103.474006 -224.779674) (xy 103.514509 -224.80763) (xy 103.550002 -224.841722)
			(xy 103.579567 -224.881066) (xy 103.602438 -224.924643) (xy 103.618022 -224.971324) (xy 103.625917 -225.019901)
			(xy 103.626412 -225.044508) (xy 103.955354 -225.044508) (xy 103.959314 -224.995454) (xy 103.971091 -224.94767)
			(xy 103.990382 -224.902394) (xy 104.016685 -224.860798) (xy 104.04932 -224.823961) (xy 104.087441 -224.792836)
			(xy 104.130062 -224.768229) (xy 104.176078 -224.750777) (xy 104.224297 -224.740933) (xy 104.273472 -224.738952)
			(xy 104.322327 -224.744884) (xy 104.369598 -224.758576) (xy 104.41406 -224.779674) (xy 104.454563 -224.80763)
			(xy 104.490056 -224.841722) (xy 104.519621 -224.881066) (xy 104.542492 -224.924643) (xy 104.558076 -224.971324)
			(xy 104.565971 -225.019901) (xy 104.566466 -225.044508) (xy 104.565971 -225.069115) (xy 104.558076 -225.117692)
			(xy 104.542492 -225.164373) (xy 104.519621 -225.20795) (xy 104.490056 -225.247294) (xy 104.454563 -225.281386)
			(xy 104.41406 -225.309342) (xy 104.369598 -225.33044) (xy 104.322327 -225.344132) (xy 104.273472 -225.350064)
			(xy 104.224297 -225.348083) (xy 104.176078 -225.338239) (xy 104.130062 -225.320787) (xy 104.087441 -225.29618)
			(xy 104.04932 -225.265055) (xy 104.016685 -225.228218) (xy 103.990382 -225.186622) (xy 103.971091 -225.141346)
			(xy 103.959314 -225.093562) (xy 103.955354 -225.044508) (xy 103.626412 -225.044508) (xy 103.625917 -225.069115)
			(xy 103.618022 -225.117692) (xy 103.602438 -225.164373) (xy 103.579567 -225.20795) (xy 103.550002 -225.247294)
			(xy 103.514509 -225.281386) (xy 103.474006 -225.309342) (xy 103.429544 -225.33044) (xy 103.382273 -225.344132)
			(xy 103.333418 -225.350064) (xy 103.284243 -225.348083) (xy 103.236024 -225.338239) (xy 103.190008 -225.320787)
			(xy 103.147387 -225.29618) (xy 103.109266 -225.265055) (xy 103.076631 -225.228218) (xy 103.050328 -225.186622)
			(xy 103.031037 -225.141346) (xy 103.01926 -225.093562) (xy 103.0153 -225.044508) (xy 101.746304 -225.044508)
			(xy 101.745809 -225.069115) (xy 101.737914 -225.117692) (xy 101.72233 -225.164373) (xy 101.699459 -225.20795)
			(xy 101.669894 -225.247294) (xy 101.634401 -225.281386) (xy 101.593898 -225.309342) (xy 101.549436 -225.33044)
			(xy 101.502165 -225.344132) (xy 101.45331 -225.350064) (xy 101.404135 -225.348083) (xy 101.355916 -225.338239)
			(xy 101.3099 -225.320787) (xy 101.267279 -225.29618) (xy 101.229158 -225.265055) (xy 101.196523 -225.228218)
			(xy 101.17022 -225.186622) (xy 101.150929 -225.141346) (xy 101.139152 -225.093562) (xy 101.135192 -225.044508)
			(xy 100.80625 -225.044508) (xy 100.805755 -225.069115) (xy 100.79786 -225.117692) (xy 100.782276 -225.164373)
			(xy 100.759405 -225.20795) (xy 100.72984 -225.247294) (xy 100.694347 -225.281386) (xy 100.653844 -225.309342)
			(xy 100.609382 -225.33044) (xy 100.562111 -225.344132) (xy 100.513256 -225.350064) (xy 100.464081 -225.348083)
			(xy 100.415862 -225.338239) (xy 100.369846 -225.320787) (xy 100.327225 -225.29618) (xy 100.289104 -225.265055)
			(xy 100.256469 -225.228218) (xy 100.230166 -225.186622) (xy 100.210875 -225.141346) (xy 100.199098 -225.093562)
			(xy 100.195138 -225.044508) (xy 98.926396 -225.044508) (xy 98.925901 -225.069115) (xy 98.918006 -225.117692)
			(xy 98.902422 -225.164373) (xy 98.879551 -225.20795) (xy 98.849986 -225.247294) (xy 98.814493 -225.281386)
			(xy 98.77399 -225.309342) (xy 98.729528 -225.33044) (xy 98.682257 -225.344132) (xy 98.633402 -225.350064)
			(xy 98.584227 -225.348083) (xy 98.536008 -225.338239) (xy 98.489992 -225.320787) (xy 98.447371 -225.29618)
			(xy 98.40925 -225.265055) (xy 98.376615 -225.228218) (xy 98.350312 -225.186622) (xy 98.331021 -225.141346)
			(xy 98.319244 -225.093562) (xy 98.315284 -225.044508) (xy 97.986342 -225.044508) (xy 97.985847 -225.069115)
			(xy 97.977952 -225.117692) (xy 97.962368 -225.164373) (xy 97.939497 -225.20795) (xy 97.909932 -225.247294)
			(xy 97.874439 -225.281386) (xy 97.833936 -225.309342) (xy 97.789474 -225.33044) (xy 97.742203 -225.344132)
			(xy 97.693348 -225.350064) (xy 97.644173 -225.348083) (xy 97.595954 -225.338239) (xy 97.549938 -225.320787)
			(xy 97.507317 -225.29618) (xy 97.469196 -225.265055) (xy 97.436561 -225.228218) (xy 97.410258 -225.186622)
			(xy 97.390967 -225.141346) (xy 97.37919 -225.093562) (xy 97.37523 -225.044508) (xy 96.106234 -225.044508)
			(xy 96.105739 -225.069115) (xy 96.097844 -225.117692) (xy 96.08226 -225.164373) (xy 96.059389 -225.20795)
			(xy 96.029824 -225.247294) (xy 95.994331 -225.281386) (xy 95.953828 -225.309342) (xy 95.909366 -225.33044)
			(xy 95.862095 -225.344132) (xy 95.81324 -225.350064) (xy 95.764065 -225.348083) (xy 95.715846 -225.338239)
			(xy 95.66983 -225.320787) (xy 95.627209 -225.29618) (xy 95.589088 -225.265055) (xy 95.556453 -225.228218)
			(xy 95.53015 -225.186622) (xy 95.510859 -225.141346) (xy 95.499082 -225.093562) (xy 95.495122 -225.044508)
			(xy 95.166434 -225.044508) (xy 95.165939 -225.069115) (xy 95.158044 -225.117692) (xy 95.14246 -225.164373)
			(xy 95.119589 -225.20795) (xy 95.090024 -225.247294) (xy 95.054531 -225.281386) (xy 95.014028 -225.309342)
			(xy 94.969566 -225.33044) (xy 94.922295 -225.344132) (xy 94.87344 -225.350064) (xy 94.824265 -225.348083)
			(xy 94.776046 -225.338239) (xy 94.73003 -225.320787) (xy 94.687409 -225.29618) (xy 94.649288 -225.265055)
			(xy 94.616653 -225.228218) (xy 94.59035 -225.186622) (xy 94.571059 -225.141346) (xy 94.559282 -225.093562)
			(xy 94.555322 -225.044508) (xy 94.236794 -225.044508) (xy 94.236282 -225.069954) (xy 94.228118 -225.120188)
			(xy 94.212002 -225.168462) (xy 94.188351 -225.213525) (xy 94.157778 -225.254211) (xy 94.121074 -225.289466)
			(xy 94.07919 -225.318376) (xy 94.033211 -225.340193) (xy 93.984327 -225.354353) (xy 93.933806 -225.360487)
			(xy 93.882954 -225.358438) (xy 93.83309 -225.348258) (xy 93.785504 -225.330211) (xy 93.74143 -225.304765)
			(xy 93.702008 -225.272578) (xy 93.66826 -225.234484) (xy 93.641059 -225.19147) (xy 93.621111 -225.14465)
			(xy 93.608932 -225.095236) (xy 93.604837 -225.044508) (xy 93.286326 -225.044508) (xy 93.285831 -225.069115)
			(xy 93.277936 -225.117692) (xy 93.262352 -225.164373) (xy 93.239481 -225.20795) (xy 93.209916 -225.247294)
			(xy 93.174423 -225.281386) (xy 93.13392 -225.309342) (xy 93.089458 -225.33044) (xy 93.042187 -225.344132)
			(xy 92.993332 -225.350064) (xy 92.944157 -225.348083) (xy 92.895938 -225.338239) (xy 92.849922 -225.320787)
			(xy 92.807301 -225.29618) (xy 92.76918 -225.265055) (xy 92.736545 -225.228218) (xy 92.710242 -225.186622)
			(xy 92.690951 -225.141346) (xy 92.679174 -225.093562) (xy 92.675214 -225.044508) (xy 92.346272 -225.044508)
			(xy 92.345777 -225.069115) (xy 92.337882 -225.117692) (xy 92.322298 -225.164373) (xy 92.299427 -225.20795)
			(xy 92.269862 -225.247294) (xy 92.234369 -225.281386) (xy 92.193866 -225.309342) (xy 92.149404 -225.33044)
			(xy 92.102133 -225.344132) (xy 92.053278 -225.350064) (xy 92.004103 -225.348083) (xy 91.955884 -225.338239)
			(xy 91.909868 -225.320787) (xy 91.867247 -225.29618) (xy 91.829126 -225.265055) (xy 91.796491 -225.228218)
			(xy 91.770188 -225.186622) (xy 91.750897 -225.141346) (xy 91.73912 -225.093562) (xy 91.73516 -225.044508)
			(xy 91.416632 -225.044508) (xy 91.41612 -225.069954) (xy 91.407956 -225.120188) (xy 91.39184 -225.168462)
			(xy 91.368189 -225.213525) (xy 91.337616 -225.254211) (xy 91.300912 -225.289466) (xy 91.259028 -225.318376)
			(xy 91.213049 -225.340193) (xy 91.164165 -225.354353) (xy 91.113644 -225.360487) (xy 91.062792 -225.358438)
			(xy 91.012928 -225.348258) (xy 90.965342 -225.330211) (xy 90.921268 -225.304765) (xy 90.881846 -225.272578)
			(xy 90.848098 -225.234484) (xy 90.820897 -225.19147) (xy 90.800949 -225.14465) (xy 90.78877 -225.095236)
			(xy 90.784675 -225.044508) (xy 90.466418 -225.044508) (xy 90.465923 -225.069115) (xy 90.458028 -225.117692)
			(xy 90.442444 -225.164373) (xy 90.419573 -225.20795) (xy 90.390008 -225.247294) (xy 90.354515 -225.281386)
			(xy 90.314012 -225.309342) (xy 90.26955 -225.33044) (xy 90.222279 -225.344132) (xy 90.173424 -225.350064)
			(xy 90.124249 -225.348083) (xy 90.07603 -225.338239) (xy 90.030014 -225.320787) (xy 89.987393 -225.29618)
			(xy 89.949272 -225.265055) (xy 89.916637 -225.228218) (xy 89.890334 -225.186622) (xy 89.871043 -225.141346)
			(xy 89.859266 -225.093562) (xy 89.855306 -225.044508) (xy 89.526364 -225.044508) (xy 89.525885 -225.069244)
			(xy 89.517908 -225.11807) (xy 89.502165 -225.164971) (xy 89.479067 -225.208721) (xy 89.449219 -225.248175)
			(xy 89.4134 -225.282301) (xy 89.372549 -225.310207) (xy 89.350342 -225.321114) (xy 89.33938 -225.32682)
			(xy 89.324336 -225.346392) (xy 89.32164 -225.358452) (xy 89.307416 -225.440494) (xy 89.30604 -225.452597)
			(xy 89.313337 -225.475801) (xy 89.321386 -225.484944) (xy 89.455244 -225.618802) (xy 89.492836 -225.621596)
			(xy 89.508076 -225.610166) (xy 89.527996 -225.595842) (xy 89.571454 -225.573072) (xy 89.617998 -225.557556)
			(xy 89.666425 -225.549693) (xy 89.690956 -225.549206) (xy 89.714951 -225.549649) (xy 89.762351 -225.55715)
			(xy 89.807994 -225.571975) (xy 89.850755 -225.593758) (xy 89.889581 -225.621963) (xy 89.923517 -225.655896)
			(xy 89.951726 -225.69472) (xy 89.973513 -225.737479) (xy 89.988343 -225.78312) (xy 89.995849 -225.830519)
			(xy 89.996264 -225.854514) (xy 90.314775 -225.854514) (xy 90.31887 -225.803786) (xy 90.331049 -225.754372)
			(xy 90.350997 -225.707552) (xy 90.378198 -225.664538) (xy 90.411946 -225.626444) (xy 90.451368 -225.594257)
			(xy 90.495442 -225.568811) (xy 90.543028 -225.550764) (xy 90.592892 -225.540584) (xy 90.643744 -225.538535)
			(xy 90.694265 -225.544669) (xy 90.743149 -225.558829) (xy 90.789128 -225.580646) (xy 90.831012 -225.609556)
			(xy 90.867716 -225.644811) (xy 90.898289 -225.685497) (xy 90.92194 -225.73056) (xy 90.938056 -225.778834)
			(xy 90.94622 -225.829068) (xy 90.946732 -225.854514) (xy 91.26526 -225.854514) (xy 91.26922 -225.80546)
			(xy 91.280997 -225.757676) (xy 91.300288 -225.7124) (xy 91.326591 -225.670804) (xy 91.359226 -225.633967)
			(xy 91.397347 -225.602842) (xy 91.439968 -225.578235) (xy 91.485984 -225.560783) (xy 91.534203 -225.550939)
			(xy 91.583378 -225.548958) (xy 91.632233 -225.55489) (xy 91.679504 -225.568582) (xy 91.723966 -225.58968)
			(xy 91.764469 -225.617636) (xy 91.799962 -225.651728) (xy 91.829527 -225.691072) (xy 91.852398 -225.734649)
			(xy 91.867982 -225.78133) (xy 91.875877 -225.829907) (xy 91.876372 -225.854514) (xy 92.194883 -225.854514)
			(xy 92.198978 -225.803786) (xy 92.211157 -225.754372) (xy 92.231105 -225.707552) (xy 92.258306 -225.664538)
			(xy 92.292054 -225.626444) (xy 92.331476 -225.594257) (xy 92.37555 -225.568811) (xy 92.423136 -225.550764)
			(xy 92.473 -225.540584) (xy 92.523852 -225.538535) (xy 92.574373 -225.544669) (xy 92.623257 -225.558829)
			(xy 92.669236 -225.580646) (xy 92.71112 -225.609556) (xy 92.747824 -225.644811) (xy 92.778397 -225.685497)
			(xy 92.802048 -225.73056) (xy 92.818164 -225.778834) (xy 92.826328 -225.829068) (xy 92.82684 -225.854514)
			(xy 93.145114 -225.854514) (xy 93.149074 -225.80546) (xy 93.160851 -225.757676) (xy 93.180142 -225.7124)
			(xy 93.206445 -225.670804) (xy 93.23908 -225.633967) (xy 93.277201 -225.602842) (xy 93.319822 -225.578235)
			(xy 93.365838 -225.560783) (xy 93.414057 -225.550939) (xy 93.463232 -225.548958) (xy 93.512087 -225.55489)
			(xy 93.559358 -225.568582) (xy 93.60382 -225.58968) (xy 93.644323 -225.617636) (xy 93.679816 -225.651728)
			(xy 93.709381 -225.691072) (xy 93.732252 -225.734649) (xy 93.747836 -225.78133) (xy 93.755731 -225.829907)
			(xy 93.756226 -225.854514) (xy 94.074737 -225.854514) (xy 94.078832 -225.803786) (xy 94.091011 -225.754372)
			(xy 94.110959 -225.707552) (xy 94.13816 -225.664538) (xy 94.171908 -225.626444) (xy 94.21133 -225.594257)
			(xy 94.255404 -225.568811) (xy 94.30299 -225.550764) (xy 94.352854 -225.540584) (xy 94.403706 -225.538535)
			(xy 94.454227 -225.544669) (xy 94.503111 -225.558829) (xy 94.54909 -225.580646) (xy 94.590974 -225.609556)
			(xy 94.627678 -225.644811) (xy 94.658251 -225.685497) (xy 94.681902 -225.73056) (xy 94.698018 -225.778834)
			(xy 94.706182 -225.829068) (xy 94.706694 -225.854514) (xy 95.014791 -225.854514) (xy 95.018886 -225.803786)
			(xy 95.031065 -225.754372) (xy 95.051013 -225.707552) (xy 95.078214 -225.664538) (xy 95.111962 -225.626444)
			(xy 95.151384 -225.594257) (xy 95.195458 -225.568811) (xy 95.243044 -225.550764) (xy 95.292908 -225.540584)
			(xy 95.34376 -225.538535) (xy 95.394281 -225.544669) (xy 95.443165 -225.558829) (xy 95.489144 -225.580646)
			(xy 95.531028 -225.609556) (xy 95.567732 -225.644811) (xy 95.598305 -225.685497) (xy 95.621956 -225.73056)
			(xy 95.638072 -225.778834) (xy 95.646236 -225.829068) (xy 95.646748 -225.854514) (xy 96.90533 -225.854514)
			(xy 96.90929 -225.80546) (xy 96.921067 -225.757676) (xy 96.940358 -225.7124) (xy 96.966661 -225.670804)
			(xy 96.999296 -225.633967) (xy 97.037417 -225.602842) (xy 97.080038 -225.578235) (xy 97.126054 -225.560783)
			(xy 97.174273 -225.550939) (xy 97.223448 -225.548958) (xy 97.272303 -225.55489) (xy 97.319574 -225.568582)
			(xy 97.364036 -225.58968) (xy 97.404539 -225.617636) (xy 97.440032 -225.651728) (xy 97.469597 -225.691072)
			(xy 97.492468 -225.734649) (xy 97.508052 -225.78133) (xy 97.515947 -225.829907) (xy 97.516442 -225.854514)
			(xy 97.84513 -225.854514) (xy 97.84909 -225.80546) (xy 97.860867 -225.757676) (xy 97.880158 -225.7124)
			(xy 97.906461 -225.670804) (xy 97.939096 -225.633967) (xy 97.977217 -225.602842) (xy 98.019838 -225.578235)
			(xy 98.065854 -225.560783) (xy 98.114073 -225.550939) (xy 98.163248 -225.548958) (xy 98.212103 -225.55489)
			(xy 98.259374 -225.568582) (xy 98.303836 -225.58968) (xy 98.344339 -225.617636) (xy 98.379832 -225.651728)
			(xy 98.409397 -225.691072) (xy 98.432268 -225.734649) (xy 98.447852 -225.78133) (xy 98.455747 -225.829907)
			(xy 98.456242 -225.854514) (xy 99.725238 -225.854514) (xy 99.729198 -225.80546) (xy 99.740975 -225.757676)
			(xy 99.760266 -225.7124) (xy 99.786569 -225.670804) (xy 99.819204 -225.633967) (xy 99.857325 -225.602842)
			(xy 99.899946 -225.578235) (xy 99.945962 -225.560783) (xy 99.994181 -225.550939) (xy 100.043356 -225.548958)
			(xy 100.092211 -225.55489) (xy 100.139482 -225.568582) (xy 100.183944 -225.58968) (xy 100.224447 -225.617636)
			(xy 100.25994 -225.651728) (xy 100.289505 -225.691072) (xy 100.312376 -225.734649) (xy 100.32796 -225.78133)
			(xy 100.335855 -225.829907) (xy 100.33635 -225.854514) (xy 100.665292 -225.854514) (xy 100.669252 -225.80546)
			(xy 100.681029 -225.757676) (xy 100.70032 -225.7124) (xy 100.726623 -225.670804) (xy 100.759258 -225.633967)
			(xy 100.797379 -225.602842) (xy 100.84 -225.578235) (xy 100.886016 -225.560783) (xy 100.934235 -225.550939)
			(xy 100.98341 -225.548958) (xy 101.032265 -225.55489) (xy 101.079536 -225.568582) (xy 101.123998 -225.58968)
			(xy 101.164501 -225.617636) (xy 101.199994 -225.651728) (xy 101.229559 -225.691072) (xy 101.25243 -225.734649)
			(xy 101.268014 -225.78133) (xy 101.275909 -225.829907) (xy 101.276404 -225.854514) (xy 102.545146 -225.854514)
			(xy 102.549106 -225.80546) (xy 102.560883 -225.757676) (xy 102.580174 -225.7124) (xy 102.606477 -225.670804)
			(xy 102.639112 -225.633967) (xy 102.677233 -225.602842) (xy 102.719854 -225.578235) (xy 102.76587 -225.560783)
			(xy 102.814089 -225.550939) (xy 102.863264 -225.548958) (xy 102.912119 -225.55489) (xy 102.95939 -225.568582)
			(xy 103.003852 -225.58968) (xy 103.044355 -225.617636) (xy 103.079848 -225.651728) (xy 103.109413 -225.691072)
			(xy 103.132284 -225.734649) (xy 103.147868 -225.78133) (xy 103.155763 -225.829907) (xy 103.156258 -225.854514)
			(xy 103.4852 -225.854514) (xy 103.48916 -225.80546) (xy 103.500937 -225.757676) (xy 103.520228 -225.7124)
			(xy 103.546531 -225.670804) (xy 103.579166 -225.633967) (xy 103.617287 -225.602842) (xy 103.659908 -225.578235)
			(xy 103.705924 -225.560783) (xy 103.754143 -225.550939) (xy 103.803318 -225.548958) (xy 103.852173 -225.55489)
			(xy 103.899444 -225.568582) (xy 103.943906 -225.58968) (xy 103.984409 -225.617636) (xy 104.019902 -225.651728)
			(xy 104.049467 -225.691072) (xy 104.072338 -225.734649) (xy 104.087922 -225.78133) (xy 104.095817 -225.829907)
			(xy 104.096312 -225.854514) (xy 105.365308 -225.854514) (xy 105.369268 -225.80546) (xy 105.381045 -225.757676)
			(xy 105.400336 -225.7124) (xy 105.426639 -225.670804) (xy 105.459274 -225.633967) (xy 105.497395 -225.602842)
			(xy 105.540016 -225.578235) (xy 105.586032 -225.560783) (xy 105.634251 -225.550939) (xy 105.683426 -225.548958)
			(xy 105.732281 -225.55489) (xy 105.779552 -225.568582) (xy 105.824014 -225.58968) (xy 105.864517 -225.617636)
			(xy 105.90001 -225.651728) (xy 105.929575 -225.691072) (xy 105.952446 -225.734649) (xy 105.96803 -225.78133)
			(xy 105.975925 -225.829907) (xy 105.97642 -225.854514) (xy 106.305362 -225.854514) (xy 106.309322 -225.80546)
			(xy 106.321099 -225.757676) (xy 106.34039 -225.7124) (xy 106.366693 -225.670804) (xy 106.399328 -225.633967)
			(xy 106.437449 -225.602842) (xy 106.48007 -225.578235) (xy 106.526086 -225.560783) (xy 106.574305 -225.550939)
			(xy 106.62348 -225.548958) (xy 106.672335 -225.55489) (xy 106.719606 -225.568582) (xy 106.764068 -225.58968)
			(xy 106.804571 -225.617636) (xy 106.840064 -225.651728) (xy 106.869629 -225.691072) (xy 106.8925 -225.734649)
			(xy 106.908084 -225.78133) (xy 106.915979 -225.829907) (xy 106.916474 -225.854514) (xy 108.185216 -225.854514)
			(xy 108.189176 -225.80546) (xy 108.200953 -225.757676) (xy 108.220244 -225.7124) (xy 108.246547 -225.670804)
			(xy 108.279182 -225.633967) (xy 108.317303 -225.602842) (xy 108.359924 -225.578235) (xy 108.40594 -225.560783)
			(xy 108.454159 -225.550939) (xy 108.503334 -225.548958) (xy 108.552189 -225.55489) (xy 108.59946 -225.568582)
			(xy 108.643922 -225.58968) (xy 108.684425 -225.617636) (xy 108.719918 -225.651728) (xy 108.749483 -225.691072)
			(xy 108.772354 -225.734649) (xy 108.787938 -225.78133) (xy 108.795833 -225.829907) (xy 108.796328 -225.854514)
			(xy 109.12527 -225.854514) (xy 109.12923 -225.80546) (xy 109.141007 -225.757676) (xy 109.160298 -225.7124)
			(xy 109.186601 -225.670804) (xy 109.219236 -225.633967) (xy 109.257357 -225.602842) (xy 109.299978 -225.578235)
			(xy 109.345994 -225.560783) (xy 109.394213 -225.550939) (xy 109.443388 -225.548958) (xy 109.492243 -225.55489)
			(xy 109.539514 -225.568582) (xy 109.583976 -225.58968) (xy 109.624479 -225.617636) (xy 109.659972 -225.651728)
			(xy 109.689537 -225.691072) (xy 109.712408 -225.734649) (xy 109.727992 -225.78133) (xy 109.735887 -225.829907)
			(xy 109.736382 -225.854514) (xy 110.065324 -225.854514) (xy 110.069284 -225.80546) (xy 110.081061 -225.757676)
			(xy 110.100352 -225.7124) (xy 110.126655 -225.670804) (xy 110.15929 -225.633967) (xy 110.197411 -225.602842)
			(xy 110.240032 -225.578235) (xy 110.286048 -225.560783) (xy 110.334267 -225.550939) (xy 110.383442 -225.548958)
			(xy 110.432297 -225.55489) (xy 110.479568 -225.568582) (xy 110.52403 -225.58968) (xy 110.564533 -225.617636)
			(xy 110.600026 -225.651728) (xy 110.629591 -225.691072) (xy 110.652462 -225.734649) (xy 110.668046 -225.78133)
			(xy 110.675941 -225.829907) (xy 110.676436 -225.854514) (xy 110.675941 -225.879121) (xy 110.668046 -225.927698)
			(xy 110.652462 -225.974379) (xy 110.629591 -226.017956) (xy 110.600026 -226.0573) (xy 110.564533 -226.091392)
			(xy 110.52403 -226.119348) (xy 110.479568 -226.140446) (xy 110.432297 -226.154138) (xy 110.383442 -226.16007)
			(xy 110.334267 -226.158089) (xy 110.286048 -226.148245) (xy 110.240032 -226.130793) (xy 110.197411 -226.106186)
			(xy 110.15929 -226.075061) (xy 110.126655 -226.038224) (xy 110.100352 -225.996628) (xy 110.081061 -225.951352)
			(xy 110.069284 -225.903568) (xy 110.065324 -225.854514) (xy 109.736382 -225.854514) (xy 109.735887 -225.879121)
			(xy 109.727992 -225.927698) (xy 109.712408 -225.974379) (xy 109.689537 -226.017956) (xy 109.659972 -226.0573)
			(xy 109.624479 -226.091392) (xy 109.583976 -226.119348) (xy 109.539514 -226.140446) (xy 109.492243 -226.154138)
			(xy 109.443388 -226.16007) (xy 109.394213 -226.158089) (xy 109.345994 -226.148245) (xy 109.299978 -226.130793)
			(xy 109.257357 -226.106186) (xy 109.219236 -226.075061) (xy 109.186601 -226.038224) (xy 109.160298 -225.996628)
			(xy 109.141007 -225.951352) (xy 109.12923 -225.903568) (xy 109.12527 -225.854514) (xy 108.796328 -225.854514)
			(xy 108.795833 -225.879121) (xy 108.787938 -225.927698) (xy 108.772354 -225.974379) (xy 108.749483 -226.017956)
			(xy 108.719918 -226.0573) (xy 108.684425 -226.091392) (xy 108.643922 -226.119348) (xy 108.59946 -226.140446)
			(xy 108.552189 -226.154138) (xy 108.503334 -226.16007) (xy 108.454159 -226.158089) (xy 108.40594 -226.148245)
			(xy 108.359924 -226.130793) (xy 108.317303 -226.106186) (xy 108.279182 -226.075061) (xy 108.246547 -226.038224)
			(xy 108.220244 -225.996628) (xy 108.200953 -225.951352) (xy 108.189176 -225.903568) (xy 108.185216 -225.854514)
			(xy 106.916474 -225.854514) (xy 106.915979 -225.879121) (xy 106.908084 -225.927698) (xy 106.8925 -225.974379)
			(xy 106.869629 -226.017956) (xy 106.840064 -226.0573) (xy 106.804571 -226.091392) (xy 106.764068 -226.119348)
			(xy 106.719606 -226.140446) (xy 106.672335 -226.154138) (xy 106.62348 -226.16007) (xy 106.574305 -226.158089)
			(xy 106.526086 -226.148245) (xy 106.48007 -226.130793) (xy 106.437449 -226.106186) (xy 106.399328 -226.075061)
			(xy 106.366693 -226.038224) (xy 106.34039 -225.996628) (xy 106.321099 -225.951352) (xy 106.309322 -225.903568)
			(xy 106.305362 -225.854514) (xy 105.97642 -225.854514) (xy 105.975925 -225.879121) (xy 105.96803 -225.927698)
			(xy 105.952446 -225.974379) (xy 105.929575 -226.017956) (xy 105.90001 -226.0573) (xy 105.864517 -226.091392)
			(xy 105.824014 -226.119348) (xy 105.779552 -226.140446) (xy 105.732281 -226.154138) (xy 105.683426 -226.16007)
			(xy 105.634251 -226.158089) (xy 105.586032 -226.148245) (xy 105.540016 -226.130793) (xy 105.497395 -226.106186)
			(xy 105.459274 -226.075061) (xy 105.426639 -226.038224) (xy 105.400336 -225.996628) (xy 105.381045 -225.951352)
			(xy 105.369268 -225.903568) (xy 105.365308 -225.854514) (xy 104.096312 -225.854514) (xy 104.095817 -225.879121)
			(xy 104.087922 -225.927698) (xy 104.072338 -225.974379) (xy 104.049467 -226.017956) (xy 104.019902 -226.0573)
			(xy 103.984409 -226.091392) (xy 103.943906 -226.119348) (xy 103.899444 -226.140446) (xy 103.852173 -226.154138)
			(xy 103.803318 -226.16007) (xy 103.754143 -226.158089) (xy 103.705924 -226.148245) (xy 103.659908 -226.130793)
			(xy 103.617287 -226.106186) (xy 103.579166 -226.075061) (xy 103.546531 -226.038224) (xy 103.520228 -225.996628)
			(xy 103.500937 -225.951352) (xy 103.48916 -225.903568) (xy 103.4852 -225.854514) (xy 103.156258 -225.854514)
			(xy 103.155763 -225.879121) (xy 103.147868 -225.927698) (xy 103.132284 -225.974379) (xy 103.109413 -226.017956)
			(xy 103.079848 -226.0573) (xy 103.044355 -226.091392) (xy 103.003852 -226.119348) (xy 102.95939 -226.140446)
			(xy 102.912119 -226.154138) (xy 102.863264 -226.16007) (xy 102.814089 -226.158089) (xy 102.76587 -226.148245)
			(xy 102.719854 -226.130793) (xy 102.677233 -226.106186) (xy 102.639112 -226.075061) (xy 102.606477 -226.038224)
			(xy 102.580174 -225.996628) (xy 102.560883 -225.951352) (xy 102.549106 -225.903568) (xy 102.545146 -225.854514)
			(xy 101.276404 -225.854514) (xy 101.275909 -225.879121) (xy 101.268014 -225.927698) (xy 101.25243 -225.974379)
			(xy 101.229559 -226.017956) (xy 101.199994 -226.0573) (xy 101.164501 -226.091392) (xy 101.123998 -226.119348)
			(xy 101.079536 -226.140446) (xy 101.032265 -226.154138) (xy 100.98341 -226.16007) (xy 100.934235 -226.158089)
			(xy 100.886016 -226.148245) (xy 100.84 -226.130793) (xy 100.797379 -226.106186) (xy 100.759258 -226.075061)
			(xy 100.726623 -226.038224) (xy 100.70032 -225.996628) (xy 100.681029 -225.951352) (xy 100.669252 -225.903568)
			(xy 100.665292 -225.854514) (xy 100.33635 -225.854514) (xy 100.335855 -225.879121) (xy 100.32796 -225.927698)
			(xy 100.312376 -225.974379) (xy 100.289505 -226.017956) (xy 100.25994 -226.0573) (xy 100.224447 -226.091392)
			(xy 100.183944 -226.119348) (xy 100.139482 -226.140446) (xy 100.092211 -226.154138) (xy 100.043356 -226.16007)
			(xy 99.994181 -226.158089) (xy 99.945962 -226.148245) (xy 99.899946 -226.130793) (xy 99.857325 -226.106186)
			(xy 99.819204 -226.075061) (xy 99.786569 -226.038224) (xy 99.760266 -225.996628) (xy 99.740975 -225.951352)
			(xy 99.729198 -225.903568) (xy 99.725238 -225.854514) (xy 98.456242 -225.854514) (xy 98.455747 -225.879121)
			(xy 98.447852 -225.927698) (xy 98.432268 -225.974379) (xy 98.409397 -226.017956) (xy 98.379832 -226.0573)
			(xy 98.344339 -226.091392) (xy 98.303836 -226.119348) (xy 98.259374 -226.140446) (xy 98.212103 -226.154138)
			(xy 98.163248 -226.16007) (xy 98.114073 -226.158089) (xy 98.065854 -226.148245) (xy 98.019838 -226.130793)
			(xy 97.977217 -226.106186) (xy 97.939096 -226.075061) (xy 97.906461 -226.038224) (xy 97.880158 -225.996628)
			(xy 97.860867 -225.951352) (xy 97.84909 -225.903568) (xy 97.84513 -225.854514) (xy 97.516442 -225.854514)
			(xy 97.515947 -225.879121) (xy 97.508052 -225.927698) (xy 97.492468 -225.974379) (xy 97.469597 -226.017956)
			(xy 97.440032 -226.0573) (xy 97.404539 -226.091392) (xy 97.364036 -226.119348) (xy 97.319574 -226.140446)
			(xy 97.272303 -226.154138) (xy 97.223448 -226.16007) (xy 97.174273 -226.158089) (xy 97.126054 -226.148245)
			(xy 97.080038 -226.130793) (xy 97.037417 -226.106186) (xy 96.999296 -226.075061) (xy 96.966661 -226.038224)
			(xy 96.940358 -225.996628) (xy 96.921067 -225.951352) (xy 96.90929 -225.903568) (xy 96.90533 -225.854514)
			(xy 95.646748 -225.854514) (xy 95.646236 -225.87996) (xy 95.638072 -225.930194) (xy 95.621956 -225.978468)
			(xy 95.598305 -226.023531) (xy 95.567732 -226.064217) (xy 95.531028 -226.099472) (xy 95.489144 -226.128382)
			(xy 95.443165 -226.150199) (xy 95.394281 -226.164359) (xy 95.34376 -226.170493) (xy 95.292908 -226.168444)
			(xy 95.243044 -226.158264) (xy 95.195458 -226.140217) (xy 95.151384 -226.114771) (xy 95.111962 -226.082584)
			(xy 95.078214 -226.04449) (xy 95.051013 -226.001476) (xy 95.031065 -225.954656) (xy 95.018886 -225.905242)
			(xy 95.014791 -225.854514) (xy 94.706694 -225.854514) (xy 94.706182 -225.87996) (xy 94.698018 -225.930194)
			(xy 94.681902 -225.978468) (xy 94.658251 -226.023531) (xy 94.627678 -226.064217) (xy 94.590974 -226.099472)
			(xy 94.54909 -226.128382) (xy 94.503111 -226.150199) (xy 94.454227 -226.164359) (xy 94.403706 -226.170493)
			(xy 94.352854 -226.168444) (xy 94.30299 -226.158264) (xy 94.255404 -226.140217) (xy 94.21133 -226.114771)
			(xy 94.171908 -226.082584) (xy 94.13816 -226.04449) (xy 94.110959 -226.001476) (xy 94.091011 -225.954656)
			(xy 94.078832 -225.905242) (xy 94.074737 -225.854514) (xy 93.756226 -225.854514) (xy 93.755731 -225.879121)
			(xy 93.747836 -225.927698) (xy 93.732252 -225.974379) (xy 93.709381 -226.017956) (xy 93.679816 -226.0573)
			(xy 93.644323 -226.091392) (xy 93.60382 -226.119348) (xy 93.559358 -226.140446) (xy 93.512087 -226.154138)
			(xy 93.463232 -226.16007) (xy 93.414057 -226.158089) (xy 93.365838 -226.148245) (xy 93.319822 -226.130793)
			(xy 93.277201 -226.106186) (xy 93.23908 -226.075061) (xy 93.206445 -226.038224) (xy 93.180142 -225.996628)
			(xy 93.160851 -225.951352) (xy 93.149074 -225.903568) (xy 93.145114 -225.854514) (xy 92.82684 -225.854514)
			(xy 92.826328 -225.87996) (xy 92.818164 -225.930194) (xy 92.802048 -225.978468) (xy 92.778397 -226.023531)
			(xy 92.747824 -226.064217) (xy 92.71112 -226.099472) (xy 92.669236 -226.128382) (xy 92.623257 -226.150199)
			(xy 92.574373 -226.164359) (xy 92.523852 -226.170493) (xy 92.473 -226.168444) (xy 92.423136 -226.158264)
			(xy 92.37555 -226.140217) (xy 92.331476 -226.114771) (xy 92.292054 -226.082584) (xy 92.258306 -226.04449)
			(xy 92.231105 -226.001476) (xy 92.211157 -225.954656) (xy 92.198978 -225.905242) (xy 92.194883 -225.854514)
			(xy 91.876372 -225.854514) (xy 91.875877 -225.879121) (xy 91.867982 -225.927698) (xy 91.852398 -225.974379)
			(xy 91.829527 -226.017956) (xy 91.799962 -226.0573) (xy 91.764469 -226.091392) (xy 91.723966 -226.119348)
			(xy 91.679504 -226.140446) (xy 91.632233 -226.154138) (xy 91.583378 -226.16007) (xy 91.534203 -226.158089)
			(xy 91.485984 -226.148245) (xy 91.439968 -226.130793) (xy 91.397347 -226.106186) (xy 91.359226 -226.075061)
			(xy 91.326591 -226.038224) (xy 91.300288 -225.996628) (xy 91.280997 -225.951352) (xy 91.26922 -225.903568)
			(xy 91.26526 -225.854514) (xy 90.946732 -225.854514) (xy 90.94622 -225.87996) (xy 90.938056 -225.930194)
			(xy 90.92194 -225.978468) (xy 90.898289 -226.023531) (xy 90.867716 -226.064217) (xy 90.831012 -226.099472)
			(xy 90.789128 -226.128382) (xy 90.743149 -226.150199) (xy 90.694265 -226.164359) (xy 90.643744 -226.170493)
			(xy 90.592892 -226.168444) (xy 90.543028 -226.158264) (xy 90.495442 -226.140217) (xy 90.451368 -226.114771)
			(xy 90.411946 -226.082584) (xy 90.378198 -226.04449) (xy 90.350997 -226.001476) (xy 90.331049 -225.954656)
			(xy 90.31887 -225.905242) (xy 90.314775 -225.854514) (xy 89.996264 -225.854514) (xy 89.995798 -225.878753)
			(xy 89.988139 -225.926624) (xy 89.973014 -225.972683) (xy 89.950805 -226.015775) (xy 89.922067 -226.054819)
			(xy 89.887524 -226.088833) (xy 89.848042 -226.116964) (xy 89.804611 -226.138505) (xy 89.758324 -226.152917)
			(xy 89.73439 -226.156774) (xy 89.715594 -226.159568) (xy 89.690956 -226.188016) (xy 89.690956 -226.359212)
			(xy 89.691218 -226.3661) (xy 89.694946 -226.379365) (xy 89.698322 -226.385374) (xy 89.699338 -226.387152)
			(xy 89.707629 -226.401726) (xy 89.722626 -226.431719) (xy 89.72931 -226.447096) (xy 89.736168 -226.463606)
			(xy 89.741248 -226.476814) (xy 89.762838 -226.493832) (xy 89.879424 -226.508818) (xy 89.905078 -226.497642)
			(xy 89.913206 -226.486212) (xy 89.927671 -226.466913) (xy 89.96166 -226.432697) (xy 90.000599 -226.404243)
			(xy 90.043524 -226.382257) (xy 90.089369 -226.367285) (xy 90.136996 -226.359697) (xy 90.16111 -226.359212)
			(xy 90.186363 -226.359734) (xy 90.23618 -226.368049) (xy 90.28395 -226.384449) (xy 90.328368 -226.408489)
			(xy 90.368224 -226.439511) (xy 90.40243 -226.47667) (xy 90.430054 -226.518953) (xy 90.450342 -226.565205)
			(xy 90.46274 -226.614166) (xy 90.466911 -226.6645) (xy 90.466909 -226.66452) (xy 90.784675 -226.66452)
			(xy 90.78877 -226.613792) (xy 90.800949 -226.564378) (xy 90.820897 -226.517558) (xy 90.848098 -226.474544)
			(xy 90.881846 -226.43645) (xy 90.921268 -226.404263) (xy 90.965342 -226.378817) (xy 91.012928 -226.36077)
			(xy 91.062792 -226.35059) (xy 91.113644 -226.348541) (xy 91.164165 -226.354675) (xy 91.213049 -226.368835)
			(xy 91.259028 -226.390652) (xy 91.300912 -226.419562) (xy 91.337616 -226.454817) (xy 91.368189 -226.495503)
			(xy 91.39184 -226.540566) (xy 91.407956 -226.58884) (xy 91.41612 -226.639074) (xy 91.416632 -226.66452)
			(xy 91.724729 -226.66452) (xy 91.728824 -226.613792) (xy 91.741003 -226.564378) (xy 91.760951 -226.517558)
			(xy 91.788152 -226.474544) (xy 91.8219 -226.43645) (xy 91.861322 -226.404263) (xy 91.905396 -226.378817)
			(xy 91.952982 -226.36077) (xy 92.002846 -226.35059) (xy 92.053698 -226.348541) (xy 92.104219 -226.354675)
			(xy 92.153103 -226.368835) (xy 92.199082 -226.390652) (xy 92.240966 -226.419562) (xy 92.27767 -226.454817)
			(xy 92.308243 -226.495503) (xy 92.331894 -226.540566) (xy 92.34801 -226.58884) (xy 92.356174 -226.639074)
			(xy 92.356686 -226.66452) (xy 92.675214 -226.66452) (xy 92.679174 -226.615466) (xy 92.690951 -226.567682)
			(xy 92.710242 -226.522406) (xy 92.736545 -226.48081) (xy 92.76918 -226.443973) (xy 92.807301 -226.412848)
			(xy 92.849922 -226.388241) (xy 92.895938 -226.370789) (xy 92.944157 -226.360945) (xy 92.993332 -226.358964)
			(xy 93.042187 -226.364896) (xy 93.089458 -226.378588) (xy 93.13392 -226.399686) (xy 93.174423 -226.427642)
			(xy 93.209916 -226.461734) (xy 93.239481 -226.501078) (xy 93.262352 -226.544655) (xy 93.277936 -226.591336)
			(xy 93.285831 -226.639913) (xy 93.286326 -226.66452) (xy 93.604837 -226.66452) (xy 93.608932 -226.613792)
			(xy 93.621111 -226.564378) (xy 93.641059 -226.517558) (xy 93.66826 -226.474544) (xy 93.702008 -226.43645)
			(xy 93.74143 -226.404263) (xy 93.785504 -226.378817) (xy 93.83309 -226.36077) (xy 93.882954 -226.35059)
			(xy 93.933806 -226.348541) (xy 93.984327 -226.354675) (xy 94.033211 -226.368835) (xy 94.07919 -226.390652)
			(xy 94.121074 -226.419562) (xy 94.157778 -226.454817) (xy 94.188351 -226.495503) (xy 94.212002 -226.540566)
			(xy 94.228118 -226.58884) (xy 94.236282 -226.639074) (xy 94.236794 -226.66452) (xy 94.555322 -226.66452)
			(xy 94.559282 -226.615466) (xy 94.571059 -226.567682) (xy 94.59035 -226.522406) (xy 94.616653 -226.48081)
			(xy 94.649288 -226.443973) (xy 94.687409 -226.412848) (xy 94.73003 -226.388241) (xy 94.776046 -226.370789)
			(xy 94.824265 -226.360945) (xy 94.87344 -226.358964) (xy 94.922295 -226.364896) (xy 94.969566 -226.378588)
			(xy 95.014028 -226.399686) (xy 95.054531 -226.427642) (xy 95.090024 -226.461734) (xy 95.119589 -226.501078)
			(xy 95.14246 -226.544655) (xy 95.158044 -226.591336) (xy 95.165939 -226.639913) (xy 95.166434 -226.66452)
			(xy 95.484691 -226.66452) (xy 95.488786 -226.613792) (xy 95.500965 -226.564378) (xy 95.520913 -226.517558)
			(xy 95.548114 -226.474544) (xy 95.581862 -226.43645) (xy 95.621284 -226.404263) (xy 95.665358 -226.378817)
			(xy 95.712944 -226.36077) (xy 95.762808 -226.35059) (xy 95.81366 -226.348541) (xy 95.864181 -226.354675)
			(xy 95.913065 -226.368835) (xy 95.959044 -226.390652) (xy 96.000928 -226.419562) (xy 96.037632 -226.454817)
			(xy 96.068205 -226.495503) (xy 96.091856 -226.540566) (xy 96.107972 -226.58884) (xy 96.116136 -226.639074)
			(xy 96.116648 -226.66452) (xy 96.435176 -226.66452) (xy 96.439136 -226.615466) (xy 96.450913 -226.567682)
			(xy 96.470204 -226.522406) (xy 96.496507 -226.48081) (xy 96.529142 -226.443973) (xy 96.567263 -226.412848)
			(xy 96.609884 -226.388241) (xy 96.6559 -226.370789) (xy 96.704119 -226.360945) (xy 96.753294 -226.358964)
			(xy 96.802149 -226.364896) (xy 96.84942 -226.378588) (xy 96.893882 -226.399686) (xy 96.934385 -226.427642)
			(xy 96.969878 -226.461734) (xy 96.999443 -226.501078) (xy 97.022314 -226.544655) (xy 97.037898 -226.591336)
			(xy 97.045793 -226.639913) (xy 97.046288 -226.66452) (xy 97.364799 -226.66452) (xy 97.368894 -226.613792)
			(xy 97.381073 -226.564378) (xy 97.401021 -226.517558) (xy 97.428222 -226.474544) (xy 97.46197 -226.43645)
			(xy 97.501392 -226.404263) (xy 97.545466 -226.378817) (xy 97.593052 -226.36077) (xy 97.642916 -226.35059)
			(xy 97.693768 -226.348541) (xy 97.744289 -226.354675) (xy 97.793173 -226.368835) (xy 97.839152 -226.390652)
			(xy 97.881036 -226.419562) (xy 97.91774 -226.454817) (xy 97.948313 -226.495503) (xy 97.971964 -226.540566)
			(xy 97.98808 -226.58884) (xy 97.996244 -226.639074) (xy 97.996756 -226.66452) (xy 98.304853 -226.66452)
			(xy 98.308948 -226.613792) (xy 98.321127 -226.564378) (xy 98.341075 -226.517558) (xy 98.368276 -226.474544)
			(xy 98.402024 -226.43645) (xy 98.441446 -226.404263) (xy 98.48552 -226.378817) (xy 98.533106 -226.36077)
			(xy 98.58297 -226.35059) (xy 98.633822 -226.348541) (xy 98.684343 -226.354675) (xy 98.733227 -226.368835)
			(xy 98.779206 -226.390652) (xy 98.82109 -226.419562) (xy 98.857794 -226.454817) (xy 98.888367 -226.495503)
			(xy 98.912018 -226.540566) (xy 98.928134 -226.58884) (xy 98.936298 -226.639074) (xy 98.93681 -226.66452)
			(xy 99.255338 -226.66452) (xy 99.259298 -226.615466) (xy 99.271075 -226.567682) (xy 99.290366 -226.522406)
			(xy 99.316669 -226.48081) (xy 99.349304 -226.443973) (xy 99.387425 -226.412848) (xy 99.430046 -226.388241)
			(xy 99.476062 -226.370789) (xy 99.524281 -226.360945) (xy 99.573456 -226.358964) (xy 99.622311 -226.364896)
			(xy 99.669582 -226.378588) (xy 99.714044 -226.399686) (xy 99.754547 -226.427642) (xy 99.79004 -226.461734)
			(xy 99.819605 -226.501078) (xy 99.842476 -226.544655) (xy 99.85806 -226.591336) (xy 99.865955 -226.639913)
			(xy 99.86645 -226.66452) (xy 100.184707 -226.66452) (xy 100.188802 -226.613792) (xy 100.200981 -226.564378)
			(xy 100.220929 -226.517558) (xy 100.24813 -226.474544) (xy 100.281878 -226.43645) (xy 100.3213 -226.404263)
			(xy 100.365374 -226.378817) (xy 100.41296 -226.36077) (xy 100.462824 -226.35059) (xy 100.513676 -226.348541)
			(xy 100.564197 -226.354675) (xy 100.613081 -226.368835) (xy 100.65906 -226.390652) (xy 100.700944 -226.419562)
			(xy 100.737648 -226.454817) (xy 100.768221 -226.495503) (xy 100.791872 -226.540566) (xy 100.807988 -226.58884)
			(xy 100.816152 -226.639074) (xy 100.816664 -226.66452) (xy 101.124761 -226.66452) (xy 101.128856 -226.613792)
			(xy 101.141035 -226.564378) (xy 101.160983 -226.517558) (xy 101.188184 -226.474544) (xy 101.221932 -226.43645)
			(xy 101.261354 -226.404263) (xy 101.305428 -226.378817) (xy 101.353014 -226.36077) (xy 101.402878 -226.35059)
			(xy 101.45373 -226.348541) (xy 101.504251 -226.354675) (xy 101.553135 -226.368835) (xy 101.599114 -226.390652)
			(xy 101.640998 -226.419562) (xy 101.677702 -226.454817) (xy 101.708275 -226.495503) (xy 101.731926 -226.540566)
			(xy 101.748042 -226.58884) (xy 101.756206 -226.639074) (xy 101.756718 -226.66452) (xy 102.075246 -226.66452)
			(xy 102.079206 -226.615466) (xy 102.090983 -226.567682) (xy 102.110274 -226.522406) (xy 102.136577 -226.48081)
			(xy 102.169212 -226.443973) (xy 102.207333 -226.412848) (xy 102.249954 -226.388241) (xy 102.29597 -226.370789)
			(xy 102.344189 -226.360945) (xy 102.393364 -226.358964) (xy 102.442219 -226.364896) (xy 102.48949 -226.378588)
			(xy 102.533952 -226.399686) (xy 102.574455 -226.427642) (xy 102.609948 -226.461734) (xy 102.639513 -226.501078)
			(xy 102.662384 -226.544655) (xy 102.677968 -226.591336) (xy 102.685863 -226.639913) (xy 102.686358 -226.66452)
			(xy 103.004869 -226.66452) (xy 103.008964 -226.613792) (xy 103.021143 -226.564378) (xy 103.041091 -226.517558)
			(xy 103.068292 -226.474544) (xy 103.10204 -226.43645) (xy 103.141462 -226.404263) (xy 103.185536 -226.378817)
			(xy 103.233122 -226.36077) (xy 103.282986 -226.35059) (xy 103.333838 -226.348541) (xy 103.384359 -226.354675)
			(xy 103.433243 -226.368835) (xy 103.479222 -226.390652) (xy 103.521106 -226.419562) (xy 103.55781 -226.454817)
			(xy 103.588383 -226.495503) (xy 103.612034 -226.540566) (xy 103.62815 -226.58884) (xy 103.636314 -226.639074)
			(xy 103.636826 -226.66452) (xy 103.944923 -226.66452) (xy 103.949018 -226.613792) (xy 103.961197 -226.564378)
			(xy 103.981145 -226.517558) (xy 104.008346 -226.474544) (xy 104.042094 -226.43645) (xy 104.081516 -226.404263)
			(xy 104.12559 -226.378817) (xy 104.173176 -226.36077) (xy 104.22304 -226.35059) (xy 104.273892 -226.348541)
			(xy 104.324413 -226.354675) (xy 104.373297 -226.368835) (xy 104.419276 -226.390652) (xy 104.46116 -226.419562)
			(xy 104.497864 -226.454817) (xy 104.528437 -226.495503) (xy 104.552088 -226.540566) (xy 104.568204 -226.58884)
			(xy 104.576368 -226.639074) (xy 104.57688 -226.66452) (xy 104.895154 -226.66452) (xy 104.899114 -226.615466)
			(xy 104.910891 -226.567682) (xy 104.930182 -226.522406) (xy 104.956485 -226.48081) (xy 104.98912 -226.443973)
			(xy 105.027241 -226.412848) (xy 105.069862 -226.388241) (xy 105.115878 -226.370789) (xy 105.164097 -226.360945)
			(xy 105.213272 -226.358964) (xy 105.262127 -226.364896) (xy 105.309398 -226.378588) (xy 105.35386 -226.399686)
			(xy 105.394363 -226.427642) (xy 105.429856 -226.461734) (xy 105.459421 -226.501078) (xy 105.482292 -226.544655)
			(xy 105.497876 -226.591336) (xy 105.505771 -226.639913) (xy 105.506266 -226.66452) (xy 105.824777 -226.66452)
			(xy 105.828872 -226.613792) (xy 105.841051 -226.564378) (xy 105.860999 -226.517558) (xy 105.8882 -226.474544)
			(xy 105.921948 -226.43645) (xy 105.96137 -226.404263) (xy 106.005444 -226.378817) (xy 106.05303 -226.36077)
			(xy 106.102894 -226.35059) (xy 106.153746 -226.348541) (xy 106.204267 -226.354675) (xy 106.253151 -226.368835)
			(xy 106.29913 -226.390652) (xy 106.341014 -226.419562) (xy 106.377718 -226.454817) (xy 106.408291 -226.495503)
			(xy 106.431942 -226.540566) (xy 106.448058 -226.58884) (xy 106.456222 -226.639074) (xy 106.456734 -226.66452)
			(xy 106.764831 -226.66452) (xy 106.768926 -226.613792) (xy 106.781105 -226.564378) (xy 106.801053 -226.517558)
			(xy 106.828254 -226.474544) (xy 106.862002 -226.43645) (xy 106.901424 -226.404263) (xy 106.945498 -226.378817)
			(xy 106.993084 -226.36077) (xy 107.042948 -226.35059) (xy 107.0938 -226.348541) (xy 107.144321 -226.354675)
			(xy 107.193205 -226.368835) (xy 107.239184 -226.390652) (xy 107.281068 -226.419562) (xy 107.317772 -226.454817)
			(xy 107.348345 -226.495503) (xy 107.371996 -226.540566) (xy 107.388112 -226.58884) (xy 107.396276 -226.639074)
			(xy 107.396788 -226.66452) (xy 107.715316 -226.66452) (xy 107.719276 -226.615466) (xy 107.731053 -226.567682)
			(xy 107.750344 -226.522406) (xy 107.776647 -226.48081) (xy 107.809282 -226.443973) (xy 107.847403 -226.412848)
			(xy 107.890024 -226.388241) (xy 107.93604 -226.370789) (xy 107.984259 -226.360945) (xy 108.033434 -226.358964)
			(xy 108.082289 -226.364896) (xy 108.12956 -226.378588) (xy 108.174022 -226.399686) (xy 108.214525 -226.427642)
			(xy 108.250018 -226.461734) (xy 108.279583 -226.501078) (xy 108.302454 -226.544655) (xy 108.318038 -226.591336)
			(xy 108.325933 -226.639913) (xy 108.326428 -226.66452) (xy 108.325933 -226.689127) (xy 108.318038 -226.737704)
			(xy 108.302454 -226.784385) (xy 108.279583 -226.827962) (xy 108.250018 -226.867306) (xy 108.214525 -226.901398)
			(xy 108.174022 -226.929354) (xy 108.12956 -226.950452) (xy 108.082289 -226.964144) (xy 108.033434 -226.970076)
			(xy 107.984259 -226.968095) (xy 107.93604 -226.958251) (xy 107.890024 -226.940799) (xy 107.847403 -226.916192)
			(xy 107.809282 -226.885067) (xy 107.776647 -226.84823) (xy 107.750344 -226.806634) (xy 107.731053 -226.761358)
			(xy 107.719276 -226.713574) (xy 107.715316 -226.66452) (xy 107.396788 -226.66452) (xy 107.396276 -226.689966)
			(xy 107.388112 -226.7402) (xy 107.371996 -226.788474) (xy 107.348345 -226.833537) (xy 107.317772 -226.874223)
			(xy 107.281068 -226.909478) (xy 107.239184 -226.938388) (xy 107.193205 -226.960205) (xy 107.144321 -226.974365)
			(xy 107.0938 -226.980499) (xy 107.042948 -226.97845) (xy 106.993084 -226.96827) (xy 106.945498 -226.950223)
			(xy 106.901424 -226.924777) (xy 106.862002 -226.89259) (xy 106.828254 -226.854496) (xy 106.801053 -226.811482)
			(xy 106.781105 -226.764662) (xy 106.768926 -226.715248) (xy 106.764831 -226.66452) (xy 106.456734 -226.66452)
			(xy 106.456222 -226.689966) (xy 106.448058 -226.7402) (xy 106.431942 -226.788474) (xy 106.408291 -226.833537)
			(xy 106.377718 -226.874223) (xy 106.341014 -226.909478) (xy 106.29913 -226.938388) (xy 106.253151 -226.960205)
			(xy 106.204267 -226.974365) (xy 106.153746 -226.980499) (xy 106.102894 -226.97845) (xy 106.05303 -226.96827)
			(xy 106.005444 -226.950223) (xy 105.96137 -226.924777) (xy 105.921948 -226.89259) (xy 105.8882 -226.854496)
			(xy 105.860999 -226.811482) (xy 105.841051 -226.764662) (xy 105.828872 -226.715248) (xy 105.824777 -226.66452)
			(xy 105.506266 -226.66452) (xy 105.505771 -226.689127) (xy 105.497876 -226.737704) (xy 105.482292 -226.784385)
			(xy 105.459421 -226.827962) (xy 105.429856 -226.867306) (xy 105.394363 -226.901398) (xy 105.35386 -226.929354)
			(xy 105.309398 -226.950452) (xy 105.262127 -226.964144) (xy 105.213272 -226.970076) (xy 105.164097 -226.968095)
			(xy 105.115878 -226.958251) (xy 105.069862 -226.940799) (xy 105.027241 -226.916192) (xy 104.98912 -226.885067)
			(xy 104.956485 -226.84823) (xy 104.930182 -226.806634) (xy 104.910891 -226.761358) (xy 104.899114 -226.713574)
			(xy 104.895154 -226.66452) (xy 104.57688 -226.66452) (xy 104.576368 -226.689966) (xy 104.568204 -226.7402)
			(xy 104.552088 -226.788474) (xy 104.528437 -226.833537) (xy 104.497864 -226.874223) (xy 104.46116 -226.909478)
			(xy 104.419276 -226.938388) (xy 104.373297 -226.960205) (xy 104.324413 -226.974365) (xy 104.273892 -226.980499)
			(xy 104.22304 -226.97845) (xy 104.173176 -226.96827) (xy 104.12559 -226.950223) (xy 104.081516 -226.924777)
			(xy 104.042094 -226.89259) (xy 104.008346 -226.854496) (xy 103.981145 -226.811482) (xy 103.961197 -226.764662)
			(xy 103.949018 -226.715248) (xy 103.944923 -226.66452) (xy 103.636826 -226.66452) (xy 103.636314 -226.689966)
			(xy 103.62815 -226.7402) (xy 103.612034 -226.788474) (xy 103.588383 -226.833537) (xy 103.55781 -226.874223)
			(xy 103.521106 -226.909478) (xy 103.479222 -226.938388) (xy 103.433243 -226.960205) (xy 103.384359 -226.974365)
			(xy 103.333838 -226.980499) (xy 103.282986 -226.97845) (xy 103.233122 -226.96827) (xy 103.185536 -226.950223)
			(xy 103.141462 -226.924777) (xy 103.10204 -226.89259) (xy 103.068292 -226.854496) (xy 103.041091 -226.811482)
			(xy 103.021143 -226.764662) (xy 103.008964 -226.715248) (xy 103.004869 -226.66452) (xy 102.686358 -226.66452)
			(xy 102.685863 -226.689127) (xy 102.677968 -226.737704) (xy 102.662384 -226.784385) (xy 102.639513 -226.827962)
			(xy 102.609948 -226.867306) (xy 102.574455 -226.901398) (xy 102.533952 -226.929354) (xy 102.48949 -226.950452)
			(xy 102.442219 -226.964144) (xy 102.393364 -226.970076) (xy 102.344189 -226.968095) (xy 102.29597 -226.958251)
			(xy 102.249954 -226.940799) (xy 102.207333 -226.916192) (xy 102.169212 -226.885067) (xy 102.136577 -226.84823)
			(xy 102.110274 -226.806634) (xy 102.090983 -226.761358) (xy 102.079206 -226.713574) (xy 102.075246 -226.66452)
			(xy 101.756718 -226.66452) (xy 101.756206 -226.689966) (xy 101.748042 -226.7402) (xy 101.731926 -226.788474)
			(xy 101.708275 -226.833537) (xy 101.677702 -226.874223) (xy 101.640998 -226.909478) (xy 101.599114 -226.938388)
			(xy 101.553135 -226.960205) (xy 101.504251 -226.974365) (xy 101.45373 -226.980499) (xy 101.402878 -226.97845)
			(xy 101.353014 -226.96827) (xy 101.305428 -226.950223) (xy 101.261354 -226.924777) (xy 101.221932 -226.89259)
			(xy 101.188184 -226.854496) (xy 101.160983 -226.811482) (xy 101.141035 -226.764662) (xy 101.128856 -226.715248)
			(xy 101.124761 -226.66452) (xy 100.816664 -226.66452) (xy 100.816152 -226.689966) (xy 100.807988 -226.7402)
			(xy 100.791872 -226.788474) (xy 100.768221 -226.833537) (xy 100.737648 -226.874223) (xy 100.700944 -226.909478)
			(xy 100.65906 -226.938388) (xy 100.613081 -226.960205) (xy 100.564197 -226.974365) (xy 100.513676 -226.980499)
			(xy 100.462824 -226.97845) (xy 100.41296 -226.96827) (xy 100.365374 -226.950223) (xy 100.3213 -226.924777)
			(xy 100.281878 -226.89259) (xy 100.24813 -226.854496) (xy 100.220929 -226.811482) (xy 100.200981 -226.764662)
			(xy 100.188802 -226.715248) (xy 100.184707 -226.66452) (xy 99.86645 -226.66452) (xy 99.865955 -226.689127)
			(xy 99.85806 -226.737704) (xy 99.842476 -226.784385) (xy 99.819605 -226.827962) (xy 99.79004 -226.867306)
			(xy 99.754547 -226.901398) (xy 99.714044 -226.929354) (xy 99.669582 -226.950452) (xy 99.622311 -226.964144)
			(xy 99.573456 -226.970076) (xy 99.524281 -226.968095) (xy 99.476062 -226.958251) (xy 99.430046 -226.940799)
			(xy 99.387425 -226.916192) (xy 99.349304 -226.885067) (xy 99.316669 -226.84823) (xy 99.290366 -226.806634)
			(xy 99.271075 -226.761358) (xy 99.259298 -226.713574) (xy 99.255338 -226.66452) (xy 98.93681 -226.66452)
			(xy 98.936298 -226.689966) (xy 98.928134 -226.7402) (xy 98.912018 -226.788474) (xy 98.888367 -226.833537)
			(xy 98.857794 -226.874223) (xy 98.82109 -226.909478) (xy 98.779206 -226.938388) (xy 98.733227 -226.960205)
			(xy 98.684343 -226.974365) (xy 98.633822 -226.980499) (xy 98.58297 -226.97845) (xy 98.533106 -226.96827)
			(xy 98.48552 -226.950223) (xy 98.441446 -226.924777) (xy 98.402024 -226.89259) (xy 98.368276 -226.854496)
			(xy 98.341075 -226.811482) (xy 98.321127 -226.764662) (xy 98.308948 -226.715248) (xy 98.304853 -226.66452)
			(xy 97.996756 -226.66452) (xy 97.996244 -226.689966) (xy 97.98808 -226.7402) (xy 97.971964 -226.788474)
			(xy 97.948313 -226.833537) (xy 97.91774 -226.874223) (xy 97.881036 -226.909478) (xy 97.839152 -226.938388)
			(xy 97.793173 -226.960205) (xy 97.744289 -226.974365) (xy 97.693768 -226.980499) (xy 97.642916 -226.97845)
			(xy 97.593052 -226.96827) (xy 97.545466 -226.950223) (xy 97.501392 -226.924777) (xy 97.46197 -226.89259)
			(xy 97.428222 -226.854496) (xy 97.401021 -226.811482) (xy 97.381073 -226.764662) (xy 97.368894 -226.715248)
			(xy 97.364799 -226.66452) (xy 97.046288 -226.66452) (xy 97.045793 -226.689127) (xy 97.037898 -226.737704)
			(xy 97.022314 -226.784385) (xy 96.999443 -226.827962) (xy 96.969878 -226.867306) (xy 96.934385 -226.901398)
			(xy 96.893882 -226.929354) (xy 96.84942 -226.950452) (xy 96.802149 -226.964144) (xy 96.753294 -226.970076)
			(xy 96.704119 -226.968095) (xy 96.6559 -226.958251) (xy 96.609884 -226.940799) (xy 96.567263 -226.916192)
			(xy 96.529142 -226.885067) (xy 96.496507 -226.84823) (xy 96.470204 -226.806634) (xy 96.450913 -226.761358)
			(xy 96.439136 -226.713574) (xy 96.435176 -226.66452) (xy 96.116648 -226.66452) (xy 96.116136 -226.689966)
			(xy 96.107972 -226.7402) (xy 96.091856 -226.788474) (xy 96.068205 -226.833537) (xy 96.037632 -226.874223)
			(xy 96.000928 -226.909478) (xy 95.959044 -226.938388) (xy 95.913065 -226.960205) (xy 95.864181 -226.974365)
			(xy 95.81366 -226.980499) (xy 95.762808 -226.97845) (xy 95.712944 -226.96827) (xy 95.665358 -226.950223)
			(xy 95.621284 -226.924777) (xy 95.581862 -226.89259) (xy 95.548114 -226.854496) (xy 95.520913 -226.811482)
			(xy 95.500965 -226.764662) (xy 95.488786 -226.715248) (xy 95.484691 -226.66452) (xy 95.166434 -226.66452)
			(xy 95.165939 -226.689127) (xy 95.158044 -226.737704) (xy 95.14246 -226.784385) (xy 95.119589 -226.827962)
			(xy 95.090024 -226.867306) (xy 95.054531 -226.901398) (xy 95.014028 -226.929354) (xy 94.969566 -226.950452)
			(xy 94.922295 -226.964144) (xy 94.87344 -226.970076) (xy 94.824265 -226.968095) (xy 94.776046 -226.958251)
			(xy 94.73003 -226.940799) (xy 94.687409 -226.916192) (xy 94.649288 -226.885067) (xy 94.616653 -226.84823)
			(xy 94.59035 -226.806634) (xy 94.571059 -226.761358) (xy 94.559282 -226.713574) (xy 94.555322 -226.66452)
			(xy 94.236794 -226.66452) (xy 94.236282 -226.689966) (xy 94.228118 -226.7402) (xy 94.212002 -226.788474)
			(xy 94.188351 -226.833537) (xy 94.157778 -226.874223) (xy 94.121074 -226.909478) (xy 94.07919 -226.938388)
			(xy 94.033211 -226.960205) (xy 93.984327 -226.974365) (xy 93.933806 -226.980499) (xy 93.882954 -226.97845)
			(xy 93.83309 -226.96827) (xy 93.785504 -226.950223) (xy 93.74143 -226.924777) (xy 93.702008 -226.89259)
			(xy 93.66826 -226.854496) (xy 93.641059 -226.811482) (xy 93.621111 -226.764662) (xy 93.608932 -226.715248)
			(xy 93.604837 -226.66452) (xy 93.286326 -226.66452) (xy 93.285831 -226.689127) (xy 93.277936 -226.737704)
			(xy 93.262352 -226.784385) (xy 93.239481 -226.827962) (xy 93.209916 -226.867306) (xy 93.174423 -226.901398)
			(xy 93.13392 -226.929354) (xy 93.089458 -226.950452) (xy 93.042187 -226.964144) (xy 92.993332 -226.970076)
			(xy 92.944157 -226.968095) (xy 92.895938 -226.958251) (xy 92.849922 -226.940799) (xy 92.807301 -226.916192)
			(xy 92.76918 -226.885067) (xy 92.736545 -226.84823) (xy 92.710242 -226.806634) (xy 92.690951 -226.761358)
			(xy 92.679174 -226.713574) (xy 92.675214 -226.66452) (xy 92.356686 -226.66452) (xy 92.356174 -226.689966)
			(xy 92.34801 -226.7402) (xy 92.331894 -226.788474) (xy 92.308243 -226.833537) (xy 92.27767 -226.874223)
			(xy 92.240966 -226.909478) (xy 92.199082 -226.938388) (xy 92.153103 -226.960205) (xy 92.104219 -226.974365)
			(xy 92.053698 -226.980499) (xy 92.002846 -226.97845) (xy 91.952982 -226.96827) (xy 91.905396 -226.950223)
			(xy 91.861322 -226.924777) (xy 91.8219 -226.89259) (xy 91.788152 -226.854496) (xy 91.760951 -226.811482)
			(xy 91.741003 -226.764662) (xy 91.728824 -226.715248) (xy 91.724729 -226.66452) (xy 91.416632 -226.66452)
			(xy 91.41612 -226.689966) (xy 91.407956 -226.7402) (xy 91.39184 -226.788474) (xy 91.368189 -226.833537)
			(xy 91.337616 -226.874223) (xy 91.300912 -226.909478) (xy 91.259028 -226.938388) (xy 91.213049 -226.960205)
			(xy 91.164165 -226.974365) (xy 91.113644 -226.980499) (xy 91.062792 -226.97845) (xy 91.012928 -226.96827)
			(xy 90.965342 -226.950223) (xy 90.921268 -226.924777) (xy 90.881846 -226.89259) (xy 90.848098 -226.854496)
			(xy 90.820897 -226.811482) (xy 90.800949 -226.764662) (xy 90.78877 -226.715248) (xy 90.784675 -226.66452)
			(xy 90.466909 -226.66452) (xy 90.46274 -226.714834) (xy 90.450342 -226.763795) (xy 90.430054 -226.810047)
			(xy 90.40243 -226.85233) (xy 90.368224 -226.889489) (xy 90.328368 -226.920511) (xy 90.28395 -226.944551)
			(xy 90.23618 -226.960951) (xy 90.186363 -226.969266) (xy 90.16111 -226.969828) (xy 90.148347 -226.969691)
			(xy 90.122912 -226.967533) (xy 90.11031 -226.96551) (xy 90.11031 -226.965764) (xy 90.086856 -226.961337)
			(xy 90.041601 -226.946176) (xy 89.999248 -226.924174) (xy 89.960824 -226.895863) (xy 89.927261 -226.861931)
			(xy 89.912952 -226.842828) (xy 89.904824 -226.831398) (xy 89.87917 -226.820222) (xy 89.762838 -226.835208)
			(xy 89.741248 -226.852226) (xy 89.736168 -226.865434) (xy 89.728021 -226.885757) (xy 89.708949 -226.925174)
			(xy 89.698068 -226.944174) (xy 89.694766 -226.949762) (xy 89.692734 -226.956366) (xy 89.690956 -226.969828)
			(xy 89.690956 -227.141024) (xy 89.715594 -227.169472) (xy 89.73439 -227.172266) (xy 89.758319 -227.176172)
			(xy 89.804616 -227.190558) (xy 89.848059 -227.21208) (xy 89.887554 -227.240197) (xy 89.922111 -227.274202)
			(xy 89.950859 -227.31324) (xy 89.973077 -227.35633) (xy 89.988207 -227.402391) (xy 89.995867 -227.450263)
			(xy 89.995867 -227.474526) (xy 90.314775 -227.474526) (xy 90.31887 -227.423798) (xy 90.331049 -227.374384)
			(xy 90.350997 -227.327564) (xy 90.378198 -227.28455) (xy 90.411946 -227.246456) (xy 90.451368 -227.214269)
			(xy 90.495442 -227.188823) (xy 90.543028 -227.170776) (xy 90.592892 -227.160596) (xy 90.643744 -227.158547)
			(xy 90.694265 -227.164681) (xy 90.743149 -227.178841) (xy 90.789128 -227.200658) (xy 90.831012 -227.229568)
			(xy 90.867716 -227.264823) (xy 90.898289 -227.305509) (xy 90.92194 -227.350572) (xy 90.938056 -227.398846)
			(xy 90.94622 -227.44908) (xy 90.946732 -227.474526) (xy 91.26526 -227.474526) (xy 91.26922 -227.425472)
			(xy 91.280997 -227.377688) (xy 91.300288 -227.332412) (xy 91.326591 -227.290816) (xy 91.359226 -227.253979)
			(xy 91.397347 -227.222854) (xy 91.439968 -227.198247) (xy 91.485984 -227.180795) (xy 91.534203 -227.170951)
			(xy 91.583378 -227.16897) (xy 91.632233 -227.174902) (xy 91.679504 -227.188594) (xy 91.723966 -227.209692)
			(xy 91.764469 -227.237648) (xy 91.799962 -227.27174) (xy 91.829527 -227.311084) (xy 91.852398 -227.354661)
			(xy 91.867982 -227.401342) (xy 91.875877 -227.449919) (xy 91.876372 -227.474526) (xy 92.194883 -227.474526)
			(xy 92.198978 -227.423798) (xy 92.211157 -227.374384) (xy 92.231105 -227.327564) (xy 92.258306 -227.28455)
			(xy 92.292054 -227.246456) (xy 92.331476 -227.214269) (xy 92.37555 -227.188823) (xy 92.423136 -227.170776)
			(xy 92.473 -227.160596) (xy 92.523852 -227.158547) (xy 92.574373 -227.164681) (xy 92.623257 -227.178841)
			(xy 92.669236 -227.200658) (xy 92.71112 -227.229568) (xy 92.747824 -227.264823) (xy 92.778397 -227.305509)
			(xy 92.802048 -227.350572) (xy 92.818164 -227.398846) (xy 92.826328 -227.44908) (xy 92.82684 -227.474526)
			(xy 93.145114 -227.474526) (xy 93.149074 -227.425472) (xy 93.160851 -227.377688) (xy 93.180142 -227.332412)
			(xy 93.206445 -227.290816) (xy 93.23908 -227.253979) (xy 93.277201 -227.222854) (xy 93.319822 -227.198247)
			(xy 93.365838 -227.180795) (xy 93.414057 -227.170951) (xy 93.463232 -227.16897) (xy 93.512087 -227.174902)
			(xy 93.559358 -227.188594) (xy 93.60382 -227.209692) (xy 93.644323 -227.237648) (xy 93.679816 -227.27174)
			(xy 93.709381 -227.311084) (xy 93.732252 -227.354661) (xy 93.747836 -227.401342) (xy 93.755731 -227.449919)
			(xy 93.756226 -227.474526) (xy 94.074737 -227.474526) (xy 94.078832 -227.423798) (xy 94.091011 -227.374384)
			(xy 94.110959 -227.327564) (xy 94.13816 -227.28455) (xy 94.171908 -227.246456) (xy 94.21133 -227.214269)
			(xy 94.255404 -227.188823) (xy 94.30299 -227.170776) (xy 94.352854 -227.160596) (xy 94.403706 -227.158547)
			(xy 94.454227 -227.164681) (xy 94.503111 -227.178841) (xy 94.54909 -227.200658) (xy 94.590974 -227.229568)
			(xy 94.627678 -227.264823) (xy 94.658251 -227.305509) (xy 94.681902 -227.350572) (xy 94.698018 -227.398846)
			(xy 94.706182 -227.44908) (xy 94.706694 -227.474526) (xy 95.014791 -227.474526) (xy 95.018886 -227.423798)
			(xy 95.031065 -227.374384) (xy 95.051013 -227.327564) (xy 95.078214 -227.28455) (xy 95.111962 -227.246456)
			(xy 95.151384 -227.214269) (xy 95.195458 -227.188823) (xy 95.243044 -227.170776) (xy 95.292908 -227.160596)
			(xy 95.34376 -227.158547) (xy 95.394281 -227.164681) (xy 95.443165 -227.178841) (xy 95.489144 -227.200658)
			(xy 95.531028 -227.229568) (xy 95.567732 -227.264823) (xy 95.598305 -227.305509) (xy 95.621956 -227.350572)
			(xy 95.638072 -227.398846) (xy 95.646236 -227.44908) (xy 95.646748 -227.474526) (xy 95.965276 -227.474526)
			(xy 95.969236 -227.425472) (xy 95.981013 -227.377688) (xy 96.000304 -227.332412) (xy 96.026607 -227.290816)
			(xy 96.059242 -227.253979) (xy 96.097363 -227.222854) (xy 96.139984 -227.198247) (xy 96.186 -227.180795)
			(xy 96.234219 -227.170951) (xy 96.283394 -227.16897) (xy 96.332249 -227.174902) (xy 96.37952 -227.188594)
			(xy 96.423982 -227.209692) (xy 96.464485 -227.237648) (xy 96.499978 -227.27174) (xy 96.529543 -227.311084)
			(xy 96.552414 -227.354661) (xy 96.567998 -227.401342) (xy 96.575893 -227.449919) (xy 96.576388 -227.474526)
			(xy 98.785184 -227.474526) (xy 98.789144 -227.425472) (xy 98.800921 -227.377688) (xy 98.820212 -227.332412)
			(xy 98.846515 -227.290816) (xy 98.87915 -227.253979) (xy 98.917271 -227.222854) (xy 98.959892 -227.198247)
			(xy 99.005908 -227.180795) (xy 99.054127 -227.170951) (xy 99.103302 -227.16897) (xy 99.152157 -227.174902)
			(xy 99.199428 -227.188594) (xy 99.24389 -227.209692) (xy 99.284393 -227.237648) (xy 99.319886 -227.27174)
			(xy 99.349451 -227.311084) (xy 99.372322 -227.354661) (xy 99.387906 -227.401342) (xy 99.395801 -227.449919)
			(xy 99.396296 -227.474526) (xy 101.605346 -227.474526) (xy 101.609306 -227.425472) (xy 101.621083 -227.377688)
			(xy 101.640374 -227.332412) (xy 101.666677 -227.290816) (xy 101.699312 -227.253979) (xy 101.737433 -227.222854)
			(xy 101.780054 -227.198247) (xy 101.82607 -227.180795) (xy 101.874289 -227.170951) (xy 101.923464 -227.16897)
			(xy 101.972319 -227.174902) (xy 102.01959 -227.188594) (xy 102.064052 -227.209692) (xy 102.104555 -227.237648)
			(xy 102.140048 -227.27174) (xy 102.169613 -227.311084) (xy 102.192484 -227.354661) (xy 102.208068 -227.401342)
			(xy 102.215963 -227.449919) (xy 102.216458 -227.474526) (xy 104.425254 -227.474526) (xy 104.429214 -227.425472)
			(xy 104.440991 -227.377688) (xy 104.460282 -227.332412) (xy 104.486585 -227.290816) (xy 104.51922 -227.253979)
			(xy 104.557341 -227.222854) (xy 104.599962 -227.198247) (xy 104.645978 -227.180795) (xy 104.694197 -227.170951)
			(xy 104.743372 -227.16897) (xy 104.792227 -227.174902) (xy 104.839498 -227.188594) (xy 104.88396 -227.209692)
			(xy 104.924463 -227.237648) (xy 104.959956 -227.27174) (xy 104.989521 -227.311084) (xy 105.012392 -227.354661)
			(xy 105.027976 -227.401342) (xy 105.035871 -227.449919) (xy 105.036366 -227.474526) (xy 107.245162 -227.474526)
			(xy 107.249122 -227.425472) (xy 107.260899 -227.377688) (xy 107.28019 -227.332412) (xy 107.306493 -227.290816)
			(xy 107.339128 -227.253979) (xy 107.377249 -227.222854) (xy 107.41987 -227.198247) (xy 107.465886 -227.180795)
			(xy 107.514105 -227.170951) (xy 107.56328 -227.16897) (xy 107.612135 -227.174902) (xy 107.659406 -227.188594)
			(xy 107.703868 -227.209692) (xy 107.744371 -227.237648) (xy 107.779864 -227.27174) (xy 107.809429 -227.311084)
			(xy 107.8323 -227.354661) (xy 107.847884 -227.401342) (xy 107.855779 -227.449919) (xy 107.856274 -227.474526)
			(xy 108.174785 -227.474526) (xy 108.17888 -227.423798) (xy 108.191059 -227.374384) (xy 108.211007 -227.327564)
			(xy 108.238208 -227.28455) (xy 108.271956 -227.246456) (xy 108.311378 -227.214269) (xy 108.355452 -227.188823)
			(xy 108.403038 -227.170776) (xy 108.452902 -227.160596) (xy 108.503754 -227.158547) (xy 108.554275 -227.164681)
			(xy 108.603159 -227.178841) (xy 108.649138 -227.200658) (xy 108.691022 -227.229568) (xy 108.727726 -227.264823)
			(xy 108.758299 -227.305509) (xy 108.78195 -227.350572) (xy 108.798066 -227.398846) (xy 108.80623 -227.44908)
			(xy 108.806742 -227.474526) (xy 109.114839 -227.474526) (xy 109.118934 -227.423798) (xy 109.131113 -227.374384)
			(xy 109.151061 -227.327564) (xy 109.178262 -227.28455) (xy 109.21201 -227.246456) (xy 109.251432 -227.214269)
			(xy 109.295506 -227.188823) (xy 109.343092 -227.170776) (xy 109.392956 -227.160596) (xy 109.443808 -227.158547)
			(xy 109.494329 -227.164681) (xy 109.543213 -227.178841) (xy 109.589192 -227.200658) (xy 109.631076 -227.229568)
			(xy 109.66778 -227.264823) (xy 109.698353 -227.305509) (xy 109.722004 -227.350572) (xy 109.73812 -227.398846)
			(xy 109.746284 -227.44908) (xy 109.746796 -227.474526) (xy 110.065324 -227.474526) (xy 110.069284 -227.425472)
			(xy 110.081061 -227.377688) (xy 110.100352 -227.332412) (xy 110.126655 -227.290816) (xy 110.15929 -227.253979)
			(xy 110.197411 -227.222854) (xy 110.240032 -227.198247) (xy 110.286048 -227.180795) (xy 110.334267 -227.170951)
			(xy 110.383442 -227.16897) (xy 110.432297 -227.174902) (xy 110.479568 -227.188594) (xy 110.52403 -227.209692)
			(xy 110.564533 -227.237648) (xy 110.600026 -227.27174) (xy 110.629591 -227.311084) (xy 110.652462 -227.354661)
			(xy 110.668046 -227.401342) (xy 110.675941 -227.449919) (xy 110.676436 -227.474526) (xy 110.675941 -227.499133)
			(xy 110.668046 -227.54771) (xy 110.652462 -227.594391) (xy 110.629591 -227.637968) (xy 110.600026 -227.677312)
			(xy 110.564533 -227.711404) (xy 110.52403 -227.73936) (xy 110.479568 -227.760458) (xy 110.432297 -227.77415)
			(xy 110.383442 -227.780082) (xy 110.334267 -227.778101) (xy 110.286048 -227.768257) (xy 110.240032 -227.750805)
			(xy 110.197411 -227.726198) (xy 110.15929 -227.695073) (xy 110.126655 -227.658236) (xy 110.100352 -227.61664)
			(xy 110.081061 -227.571364) (xy 110.069284 -227.52358) (xy 110.065324 -227.474526) (xy 109.746796 -227.474526)
			(xy 109.746284 -227.499972) (xy 109.73812 -227.550206) (xy 109.722004 -227.59848) (xy 109.698353 -227.643543)
			(xy 109.66778 -227.684229) (xy 109.631076 -227.719484) (xy 109.589192 -227.748394) (xy 109.543213 -227.770211)
			(xy 109.494329 -227.784371) (xy 109.443808 -227.790505) (xy 109.392956 -227.788456) (xy 109.343092 -227.778276)
			(xy 109.295506 -227.760229) (xy 109.251432 -227.734783) (xy 109.21201 -227.702596) (xy 109.178262 -227.664502)
			(xy 109.151061 -227.621488) (xy 109.131113 -227.574668) (xy 109.118934 -227.525254) (xy 109.114839 -227.474526)
			(xy 108.806742 -227.474526) (xy 108.80623 -227.499972) (xy 108.798066 -227.550206) (xy 108.78195 -227.59848)
			(xy 108.758299 -227.643543) (xy 108.727726 -227.684229) (xy 108.691022 -227.719484) (xy 108.649138 -227.748394)
			(xy 108.603159 -227.770211) (xy 108.554275 -227.784371) (xy 108.503754 -227.790505) (xy 108.452902 -227.788456)
			(xy 108.403038 -227.778276) (xy 108.355452 -227.760229) (xy 108.311378 -227.734783) (xy 108.271956 -227.702596)
			(xy 108.238208 -227.664502) (xy 108.211007 -227.621488) (xy 108.191059 -227.574668) (xy 108.17888 -227.525254)
			(xy 108.174785 -227.474526) (xy 107.856274 -227.474526) (xy 107.855779 -227.499133) (xy 107.847884 -227.54771)
			(xy 107.8323 -227.594391) (xy 107.809429 -227.637968) (xy 107.779864 -227.677312) (xy 107.744371 -227.711404)
			(xy 107.703868 -227.73936) (xy 107.659406 -227.760458) (xy 107.612135 -227.77415) (xy 107.56328 -227.780082)
			(xy 107.514105 -227.778101) (xy 107.465886 -227.768257) (xy 107.41987 -227.750805) (xy 107.377249 -227.726198)
			(xy 107.339128 -227.695073) (xy 107.306493 -227.658236) (xy 107.28019 -227.61664) (xy 107.260899 -227.571364)
			(xy 107.249122 -227.52358) (xy 107.245162 -227.474526) (xy 105.036366 -227.474526) (xy 105.035871 -227.499133)
			(xy 105.027976 -227.54771) (xy 105.012392 -227.594391) (xy 104.989521 -227.637968) (xy 104.959956 -227.677312)
			(xy 104.924463 -227.711404) (xy 104.88396 -227.73936) (xy 104.839498 -227.760458) (xy 104.792227 -227.77415)
			(xy 104.743372 -227.780082) (xy 104.694197 -227.778101) (xy 104.645978 -227.768257) (xy 104.599962 -227.750805)
			(xy 104.557341 -227.726198) (xy 104.51922 -227.695073) (xy 104.486585 -227.658236) (xy 104.460282 -227.61664)
			(xy 104.440991 -227.571364) (xy 104.429214 -227.52358) (xy 104.425254 -227.474526) (xy 102.216458 -227.474526)
			(xy 102.215963 -227.499133) (xy 102.208068 -227.54771) (xy 102.192484 -227.594391) (xy 102.169613 -227.637968)
			(xy 102.140048 -227.677312) (xy 102.104555 -227.711404) (xy 102.064052 -227.73936) (xy 102.01959 -227.760458)
			(xy 101.972319 -227.77415) (xy 101.923464 -227.780082) (xy 101.874289 -227.778101) (xy 101.82607 -227.768257)
			(xy 101.780054 -227.750805) (xy 101.737433 -227.726198) (xy 101.699312 -227.695073) (xy 101.666677 -227.658236)
			(xy 101.640374 -227.61664) (xy 101.621083 -227.571364) (xy 101.609306 -227.52358) (xy 101.605346 -227.474526)
			(xy 99.396296 -227.474526) (xy 99.395801 -227.499133) (xy 99.387906 -227.54771) (xy 99.372322 -227.594391)
			(xy 99.349451 -227.637968) (xy 99.319886 -227.677312) (xy 99.284393 -227.711404) (xy 99.24389 -227.73936)
			(xy 99.199428 -227.760458) (xy 99.152157 -227.77415) (xy 99.103302 -227.780082) (xy 99.054127 -227.778101)
			(xy 99.005908 -227.768257) (xy 98.959892 -227.750805) (xy 98.917271 -227.726198) (xy 98.87915 -227.695073)
			(xy 98.846515 -227.658236) (xy 98.820212 -227.61664) (xy 98.800921 -227.571364) (xy 98.789144 -227.52358)
			(xy 98.785184 -227.474526) (xy 96.576388 -227.474526) (xy 96.575893 -227.499133) (xy 96.567998 -227.54771)
			(xy 96.552414 -227.594391) (xy 96.529543 -227.637968) (xy 96.499978 -227.677312) (xy 96.464485 -227.711404)
			(xy 96.423982 -227.73936) (xy 96.37952 -227.760458) (xy 96.332249 -227.77415) (xy 96.283394 -227.780082)
			(xy 96.234219 -227.778101) (xy 96.186 -227.768257) (xy 96.139984 -227.750805) (xy 96.097363 -227.726198)
			(xy 96.059242 -227.695073) (xy 96.026607 -227.658236) (xy 96.000304 -227.61664) (xy 95.981013 -227.571364)
			(xy 95.969236 -227.52358) (xy 95.965276 -227.474526) (xy 95.646748 -227.474526) (xy 95.646236 -227.499972)
			(xy 95.638072 -227.550206) (xy 95.621956 -227.59848) (xy 95.598305 -227.643543) (xy 95.567732 -227.684229)
			(xy 95.531028 -227.719484) (xy 95.489144 -227.748394) (xy 95.443165 -227.770211) (xy 95.394281 -227.784371)
			(xy 95.34376 -227.790505) (xy 95.292908 -227.788456) (xy 95.243044 -227.778276) (xy 95.195458 -227.760229)
			(xy 95.151384 -227.734783) (xy 95.111962 -227.702596) (xy 95.078214 -227.664502) (xy 95.051013 -227.621488)
			(xy 95.031065 -227.574668) (xy 95.018886 -227.525254) (xy 95.014791 -227.474526) (xy 94.706694 -227.474526)
			(xy 94.706182 -227.499972) (xy 94.698018 -227.550206) (xy 94.681902 -227.59848) (xy 94.658251 -227.643543)
			(xy 94.627678 -227.684229) (xy 94.590974 -227.719484) (xy 94.54909 -227.748394) (xy 94.503111 -227.770211)
			(xy 94.454227 -227.784371) (xy 94.403706 -227.790505) (xy 94.352854 -227.788456) (xy 94.30299 -227.778276)
			(xy 94.255404 -227.760229) (xy 94.21133 -227.734783) (xy 94.171908 -227.702596) (xy 94.13816 -227.664502)
			(xy 94.110959 -227.621488) (xy 94.091011 -227.574668) (xy 94.078832 -227.525254) (xy 94.074737 -227.474526)
			(xy 93.756226 -227.474526) (xy 93.755731 -227.499133) (xy 93.747836 -227.54771) (xy 93.732252 -227.594391)
			(xy 93.709381 -227.637968) (xy 93.679816 -227.677312) (xy 93.644323 -227.711404) (xy 93.60382 -227.73936)
			(xy 93.559358 -227.760458) (xy 93.512087 -227.77415) (xy 93.463232 -227.780082) (xy 93.414057 -227.778101)
			(xy 93.365838 -227.768257) (xy 93.319822 -227.750805) (xy 93.277201 -227.726198) (xy 93.23908 -227.695073)
			(xy 93.206445 -227.658236) (xy 93.180142 -227.61664) (xy 93.160851 -227.571364) (xy 93.149074 -227.52358)
			(xy 93.145114 -227.474526) (xy 92.82684 -227.474526) (xy 92.826328 -227.499972) (xy 92.818164 -227.550206)
			(xy 92.802048 -227.59848) (xy 92.778397 -227.643543) (xy 92.747824 -227.684229) (xy 92.71112 -227.719484)
			(xy 92.669236 -227.748394) (xy 92.623257 -227.770211) (xy 92.574373 -227.784371) (xy 92.523852 -227.790505)
			(xy 92.473 -227.788456) (xy 92.423136 -227.778276) (xy 92.37555 -227.760229) (xy 92.331476 -227.734783)
			(xy 92.292054 -227.702596) (xy 92.258306 -227.664502) (xy 92.231105 -227.621488) (xy 92.211157 -227.574668)
			(xy 92.198978 -227.525254) (xy 92.194883 -227.474526) (xy 91.876372 -227.474526) (xy 91.875877 -227.499133)
			(xy 91.867982 -227.54771) (xy 91.852398 -227.594391) (xy 91.829527 -227.637968) (xy 91.799962 -227.677312)
			(xy 91.764469 -227.711404) (xy 91.723966 -227.73936) (xy 91.679504 -227.760458) (xy 91.632233 -227.77415)
			(xy 91.583378 -227.780082) (xy 91.534203 -227.778101) (xy 91.485984 -227.768257) (xy 91.439968 -227.750805)
			(xy 91.397347 -227.726198) (xy 91.359226 -227.695073) (xy 91.326591 -227.658236) (xy 91.300288 -227.61664)
			(xy 91.280997 -227.571364) (xy 91.26922 -227.52358) (xy 91.26526 -227.474526) (xy 90.946732 -227.474526)
			(xy 90.94622 -227.499972) (xy 90.938056 -227.550206) (xy 90.92194 -227.59848) (xy 90.898289 -227.643543)
			(xy 90.867716 -227.684229) (xy 90.831012 -227.719484) (xy 90.789128 -227.748394) (xy 90.743149 -227.770211)
			(xy 90.694265 -227.784371) (xy 90.643744 -227.790505) (xy 90.592892 -227.788456) (xy 90.543028 -227.778276)
			(xy 90.495442 -227.760229) (xy 90.451368 -227.734783) (xy 90.411946 -227.702596) (xy 90.378198 -227.664502)
			(xy 90.350997 -227.621488) (xy 90.331049 -227.574668) (xy 90.31887 -227.525254) (xy 90.314775 -227.474526)
			(xy 89.995867 -227.474526) (xy 89.995867 -227.498744) (xy 89.988205 -227.546617) (xy 89.973074 -227.592676)
			(xy 89.950855 -227.635767) (xy 89.922106 -227.674804) (xy 89.887549 -227.708808) (xy 89.848052 -227.736923)
			(xy 89.804609 -227.758444) (xy 89.758311 -227.77283) (xy 89.73439 -227.776786) (xy 89.715594 -227.77958)
			(xy 89.690956 -227.808028) (xy 89.690956 -227.972874) (xy 89.691128 -227.979605) (xy 89.694607 -227.992607)
			(xy 89.697814 -227.998528) (xy 89.702132 -228.00564) (xy 89.708342 -228.016523) (xy 89.719901 -228.038757)
			(xy 89.725246 -228.05009) (xy 89.738454 -228.081078) (xy 89.743534 -228.094032) (xy 89.765378 -228.11105)
			(xy 89.867486 -228.124258) (xy 89.874224 -228.12484) (xy 89.887606 -228.122916) (xy 89.893902 -228.120448)
			(xy 89.900506 -228.117654) (xy 89.91092 -228.109526) (xy 89.914984 -228.103938) (xy 89.92948 -228.084971)
			(xy 89.963373 -228.051354) (xy 90.002083 -228.02342) (xy 90.044667 -228.001847) (xy 90.090089 -227.987162)
			(xy 90.137242 -227.979722) (xy 90.16111 -227.979224) (xy 90.186362 -227.979746) (xy 90.236177 -227.98806)
			(xy 90.283945 -228.00446) (xy 90.328361 -228.028499) (xy 90.368216 -228.05952) (xy 90.402421 -228.096678)
			(xy 90.430044 -228.138959) (xy 90.450331 -228.185209) (xy 90.462728 -228.234168) (xy 90.466899 -228.2845)
			(xy 90.466896 -228.284532) (xy 90.784675 -228.284532) (xy 90.78877 -228.233804) (xy 90.800949 -228.18439)
			(xy 90.820897 -228.13757) (xy 90.848098 -228.094556) (xy 90.881846 -228.056462) (xy 90.921268 -228.024275)
			(xy 90.965342 -227.998829) (xy 91.012928 -227.980782) (xy 91.062792 -227.970602) (xy 91.113644 -227.968553)
			(xy 91.164165 -227.974687) (xy 91.213049 -227.988847) (xy 91.259028 -228.010664) (xy 91.300912 -228.039574)
			(xy 91.337616 -228.074829) (xy 91.368189 -228.115515) (xy 91.39184 -228.160578) (xy 91.407956 -228.208852)
			(xy 91.41612 -228.259086) (xy 91.416632 -228.284532) (xy 91.724729 -228.284532) (xy 91.728824 -228.233804)
			(xy 91.741003 -228.18439) (xy 91.760951 -228.13757) (xy 91.788152 -228.094556) (xy 91.8219 -228.056462)
			(xy 91.861322 -228.024275) (xy 91.905396 -227.998829) (xy 91.952982 -227.980782) (xy 92.002846 -227.970602)
			(xy 92.053698 -227.968553) (xy 92.104219 -227.974687) (xy 92.153103 -227.988847) (xy 92.199082 -228.010664)
			(xy 92.240966 -228.039574) (xy 92.27767 -228.074829) (xy 92.308243 -228.115515) (xy 92.331894 -228.160578)
			(xy 92.34801 -228.208852) (xy 92.356174 -228.259086) (xy 92.356686 -228.284532) (xy 92.675214 -228.284532)
			(xy 92.679174 -228.235478) (xy 92.690951 -228.187694) (xy 92.710242 -228.142418) (xy 92.736545 -228.100822)
			(xy 92.76918 -228.063985) (xy 92.807301 -228.03286) (xy 92.849922 -228.008253) (xy 92.895938 -227.990801)
			(xy 92.944157 -227.980957) (xy 92.993332 -227.978976) (xy 93.042187 -227.984908) (xy 93.089458 -227.9986)
			(xy 93.13392 -228.019698) (xy 93.174423 -228.047654) (xy 93.209916 -228.081746) (xy 93.239481 -228.12109)
			(xy 93.262352 -228.164667) (xy 93.277936 -228.211348) (xy 93.285831 -228.259925) (xy 93.286326 -228.284532)
			(xy 93.604837 -228.284532) (xy 93.608932 -228.233804) (xy 93.621111 -228.18439) (xy 93.641059 -228.13757)
			(xy 93.66826 -228.094556) (xy 93.702008 -228.056462) (xy 93.74143 -228.024275) (xy 93.785504 -227.998829)
			(xy 93.83309 -227.980782) (xy 93.882954 -227.970602) (xy 93.933806 -227.968553) (xy 93.984327 -227.974687)
			(xy 94.033211 -227.988847) (xy 94.07919 -228.010664) (xy 94.121074 -228.039574) (xy 94.157778 -228.074829)
			(xy 94.188351 -228.115515) (xy 94.212002 -228.160578) (xy 94.228118 -228.208852) (xy 94.236282 -228.259086)
			(xy 94.236794 -228.284532) (xy 94.555322 -228.284532) (xy 94.559282 -228.235478) (xy 94.571059 -228.187694)
			(xy 94.59035 -228.142418) (xy 94.616653 -228.100822) (xy 94.649288 -228.063985) (xy 94.687409 -228.03286)
			(xy 94.73003 -228.008253) (xy 94.776046 -227.990801) (xy 94.824265 -227.980957) (xy 94.87344 -227.978976)
			(xy 94.922295 -227.984908) (xy 94.969566 -227.9986) (xy 95.014028 -228.019698) (xy 95.054531 -228.047654)
			(xy 95.090024 -228.081746) (xy 95.119589 -228.12109) (xy 95.14246 -228.164667) (xy 95.158044 -228.211348)
			(xy 95.165939 -228.259925) (xy 95.166434 -228.284532) (xy 95.484691 -228.284532) (xy 95.488786 -228.233804)
			(xy 95.500965 -228.18439) (xy 95.520913 -228.13757) (xy 95.548114 -228.094556) (xy 95.581862 -228.056462)
			(xy 95.621284 -228.024275) (xy 95.665358 -227.998829) (xy 95.712944 -227.980782) (xy 95.762808 -227.970602)
			(xy 95.81366 -227.968553) (xy 95.864181 -227.974687) (xy 95.913065 -227.988847) (xy 95.959044 -228.010664)
			(xy 96.000928 -228.039574) (xy 96.037632 -228.074829) (xy 96.068205 -228.115515) (xy 96.091856 -228.160578)
			(xy 96.107972 -228.208852) (xy 96.116136 -228.259086) (xy 96.116648 -228.284532) (xy 96.435176 -228.284532)
			(xy 96.439136 -228.235478) (xy 96.450913 -228.187694) (xy 96.470204 -228.142418) (xy 96.496507 -228.100822)
			(xy 96.529142 -228.063985) (xy 96.567263 -228.03286) (xy 96.609884 -228.008253) (xy 96.6559 -227.990801)
			(xy 96.704119 -227.980957) (xy 96.753294 -227.978976) (xy 96.802149 -227.984908) (xy 96.84942 -227.9986)
			(xy 96.893882 -228.019698) (xy 96.934385 -228.047654) (xy 96.969878 -228.081746) (xy 96.999443 -228.12109)
			(xy 97.022314 -228.164667) (xy 97.037898 -228.211348) (xy 97.045793 -228.259925) (xy 97.046288 -228.284532)
			(xy 97.364799 -228.284532) (xy 97.368894 -228.233804) (xy 97.381073 -228.18439) (xy 97.401021 -228.13757)
			(xy 97.428222 -228.094556) (xy 97.46197 -228.056462) (xy 97.501392 -228.024275) (xy 97.545466 -227.998829)
			(xy 97.593052 -227.980782) (xy 97.642916 -227.970602) (xy 97.693768 -227.968553) (xy 97.744289 -227.974687)
			(xy 97.793173 -227.988847) (xy 97.839152 -228.010664) (xy 97.881036 -228.039574) (xy 97.91774 -228.074829)
			(xy 97.948313 -228.115515) (xy 97.971964 -228.160578) (xy 97.98808 -228.208852) (xy 97.996244 -228.259086)
			(xy 97.996756 -228.284532) (xy 98.304853 -228.284532) (xy 98.308948 -228.233804) (xy 98.321127 -228.18439)
			(xy 98.341075 -228.13757) (xy 98.368276 -228.094556) (xy 98.402024 -228.056462) (xy 98.441446 -228.024275)
			(xy 98.48552 -227.998829) (xy 98.533106 -227.980782) (xy 98.58297 -227.970602) (xy 98.633822 -227.968553)
			(xy 98.684343 -227.974687) (xy 98.733227 -227.988847) (xy 98.779206 -228.010664) (xy 98.82109 -228.039574)
			(xy 98.857794 -228.074829) (xy 98.888367 -228.115515) (xy 98.912018 -228.160578) (xy 98.928134 -228.208852)
			(xy 98.936298 -228.259086) (xy 98.93681 -228.284532) (xy 99.255338 -228.284532) (xy 99.259298 -228.235478)
			(xy 99.271075 -228.187694) (xy 99.290366 -228.142418) (xy 99.316669 -228.100822) (xy 99.349304 -228.063985)
			(xy 99.387425 -228.03286) (xy 99.430046 -228.008253) (xy 99.476062 -227.990801) (xy 99.524281 -227.980957)
			(xy 99.573456 -227.978976) (xy 99.622311 -227.984908) (xy 99.669582 -227.9986) (xy 99.714044 -228.019698)
			(xy 99.754547 -228.047654) (xy 99.79004 -228.081746) (xy 99.819605 -228.12109) (xy 99.842476 -228.164667)
			(xy 99.85806 -228.211348) (xy 99.865955 -228.259925) (xy 99.86645 -228.284532) (xy 100.184707 -228.284532)
			(xy 100.188802 -228.233804) (xy 100.200981 -228.18439) (xy 100.220929 -228.13757) (xy 100.24813 -228.094556)
			(xy 100.281878 -228.056462) (xy 100.3213 -228.024275) (xy 100.365374 -227.998829) (xy 100.41296 -227.980782)
			(xy 100.462824 -227.970602) (xy 100.513676 -227.968553) (xy 100.564197 -227.974687) (xy 100.613081 -227.988847)
			(xy 100.65906 -228.010664) (xy 100.700944 -228.039574) (xy 100.737648 -228.074829) (xy 100.768221 -228.115515)
			(xy 100.791872 -228.160578) (xy 100.807988 -228.208852) (xy 100.816152 -228.259086) (xy 100.816664 -228.284532)
			(xy 101.124761 -228.284532) (xy 101.128856 -228.233804) (xy 101.141035 -228.18439) (xy 101.160983 -228.13757)
			(xy 101.188184 -228.094556) (xy 101.221932 -228.056462) (xy 101.261354 -228.024275) (xy 101.305428 -227.998829)
			(xy 101.353014 -227.980782) (xy 101.402878 -227.970602) (xy 101.45373 -227.968553) (xy 101.504251 -227.974687)
			(xy 101.553135 -227.988847) (xy 101.599114 -228.010664) (xy 101.640998 -228.039574) (xy 101.677702 -228.074829)
			(xy 101.708275 -228.115515) (xy 101.731926 -228.160578) (xy 101.748042 -228.208852) (xy 101.756206 -228.259086)
			(xy 101.756718 -228.284532) (xy 102.075246 -228.284532) (xy 102.079206 -228.235478) (xy 102.090983 -228.187694)
			(xy 102.110274 -228.142418) (xy 102.136577 -228.100822) (xy 102.169212 -228.063985) (xy 102.207333 -228.03286)
			(xy 102.249954 -228.008253) (xy 102.29597 -227.990801) (xy 102.344189 -227.980957) (xy 102.393364 -227.978976)
			(xy 102.442219 -227.984908) (xy 102.48949 -227.9986) (xy 102.533952 -228.019698) (xy 102.574455 -228.047654)
			(xy 102.609948 -228.081746) (xy 102.639513 -228.12109) (xy 102.662384 -228.164667) (xy 102.677968 -228.211348)
			(xy 102.685863 -228.259925) (xy 102.686358 -228.284532) (xy 103.004869 -228.284532) (xy 103.008964 -228.233804)
			(xy 103.021143 -228.18439) (xy 103.041091 -228.13757) (xy 103.068292 -228.094556) (xy 103.10204 -228.056462)
			(xy 103.141462 -228.024275) (xy 103.185536 -227.998829) (xy 103.233122 -227.980782) (xy 103.282986 -227.970602)
			(xy 103.333838 -227.968553) (xy 103.384359 -227.974687) (xy 103.433243 -227.988847) (xy 103.479222 -228.010664)
			(xy 103.521106 -228.039574) (xy 103.55781 -228.074829) (xy 103.588383 -228.115515) (xy 103.612034 -228.160578)
			(xy 103.62815 -228.208852) (xy 103.636314 -228.259086) (xy 103.636826 -228.284532) (xy 103.944923 -228.284532)
			(xy 103.949018 -228.233804) (xy 103.961197 -228.18439) (xy 103.981145 -228.13757) (xy 104.008346 -228.094556)
			(xy 104.042094 -228.056462) (xy 104.081516 -228.024275) (xy 104.12559 -227.998829) (xy 104.173176 -227.980782)
			(xy 104.22304 -227.970602) (xy 104.273892 -227.968553) (xy 104.324413 -227.974687) (xy 104.373297 -227.988847)
			(xy 104.419276 -228.010664) (xy 104.46116 -228.039574) (xy 104.497864 -228.074829) (xy 104.528437 -228.115515)
			(xy 104.552088 -228.160578) (xy 104.568204 -228.208852) (xy 104.576368 -228.259086) (xy 104.57688 -228.284532)
			(xy 104.895154 -228.284532) (xy 104.899114 -228.235478) (xy 104.910891 -228.187694) (xy 104.930182 -228.142418)
			(xy 104.956485 -228.100822) (xy 104.98912 -228.063985) (xy 105.027241 -228.03286) (xy 105.069862 -228.008253)
			(xy 105.115878 -227.990801) (xy 105.164097 -227.980957) (xy 105.213272 -227.978976) (xy 105.262127 -227.984908)
			(xy 105.309398 -227.9986) (xy 105.35386 -228.019698) (xy 105.394363 -228.047654) (xy 105.429856 -228.081746)
			(xy 105.459421 -228.12109) (xy 105.482292 -228.164667) (xy 105.497876 -228.211348) (xy 105.505771 -228.259925)
			(xy 105.506266 -228.284532) (xy 105.824777 -228.284532) (xy 105.828872 -228.233804) (xy 105.841051 -228.18439)
			(xy 105.860999 -228.13757) (xy 105.8882 -228.094556) (xy 105.921948 -228.056462) (xy 105.96137 -228.024275)
			(xy 106.005444 -227.998829) (xy 106.05303 -227.980782) (xy 106.102894 -227.970602) (xy 106.153746 -227.968553)
			(xy 106.204267 -227.974687) (xy 106.253151 -227.988847) (xy 106.29913 -228.010664) (xy 106.341014 -228.039574)
			(xy 106.377718 -228.074829) (xy 106.408291 -228.115515) (xy 106.431942 -228.160578) (xy 106.448058 -228.208852)
			(xy 106.456222 -228.259086) (xy 106.456734 -228.284532) (xy 106.764831 -228.284532) (xy 106.768926 -228.233804)
			(xy 106.781105 -228.18439) (xy 106.801053 -228.13757) (xy 106.828254 -228.094556) (xy 106.862002 -228.056462)
			(xy 106.901424 -228.024275) (xy 106.945498 -227.998829) (xy 106.993084 -227.980782) (xy 107.042948 -227.970602)
			(xy 107.0938 -227.968553) (xy 107.144321 -227.974687) (xy 107.193205 -227.988847) (xy 107.239184 -228.010664)
			(xy 107.281068 -228.039574) (xy 107.317772 -228.074829) (xy 107.348345 -228.115515) (xy 107.371996 -228.160578)
			(xy 107.388112 -228.208852) (xy 107.396276 -228.259086) (xy 107.396788 -228.284532) (xy 107.715316 -228.284532)
			(xy 107.719276 -228.235478) (xy 107.731053 -228.187694) (xy 107.750344 -228.142418) (xy 107.776647 -228.100822)
			(xy 107.809282 -228.063985) (xy 107.847403 -228.03286) (xy 107.890024 -228.008253) (xy 107.93604 -227.990801)
			(xy 107.984259 -227.980957) (xy 108.033434 -227.978976) (xy 108.082289 -227.984908) (xy 108.12956 -227.9986)
			(xy 108.174022 -228.019698) (xy 108.214525 -228.047654) (xy 108.250018 -228.081746) (xy 108.279583 -228.12109)
			(xy 108.302454 -228.164667) (xy 108.318038 -228.211348) (xy 108.325933 -228.259925) (xy 108.326428 -228.284532)
			(xy 108.325933 -228.309139) (xy 108.318038 -228.357716) (xy 108.302454 -228.404397) (xy 108.279583 -228.447974)
			(xy 108.250018 -228.487318) (xy 108.214525 -228.52141) (xy 108.174022 -228.549366) (xy 108.12956 -228.570464)
			(xy 108.082289 -228.584156) (xy 108.033434 -228.590088) (xy 107.984259 -228.588107) (xy 107.93604 -228.578263)
			(xy 107.890024 -228.560811) (xy 107.847403 -228.536204) (xy 107.809282 -228.505079) (xy 107.776647 -228.468242)
			(xy 107.750344 -228.426646) (xy 107.731053 -228.38137) (xy 107.719276 -228.333586) (xy 107.715316 -228.284532)
			(xy 107.396788 -228.284532) (xy 107.396276 -228.309978) (xy 107.388112 -228.360212) (xy 107.371996 -228.408486)
			(xy 107.348345 -228.453549) (xy 107.317772 -228.494235) (xy 107.281068 -228.52949) (xy 107.239184 -228.5584)
			(xy 107.193205 -228.580217) (xy 107.144321 -228.594377) (xy 107.0938 -228.600511) (xy 107.042948 -228.598462)
			(xy 106.993084 -228.588282) (xy 106.945498 -228.570235) (xy 106.901424 -228.544789) (xy 106.862002 -228.512602)
			(xy 106.828254 -228.474508) (xy 106.801053 -228.431494) (xy 106.781105 -228.384674) (xy 106.768926 -228.33526)
			(xy 106.764831 -228.284532) (xy 106.456734 -228.284532) (xy 106.456222 -228.309978) (xy 106.448058 -228.360212)
			(xy 106.431942 -228.408486) (xy 106.408291 -228.453549) (xy 106.377718 -228.494235) (xy 106.341014 -228.52949)
			(xy 106.29913 -228.5584) (xy 106.253151 -228.580217) (xy 106.204267 -228.594377) (xy 106.153746 -228.600511)
			(xy 106.102894 -228.598462) (xy 106.05303 -228.588282) (xy 106.005444 -228.570235) (xy 105.96137 -228.544789)
			(xy 105.921948 -228.512602) (xy 105.8882 -228.474508) (xy 105.860999 -228.431494) (xy 105.841051 -228.384674)
			(xy 105.828872 -228.33526) (xy 105.824777 -228.284532) (xy 105.506266 -228.284532) (xy 105.505771 -228.309139)
			(xy 105.497876 -228.357716) (xy 105.482292 -228.404397) (xy 105.459421 -228.447974) (xy 105.429856 -228.487318)
			(xy 105.394363 -228.52141) (xy 105.35386 -228.549366) (xy 105.309398 -228.570464) (xy 105.262127 -228.584156)
			(xy 105.213272 -228.590088) (xy 105.164097 -228.588107) (xy 105.115878 -228.578263) (xy 105.069862 -228.560811)
			(xy 105.027241 -228.536204) (xy 104.98912 -228.505079) (xy 104.956485 -228.468242) (xy 104.930182 -228.426646)
			(xy 104.910891 -228.38137) (xy 104.899114 -228.333586) (xy 104.895154 -228.284532) (xy 104.57688 -228.284532)
			(xy 104.576368 -228.309978) (xy 104.568204 -228.360212) (xy 104.552088 -228.408486) (xy 104.528437 -228.453549)
			(xy 104.497864 -228.494235) (xy 104.46116 -228.52949) (xy 104.419276 -228.5584) (xy 104.373297 -228.580217)
			(xy 104.324413 -228.594377) (xy 104.273892 -228.600511) (xy 104.22304 -228.598462) (xy 104.173176 -228.588282)
			(xy 104.12559 -228.570235) (xy 104.081516 -228.544789) (xy 104.042094 -228.512602) (xy 104.008346 -228.474508)
			(xy 103.981145 -228.431494) (xy 103.961197 -228.384674) (xy 103.949018 -228.33526) (xy 103.944923 -228.284532)
			(xy 103.636826 -228.284532) (xy 103.636314 -228.309978) (xy 103.62815 -228.360212) (xy 103.612034 -228.408486)
			(xy 103.588383 -228.453549) (xy 103.55781 -228.494235) (xy 103.521106 -228.52949) (xy 103.479222 -228.5584)
			(xy 103.433243 -228.580217) (xy 103.384359 -228.594377) (xy 103.333838 -228.600511) (xy 103.282986 -228.598462)
			(xy 103.233122 -228.588282) (xy 103.185536 -228.570235) (xy 103.141462 -228.544789) (xy 103.10204 -228.512602)
			(xy 103.068292 -228.474508) (xy 103.041091 -228.431494) (xy 103.021143 -228.384674) (xy 103.008964 -228.33526)
			(xy 103.004869 -228.284532) (xy 102.686358 -228.284532) (xy 102.685863 -228.309139) (xy 102.677968 -228.357716)
			(xy 102.662384 -228.404397) (xy 102.639513 -228.447974) (xy 102.609948 -228.487318) (xy 102.574455 -228.52141)
			(xy 102.533952 -228.549366) (xy 102.48949 -228.570464) (xy 102.442219 -228.584156) (xy 102.393364 -228.590088)
			(xy 102.344189 -228.588107) (xy 102.29597 -228.578263) (xy 102.249954 -228.560811) (xy 102.207333 -228.536204)
			(xy 102.169212 -228.505079) (xy 102.136577 -228.468242) (xy 102.110274 -228.426646) (xy 102.090983 -228.38137)
			(xy 102.079206 -228.333586) (xy 102.075246 -228.284532) (xy 101.756718 -228.284532) (xy 101.756206 -228.309978)
			(xy 101.748042 -228.360212) (xy 101.731926 -228.408486) (xy 101.708275 -228.453549) (xy 101.677702 -228.494235)
			(xy 101.640998 -228.52949) (xy 101.599114 -228.5584) (xy 101.553135 -228.580217) (xy 101.504251 -228.594377)
			(xy 101.45373 -228.600511) (xy 101.402878 -228.598462) (xy 101.353014 -228.588282) (xy 101.305428 -228.570235)
			(xy 101.261354 -228.544789) (xy 101.221932 -228.512602) (xy 101.188184 -228.474508) (xy 101.160983 -228.431494)
			(xy 101.141035 -228.384674) (xy 101.128856 -228.33526) (xy 101.124761 -228.284532) (xy 100.816664 -228.284532)
			(xy 100.816152 -228.309978) (xy 100.807988 -228.360212) (xy 100.791872 -228.408486) (xy 100.768221 -228.453549)
			(xy 100.737648 -228.494235) (xy 100.700944 -228.52949) (xy 100.65906 -228.5584) (xy 100.613081 -228.580217)
			(xy 100.564197 -228.594377) (xy 100.513676 -228.600511) (xy 100.462824 -228.598462) (xy 100.41296 -228.588282)
			(xy 100.365374 -228.570235) (xy 100.3213 -228.544789) (xy 100.281878 -228.512602) (xy 100.24813 -228.474508)
			(xy 100.220929 -228.431494) (xy 100.200981 -228.384674) (xy 100.188802 -228.33526) (xy 100.184707 -228.284532)
			(xy 99.86645 -228.284532) (xy 99.865955 -228.309139) (xy 99.85806 -228.357716) (xy 99.842476 -228.404397)
			(xy 99.819605 -228.447974) (xy 99.79004 -228.487318) (xy 99.754547 -228.52141) (xy 99.714044 -228.549366)
			(xy 99.669582 -228.570464) (xy 99.622311 -228.584156) (xy 99.573456 -228.590088) (xy 99.524281 -228.588107)
			(xy 99.476062 -228.578263) (xy 99.430046 -228.560811) (xy 99.387425 -228.536204) (xy 99.349304 -228.505079)
			(xy 99.316669 -228.468242) (xy 99.290366 -228.426646) (xy 99.271075 -228.38137) (xy 99.259298 -228.333586)
			(xy 99.255338 -228.284532) (xy 98.93681 -228.284532) (xy 98.936298 -228.309978) (xy 98.928134 -228.360212)
			(xy 98.912018 -228.408486) (xy 98.888367 -228.453549) (xy 98.857794 -228.494235) (xy 98.82109 -228.52949)
			(xy 98.779206 -228.5584) (xy 98.733227 -228.580217) (xy 98.684343 -228.594377) (xy 98.633822 -228.600511)
			(xy 98.58297 -228.598462) (xy 98.533106 -228.588282) (xy 98.48552 -228.570235) (xy 98.441446 -228.544789)
			(xy 98.402024 -228.512602) (xy 98.368276 -228.474508) (xy 98.341075 -228.431494) (xy 98.321127 -228.384674)
			(xy 98.308948 -228.33526) (xy 98.304853 -228.284532) (xy 97.996756 -228.284532) (xy 97.996244 -228.309978)
			(xy 97.98808 -228.360212) (xy 97.971964 -228.408486) (xy 97.948313 -228.453549) (xy 97.91774 -228.494235)
			(xy 97.881036 -228.52949) (xy 97.839152 -228.5584) (xy 97.793173 -228.580217) (xy 97.744289 -228.594377)
			(xy 97.693768 -228.600511) (xy 97.642916 -228.598462) (xy 97.593052 -228.588282) (xy 97.545466 -228.570235)
			(xy 97.501392 -228.544789) (xy 97.46197 -228.512602) (xy 97.428222 -228.474508) (xy 97.401021 -228.431494)
			(xy 97.381073 -228.384674) (xy 97.368894 -228.33526) (xy 97.364799 -228.284532) (xy 97.046288 -228.284532)
			(xy 97.045793 -228.309139) (xy 97.037898 -228.357716) (xy 97.022314 -228.404397) (xy 96.999443 -228.447974)
			(xy 96.969878 -228.487318) (xy 96.934385 -228.52141) (xy 96.893882 -228.549366) (xy 96.84942 -228.570464)
			(xy 96.802149 -228.584156) (xy 96.753294 -228.590088) (xy 96.704119 -228.588107) (xy 96.6559 -228.578263)
			(xy 96.609884 -228.560811) (xy 96.567263 -228.536204) (xy 96.529142 -228.505079) (xy 96.496507 -228.468242)
			(xy 96.470204 -228.426646) (xy 96.450913 -228.38137) (xy 96.439136 -228.333586) (xy 96.435176 -228.284532)
			(xy 96.116648 -228.284532) (xy 96.116136 -228.309978) (xy 96.107972 -228.360212) (xy 96.091856 -228.408486)
			(xy 96.068205 -228.453549) (xy 96.037632 -228.494235) (xy 96.000928 -228.52949) (xy 95.959044 -228.5584)
			(xy 95.913065 -228.580217) (xy 95.864181 -228.594377) (xy 95.81366 -228.600511) (xy 95.762808 -228.598462)
			(xy 95.712944 -228.588282) (xy 95.665358 -228.570235) (xy 95.621284 -228.544789) (xy 95.581862 -228.512602)
			(xy 95.548114 -228.474508) (xy 95.520913 -228.431494) (xy 95.500965 -228.384674) (xy 95.488786 -228.33526)
			(xy 95.484691 -228.284532) (xy 95.166434 -228.284532) (xy 95.165939 -228.309139) (xy 95.158044 -228.357716)
			(xy 95.14246 -228.404397) (xy 95.119589 -228.447974) (xy 95.090024 -228.487318) (xy 95.054531 -228.52141)
			(xy 95.014028 -228.549366) (xy 94.969566 -228.570464) (xy 94.922295 -228.584156) (xy 94.87344 -228.590088)
			(xy 94.824265 -228.588107) (xy 94.776046 -228.578263) (xy 94.73003 -228.560811) (xy 94.687409 -228.536204)
			(xy 94.649288 -228.505079) (xy 94.616653 -228.468242) (xy 94.59035 -228.426646) (xy 94.571059 -228.38137)
			(xy 94.559282 -228.333586) (xy 94.555322 -228.284532) (xy 94.236794 -228.284532) (xy 94.236282 -228.309978)
			(xy 94.228118 -228.360212) (xy 94.212002 -228.408486) (xy 94.188351 -228.453549) (xy 94.157778 -228.494235)
			(xy 94.121074 -228.52949) (xy 94.07919 -228.5584) (xy 94.033211 -228.580217) (xy 93.984327 -228.594377)
			(xy 93.933806 -228.600511) (xy 93.882954 -228.598462) (xy 93.83309 -228.588282) (xy 93.785504 -228.570235)
			(xy 93.74143 -228.544789) (xy 93.702008 -228.512602) (xy 93.66826 -228.474508) (xy 93.641059 -228.431494)
			(xy 93.621111 -228.384674) (xy 93.608932 -228.33526) (xy 93.604837 -228.284532) (xy 93.286326 -228.284532)
			(xy 93.285831 -228.309139) (xy 93.277936 -228.357716) (xy 93.262352 -228.404397) (xy 93.239481 -228.447974)
			(xy 93.209916 -228.487318) (xy 93.174423 -228.52141) (xy 93.13392 -228.549366) (xy 93.089458 -228.570464)
			(xy 93.042187 -228.584156) (xy 92.993332 -228.590088) (xy 92.944157 -228.588107) (xy 92.895938 -228.578263)
			(xy 92.849922 -228.560811) (xy 92.807301 -228.536204) (xy 92.76918 -228.505079) (xy 92.736545 -228.468242)
			(xy 92.710242 -228.426646) (xy 92.690951 -228.38137) (xy 92.679174 -228.333586) (xy 92.675214 -228.284532)
			(xy 92.356686 -228.284532) (xy 92.356174 -228.309978) (xy 92.34801 -228.360212) (xy 92.331894 -228.408486)
			(xy 92.308243 -228.453549) (xy 92.27767 -228.494235) (xy 92.240966 -228.52949) (xy 92.199082 -228.5584)
			(xy 92.153103 -228.580217) (xy 92.104219 -228.594377) (xy 92.053698 -228.600511) (xy 92.002846 -228.598462)
			(xy 91.952982 -228.588282) (xy 91.905396 -228.570235) (xy 91.861322 -228.544789) (xy 91.8219 -228.512602)
			(xy 91.788152 -228.474508) (xy 91.760951 -228.431494) (xy 91.741003 -228.384674) (xy 91.728824 -228.33526)
			(xy 91.724729 -228.284532) (xy 91.416632 -228.284532) (xy 91.41612 -228.309978) (xy 91.407956 -228.360212)
			(xy 91.39184 -228.408486) (xy 91.368189 -228.453549) (xy 91.337616 -228.494235) (xy 91.300912 -228.52949)
			(xy 91.259028 -228.5584) (xy 91.213049 -228.580217) (xy 91.164165 -228.594377) (xy 91.113644 -228.600511)
			(xy 91.062792 -228.598462) (xy 91.012928 -228.588282) (xy 90.965342 -228.570235) (xy 90.921268 -228.544789)
			(xy 90.881846 -228.512602) (xy 90.848098 -228.474508) (xy 90.820897 -228.431494) (xy 90.800949 -228.384674)
			(xy 90.78877 -228.33526) (xy 90.784675 -228.284532) (xy 90.466896 -228.284532) (xy 90.462728 -228.334832)
			(xy 90.450331 -228.383791) (xy 90.430044 -228.430041) (xy 90.402421 -228.472322) (xy 90.368216 -228.50948)
			(xy 90.328361 -228.540501) (xy 90.283945 -228.56454) (xy 90.236177 -228.58094) (xy 90.186362 -228.589254)
			(xy 90.16111 -228.58984) (xy 90.13724 -228.589379) (xy 90.090081 -228.581946) (xy 90.044656 -228.567259)
			(xy 90.002072 -228.545677) (xy 89.963369 -228.517726) (xy 89.929491 -228.484089) (xy 89.914984 -228.465126)
			(xy 89.91092 -228.459538) (xy 89.900506 -228.45141) (xy 89.893902 -228.448616) (xy 89.887618 -228.446101)
			(xy 89.874226 -228.44418) (xy 89.867486 -228.444806) (xy 89.765378 -228.458014) (xy 89.743534 -228.475032)
			(xy 89.738454 -228.487986) (xy 89.729852 -228.5092) (xy 89.709635 -228.550274) (xy 89.698068 -228.570028)
			(xy 89.694512 -228.57587) (xy 89.690956 -228.589078) (xy 89.690956 -228.761036) (xy 89.715594 -228.789484)
			(xy 89.73439 -228.792278) (xy 89.758318 -228.796184) (xy 89.804613 -228.81057) (xy 89.848054 -228.832091)
			(xy 89.887548 -228.860207) (xy 89.922103 -228.894211) (xy 89.95085 -228.933247) (xy 89.973067 -228.976337)
			(xy 89.988195 -229.022395) (xy 89.995856 -229.070266) (xy 89.995855 -229.094538) (xy 90.314775 -229.094538)
			(xy 90.31887 -229.04381) (xy 90.331049 -228.994396) (xy 90.350997 -228.947576) (xy 90.378198 -228.904562)
			(xy 90.411946 -228.866468) (xy 90.451368 -228.834281) (xy 90.495442 -228.808835) (xy 90.543028 -228.790788)
			(xy 90.592892 -228.780608) (xy 90.643744 -228.778559) (xy 90.694265 -228.784693) (xy 90.743149 -228.798853)
			(xy 90.789128 -228.82067) (xy 90.831012 -228.84958) (xy 90.867716 -228.884835) (xy 90.898289 -228.925521)
			(xy 90.92194 -228.970584) (xy 90.938056 -229.018858) (xy 90.94622 -229.069092) (xy 90.946732 -229.094538)
			(xy 91.26526 -229.094538) (xy 91.26922 -229.045484) (xy 91.280997 -228.9977) (xy 91.300288 -228.952424)
			(xy 91.326591 -228.910828) (xy 91.359226 -228.873991) (xy 91.397347 -228.842866) (xy 91.439968 -228.818259)
			(xy 91.485984 -228.800807) (xy 91.534203 -228.790963) (xy 91.583378 -228.788982) (xy 91.632233 -228.794914)
			(xy 91.679504 -228.808606) (xy 91.723966 -228.829704) (xy 91.764469 -228.85766) (xy 91.799962 -228.891752)
			(xy 91.829527 -228.931096) (xy 91.852398 -228.974673) (xy 91.867982 -229.021354) (xy 91.875877 -229.069931)
			(xy 91.876372 -229.094538) (xy 92.194883 -229.094538) (xy 92.198978 -229.04381) (xy 92.211157 -228.994396)
			(xy 92.231105 -228.947576) (xy 92.258306 -228.904562) (xy 92.292054 -228.866468) (xy 92.331476 -228.834281)
			(xy 92.37555 -228.808835) (xy 92.423136 -228.790788) (xy 92.473 -228.780608) (xy 92.523852 -228.778559)
			(xy 92.574373 -228.784693) (xy 92.623257 -228.798853) (xy 92.669236 -228.82067) (xy 92.71112 -228.84958)
			(xy 92.747824 -228.884835) (xy 92.778397 -228.925521) (xy 92.802048 -228.970584) (xy 92.818164 -229.018858)
			(xy 92.826328 -229.069092) (xy 92.82684 -229.094538) (xy 93.145114 -229.094538) (xy 93.149074 -229.045484)
			(xy 93.160851 -228.9977) (xy 93.180142 -228.952424) (xy 93.206445 -228.910828) (xy 93.23908 -228.873991)
			(xy 93.277201 -228.842866) (xy 93.319822 -228.818259) (xy 93.365838 -228.800807) (xy 93.414057 -228.790963)
			(xy 93.463232 -228.788982) (xy 93.512087 -228.794914) (xy 93.559358 -228.808606) (xy 93.60382 -228.829704)
			(xy 93.644323 -228.85766) (xy 93.679816 -228.891752) (xy 93.709381 -228.931096) (xy 93.732252 -228.974673)
			(xy 93.747836 -229.021354) (xy 93.755731 -229.069931) (xy 93.756226 -229.094538) (xy 94.074737 -229.094538)
			(xy 94.078832 -229.04381) (xy 94.091011 -228.994396) (xy 94.110959 -228.947576) (xy 94.13816 -228.904562)
			(xy 94.171908 -228.866468) (xy 94.21133 -228.834281) (xy 94.255404 -228.808835) (xy 94.30299 -228.790788)
			(xy 94.352854 -228.780608) (xy 94.403706 -228.778559) (xy 94.454227 -228.784693) (xy 94.503111 -228.798853)
			(xy 94.54909 -228.82067) (xy 94.590974 -228.84958) (xy 94.627678 -228.884835) (xy 94.658251 -228.925521)
			(xy 94.681902 -228.970584) (xy 94.698018 -229.018858) (xy 94.706182 -229.069092) (xy 94.706694 -229.094538)
			(xy 95.014791 -229.094538) (xy 95.018886 -229.04381) (xy 95.031065 -228.994396) (xy 95.051013 -228.947576)
			(xy 95.078214 -228.904562) (xy 95.111962 -228.866468) (xy 95.151384 -228.834281) (xy 95.195458 -228.808835)
			(xy 95.243044 -228.790788) (xy 95.292908 -228.780608) (xy 95.34376 -228.778559) (xy 95.394281 -228.784693)
			(xy 95.443165 -228.798853) (xy 95.489144 -228.82067) (xy 95.531028 -228.84958) (xy 95.567732 -228.884835)
			(xy 95.598305 -228.925521) (xy 95.621956 -228.970584) (xy 95.638072 -229.018858) (xy 95.646236 -229.069092)
			(xy 95.646748 -229.094538) (xy 95.965276 -229.094538) (xy 95.969236 -229.045484) (xy 95.981013 -228.9977)
			(xy 96.000304 -228.952424) (xy 96.026607 -228.910828) (xy 96.059242 -228.873991) (xy 96.097363 -228.842866)
			(xy 96.139984 -228.818259) (xy 96.186 -228.800807) (xy 96.234219 -228.790963) (xy 96.283394 -228.788982)
			(xy 96.332249 -228.794914) (xy 96.37952 -228.808606) (xy 96.423982 -228.829704) (xy 96.464485 -228.85766)
			(xy 96.499978 -228.891752) (xy 96.529543 -228.931096) (xy 96.552414 -228.974673) (xy 96.567998 -229.021354)
			(xy 96.575893 -229.069931) (xy 96.576388 -229.094538) (xy 96.90533 -229.094538) (xy 96.90929 -229.045484)
			(xy 96.921067 -228.9977) (xy 96.940358 -228.952424) (xy 96.966661 -228.910828) (xy 96.999296 -228.873991)
			(xy 97.037417 -228.842866) (xy 97.080038 -228.818259) (xy 97.126054 -228.800807) (xy 97.174273 -228.790963)
			(xy 97.223448 -228.788982) (xy 97.272303 -228.794914) (xy 97.319574 -228.808606) (xy 97.364036 -228.829704)
			(xy 97.404539 -228.85766) (xy 97.440032 -228.891752) (xy 97.469597 -228.931096) (xy 97.492468 -228.974673)
			(xy 97.508052 -229.021354) (xy 97.515947 -229.069931) (xy 97.516442 -229.094538) (xy 97.84513 -229.094538)
			(xy 97.84909 -229.045484) (xy 97.860867 -228.9977) (xy 97.880158 -228.952424) (xy 97.906461 -228.910828)
			(xy 97.939096 -228.873991) (xy 97.977217 -228.842866) (xy 98.019838 -228.818259) (xy 98.065854 -228.800807)
			(xy 98.114073 -228.790963) (xy 98.163248 -228.788982) (xy 98.212103 -228.794914) (xy 98.259374 -228.808606)
			(xy 98.303836 -228.829704) (xy 98.344339 -228.85766) (xy 98.379832 -228.891752) (xy 98.409397 -228.931096)
			(xy 98.432268 -228.974673) (xy 98.447852 -229.021354) (xy 98.455747 -229.069931) (xy 98.456242 -229.094538)
			(xy 98.785184 -229.094538) (xy 98.789144 -229.045484) (xy 98.800921 -228.9977) (xy 98.820212 -228.952424)
			(xy 98.846515 -228.910828) (xy 98.87915 -228.873991) (xy 98.917271 -228.842866) (xy 98.959892 -228.818259)
			(xy 99.005908 -228.800807) (xy 99.054127 -228.790963) (xy 99.103302 -228.788982) (xy 99.152157 -228.794914)
			(xy 99.199428 -228.808606) (xy 99.24389 -228.829704) (xy 99.284393 -228.85766) (xy 99.319886 -228.891752)
			(xy 99.349451 -228.931096) (xy 99.372322 -228.974673) (xy 99.387906 -229.021354) (xy 99.395801 -229.069931)
			(xy 99.396296 -229.094538) (xy 99.725238 -229.094538) (xy 99.729198 -229.045484) (xy 99.740975 -228.9977)
			(xy 99.760266 -228.952424) (xy 99.786569 -228.910828) (xy 99.819204 -228.873991) (xy 99.857325 -228.842866)
			(xy 99.899946 -228.818259) (xy 99.945962 -228.800807) (xy 99.994181 -228.790963) (xy 100.043356 -228.788982)
			(xy 100.092211 -228.794914) (xy 100.139482 -228.808606) (xy 100.183944 -228.829704) (xy 100.224447 -228.85766)
			(xy 100.25994 -228.891752) (xy 100.289505 -228.931096) (xy 100.312376 -228.974673) (xy 100.32796 -229.021354)
			(xy 100.335855 -229.069931) (xy 100.33635 -229.094538) (xy 100.665292 -229.094538) (xy 100.669252 -229.045484)
			(xy 100.681029 -228.9977) (xy 100.70032 -228.952424) (xy 100.726623 -228.910828) (xy 100.759258 -228.873991)
			(xy 100.797379 -228.842866) (xy 100.84 -228.818259) (xy 100.886016 -228.800807) (xy 100.934235 -228.790963)
			(xy 100.98341 -228.788982) (xy 101.032265 -228.794914) (xy 101.079536 -228.808606) (xy 101.123998 -228.829704)
			(xy 101.164501 -228.85766) (xy 101.199994 -228.891752) (xy 101.229559 -228.931096) (xy 101.25243 -228.974673)
			(xy 101.268014 -229.021354) (xy 101.275909 -229.069931) (xy 101.276404 -229.094538) (xy 101.605346 -229.094538)
			(xy 101.609306 -229.045484) (xy 101.621083 -228.9977) (xy 101.640374 -228.952424) (xy 101.666677 -228.910828)
			(xy 101.699312 -228.873991) (xy 101.737433 -228.842866) (xy 101.780054 -228.818259) (xy 101.82607 -228.800807)
			(xy 101.874289 -228.790963) (xy 101.923464 -228.788982) (xy 101.972319 -228.794914) (xy 102.01959 -228.808606)
			(xy 102.064052 -228.829704) (xy 102.104555 -228.85766) (xy 102.140048 -228.891752) (xy 102.169613 -228.931096)
			(xy 102.192484 -228.974673) (xy 102.208068 -229.021354) (xy 102.215963 -229.069931) (xy 102.216458 -229.094538)
			(xy 102.545146 -229.094538) (xy 102.549106 -229.045484) (xy 102.560883 -228.9977) (xy 102.580174 -228.952424)
			(xy 102.606477 -228.910828) (xy 102.639112 -228.873991) (xy 102.677233 -228.842866) (xy 102.719854 -228.818259)
			(xy 102.76587 -228.800807) (xy 102.814089 -228.790963) (xy 102.863264 -228.788982) (xy 102.912119 -228.794914)
			(xy 102.95939 -228.808606) (xy 103.003852 -228.829704) (xy 103.044355 -228.85766) (xy 103.079848 -228.891752)
			(xy 103.109413 -228.931096) (xy 103.132284 -228.974673) (xy 103.147868 -229.021354) (xy 103.155763 -229.069931)
			(xy 103.156258 -229.094538) (xy 103.4852 -229.094538) (xy 103.48916 -229.045484) (xy 103.500937 -228.9977)
			(xy 103.520228 -228.952424) (xy 103.546531 -228.910828) (xy 103.579166 -228.873991) (xy 103.617287 -228.842866)
			(xy 103.659908 -228.818259) (xy 103.705924 -228.800807) (xy 103.754143 -228.790963) (xy 103.803318 -228.788982)
			(xy 103.852173 -228.794914) (xy 103.899444 -228.808606) (xy 103.943906 -228.829704) (xy 103.984409 -228.85766)
			(xy 104.019902 -228.891752) (xy 104.049467 -228.931096) (xy 104.072338 -228.974673) (xy 104.087922 -229.021354)
			(xy 104.095817 -229.069931) (xy 104.096312 -229.094538) (xy 104.425254 -229.094538) (xy 104.429214 -229.045484)
			(xy 104.440991 -228.9977) (xy 104.460282 -228.952424) (xy 104.486585 -228.910828) (xy 104.51922 -228.873991)
			(xy 104.557341 -228.842866) (xy 104.599962 -228.818259) (xy 104.645978 -228.800807) (xy 104.694197 -228.790963)
			(xy 104.743372 -228.788982) (xy 104.792227 -228.794914) (xy 104.839498 -228.808606) (xy 104.88396 -228.829704)
			(xy 104.924463 -228.85766) (xy 104.959956 -228.891752) (xy 104.989521 -228.931096) (xy 105.012392 -228.974673)
			(xy 105.027976 -229.021354) (xy 105.035871 -229.069931) (xy 105.036366 -229.094538) (xy 105.365308 -229.094538)
			(xy 105.369268 -229.045484) (xy 105.381045 -228.9977) (xy 105.400336 -228.952424) (xy 105.426639 -228.910828)
			(xy 105.459274 -228.873991) (xy 105.497395 -228.842866) (xy 105.540016 -228.818259) (xy 105.586032 -228.800807)
			(xy 105.634251 -228.790963) (xy 105.683426 -228.788982) (xy 105.732281 -228.794914) (xy 105.779552 -228.808606)
			(xy 105.824014 -228.829704) (xy 105.864517 -228.85766) (xy 105.90001 -228.891752) (xy 105.929575 -228.931096)
			(xy 105.952446 -228.974673) (xy 105.96803 -229.021354) (xy 105.975925 -229.069931) (xy 105.97642 -229.094538)
			(xy 106.305362 -229.094538) (xy 106.309322 -229.045484) (xy 106.321099 -228.9977) (xy 106.34039 -228.952424)
			(xy 106.366693 -228.910828) (xy 106.399328 -228.873991) (xy 106.437449 -228.842866) (xy 106.48007 -228.818259)
			(xy 106.526086 -228.800807) (xy 106.574305 -228.790963) (xy 106.62348 -228.788982) (xy 106.672335 -228.794914)
			(xy 106.719606 -228.808606) (xy 106.764068 -228.829704) (xy 106.804571 -228.85766) (xy 106.840064 -228.891752)
			(xy 106.869629 -228.931096) (xy 106.8925 -228.974673) (xy 106.908084 -229.021354) (xy 106.915979 -229.069931)
			(xy 106.916474 -229.094538) (xy 107.245162 -229.094538) (xy 107.249122 -229.045484) (xy 107.260899 -228.9977)
			(xy 107.28019 -228.952424) (xy 107.306493 -228.910828) (xy 107.339128 -228.873991) (xy 107.377249 -228.842866)
			(xy 107.41987 -228.818259) (xy 107.465886 -228.800807) (xy 107.514105 -228.790963) (xy 107.56328 -228.788982)
			(xy 107.612135 -228.794914) (xy 107.659406 -228.808606) (xy 107.703868 -228.829704) (xy 107.744371 -228.85766)
			(xy 107.779864 -228.891752) (xy 107.809429 -228.931096) (xy 107.8323 -228.974673) (xy 107.847884 -229.021354)
			(xy 107.855779 -229.069931) (xy 107.856274 -229.094538) (xy 108.174785 -229.094538) (xy 108.17888 -229.04381)
			(xy 108.191059 -228.994396) (xy 108.211007 -228.947576) (xy 108.238208 -228.904562) (xy 108.271956 -228.866468)
			(xy 108.311378 -228.834281) (xy 108.355452 -228.808835) (xy 108.403038 -228.790788) (xy 108.452902 -228.780608)
			(xy 108.503754 -228.778559) (xy 108.554275 -228.784693) (xy 108.603159 -228.798853) (xy 108.649138 -228.82067)
			(xy 108.691022 -228.84958) (xy 108.727726 -228.884835) (xy 108.758299 -228.925521) (xy 108.78195 -228.970584)
			(xy 108.798066 -229.018858) (xy 108.80623 -229.069092) (xy 108.806742 -229.094538) (xy 109.114839 -229.094538)
			(xy 109.118934 -229.04381) (xy 109.131113 -228.994396) (xy 109.151061 -228.947576) (xy 109.178262 -228.904562)
			(xy 109.21201 -228.866468) (xy 109.251432 -228.834281) (xy 109.295506 -228.808835) (xy 109.343092 -228.790788)
			(xy 109.392956 -228.780608) (xy 109.443808 -228.778559) (xy 109.494329 -228.784693) (xy 109.543213 -228.798853)
			(xy 109.589192 -228.82067) (xy 109.631076 -228.84958) (xy 109.66778 -228.884835) (xy 109.698353 -228.925521)
			(xy 109.722004 -228.970584) (xy 109.73812 -229.018858) (xy 109.746284 -229.069092) (xy 109.746796 -229.094538)
			(xy 110.065324 -229.094538) (xy 110.069284 -229.045484) (xy 110.081061 -228.9977) (xy 110.100352 -228.952424)
			(xy 110.126655 -228.910828) (xy 110.15929 -228.873991) (xy 110.197411 -228.842866) (xy 110.240032 -228.818259)
			(xy 110.286048 -228.800807) (xy 110.334267 -228.790963) (xy 110.383442 -228.788982) (xy 110.432297 -228.794914)
			(xy 110.479568 -228.808606) (xy 110.52403 -228.829704) (xy 110.564533 -228.85766) (xy 110.600026 -228.891752)
			(xy 110.629591 -228.931096) (xy 110.652462 -228.974673) (xy 110.668046 -229.021354) (xy 110.675941 -229.069931)
			(xy 110.676436 -229.094538) (xy 110.675941 -229.119145) (xy 110.668046 -229.167722) (xy 110.652462 -229.214403)
			(xy 110.629591 -229.25798) (xy 110.600026 -229.297324) (xy 110.564533 -229.331416) (xy 110.52403 -229.359372)
			(xy 110.479568 -229.38047) (xy 110.432297 -229.394162) (xy 110.383442 -229.400094) (xy 110.334267 -229.398113)
			(xy 110.286048 -229.388269) (xy 110.240032 -229.370817) (xy 110.197411 -229.34621) (xy 110.15929 -229.315085)
			(xy 110.126655 -229.278248) (xy 110.100352 -229.236652) (xy 110.081061 -229.191376) (xy 110.069284 -229.143592)
			(xy 110.065324 -229.094538) (xy 109.746796 -229.094538) (xy 109.746284 -229.119984) (xy 109.73812 -229.170218)
			(xy 109.722004 -229.218492) (xy 109.698353 -229.263555) (xy 109.66778 -229.304241) (xy 109.631076 -229.339496)
			(xy 109.589192 -229.368406) (xy 109.543213 -229.390223) (xy 109.494329 -229.404383) (xy 109.443808 -229.410517)
			(xy 109.392956 -229.408468) (xy 109.343092 -229.398288) (xy 109.295506 -229.380241) (xy 109.251432 -229.354795)
			(xy 109.21201 -229.322608) (xy 109.178262 -229.284514) (xy 109.151061 -229.2415) (xy 109.131113 -229.19468)
			(xy 109.118934 -229.145266) (xy 109.114839 -229.094538) (xy 108.806742 -229.094538) (xy 108.80623 -229.119984)
			(xy 108.798066 -229.170218) (xy 108.78195 -229.218492) (xy 108.758299 -229.263555) (xy 108.727726 -229.304241)
			(xy 108.691022 -229.339496) (xy 108.649138 -229.368406) (xy 108.603159 -229.390223) (xy 108.554275 -229.404383)
			(xy 108.503754 -229.410517) (xy 108.452902 -229.408468) (xy 108.403038 -229.398288) (xy 108.355452 -229.380241)
			(xy 108.311378 -229.354795) (xy 108.271956 -229.322608) (xy 108.238208 -229.284514) (xy 108.211007 -229.2415)
			(xy 108.191059 -229.19468) (xy 108.17888 -229.145266) (xy 108.174785 -229.094538) (xy 107.856274 -229.094538)
			(xy 107.855779 -229.119145) (xy 107.847884 -229.167722) (xy 107.8323 -229.214403) (xy 107.809429 -229.25798)
			(xy 107.779864 -229.297324) (xy 107.744371 -229.331416) (xy 107.703868 -229.359372) (xy 107.659406 -229.38047)
			(xy 107.612135 -229.394162) (xy 107.56328 -229.400094) (xy 107.514105 -229.398113) (xy 107.465886 -229.388269)
			(xy 107.41987 -229.370817) (xy 107.377249 -229.34621) (xy 107.339128 -229.315085) (xy 107.306493 -229.278248)
			(xy 107.28019 -229.236652) (xy 107.260899 -229.191376) (xy 107.249122 -229.143592) (xy 107.245162 -229.094538)
			(xy 106.916474 -229.094538) (xy 106.915979 -229.119145) (xy 106.908084 -229.167722) (xy 106.8925 -229.214403)
			(xy 106.869629 -229.25798) (xy 106.840064 -229.297324) (xy 106.804571 -229.331416) (xy 106.764068 -229.359372)
			(xy 106.719606 -229.38047) (xy 106.672335 -229.394162) (xy 106.62348 -229.400094) (xy 106.574305 -229.398113)
			(xy 106.526086 -229.388269) (xy 106.48007 -229.370817) (xy 106.437449 -229.34621) (xy 106.399328 -229.315085)
			(xy 106.366693 -229.278248) (xy 106.34039 -229.236652) (xy 106.321099 -229.191376) (xy 106.309322 -229.143592)
			(xy 106.305362 -229.094538) (xy 105.97642 -229.094538) (xy 105.975925 -229.119145) (xy 105.96803 -229.167722)
			(xy 105.952446 -229.214403) (xy 105.929575 -229.25798) (xy 105.90001 -229.297324) (xy 105.864517 -229.331416)
			(xy 105.824014 -229.359372) (xy 105.779552 -229.38047) (xy 105.732281 -229.394162) (xy 105.683426 -229.400094)
			(xy 105.634251 -229.398113) (xy 105.586032 -229.388269) (xy 105.540016 -229.370817) (xy 105.497395 -229.34621)
			(xy 105.459274 -229.315085) (xy 105.426639 -229.278248) (xy 105.400336 -229.236652) (xy 105.381045 -229.191376)
			(xy 105.369268 -229.143592) (xy 105.365308 -229.094538) (xy 105.036366 -229.094538) (xy 105.035871 -229.119145)
			(xy 105.027976 -229.167722) (xy 105.012392 -229.214403) (xy 104.989521 -229.25798) (xy 104.959956 -229.297324)
			(xy 104.924463 -229.331416) (xy 104.88396 -229.359372) (xy 104.839498 -229.38047) (xy 104.792227 -229.394162)
			(xy 104.743372 -229.400094) (xy 104.694197 -229.398113) (xy 104.645978 -229.388269) (xy 104.599962 -229.370817)
			(xy 104.557341 -229.34621) (xy 104.51922 -229.315085) (xy 104.486585 -229.278248) (xy 104.460282 -229.236652)
			(xy 104.440991 -229.191376) (xy 104.429214 -229.143592) (xy 104.425254 -229.094538) (xy 104.096312 -229.094538)
			(xy 104.095817 -229.119145) (xy 104.087922 -229.167722) (xy 104.072338 -229.214403) (xy 104.049467 -229.25798)
			(xy 104.019902 -229.297324) (xy 103.984409 -229.331416) (xy 103.943906 -229.359372) (xy 103.899444 -229.38047)
			(xy 103.852173 -229.394162) (xy 103.803318 -229.400094) (xy 103.754143 -229.398113) (xy 103.705924 -229.388269)
			(xy 103.659908 -229.370817) (xy 103.617287 -229.34621) (xy 103.579166 -229.315085) (xy 103.546531 -229.278248)
			(xy 103.520228 -229.236652) (xy 103.500937 -229.191376) (xy 103.48916 -229.143592) (xy 103.4852 -229.094538)
			(xy 103.156258 -229.094538) (xy 103.155763 -229.119145) (xy 103.147868 -229.167722) (xy 103.132284 -229.214403)
			(xy 103.109413 -229.25798) (xy 103.079848 -229.297324) (xy 103.044355 -229.331416) (xy 103.003852 -229.359372)
			(xy 102.95939 -229.38047) (xy 102.912119 -229.394162) (xy 102.863264 -229.400094) (xy 102.814089 -229.398113)
			(xy 102.76587 -229.388269) (xy 102.719854 -229.370817) (xy 102.677233 -229.34621) (xy 102.639112 -229.315085)
			(xy 102.606477 -229.278248) (xy 102.580174 -229.236652) (xy 102.560883 -229.191376) (xy 102.549106 -229.143592)
			(xy 102.545146 -229.094538) (xy 102.216458 -229.094538) (xy 102.215963 -229.119145) (xy 102.208068 -229.167722)
			(xy 102.192484 -229.214403) (xy 102.169613 -229.25798) (xy 102.140048 -229.297324) (xy 102.104555 -229.331416)
			(xy 102.064052 -229.359372) (xy 102.01959 -229.38047) (xy 101.972319 -229.394162) (xy 101.923464 -229.400094)
			(xy 101.874289 -229.398113) (xy 101.82607 -229.388269) (xy 101.780054 -229.370817) (xy 101.737433 -229.34621)
			(xy 101.699312 -229.315085) (xy 101.666677 -229.278248) (xy 101.640374 -229.236652) (xy 101.621083 -229.191376)
			(xy 101.609306 -229.143592) (xy 101.605346 -229.094538) (xy 101.276404 -229.094538) (xy 101.275909 -229.119145)
			(xy 101.268014 -229.167722) (xy 101.25243 -229.214403) (xy 101.229559 -229.25798) (xy 101.199994 -229.297324)
			(xy 101.164501 -229.331416) (xy 101.123998 -229.359372) (xy 101.079536 -229.38047) (xy 101.032265 -229.394162)
			(xy 100.98341 -229.400094) (xy 100.934235 -229.398113) (xy 100.886016 -229.388269) (xy 100.84 -229.370817)
			(xy 100.797379 -229.34621) (xy 100.759258 -229.315085) (xy 100.726623 -229.278248) (xy 100.70032 -229.236652)
			(xy 100.681029 -229.191376) (xy 100.669252 -229.143592) (xy 100.665292 -229.094538) (xy 100.33635 -229.094538)
			(xy 100.335855 -229.119145) (xy 100.32796 -229.167722) (xy 100.312376 -229.214403) (xy 100.289505 -229.25798)
			(xy 100.25994 -229.297324) (xy 100.224447 -229.331416) (xy 100.183944 -229.359372) (xy 100.139482 -229.38047)
			(xy 100.092211 -229.394162) (xy 100.043356 -229.400094) (xy 99.994181 -229.398113) (xy 99.945962 -229.388269)
			(xy 99.899946 -229.370817) (xy 99.857325 -229.34621) (xy 99.819204 -229.315085) (xy 99.786569 -229.278248)
			(xy 99.760266 -229.236652) (xy 99.740975 -229.191376) (xy 99.729198 -229.143592) (xy 99.725238 -229.094538)
			(xy 99.396296 -229.094538) (xy 99.395801 -229.119145) (xy 99.387906 -229.167722) (xy 99.372322 -229.214403)
			(xy 99.349451 -229.25798) (xy 99.319886 -229.297324) (xy 99.284393 -229.331416) (xy 99.24389 -229.359372)
			(xy 99.199428 -229.38047) (xy 99.152157 -229.394162) (xy 99.103302 -229.400094) (xy 99.054127 -229.398113)
			(xy 99.005908 -229.388269) (xy 98.959892 -229.370817) (xy 98.917271 -229.34621) (xy 98.87915 -229.315085)
			(xy 98.846515 -229.278248) (xy 98.820212 -229.236652) (xy 98.800921 -229.191376) (xy 98.789144 -229.143592)
			(xy 98.785184 -229.094538) (xy 98.456242 -229.094538) (xy 98.455747 -229.119145) (xy 98.447852 -229.167722)
			(xy 98.432268 -229.214403) (xy 98.409397 -229.25798) (xy 98.379832 -229.297324) (xy 98.344339 -229.331416)
			(xy 98.303836 -229.359372) (xy 98.259374 -229.38047) (xy 98.212103 -229.394162) (xy 98.163248 -229.400094)
			(xy 98.114073 -229.398113) (xy 98.065854 -229.388269) (xy 98.019838 -229.370817) (xy 97.977217 -229.34621)
			(xy 97.939096 -229.315085) (xy 97.906461 -229.278248) (xy 97.880158 -229.236652) (xy 97.860867 -229.191376)
			(xy 97.84909 -229.143592) (xy 97.84513 -229.094538) (xy 97.516442 -229.094538) (xy 97.515947 -229.119145)
			(xy 97.508052 -229.167722) (xy 97.492468 -229.214403) (xy 97.469597 -229.25798) (xy 97.440032 -229.297324)
			(xy 97.404539 -229.331416) (xy 97.364036 -229.359372) (xy 97.319574 -229.38047) (xy 97.272303 -229.394162)
			(xy 97.223448 -229.400094) (xy 97.174273 -229.398113) (xy 97.126054 -229.388269) (xy 97.080038 -229.370817)
			(xy 97.037417 -229.34621) (xy 96.999296 -229.315085) (xy 96.966661 -229.278248) (xy 96.940358 -229.236652)
			(xy 96.921067 -229.191376) (xy 96.90929 -229.143592) (xy 96.90533 -229.094538) (xy 96.576388 -229.094538)
			(xy 96.575893 -229.119145) (xy 96.567998 -229.167722) (xy 96.552414 -229.214403) (xy 96.529543 -229.25798)
			(xy 96.499978 -229.297324) (xy 96.464485 -229.331416) (xy 96.423982 -229.359372) (xy 96.37952 -229.38047)
			(xy 96.332249 -229.394162) (xy 96.283394 -229.400094) (xy 96.234219 -229.398113) (xy 96.186 -229.388269)
			(xy 96.139984 -229.370817) (xy 96.097363 -229.34621) (xy 96.059242 -229.315085) (xy 96.026607 -229.278248)
			(xy 96.000304 -229.236652) (xy 95.981013 -229.191376) (xy 95.969236 -229.143592) (xy 95.965276 -229.094538)
			(xy 95.646748 -229.094538) (xy 95.646236 -229.119984) (xy 95.638072 -229.170218) (xy 95.621956 -229.218492)
			(xy 95.598305 -229.263555) (xy 95.567732 -229.304241) (xy 95.531028 -229.339496) (xy 95.489144 -229.368406)
			(xy 95.443165 -229.390223) (xy 95.394281 -229.404383) (xy 95.34376 -229.410517) (xy 95.292908 -229.408468)
			(xy 95.243044 -229.398288) (xy 95.195458 -229.380241) (xy 95.151384 -229.354795) (xy 95.111962 -229.322608)
			(xy 95.078214 -229.284514) (xy 95.051013 -229.2415) (xy 95.031065 -229.19468) (xy 95.018886 -229.145266)
			(xy 95.014791 -229.094538) (xy 94.706694 -229.094538) (xy 94.706182 -229.119984) (xy 94.698018 -229.170218)
			(xy 94.681902 -229.218492) (xy 94.658251 -229.263555) (xy 94.627678 -229.304241) (xy 94.590974 -229.339496)
			(xy 94.54909 -229.368406) (xy 94.503111 -229.390223) (xy 94.454227 -229.404383) (xy 94.403706 -229.410517)
			(xy 94.352854 -229.408468) (xy 94.30299 -229.398288) (xy 94.255404 -229.380241) (xy 94.21133 -229.354795)
			(xy 94.171908 -229.322608) (xy 94.13816 -229.284514) (xy 94.110959 -229.2415) (xy 94.091011 -229.19468)
			(xy 94.078832 -229.145266) (xy 94.074737 -229.094538) (xy 93.756226 -229.094538) (xy 93.755731 -229.119145)
			(xy 93.747836 -229.167722) (xy 93.732252 -229.214403) (xy 93.709381 -229.25798) (xy 93.679816 -229.297324)
			(xy 93.644323 -229.331416) (xy 93.60382 -229.359372) (xy 93.559358 -229.38047) (xy 93.512087 -229.394162)
			(xy 93.463232 -229.400094) (xy 93.414057 -229.398113) (xy 93.365838 -229.388269) (xy 93.319822 -229.370817)
			(xy 93.277201 -229.34621) (xy 93.23908 -229.315085) (xy 93.206445 -229.278248) (xy 93.180142 -229.236652)
			(xy 93.160851 -229.191376) (xy 93.149074 -229.143592) (xy 93.145114 -229.094538) (xy 92.82684 -229.094538)
			(xy 92.826328 -229.119984) (xy 92.818164 -229.170218) (xy 92.802048 -229.218492) (xy 92.778397 -229.263555)
			(xy 92.747824 -229.304241) (xy 92.71112 -229.339496) (xy 92.669236 -229.368406) (xy 92.623257 -229.390223)
			(xy 92.574373 -229.404383) (xy 92.523852 -229.410517) (xy 92.473 -229.408468) (xy 92.423136 -229.398288)
			(xy 92.37555 -229.380241) (xy 92.331476 -229.354795) (xy 92.292054 -229.322608) (xy 92.258306 -229.284514)
			(xy 92.231105 -229.2415) (xy 92.211157 -229.19468) (xy 92.198978 -229.145266) (xy 92.194883 -229.094538)
			(xy 91.876372 -229.094538) (xy 91.875877 -229.119145) (xy 91.867982 -229.167722) (xy 91.852398 -229.214403)
			(xy 91.829527 -229.25798) (xy 91.799962 -229.297324) (xy 91.764469 -229.331416) (xy 91.723966 -229.359372)
			(xy 91.679504 -229.38047) (xy 91.632233 -229.394162) (xy 91.583378 -229.400094) (xy 91.534203 -229.398113)
			(xy 91.485984 -229.388269) (xy 91.439968 -229.370817) (xy 91.397347 -229.34621) (xy 91.359226 -229.315085)
			(xy 91.326591 -229.278248) (xy 91.300288 -229.236652) (xy 91.280997 -229.191376) (xy 91.26922 -229.143592)
			(xy 91.26526 -229.094538) (xy 90.946732 -229.094538) (xy 90.94622 -229.119984) (xy 90.938056 -229.170218)
			(xy 90.92194 -229.218492) (xy 90.898289 -229.263555) (xy 90.867716 -229.304241) (xy 90.831012 -229.339496)
			(xy 90.789128 -229.368406) (xy 90.743149 -229.390223) (xy 90.694265 -229.404383) (xy 90.643744 -229.410517)
			(xy 90.592892 -229.408468) (xy 90.543028 -229.398288) (xy 90.495442 -229.380241) (xy 90.451368 -229.354795)
			(xy 90.411946 -229.322608) (xy 90.378198 -229.284514) (xy 90.350997 -229.2415) (xy 90.331049 -229.19468)
			(xy 90.31887 -229.145266) (xy 90.314775 -229.094538) (xy 89.995855 -229.094538) (xy 89.995855 -229.118745)
			(xy 89.988193 -229.166615) (xy 89.973063 -229.212673) (xy 89.950844 -229.255762) (xy 89.922096 -229.294797)
			(xy 89.88754 -229.3288) (xy 89.848045 -229.356914) (xy 89.804603 -229.378434) (xy 89.758307 -229.392819)
			(xy 89.73439 -229.396798) (xy 89.715594 -229.399592) (xy 89.690956 -229.42804) (xy 89.690956 -229.598982)
			(xy 89.691215 -229.605871) (xy 89.694936 -229.61914) (xy 89.698322 -229.625144) (xy 89.699338 -229.626922)
			(xy 89.70763 -229.641496) (xy 89.722628 -229.671488) (xy 89.72931 -229.686866) (xy 89.736168 -229.703376)
			(xy 89.741248 -229.716584) (xy 89.762838 -229.733602) (xy 89.879424 -229.748588) (xy 89.905078 -229.737412)
			(xy 89.913206 -229.725982) (xy 89.927672 -229.706685) (xy 89.961662 -229.672472) (xy 90.000602 -229.644021)
			(xy 90.043527 -229.622037) (xy 90.089371 -229.607066) (xy 90.136997 -229.59948) (xy 90.16111 -229.598982)
			(xy 90.186366 -229.599504) (xy 90.236188 -229.60782) (xy 90.283962 -229.624222) (xy 90.328384 -229.648264)
			(xy 90.368244 -229.679289) (xy 90.402454 -229.716452) (xy 90.430081 -229.758739) (xy 90.45037 -229.804996)
			(xy 90.46277 -229.853961) (xy 90.46694 -229.90429) (xy 90.784675 -229.90429) (xy 90.78877 -229.853562)
			(xy 90.800949 -229.804148) (xy 90.820897 -229.757328) (xy 90.848098 -229.714314) (xy 90.881846 -229.67622)
			(xy 90.921268 -229.644033) (xy 90.965342 -229.618587) (xy 91.012928 -229.60054) (xy 91.062792 -229.59036)
			(xy 91.113644 -229.588311) (xy 91.164165 -229.594445) (xy 91.213049 -229.608605) (xy 91.259028 -229.630422)
			(xy 91.300912 -229.659332) (xy 91.337616 -229.694587) (xy 91.368189 -229.735273) (xy 91.39184 -229.780336)
			(xy 91.407956 -229.82861) (xy 91.41612 -229.878844) (xy 91.416632 -229.90429) (xy 91.724729 -229.90429)
			(xy 91.728824 -229.853562) (xy 91.741003 -229.804148) (xy 91.760951 -229.757328) (xy 91.788152 -229.714314)
			(xy 91.8219 -229.67622) (xy 91.861322 -229.644033) (xy 91.905396 -229.618587) (xy 91.952982 -229.60054)
			(xy 92.002846 -229.59036) (xy 92.053698 -229.588311) (xy 92.104219 -229.594445) (xy 92.153103 -229.608605)
			(xy 92.199082 -229.630422) (xy 92.240966 -229.659332) (xy 92.27767 -229.694587) (xy 92.308243 -229.735273)
			(xy 92.331894 -229.780336) (xy 92.34801 -229.82861) (xy 92.356174 -229.878844) (xy 92.356686 -229.90429)
			(xy 92.675214 -229.90429) (xy 92.679174 -229.855236) (xy 92.690951 -229.807452) (xy 92.710242 -229.762176)
			(xy 92.736545 -229.72058) (xy 92.76918 -229.683743) (xy 92.807301 -229.652618) (xy 92.849922 -229.628011)
			(xy 92.895938 -229.610559) (xy 92.944157 -229.600715) (xy 92.993332 -229.598734) (xy 93.042187 -229.604666)
			(xy 93.089458 -229.618358) (xy 93.13392 -229.639456) (xy 93.174423 -229.667412) (xy 93.209916 -229.701504)
			(xy 93.239481 -229.740848) (xy 93.262352 -229.784425) (xy 93.277936 -229.831106) (xy 93.285831 -229.879683)
			(xy 93.286326 -229.90429) (xy 93.604837 -229.90429) (xy 93.608932 -229.853562) (xy 93.621111 -229.804148)
			(xy 93.641059 -229.757328) (xy 93.66826 -229.714314) (xy 93.702008 -229.67622) (xy 93.74143 -229.644033)
			(xy 93.785504 -229.618587) (xy 93.83309 -229.60054) (xy 93.882954 -229.59036) (xy 93.933806 -229.588311)
			(xy 93.984327 -229.594445) (xy 94.033211 -229.608605) (xy 94.07919 -229.630422) (xy 94.121074 -229.659332)
			(xy 94.157778 -229.694587) (xy 94.188351 -229.735273) (xy 94.212002 -229.780336) (xy 94.228118 -229.82861)
			(xy 94.236282 -229.878844) (xy 94.236794 -229.90429) (xy 94.555322 -229.90429) (xy 94.559282 -229.855236)
			(xy 94.571059 -229.807452) (xy 94.59035 -229.762176) (xy 94.616653 -229.72058) (xy 94.649288 -229.683743)
			(xy 94.687409 -229.652618) (xy 94.73003 -229.628011) (xy 94.776046 -229.610559) (xy 94.824265 -229.600715)
			(xy 94.87344 -229.598734) (xy 94.922295 -229.604666) (xy 94.969566 -229.618358) (xy 95.014028 -229.639456)
			(xy 95.054531 -229.667412) (xy 95.090024 -229.701504) (xy 95.119589 -229.740848) (xy 95.14246 -229.784425)
			(xy 95.158044 -229.831106) (xy 95.165939 -229.879683) (xy 95.166434 -229.90429) (xy 95.484691 -229.90429)
			(xy 95.488786 -229.853562) (xy 95.500965 -229.804148) (xy 95.520913 -229.757328) (xy 95.548114 -229.714314)
			(xy 95.581862 -229.67622) (xy 95.621284 -229.644033) (xy 95.665358 -229.618587) (xy 95.712944 -229.60054)
			(xy 95.762808 -229.59036) (xy 95.81366 -229.588311) (xy 95.864181 -229.594445) (xy 95.913065 -229.608605)
			(xy 95.959044 -229.630422) (xy 96.000928 -229.659332) (xy 96.037632 -229.694587) (xy 96.068205 -229.735273)
			(xy 96.091856 -229.780336) (xy 96.107972 -229.82861) (xy 96.116136 -229.878844) (xy 96.116648 -229.90429)
			(xy 96.435176 -229.90429) (xy 96.439136 -229.855236) (xy 96.450913 -229.807452) (xy 96.470204 -229.762176)
			(xy 96.496507 -229.72058) (xy 96.529142 -229.683743) (xy 96.567263 -229.652618) (xy 96.609884 -229.628011)
			(xy 96.6559 -229.610559) (xy 96.704119 -229.600715) (xy 96.753294 -229.598734) (xy 96.802149 -229.604666)
			(xy 96.84942 -229.618358) (xy 96.893882 -229.639456) (xy 96.934385 -229.667412) (xy 96.969878 -229.701504)
			(xy 96.999443 -229.740848) (xy 97.022314 -229.784425) (xy 97.037898 -229.831106) (xy 97.045793 -229.879683)
			(xy 97.046288 -229.90429) (xy 97.364799 -229.90429) (xy 97.368894 -229.853562) (xy 97.381073 -229.804148)
			(xy 97.401021 -229.757328) (xy 97.428222 -229.714314) (xy 97.46197 -229.67622) (xy 97.501392 -229.644033)
			(xy 97.545466 -229.618587) (xy 97.593052 -229.60054) (xy 97.642916 -229.59036) (xy 97.693768 -229.588311)
			(xy 97.744289 -229.594445) (xy 97.793173 -229.608605) (xy 97.839152 -229.630422) (xy 97.881036 -229.659332)
			(xy 97.91774 -229.694587) (xy 97.948313 -229.735273) (xy 97.971964 -229.780336) (xy 97.98808 -229.82861)
			(xy 97.996244 -229.878844) (xy 97.996756 -229.90429) (xy 98.304853 -229.90429) (xy 98.308948 -229.853562)
			(xy 98.321127 -229.804148) (xy 98.341075 -229.757328) (xy 98.368276 -229.714314) (xy 98.402024 -229.67622)
			(xy 98.441446 -229.644033) (xy 98.48552 -229.618587) (xy 98.533106 -229.60054) (xy 98.58297 -229.59036)
			(xy 98.633822 -229.588311) (xy 98.684343 -229.594445) (xy 98.733227 -229.608605) (xy 98.779206 -229.630422)
			(xy 98.82109 -229.659332) (xy 98.857794 -229.694587) (xy 98.888367 -229.735273) (xy 98.912018 -229.780336)
			(xy 98.928134 -229.82861) (xy 98.936298 -229.878844) (xy 98.93681 -229.90429) (xy 99.255338 -229.90429)
			(xy 99.259298 -229.855236) (xy 99.271075 -229.807452) (xy 99.290366 -229.762176) (xy 99.316669 -229.72058)
			(xy 99.349304 -229.683743) (xy 99.387425 -229.652618) (xy 99.430046 -229.628011) (xy 99.476062 -229.610559)
			(xy 99.524281 -229.600715) (xy 99.573456 -229.598734) (xy 99.622311 -229.604666) (xy 99.669582 -229.618358)
			(xy 99.714044 -229.639456) (xy 99.754547 -229.667412) (xy 99.79004 -229.701504) (xy 99.819605 -229.740848)
			(xy 99.842476 -229.784425) (xy 99.85806 -229.831106) (xy 99.865955 -229.879683) (xy 99.86645 -229.90429)
			(xy 100.184707 -229.90429) (xy 100.188802 -229.853562) (xy 100.200981 -229.804148) (xy 100.220929 -229.757328)
			(xy 100.24813 -229.714314) (xy 100.281878 -229.67622) (xy 100.3213 -229.644033) (xy 100.365374 -229.618587)
			(xy 100.41296 -229.60054) (xy 100.462824 -229.59036) (xy 100.513676 -229.588311) (xy 100.564197 -229.594445)
			(xy 100.613081 -229.608605) (xy 100.65906 -229.630422) (xy 100.700944 -229.659332) (xy 100.737648 -229.694587)
			(xy 100.768221 -229.735273) (xy 100.791872 -229.780336) (xy 100.807988 -229.82861) (xy 100.816152 -229.878844)
			(xy 100.816664 -229.90429) (xy 101.124761 -229.90429) (xy 101.128856 -229.853562) (xy 101.141035 -229.804148)
			(xy 101.160983 -229.757328) (xy 101.188184 -229.714314) (xy 101.221932 -229.67622) (xy 101.261354 -229.644033)
			(xy 101.305428 -229.618587) (xy 101.353014 -229.60054) (xy 101.402878 -229.59036) (xy 101.45373 -229.588311)
			(xy 101.504251 -229.594445) (xy 101.553135 -229.608605) (xy 101.599114 -229.630422) (xy 101.640998 -229.659332)
			(xy 101.677702 -229.694587) (xy 101.708275 -229.735273) (xy 101.731926 -229.780336) (xy 101.748042 -229.82861)
			(xy 101.756206 -229.878844) (xy 101.756718 -229.90429) (xy 102.075246 -229.90429) (xy 102.079206 -229.855236)
			(xy 102.090983 -229.807452) (xy 102.110274 -229.762176) (xy 102.136577 -229.72058) (xy 102.169212 -229.683743)
			(xy 102.207333 -229.652618) (xy 102.249954 -229.628011) (xy 102.29597 -229.610559) (xy 102.344189 -229.600715)
			(xy 102.393364 -229.598734) (xy 102.442219 -229.604666) (xy 102.48949 -229.618358) (xy 102.533952 -229.639456)
			(xy 102.574455 -229.667412) (xy 102.609948 -229.701504) (xy 102.639513 -229.740848) (xy 102.662384 -229.784425)
			(xy 102.677968 -229.831106) (xy 102.685863 -229.879683) (xy 102.686358 -229.90429) (xy 103.004869 -229.90429)
			(xy 103.008964 -229.853562) (xy 103.021143 -229.804148) (xy 103.041091 -229.757328) (xy 103.068292 -229.714314)
			(xy 103.10204 -229.67622) (xy 103.141462 -229.644033) (xy 103.185536 -229.618587) (xy 103.233122 -229.60054)
			(xy 103.282986 -229.59036) (xy 103.333838 -229.588311) (xy 103.384359 -229.594445) (xy 103.433243 -229.608605)
			(xy 103.479222 -229.630422) (xy 103.521106 -229.659332) (xy 103.55781 -229.694587) (xy 103.588383 -229.735273)
			(xy 103.612034 -229.780336) (xy 103.62815 -229.82861) (xy 103.636314 -229.878844) (xy 103.636826 -229.90429)
			(xy 103.944923 -229.90429) (xy 103.949018 -229.853562) (xy 103.961197 -229.804148) (xy 103.981145 -229.757328)
			(xy 104.008346 -229.714314) (xy 104.042094 -229.67622) (xy 104.081516 -229.644033) (xy 104.12559 -229.618587)
			(xy 104.173176 -229.60054) (xy 104.22304 -229.59036) (xy 104.273892 -229.588311) (xy 104.324413 -229.594445)
			(xy 104.373297 -229.608605) (xy 104.419276 -229.630422) (xy 104.46116 -229.659332) (xy 104.497864 -229.694587)
			(xy 104.528437 -229.735273) (xy 104.552088 -229.780336) (xy 104.568204 -229.82861) (xy 104.576368 -229.878844)
			(xy 104.57688 -229.90429) (xy 104.895154 -229.90429) (xy 104.899114 -229.855236) (xy 104.910891 -229.807452)
			(xy 104.930182 -229.762176) (xy 104.956485 -229.72058) (xy 104.98912 -229.683743) (xy 105.027241 -229.652618)
			(xy 105.069862 -229.628011) (xy 105.115878 -229.610559) (xy 105.164097 -229.600715) (xy 105.213272 -229.598734)
			(xy 105.262127 -229.604666) (xy 105.309398 -229.618358) (xy 105.35386 -229.639456) (xy 105.394363 -229.667412)
			(xy 105.429856 -229.701504) (xy 105.459421 -229.740848) (xy 105.482292 -229.784425) (xy 105.497876 -229.831106)
			(xy 105.505771 -229.879683) (xy 105.506266 -229.90429) (xy 105.824777 -229.90429) (xy 105.828872 -229.853562)
			(xy 105.841051 -229.804148) (xy 105.860999 -229.757328) (xy 105.8882 -229.714314) (xy 105.921948 -229.67622)
			(xy 105.96137 -229.644033) (xy 106.005444 -229.618587) (xy 106.05303 -229.60054) (xy 106.102894 -229.59036)
			(xy 106.153746 -229.588311) (xy 106.204267 -229.594445) (xy 106.253151 -229.608605) (xy 106.29913 -229.630422)
			(xy 106.341014 -229.659332) (xy 106.377718 -229.694587) (xy 106.408291 -229.735273) (xy 106.431942 -229.780336)
			(xy 106.448058 -229.82861) (xy 106.456222 -229.878844) (xy 106.456734 -229.90429) (xy 106.764831 -229.90429)
			(xy 106.768926 -229.853562) (xy 106.781105 -229.804148) (xy 106.801053 -229.757328) (xy 106.828254 -229.714314)
			(xy 106.862002 -229.67622) (xy 106.901424 -229.644033) (xy 106.945498 -229.618587) (xy 106.993084 -229.60054)
			(xy 107.042948 -229.59036) (xy 107.0938 -229.588311) (xy 107.144321 -229.594445) (xy 107.193205 -229.608605)
			(xy 107.239184 -229.630422) (xy 107.281068 -229.659332) (xy 107.317772 -229.694587) (xy 107.348345 -229.735273)
			(xy 107.371996 -229.780336) (xy 107.388112 -229.82861) (xy 107.396276 -229.878844) (xy 107.396788 -229.90429)
			(xy 107.715316 -229.90429) (xy 107.719276 -229.855236) (xy 107.731053 -229.807452) (xy 107.750344 -229.762176)
			(xy 107.776647 -229.72058) (xy 107.809282 -229.683743) (xy 107.847403 -229.652618) (xy 107.890024 -229.628011)
			(xy 107.93604 -229.610559) (xy 107.984259 -229.600715) (xy 108.033434 -229.598734) (xy 108.082289 -229.604666)
			(xy 108.12956 -229.618358) (xy 108.174022 -229.639456) (xy 108.214525 -229.667412) (xy 108.250018 -229.701504)
			(xy 108.279583 -229.740848) (xy 108.302454 -229.784425) (xy 108.318038 -229.831106) (xy 108.325933 -229.879683)
			(xy 108.326428 -229.90429) (xy 108.65537 -229.90429) (xy 108.65933 -229.855236) (xy 108.671107 -229.807452)
			(xy 108.690398 -229.762176) (xy 108.716701 -229.72058) (xy 108.749336 -229.683743) (xy 108.787457 -229.652618)
			(xy 108.830078 -229.628011) (xy 108.876094 -229.610559) (xy 108.924313 -229.600715) (xy 108.973488 -229.598734)
			(xy 109.022343 -229.604666) (xy 109.069614 -229.618358) (xy 109.114076 -229.639456) (xy 109.154579 -229.667412)
			(xy 109.190072 -229.701504) (xy 109.219637 -229.740848) (xy 109.242508 -229.784425) (xy 109.258092 -229.831106)
			(xy 109.265987 -229.879683) (xy 109.266482 -229.90429) (xy 109.59517 -229.90429) (xy 109.59913 -229.855236)
			(xy 109.610907 -229.807452) (xy 109.630198 -229.762176) (xy 109.656501 -229.72058) (xy 109.689136 -229.683743)
			(xy 109.727257 -229.652618) (xy 109.769878 -229.628011) (xy 109.815894 -229.610559) (xy 109.864113 -229.600715)
			(xy 109.913288 -229.598734) (xy 109.962143 -229.604666) (xy 110.009414 -229.618358) (xy 110.053876 -229.639456)
			(xy 110.094379 -229.667412) (xy 110.129872 -229.701504) (xy 110.159437 -229.740848) (xy 110.182308 -229.784425)
			(xy 110.197892 -229.831106) (xy 110.205787 -229.879683) (xy 110.206282 -229.90429) (xy 110.205787 -229.928897)
			(xy 110.197892 -229.977474) (xy 110.182308 -230.024155) (xy 110.159437 -230.067732) (xy 110.129872 -230.107076)
			(xy 110.094379 -230.141168) (xy 110.053876 -230.169124) (xy 110.009414 -230.190222) (xy 109.962143 -230.203914)
			(xy 109.913288 -230.209846) (xy 109.864113 -230.207865) (xy 109.815894 -230.198021) (xy 109.769878 -230.180569)
			(xy 109.727257 -230.155962) (xy 109.689136 -230.124837) (xy 109.656501 -230.088) (xy 109.630198 -230.046404)
			(xy 109.610907 -230.001128) (xy 109.59913 -229.953344) (xy 109.59517 -229.90429) (xy 109.266482 -229.90429)
			(xy 109.265987 -229.928897) (xy 109.258092 -229.977474) (xy 109.242508 -230.024155) (xy 109.219637 -230.067732)
			(xy 109.190072 -230.107076) (xy 109.154579 -230.141168) (xy 109.114076 -230.169124) (xy 109.069614 -230.190222)
			(xy 109.022343 -230.203914) (xy 108.973488 -230.209846) (xy 108.924313 -230.207865) (xy 108.876094 -230.198021)
			(xy 108.830078 -230.180569) (xy 108.787457 -230.155962) (xy 108.749336 -230.124837) (xy 108.716701 -230.088)
			(xy 108.690398 -230.046404) (xy 108.671107 -230.001128) (xy 108.65933 -229.953344) (xy 108.65537 -229.90429)
			(xy 108.326428 -229.90429) (xy 108.325933 -229.928897) (xy 108.318038 -229.977474) (xy 108.302454 -230.024155)
			(xy 108.279583 -230.067732) (xy 108.250018 -230.107076) (xy 108.214525 -230.141168) (xy 108.174022 -230.169124)
			(xy 108.12956 -230.190222) (xy 108.082289 -230.203914) (xy 108.033434 -230.209846) (xy 107.984259 -230.207865)
			(xy 107.93604 -230.198021) (xy 107.890024 -230.180569) (xy 107.847403 -230.155962) (xy 107.809282 -230.124837)
			(xy 107.776647 -230.088) (xy 107.750344 -230.046404) (xy 107.731053 -230.001128) (xy 107.719276 -229.953344)
			(xy 107.715316 -229.90429) (xy 107.396788 -229.90429) (xy 107.396276 -229.929736) (xy 107.388112 -229.97997)
			(xy 107.371996 -230.028244) (xy 107.348345 -230.073307) (xy 107.317772 -230.113993) (xy 107.281068 -230.149248)
			(xy 107.239184 -230.178158) (xy 107.193205 -230.199975) (xy 107.144321 -230.214135) (xy 107.0938 -230.220269)
			(xy 107.042948 -230.21822) (xy 106.993084 -230.20804) (xy 106.945498 -230.189993) (xy 106.901424 -230.164547)
			(xy 106.862002 -230.13236) (xy 106.828254 -230.094266) (xy 106.801053 -230.051252) (xy 106.781105 -230.004432)
			(xy 106.768926 -229.955018) (xy 106.764831 -229.90429) (xy 106.456734 -229.90429) (xy 106.456222 -229.929736)
			(xy 106.448058 -229.97997) (xy 106.431942 -230.028244) (xy 106.408291 -230.073307) (xy 106.377718 -230.113993)
			(xy 106.341014 -230.149248) (xy 106.29913 -230.178158) (xy 106.253151 -230.199975) (xy 106.204267 -230.214135)
			(xy 106.153746 -230.220269) (xy 106.102894 -230.21822) (xy 106.05303 -230.20804) (xy 106.005444 -230.189993)
			(xy 105.96137 -230.164547) (xy 105.921948 -230.13236) (xy 105.8882 -230.094266) (xy 105.860999 -230.051252)
			(xy 105.841051 -230.004432) (xy 105.828872 -229.955018) (xy 105.824777 -229.90429) (xy 105.506266 -229.90429)
			(xy 105.505771 -229.928897) (xy 105.497876 -229.977474) (xy 105.482292 -230.024155) (xy 105.459421 -230.067732)
			(xy 105.429856 -230.107076) (xy 105.394363 -230.141168) (xy 105.35386 -230.169124) (xy 105.309398 -230.190222)
			(xy 105.262127 -230.203914) (xy 105.213272 -230.209846) (xy 105.164097 -230.207865) (xy 105.115878 -230.198021)
			(xy 105.069862 -230.180569) (xy 105.027241 -230.155962) (xy 104.98912 -230.124837) (xy 104.956485 -230.088)
			(xy 104.930182 -230.046404) (xy 104.910891 -230.001128) (xy 104.899114 -229.953344) (xy 104.895154 -229.90429)
			(xy 104.57688 -229.90429) (xy 104.576368 -229.929736) (xy 104.568204 -229.97997) (xy 104.552088 -230.028244)
			(xy 104.528437 -230.073307) (xy 104.497864 -230.113993) (xy 104.46116 -230.149248) (xy 104.419276 -230.178158)
			(xy 104.373297 -230.199975) (xy 104.324413 -230.214135) (xy 104.273892 -230.220269) (xy 104.22304 -230.21822)
			(xy 104.173176 -230.20804) (xy 104.12559 -230.189993) (xy 104.081516 -230.164547) (xy 104.042094 -230.13236)
			(xy 104.008346 -230.094266) (xy 103.981145 -230.051252) (xy 103.961197 -230.004432) (xy 103.949018 -229.955018)
			(xy 103.944923 -229.90429) (xy 103.636826 -229.90429) (xy 103.636314 -229.929736) (xy 103.62815 -229.97997)
			(xy 103.612034 -230.028244) (xy 103.588383 -230.073307) (xy 103.55781 -230.113993) (xy 103.521106 -230.149248)
			(xy 103.479222 -230.178158) (xy 103.433243 -230.199975) (xy 103.384359 -230.214135) (xy 103.333838 -230.220269)
			(xy 103.282986 -230.21822) (xy 103.233122 -230.20804) (xy 103.185536 -230.189993) (xy 103.141462 -230.164547)
			(xy 103.10204 -230.13236) (xy 103.068292 -230.094266) (xy 103.041091 -230.051252) (xy 103.021143 -230.004432)
			(xy 103.008964 -229.955018) (xy 103.004869 -229.90429) (xy 102.686358 -229.90429) (xy 102.685863 -229.928897)
			(xy 102.677968 -229.977474) (xy 102.662384 -230.024155) (xy 102.639513 -230.067732) (xy 102.609948 -230.107076)
			(xy 102.574455 -230.141168) (xy 102.533952 -230.169124) (xy 102.48949 -230.190222) (xy 102.442219 -230.203914)
			(xy 102.393364 -230.209846) (xy 102.344189 -230.207865) (xy 102.29597 -230.198021) (xy 102.249954 -230.180569)
			(xy 102.207333 -230.155962) (xy 102.169212 -230.124837) (xy 102.136577 -230.088) (xy 102.110274 -230.046404)
			(xy 102.090983 -230.001128) (xy 102.079206 -229.953344) (xy 102.075246 -229.90429) (xy 101.756718 -229.90429)
			(xy 101.756206 -229.929736) (xy 101.748042 -229.97997) (xy 101.731926 -230.028244) (xy 101.708275 -230.073307)
			(xy 101.677702 -230.113993) (xy 101.640998 -230.149248) (xy 101.599114 -230.178158) (xy 101.553135 -230.199975)
			(xy 101.504251 -230.214135) (xy 101.45373 -230.220269) (xy 101.402878 -230.21822) (xy 101.353014 -230.20804)
			(xy 101.305428 -230.189993) (xy 101.261354 -230.164547) (xy 101.221932 -230.13236) (xy 101.188184 -230.094266)
			(xy 101.160983 -230.051252) (xy 101.141035 -230.004432) (xy 101.128856 -229.955018) (xy 101.124761 -229.90429)
			(xy 100.816664 -229.90429) (xy 100.816152 -229.929736) (xy 100.807988 -229.97997) (xy 100.791872 -230.028244)
			(xy 100.768221 -230.073307) (xy 100.737648 -230.113993) (xy 100.700944 -230.149248) (xy 100.65906 -230.178158)
			(xy 100.613081 -230.199975) (xy 100.564197 -230.214135) (xy 100.513676 -230.220269) (xy 100.462824 -230.21822)
			(xy 100.41296 -230.20804) (xy 100.365374 -230.189993) (xy 100.3213 -230.164547) (xy 100.281878 -230.13236)
			(xy 100.24813 -230.094266) (xy 100.220929 -230.051252) (xy 100.200981 -230.004432) (xy 100.188802 -229.955018)
			(xy 100.184707 -229.90429) (xy 99.86645 -229.90429) (xy 99.865955 -229.928897) (xy 99.85806 -229.977474)
			(xy 99.842476 -230.024155) (xy 99.819605 -230.067732) (xy 99.79004 -230.107076) (xy 99.754547 -230.141168)
			(xy 99.714044 -230.169124) (xy 99.669582 -230.190222) (xy 99.622311 -230.203914) (xy 99.573456 -230.209846)
			(xy 99.524281 -230.207865) (xy 99.476062 -230.198021) (xy 99.430046 -230.180569) (xy 99.387425 -230.155962)
			(xy 99.349304 -230.124837) (xy 99.316669 -230.088) (xy 99.290366 -230.046404) (xy 99.271075 -230.001128)
			(xy 99.259298 -229.953344) (xy 99.255338 -229.90429) (xy 98.93681 -229.90429) (xy 98.936298 -229.929736)
			(xy 98.928134 -229.97997) (xy 98.912018 -230.028244) (xy 98.888367 -230.073307) (xy 98.857794 -230.113993)
			(xy 98.82109 -230.149248) (xy 98.779206 -230.178158) (xy 98.733227 -230.199975) (xy 98.684343 -230.214135)
			(xy 98.633822 -230.220269) (xy 98.58297 -230.21822) (xy 98.533106 -230.20804) (xy 98.48552 -230.189993)
			(xy 98.441446 -230.164547) (xy 98.402024 -230.13236) (xy 98.368276 -230.094266) (xy 98.341075 -230.051252)
			(xy 98.321127 -230.004432) (xy 98.308948 -229.955018) (xy 98.304853 -229.90429) (xy 97.996756 -229.90429)
			(xy 97.996244 -229.929736) (xy 97.98808 -229.97997) (xy 97.971964 -230.028244) (xy 97.948313 -230.073307)
			(xy 97.91774 -230.113993) (xy 97.881036 -230.149248) (xy 97.839152 -230.178158) (xy 97.793173 -230.199975)
			(xy 97.744289 -230.214135) (xy 97.693768 -230.220269) (xy 97.642916 -230.21822) (xy 97.593052 -230.20804)
			(xy 97.545466 -230.189993) (xy 97.501392 -230.164547) (xy 97.46197 -230.13236) (xy 97.428222 -230.094266)
			(xy 97.401021 -230.051252) (xy 97.381073 -230.004432) (xy 97.368894 -229.955018) (xy 97.364799 -229.90429)
			(xy 97.046288 -229.90429) (xy 97.045793 -229.928897) (xy 97.037898 -229.977474) (xy 97.022314 -230.024155)
			(xy 96.999443 -230.067732) (xy 96.969878 -230.107076) (xy 96.934385 -230.141168) (xy 96.893882 -230.169124)
			(xy 96.84942 -230.190222) (xy 96.802149 -230.203914) (xy 96.753294 -230.209846) (xy 96.704119 -230.207865)
			(xy 96.6559 -230.198021) (xy 96.609884 -230.180569) (xy 96.567263 -230.155962) (xy 96.529142 -230.124837)
			(xy 96.496507 -230.088) (xy 96.470204 -230.046404) (xy 96.450913 -230.001128) (xy 96.439136 -229.953344)
			(xy 96.435176 -229.90429) (xy 96.116648 -229.90429) (xy 96.116136 -229.929736) (xy 96.107972 -229.97997)
			(xy 96.091856 -230.028244) (xy 96.068205 -230.073307) (xy 96.037632 -230.113993) (xy 96.000928 -230.149248)
			(xy 95.959044 -230.178158) (xy 95.913065 -230.199975) (xy 95.864181 -230.214135) (xy 95.81366 -230.220269)
			(xy 95.762808 -230.21822) (xy 95.712944 -230.20804) (xy 95.665358 -230.189993) (xy 95.621284 -230.164547)
			(xy 95.581862 -230.13236) (xy 95.548114 -230.094266) (xy 95.520913 -230.051252) (xy 95.500965 -230.004432)
			(xy 95.488786 -229.955018) (xy 95.484691 -229.90429) (xy 95.166434 -229.90429) (xy 95.165939 -229.928897)
			(xy 95.158044 -229.977474) (xy 95.14246 -230.024155) (xy 95.119589 -230.067732) (xy 95.090024 -230.107076)
			(xy 95.054531 -230.141168) (xy 95.014028 -230.169124) (xy 94.969566 -230.190222) (xy 94.922295 -230.203914)
			(xy 94.87344 -230.209846) (xy 94.824265 -230.207865) (xy 94.776046 -230.198021) (xy 94.73003 -230.180569)
			(xy 94.687409 -230.155962) (xy 94.649288 -230.124837) (xy 94.616653 -230.088) (xy 94.59035 -230.046404)
			(xy 94.571059 -230.001128) (xy 94.559282 -229.953344) (xy 94.555322 -229.90429) (xy 94.236794 -229.90429)
			(xy 94.236282 -229.929736) (xy 94.228118 -229.97997) (xy 94.212002 -230.028244) (xy 94.188351 -230.073307)
			(xy 94.157778 -230.113993) (xy 94.121074 -230.149248) (xy 94.07919 -230.178158) (xy 94.033211 -230.199975)
			(xy 93.984327 -230.214135) (xy 93.933806 -230.220269) (xy 93.882954 -230.21822) (xy 93.83309 -230.20804)
			(xy 93.785504 -230.189993) (xy 93.74143 -230.164547) (xy 93.702008 -230.13236) (xy 93.66826 -230.094266)
			(xy 93.641059 -230.051252) (xy 93.621111 -230.004432) (xy 93.608932 -229.955018) (xy 93.604837 -229.90429)
			(xy 93.286326 -229.90429) (xy 93.285831 -229.928897) (xy 93.277936 -229.977474) (xy 93.262352 -230.024155)
			(xy 93.239481 -230.067732) (xy 93.209916 -230.107076) (xy 93.174423 -230.141168) (xy 93.13392 -230.169124)
			(xy 93.089458 -230.190222) (xy 93.042187 -230.203914) (xy 92.993332 -230.209846) (xy 92.944157 -230.207865)
			(xy 92.895938 -230.198021) (xy 92.849922 -230.180569) (xy 92.807301 -230.155962) (xy 92.76918 -230.124837)
			(xy 92.736545 -230.088) (xy 92.710242 -230.046404) (xy 92.690951 -230.001128) (xy 92.679174 -229.953344)
			(xy 92.675214 -229.90429) (xy 92.356686 -229.90429) (xy 92.356174 -229.929736) (xy 92.34801 -229.97997)
			(xy 92.331894 -230.028244) (xy 92.308243 -230.073307) (xy 92.27767 -230.113993) (xy 92.240966 -230.149248)
			(xy 92.199082 -230.178158) (xy 92.153103 -230.199975) (xy 92.104219 -230.214135) (xy 92.053698 -230.220269)
			(xy 92.002846 -230.21822) (xy 91.952982 -230.20804) (xy 91.905396 -230.189993) (xy 91.861322 -230.164547)
			(xy 91.8219 -230.13236) (xy 91.788152 -230.094266) (xy 91.760951 -230.051252) (xy 91.741003 -230.004432)
			(xy 91.728824 -229.955018) (xy 91.724729 -229.90429) (xy 91.416632 -229.90429) (xy 91.41612 -229.929736)
			(xy 91.407956 -229.97997) (xy 91.39184 -230.028244) (xy 91.368189 -230.073307) (xy 91.337616 -230.113993)
			(xy 91.300912 -230.149248) (xy 91.259028 -230.178158) (xy 91.213049 -230.199975) (xy 91.164165 -230.214135)
			(xy 91.113644 -230.220269) (xy 91.062792 -230.21822) (xy 91.012928 -230.20804) (xy 90.965342 -230.189993)
			(xy 90.921268 -230.164547) (xy 90.881846 -230.13236) (xy 90.848098 -230.094266) (xy 90.820897 -230.051252)
			(xy 90.800949 -230.004432) (xy 90.78877 -229.955018) (xy 90.784675 -229.90429) (xy 90.46694 -229.90429)
			(xy 90.466941 -229.9043) (xy 90.46277 -229.954639) (xy 90.45037 -230.003604) (xy 90.430081 -230.049861)
			(xy 90.402454 -230.092148) (xy 90.368244 -230.129311) (xy 90.328384 -230.160336) (xy 90.283962 -230.184378)
			(xy 90.236188 -230.20078) (xy 90.186366 -230.209096) (xy 90.16111 -230.209598) (xy 90.148347 -230.209461)
			(xy 90.122912 -230.207303) (xy 90.11031 -230.20528) (xy 90.11031 -230.205534) (xy 90.086857 -230.201107)
			(xy 90.041603 -230.185945) (xy 89.999251 -230.163941) (xy 89.960829 -230.135629) (xy 89.927269 -230.101695)
			(xy 89.912952 -230.082598) (xy 89.904824 -230.071168) (xy 89.87917 -230.059992) (xy 89.762838 -230.074978)
			(xy 89.741248 -230.091996) (xy 89.736168 -230.105204) (xy 89.728022 -230.125527) (xy 89.708951 -230.164945)
			(xy 89.698068 -230.183944) (xy 89.694766 -230.189532) (xy 89.692734 -230.196136) (xy 89.690956 -230.209598)
			(xy 89.690956 -230.381048) (xy 89.715594 -230.409496) (xy 89.73439 -230.412036) (xy 89.758317 -230.415943)
			(xy 89.804612 -230.430331) (xy 89.848051 -230.451857) (xy 89.887542 -230.479977) (xy 89.922092 -230.513986)
			(xy 89.950832 -230.553028) (xy 89.97304 -230.596121) (xy 89.988158 -230.642183) (xy 89.995805 -230.690056)
			(xy 89.996264 -230.714296) (xy 89.996264 -230.71455) (xy 90.314775 -230.71455) (xy 90.31887 -230.663822)
			(xy 90.331049 -230.614408) (xy 90.350997 -230.567588) (xy 90.378198 -230.524574) (xy 90.411946 -230.48648)
			(xy 90.451368 -230.454293) (xy 90.495442 -230.428847) (xy 90.543028 -230.4108) (xy 90.592892 -230.40062)
			(xy 90.643744 -230.398571) (xy 90.694265 -230.404705) (xy 90.743149 -230.418865) (xy 90.789128 -230.440682)
			(xy 90.831012 -230.469592) (xy 90.867716 -230.504847) (xy 90.898289 -230.545533) (xy 90.92194 -230.590596)
			(xy 90.938056 -230.63887) (xy 90.94622 -230.689104) (xy 90.946732 -230.71455) (xy 91.26526 -230.71455)
			(xy 91.26922 -230.665496) (xy 91.280997 -230.617712) (xy 91.300288 -230.572436) (xy 91.326591 -230.53084)
			(xy 91.359226 -230.494003) (xy 91.397347 -230.462878) (xy 91.439968 -230.438271) (xy 91.485984 -230.420819)
			(xy 91.534203 -230.410975) (xy 91.583378 -230.408994) (xy 91.632233 -230.414926) (xy 91.679504 -230.428618)
			(xy 91.723966 -230.449716) (xy 91.764469 -230.477672) (xy 91.799962 -230.511764) (xy 91.829527 -230.551108)
			(xy 91.852398 -230.594685) (xy 91.867982 -230.641366) (xy 91.875877 -230.689943) (xy 91.876372 -230.71455)
			(xy 92.194883 -230.71455) (xy 92.198978 -230.663822) (xy 92.211157 -230.614408) (xy 92.231105 -230.567588)
			(xy 92.258306 -230.524574) (xy 92.292054 -230.48648) (xy 92.331476 -230.454293) (xy 92.37555 -230.428847)
			(xy 92.423136 -230.4108) (xy 92.473 -230.40062) (xy 92.523852 -230.398571) (xy 92.574373 -230.404705)
			(xy 92.623257 -230.418865) (xy 92.669236 -230.440682) (xy 92.71112 -230.469592) (xy 92.747824 -230.504847)
			(xy 92.778397 -230.545533) (xy 92.802048 -230.590596) (xy 92.818164 -230.63887) (xy 92.826328 -230.689104)
			(xy 92.826835 -230.714296) (xy 93.145114 -230.714296) (xy 93.149074 -230.665242) (xy 93.160851 -230.617458)
			(xy 93.180142 -230.572182) (xy 93.206445 -230.530586) (xy 93.23908 -230.493749) (xy 93.277201 -230.462624)
			(xy 93.319822 -230.438017) (xy 93.365838 -230.420565) (xy 93.414057 -230.410721) (xy 93.463232 -230.40874)
			(xy 93.512087 -230.414672) (xy 93.559358 -230.428364) (xy 93.60382 -230.449462) (xy 93.644323 -230.477418)
			(xy 93.679816 -230.51151) (xy 93.709381 -230.550854) (xy 93.732252 -230.594431) (xy 93.747836 -230.641112)
			(xy 93.755731 -230.689689) (xy 93.756226 -230.714296) (xy 93.756221 -230.71455) (xy 94.074737 -230.71455)
			(xy 94.078832 -230.663822) (xy 94.091011 -230.614408) (xy 94.110959 -230.567588) (xy 94.13816 -230.524574)
			(xy 94.171908 -230.48648) (xy 94.21133 -230.454293) (xy 94.255404 -230.428847) (xy 94.30299 -230.4108)
			(xy 94.352854 -230.40062) (xy 94.403706 -230.398571) (xy 94.454227 -230.404705) (xy 94.503111 -230.418865)
			(xy 94.54909 -230.440682) (xy 94.590974 -230.469592) (xy 94.627678 -230.504847) (xy 94.658251 -230.545533)
			(xy 94.681902 -230.590596) (xy 94.698018 -230.63887) (xy 94.706182 -230.689104) (xy 94.706694 -230.71455)
			(xy 95.014791 -230.71455) (xy 95.018886 -230.663822) (xy 95.031065 -230.614408) (xy 95.051013 -230.567588)
			(xy 95.078214 -230.524574) (xy 95.111962 -230.48648) (xy 95.151384 -230.454293) (xy 95.195458 -230.428847)
			(xy 95.243044 -230.4108) (xy 95.292908 -230.40062) (xy 95.34376 -230.398571) (xy 95.394281 -230.404705)
			(xy 95.443165 -230.418865) (xy 95.489144 -230.440682) (xy 95.531028 -230.469592) (xy 95.567732 -230.504847)
			(xy 95.598305 -230.545533) (xy 95.621956 -230.590596) (xy 95.638072 -230.63887) (xy 95.646236 -230.689104)
			(xy 95.646748 -230.71455) (xy 95.965276 -230.71455) (xy 95.969236 -230.665496) (xy 95.981013 -230.617712)
			(xy 96.000304 -230.572436) (xy 96.026607 -230.53084) (xy 96.059242 -230.494003) (xy 96.097363 -230.462878)
			(xy 96.139984 -230.438271) (xy 96.186 -230.420819) (xy 96.234219 -230.410975) (xy 96.283394 -230.408994)
			(xy 96.332249 -230.414926) (xy 96.37952 -230.428618) (xy 96.423982 -230.449716) (xy 96.464485 -230.477672)
			(xy 96.499978 -230.511764) (xy 96.529543 -230.551108) (xy 96.552414 -230.594685) (xy 96.567998 -230.641366)
			(xy 96.575893 -230.689943) (xy 96.576388 -230.71455) (xy 98.785184 -230.71455) (xy 98.789144 -230.665496)
			(xy 98.800921 -230.617712) (xy 98.820212 -230.572436) (xy 98.846515 -230.53084) (xy 98.87915 -230.494003)
			(xy 98.917271 -230.462878) (xy 98.959892 -230.438271) (xy 99.005908 -230.420819) (xy 99.054127 -230.410975)
			(xy 99.103302 -230.408994) (xy 99.152157 -230.414926) (xy 99.199428 -230.428618) (xy 99.24389 -230.449716)
			(xy 99.284393 -230.477672) (xy 99.319886 -230.511764) (xy 99.349451 -230.551108) (xy 99.372322 -230.594685)
			(xy 99.387906 -230.641366) (xy 99.395801 -230.689943) (xy 99.396291 -230.714296) (xy 101.605346 -230.714296)
			(xy 101.609306 -230.665242) (xy 101.621083 -230.617458) (xy 101.640374 -230.572182) (xy 101.666677 -230.530586)
			(xy 101.699312 -230.493749) (xy 101.737433 -230.462624) (xy 101.780054 -230.438017) (xy 101.82607 -230.420565)
			(xy 101.874289 -230.410721) (xy 101.923464 -230.40874) (xy 101.972319 -230.414672) (xy 102.01959 -230.428364)
			(xy 102.064052 -230.449462) (xy 102.104555 -230.477418) (xy 102.140048 -230.51151) (xy 102.169613 -230.550854)
			(xy 102.192484 -230.594431) (xy 102.208068 -230.641112) (xy 102.215963 -230.689689) (xy 102.216458 -230.714296)
			(xy 102.216453 -230.71455) (xy 104.425254 -230.71455) (xy 104.429214 -230.665496) (xy 104.440991 -230.617712)
			(xy 104.460282 -230.572436) (xy 104.486585 -230.53084) (xy 104.51922 -230.494003) (xy 104.557341 -230.462878)
			(xy 104.599962 -230.438271) (xy 104.645978 -230.420819) (xy 104.694197 -230.410975) (xy 104.743372 -230.408994)
			(xy 104.792227 -230.414926) (xy 104.839498 -230.428618) (xy 104.88396 -230.449716) (xy 104.924463 -230.477672)
			(xy 104.959956 -230.511764) (xy 104.989521 -230.551108) (xy 105.012392 -230.594685) (xy 105.027976 -230.641366)
			(xy 105.035871 -230.689943) (xy 105.036361 -230.714296) (xy 107.245162 -230.714296) (xy 107.249122 -230.665242)
			(xy 107.260899 -230.617458) (xy 107.28019 -230.572182) (xy 107.306493 -230.530586) (xy 107.339128 -230.493749)
			(xy 107.377249 -230.462624) (xy 107.41987 -230.438017) (xy 107.465886 -230.420565) (xy 107.514105 -230.410721)
			(xy 107.56328 -230.40874) (xy 107.612135 -230.414672) (xy 107.659406 -230.428364) (xy 107.703868 -230.449462)
			(xy 107.744371 -230.477418) (xy 107.779864 -230.51151) (xy 107.809429 -230.550854) (xy 107.8323 -230.594431)
			(xy 107.847884 -230.641112) (xy 107.855779 -230.689689) (xy 107.856274 -230.714296) (xy 107.856269 -230.71455)
			(xy 108.174785 -230.71455) (xy 108.17888 -230.663822) (xy 108.191059 -230.614408) (xy 108.211007 -230.567588)
			(xy 108.238208 -230.524574) (xy 108.271956 -230.48648) (xy 108.311378 -230.454293) (xy 108.355452 -230.428847)
			(xy 108.403038 -230.4108) (xy 108.452902 -230.40062) (xy 108.503754 -230.398571) (xy 108.554275 -230.404705)
			(xy 108.603159 -230.418865) (xy 108.649138 -230.440682) (xy 108.691022 -230.469592) (xy 108.727726 -230.504847)
			(xy 108.758299 -230.545533) (xy 108.78195 -230.590596) (xy 108.798066 -230.63887) (xy 108.80623 -230.689104)
			(xy 108.806742 -230.71455) (xy 109.114839 -230.71455) (xy 109.118934 -230.663822) (xy 109.131113 -230.614408)
			(xy 109.151061 -230.567588) (xy 109.178262 -230.524574) (xy 109.21201 -230.48648) (xy 109.251432 -230.454293)
			(xy 109.295506 -230.428847) (xy 109.343092 -230.4108) (xy 109.392956 -230.40062) (xy 109.443808 -230.398571)
			(xy 109.494329 -230.404705) (xy 109.543213 -230.418865) (xy 109.589192 -230.440682) (xy 109.631076 -230.469592)
			(xy 109.66778 -230.504847) (xy 109.698353 -230.545533) (xy 109.722004 -230.590596) (xy 109.73812 -230.63887)
			(xy 109.746284 -230.689104) (xy 109.746796 -230.71455) (xy 110.065324 -230.71455) (xy 110.069284 -230.665496)
			(xy 110.081061 -230.617712) (xy 110.100352 -230.572436) (xy 110.126655 -230.53084) (xy 110.15929 -230.494003)
			(xy 110.197411 -230.462878) (xy 110.240032 -230.438271) (xy 110.286048 -230.420819) (xy 110.334267 -230.410975)
			(xy 110.383442 -230.408994) (xy 110.432297 -230.414926) (xy 110.479568 -230.428618) (xy 110.52403 -230.449716)
			(xy 110.564533 -230.477672) (xy 110.600026 -230.511764) (xy 110.629591 -230.551108) (xy 110.652462 -230.594685)
			(xy 110.668046 -230.641366) (xy 110.675941 -230.689943) (xy 110.676436 -230.71455) (xy 110.675941 -230.739157)
			(xy 110.668046 -230.787734) (xy 110.652462 -230.834415) (xy 110.629591 -230.877992) (xy 110.600026 -230.917336)
			(xy 110.564533 -230.951428) (xy 110.52403 -230.979384) (xy 110.479568 -231.000482) (xy 110.432297 -231.014174)
			(xy 110.383442 -231.020106) (xy 110.334267 -231.018125) (xy 110.286048 -231.008281) (xy 110.240032 -230.990829)
			(xy 110.197411 -230.966222) (xy 110.15929 -230.935097) (xy 110.126655 -230.89826) (xy 110.100352 -230.856664)
			(xy 110.081061 -230.811388) (xy 110.069284 -230.763604) (xy 110.065324 -230.71455) (xy 109.746796 -230.71455)
			(xy 109.746284 -230.739996) (xy 109.73812 -230.79023) (xy 109.722004 -230.838504) (xy 109.698353 -230.883567)
			(xy 109.66778 -230.924253) (xy 109.631076 -230.959508) (xy 109.589192 -230.988418) (xy 109.543213 -231.010235)
			(xy 109.494329 -231.024395) (xy 109.443808 -231.030529) (xy 109.392956 -231.02848) (xy 109.343092 -231.0183)
			(xy 109.295506 -231.000253) (xy 109.251432 -230.974807) (xy 109.21201 -230.94262) (xy 109.178262 -230.904526)
			(xy 109.151061 -230.861512) (xy 109.131113 -230.814692) (xy 109.118934 -230.765278) (xy 109.114839 -230.71455)
			(xy 108.806742 -230.71455) (xy 108.80623 -230.739996) (xy 108.798066 -230.79023) (xy 108.78195 -230.838504)
			(xy 108.758299 -230.883567) (xy 108.727726 -230.924253) (xy 108.691022 -230.959508) (xy 108.649138 -230.988418)
			(xy 108.603159 -231.010235) (xy 108.554275 -231.024395) (xy 108.503754 -231.030529) (xy 108.452902 -231.02848)
			(xy 108.403038 -231.0183) (xy 108.355452 -231.000253) (xy 108.311378 -230.974807) (xy 108.271956 -230.94262)
			(xy 108.238208 -230.904526) (xy 108.211007 -230.861512) (xy 108.191059 -230.814692) (xy 108.17888 -230.765278)
			(xy 108.174785 -230.71455) (xy 107.856269 -230.71455) (xy 107.855779 -230.738903) (xy 107.847884 -230.78748)
			(xy 107.8323 -230.834161) (xy 107.809429 -230.877738) (xy 107.779864 -230.917082) (xy 107.744371 -230.951174)
			(xy 107.703868 -230.97913) (xy 107.659406 -231.000228) (xy 107.612135 -231.01392) (xy 107.56328 -231.019852)
			(xy 107.514105 -231.017871) (xy 107.465886 -231.008027) (xy 107.41987 -230.990575) (xy 107.377249 -230.965968)
			(xy 107.339128 -230.934843) (xy 107.306493 -230.898006) (xy 107.28019 -230.85641) (xy 107.260899 -230.811134)
			(xy 107.249122 -230.76335) (xy 107.245162 -230.714296) (xy 105.036361 -230.714296) (xy 105.036366 -230.71455)
			(xy 105.035871 -230.739157) (xy 105.027976 -230.787734) (xy 105.012392 -230.834415) (xy 104.989521 -230.877992)
			(xy 104.959956 -230.917336) (xy 104.924463 -230.951428) (xy 104.88396 -230.979384) (xy 104.839498 -231.000482)
			(xy 104.792227 -231.014174) (xy 104.743372 -231.020106) (xy 104.694197 -231.018125) (xy 104.645978 -231.008281)
			(xy 104.599962 -230.990829) (xy 104.557341 -230.966222) (xy 104.51922 -230.935097) (xy 104.486585 -230.89826)
			(xy 104.460282 -230.856664) (xy 104.440991 -230.811388) (xy 104.429214 -230.763604) (xy 104.425254 -230.71455)
			(xy 102.216453 -230.71455) (xy 102.215963 -230.738903) (xy 102.208068 -230.78748) (xy 102.192484 -230.834161)
			(xy 102.169613 -230.877738) (xy 102.140048 -230.917082) (xy 102.104555 -230.951174) (xy 102.064052 -230.97913)
			(xy 102.01959 -231.000228) (xy 101.972319 -231.01392) (xy 101.923464 -231.019852) (xy 101.874289 -231.017871)
			(xy 101.82607 -231.008027) (xy 101.780054 -230.990575) (xy 101.737433 -230.965968) (xy 101.699312 -230.934843)
			(xy 101.666677 -230.898006) (xy 101.640374 -230.85641) (xy 101.621083 -230.811134) (xy 101.609306 -230.76335)
			(xy 101.605346 -230.714296) (xy 99.396291 -230.714296) (xy 99.396296 -230.71455) (xy 99.395801 -230.739157)
			(xy 99.387906 -230.787734) (xy 99.372322 -230.834415) (xy 99.349451 -230.877992) (xy 99.319886 -230.917336)
			(xy 99.284393 -230.951428) (xy 99.24389 -230.979384) (xy 99.199428 -231.000482) (xy 99.152157 -231.014174)
			(xy 99.103302 -231.020106) (xy 99.054127 -231.018125) (xy 99.005908 -231.008281) (xy 98.959892 -230.990829)
			(xy 98.917271 -230.966222) (xy 98.87915 -230.935097) (xy 98.846515 -230.89826) (xy 98.820212 -230.856664)
			(xy 98.800921 -230.811388) (xy 98.789144 -230.763604) (xy 98.785184 -230.71455) (xy 96.576388 -230.71455)
			(xy 96.575893 -230.739157) (xy 96.567998 -230.787734) (xy 96.552414 -230.834415) (xy 96.529543 -230.877992)
			(xy 96.499978 -230.917336) (xy 96.464485 -230.951428) (xy 96.423982 -230.979384) (xy 96.37952 -231.000482)
			(xy 96.332249 -231.014174) (xy 96.283394 -231.020106) (xy 96.234219 -231.018125) (xy 96.186 -231.008281)
			(xy 96.139984 -230.990829) (xy 96.097363 -230.966222) (xy 96.059242 -230.935097) (xy 96.026607 -230.89826)
			(xy 96.000304 -230.856664) (xy 95.981013 -230.811388) (xy 95.969236 -230.763604) (xy 95.965276 -230.71455)
			(xy 95.646748 -230.71455) (xy 95.646236 -230.739996) (xy 95.638072 -230.79023) (xy 95.621956 -230.838504)
			(xy 95.598305 -230.883567) (xy 95.567732 -230.924253) (xy 95.531028 -230.959508) (xy 95.489144 -230.988418)
			(xy 95.443165 -231.010235) (xy 95.394281 -231.024395) (xy 95.34376 -231.030529) (xy 95.292908 -231.02848)
			(xy 95.243044 -231.0183) (xy 95.195458 -231.000253) (xy 95.151384 -230.974807) (xy 95.111962 -230.94262)
			(xy 95.078214 -230.904526) (xy 95.051013 -230.861512) (xy 95.031065 -230.814692) (xy 95.018886 -230.765278)
			(xy 95.014791 -230.71455) (xy 94.706694 -230.71455) (xy 94.706182 -230.739996) (xy 94.698018 -230.79023)
			(xy 94.681902 -230.838504) (xy 94.658251 -230.883567) (xy 94.627678 -230.924253) (xy 94.590974 -230.959508)
			(xy 94.54909 -230.988418) (xy 94.503111 -231.010235) (xy 94.454227 -231.024395) (xy 94.403706 -231.030529)
			(xy 94.352854 -231.02848) (xy 94.30299 -231.0183) (xy 94.255404 -231.000253) (xy 94.21133 -230.974807)
			(xy 94.171908 -230.94262) (xy 94.13816 -230.904526) (xy 94.110959 -230.861512) (xy 94.091011 -230.814692)
			(xy 94.078832 -230.765278) (xy 94.074737 -230.71455) (xy 93.756221 -230.71455) (xy 93.755731 -230.738903)
			(xy 93.747836 -230.78748) (xy 93.732252 -230.834161) (xy 93.709381 -230.877738) (xy 93.679816 -230.917082)
			(xy 93.644323 -230.951174) (xy 93.60382 -230.97913) (xy 93.559358 -231.000228) (xy 93.512087 -231.01392)
			(xy 93.463232 -231.019852) (xy 93.414057 -231.017871) (xy 93.365838 -231.008027) (xy 93.319822 -230.990575)
			(xy 93.277201 -230.965968) (xy 93.23908 -230.934843) (xy 93.206445 -230.898006) (xy 93.180142 -230.85641)
			(xy 93.160851 -230.811134) (xy 93.149074 -230.76335) (xy 93.145114 -230.714296) (xy 92.826835 -230.714296)
			(xy 92.82684 -230.71455) (xy 92.826328 -230.739996) (xy 92.818164 -230.79023) (xy 92.802048 -230.838504)
			(xy 92.778397 -230.883567) (xy 92.747824 -230.924253) (xy 92.71112 -230.959508) (xy 92.669236 -230.988418)
			(xy 92.623257 -231.010235) (xy 92.574373 -231.024395) (xy 92.523852 -231.030529) (xy 92.473 -231.02848)
			(xy 92.423136 -231.0183) (xy 92.37555 -231.000253) (xy 92.331476 -230.974807) (xy 92.292054 -230.94262)
			(xy 92.258306 -230.904526) (xy 92.231105 -230.861512) (xy 92.211157 -230.814692) (xy 92.198978 -230.765278)
			(xy 92.194883 -230.71455) (xy 91.876372 -230.71455) (xy 91.875877 -230.739157) (xy 91.867982 -230.787734)
			(xy 91.852398 -230.834415) (xy 91.829527 -230.877992) (xy 91.799962 -230.917336) (xy 91.764469 -230.951428)
			(xy 91.723966 -230.979384) (xy 91.679504 -231.000482) (xy 91.632233 -231.014174) (xy 91.583378 -231.020106)
			(xy 91.534203 -231.018125) (xy 91.485984 -231.008281) (xy 91.439968 -230.990829) (xy 91.397347 -230.966222)
			(xy 91.359226 -230.935097) (xy 91.326591 -230.89826) (xy 91.300288 -230.856664) (xy 91.280997 -230.811388)
			(xy 91.26922 -230.763604) (xy 91.26526 -230.71455) (xy 90.946732 -230.71455) (xy 90.94622 -230.739996)
			(xy 90.938056 -230.79023) (xy 90.92194 -230.838504) (xy 90.898289 -230.883567) (xy 90.867716 -230.924253)
			(xy 90.831012 -230.959508) (xy 90.789128 -230.988418) (xy 90.743149 -231.010235) (xy 90.694265 -231.024395)
			(xy 90.643744 -231.030529) (xy 90.592892 -231.02848) (xy 90.543028 -231.0183) (xy 90.495442 -231.000253)
			(xy 90.451368 -230.974807) (xy 90.411946 -230.94262) (xy 90.378198 -230.904526) (xy 90.350997 -230.861512)
			(xy 90.331049 -230.814692) (xy 90.31887 -230.765278) (xy 90.314775 -230.71455) (xy 89.996264 -230.71455)
			(xy 89.995795 -230.738788) (xy 89.988131 -230.786654) (xy 89.973004 -230.832708) (xy 89.950792 -230.875796)
			(xy 89.922054 -230.914834) (xy 89.887511 -230.948844) (xy 89.84803 -230.976971) (xy 89.804602 -230.998509)
			(xy 89.758317 -231.012918) (xy 89.73439 -231.01681) (xy 89.715594 -231.019604) (xy 89.690956 -231.048052)
			(xy 89.690956 -231.218994) (xy 89.691216 -231.225883) (xy 89.69494 -231.23915) (xy 89.698322 -231.245156)
			(xy 89.699338 -231.246934) (xy 89.707629 -231.261508) (xy 89.722627 -231.2915) (xy 89.72931 -231.306878)
			(xy 89.736168 -231.323388) (xy 89.741248 -231.336596) (xy 89.762838 -231.353614) (xy 89.879424 -231.3686)
			(xy 89.905078 -231.357424) (xy 89.913206 -231.345994) (xy 89.927672 -231.326696) (xy 89.961661 -231.292482)
			(xy 90.000601 -231.26403) (xy 90.043526 -231.242045) (xy 90.08937 -231.227074) (xy 90.136997 -231.219487)
			(xy 90.16111 -231.218994) (xy 90.186365 -231.219516) (xy 90.236185 -231.227831) (xy 90.283957 -231.244233)
			(xy 90.328378 -231.268274) (xy 90.368236 -231.299298) (xy 90.402445 -231.336459) (xy 90.43007 -231.378744)
			(xy 90.450359 -231.424999) (xy 90.462758 -231.473963) (xy 90.466929 -231.5243) (xy 90.466929 -231.524302)
			(xy 90.784675 -231.524302) (xy 90.78877 -231.473574) (xy 90.800949 -231.42416) (xy 90.820897 -231.37734)
			(xy 90.848098 -231.334326) (xy 90.881846 -231.296232) (xy 90.921268 -231.264045) (xy 90.965342 -231.238599)
			(xy 91.012928 -231.220552) (xy 91.062792 -231.210372) (xy 91.113644 -231.208323) (xy 91.164165 -231.214457)
			(xy 91.213049 -231.228617) (xy 91.259028 -231.250434) (xy 91.300912 -231.279344) (xy 91.337616 -231.314599)
			(xy 91.368189 -231.355285) (xy 91.39184 -231.400348) (xy 91.407956 -231.448622) (xy 91.41612 -231.498856)
			(xy 91.416632 -231.524302) (xy 91.724729 -231.524302) (xy 91.728824 -231.473574) (xy 91.741003 -231.42416)
			(xy 91.760951 -231.37734) (xy 91.788152 -231.334326) (xy 91.8219 -231.296232) (xy 91.861322 -231.264045)
			(xy 91.905396 -231.238599) (xy 91.952982 -231.220552) (xy 92.002846 -231.210372) (xy 92.053698 -231.208323)
			(xy 92.104219 -231.214457) (xy 92.153103 -231.228617) (xy 92.199082 -231.250434) (xy 92.240966 -231.279344)
			(xy 92.27767 -231.314599) (xy 92.308243 -231.355285) (xy 92.331894 -231.400348) (xy 92.34801 -231.448622)
			(xy 92.356174 -231.498856) (xy 92.356686 -231.524302) (xy 92.675214 -231.524302) (xy 92.679174 -231.475248)
			(xy 92.690951 -231.427464) (xy 92.710242 -231.382188) (xy 92.736545 -231.340592) (xy 92.76918 -231.303755)
			(xy 92.807301 -231.27263) (xy 92.849922 -231.248023) (xy 92.895938 -231.230571) (xy 92.944157 -231.220727)
			(xy 92.993332 -231.218746) (xy 93.042187 -231.224678) (xy 93.089458 -231.23837) (xy 93.13392 -231.259468)
			(xy 93.174423 -231.287424) (xy 93.209916 -231.321516) (xy 93.239481 -231.36086) (xy 93.262352 -231.404437)
			(xy 93.277936 -231.451118) (xy 93.285831 -231.499695) (xy 93.286326 -231.524302) (xy 93.604837 -231.524302)
			(xy 93.608932 -231.473574) (xy 93.621111 -231.42416) (xy 93.641059 -231.37734) (xy 93.66826 -231.334326)
			(xy 93.702008 -231.296232) (xy 93.74143 -231.264045) (xy 93.785504 -231.238599) (xy 93.83309 -231.220552)
			(xy 93.882954 -231.210372) (xy 93.933806 -231.208323) (xy 93.984327 -231.214457) (xy 94.033211 -231.228617)
			(xy 94.07919 -231.250434) (xy 94.121074 -231.279344) (xy 94.157778 -231.314599) (xy 94.188351 -231.355285)
			(xy 94.212002 -231.400348) (xy 94.228118 -231.448622) (xy 94.236282 -231.498856) (xy 94.236794 -231.524302)
			(xy 94.555322 -231.524302) (xy 94.559282 -231.475248) (xy 94.571059 -231.427464) (xy 94.59035 -231.382188)
			(xy 94.616653 -231.340592) (xy 94.649288 -231.303755) (xy 94.687409 -231.27263) (xy 94.73003 -231.248023)
			(xy 94.776046 -231.230571) (xy 94.824265 -231.220727) (xy 94.87344 -231.218746) (xy 94.922295 -231.224678)
			(xy 94.969566 -231.23837) (xy 95.014028 -231.259468) (xy 95.054531 -231.287424) (xy 95.090024 -231.321516)
			(xy 95.119589 -231.36086) (xy 95.14246 -231.404437) (xy 95.158044 -231.451118) (xy 95.165939 -231.499695)
			(xy 95.166434 -231.524302) (xy 95.484691 -231.524302) (xy 95.488786 -231.473574) (xy 95.500965 -231.42416)
			(xy 95.520913 -231.37734) (xy 95.548114 -231.334326) (xy 95.581862 -231.296232) (xy 95.621284 -231.264045)
			(xy 95.665358 -231.238599) (xy 95.712944 -231.220552) (xy 95.762808 -231.210372) (xy 95.81366 -231.208323)
			(xy 95.864181 -231.214457) (xy 95.913065 -231.228617) (xy 95.959044 -231.250434) (xy 96.000928 -231.279344)
			(xy 96.037632 -231.314599) (xy 96.068205 -231.355285) (xy 96.091856 -231.400348) (xy 96.107972 -231.448622)
			(xy 96.116136 -231.498856) (xy 96.116648 -231.524302) (xy 96.435176 -231.524302) (xy 96.439136 -231.475248)
			(xy 96.450913 -231.427464) (xy 96.470204 -231.382188) (xy 96.496507 -231.340592) (xy 96.529142 -231.303755)
			(xy 96.567263 -231.27263) (xy 96.609884 -231.248023) (xy 96.6559 -231.230571) (xy 96.704119 -231.220727)
			(xy 96.753294 -231.218746) (xy 96.802149 -231.224678) (xy 96.84942 -231.23837) (xy 96.893882 -231.259468)
			(xy 96.934385 -231.287424) (xy 96.969878 -231.321516) (xy 96.999443 -231.36086) (xy 97.022314 -231.404437)
			(xy 97.037898 -231.451118) (xy 97.045793 -231.499695) (xy 97.046288 -231.524302) (xy 97.364799 -231.524302)
			(xy 97.368894 -231.473574) (xy 97.381073 -231.42416) (xy 97.401021 -231.37734) (xy 97.428222 -231.334326)
			(xy 97.46197 -231.296232) (xy 97.501392 -231.264045) (xy 97.545466 -231.238599) (xy 97.593052 -231.220552)
			(xy 97.642916 -231.210372) (xy 97.693768 -231.208323) (xy 97.744289 -231.214457) (xy 97.793173 -231.228617)
			(xy 97.839152 -231.250434) (xy 97.881036 -231.279344) (xy 97.91774 -231.314599) (xy 97.948313 -231.355285)
			(xy 97.971964 -231.400348) (xy 97.98808 -231.448622) (xy 97.996244 -231.498856) (xy 97.996756 -231.524302)
			(xy 98.304853 -231.524302) (xy 98.308948 -231.473574) (xy 98.321127 -231.42416) (xy 98.341075 -231.37734)
			(xy 98.368276 -231.334326) (xy 98.402024 -231.296232) (xy 98.441446 -231.264045) (xy 98.48552 -231.238599)
			(xy 98.533106 -231.220552) (xy 98.58297 -231.210372) (xy 98.633822 -231.208323) (xy 98.684343 -231.214457)
			(xy 98.733227 -231.228617) (xy 98.779206 -231.250434) (xy 98.82109 -231.279344) (xy 98.857794 -231.314599)
			(xy 98.888367 -231.355285) (xy 98.912018 -231.400348) (xy 98.928134 -231.448622) (xy 98.936298 -231.498856)
			(xy 98.93681 -231.524302) (xy 99.255338 -231.524302) (xy 99.259298 -231.475248) (xy 99.271075 -231.427464)
			(xy 99.290366 -231.382188) (xy 99.316669 -231.340592) (xy 99.349304 -231.303755) (xy 99.387425 -231.27263)
			(xy 99.430046 -231.248023) (xy 99.476062 -231.230571) (xy 99.524281 -231.220727) (xy 99.573456 -231.218746)
			(xy 99.622311 -231.224678) (xy 99.669582 -231.23837) (xy 99.714044 -231.259468) (xy 99.754547 -231.287424)
			(xy 99.79004 -231.321516) (xy 99.819605 -231.36086) (xy 99.842476 -231.404437) (xy 99.85806 -231.451118)
			(xy 99.865955 -231.499695) (xy 99.86645 -231.524302) (xy 100.184707 -231.524302) (xy 100.188802 -231.473574)
			(xy 100.200981 -231.42416) (xy 100.220929 -231.37734) (xy 100.24813 -231.334326) (xy 100.281878 -231.296232)
			(xy 100.3213 -231.264045) (xy 100.365374 -231.238599) (xy 100.41296 -231.220552) (xy 100.462824 -231.210372)
			(xy 100.513676 -231.208323) (xy 100.564197 -231.214457) (xy 100.613081 -231.228617) (xy 100.65906 -231.250434)
			(xy 100.700944 -231.279344) (xy 100.737648 -231.314599) (xy 100.768221 -231.355285) (xy 100.791872 -231.400348)
			(xy 100.807988 -231.448622) (xy 100.816152 -231.498856) (xy 100.816664 -231.524302) (xy 101.124761 -231.524302)
			(xy 101.128856 -231.473574) (xy 101.141035 -231.42416) (xy 101.160983 -231.37734) (xy 101.188184 -231.334326)
			(xy 101.221932 -231.296232) (xy 101.261354 -231.264045) (xy 101.305428 -231.238599) (xy 101.353014 -231.220552)
			(xy 101.402878 -231.210372) (xy 101.45373 -231.208323) (xy 101.504251 -231.214457) (xy 101.553135 -231.228617)
			(xy 101.599114 -231.250434) (xy 101.640998 -231.279344) (xy 101.677702 -231.314599) (xy 101.708275 -231.355285)
			(xy 101.731926 -231.400348) (xy 101.748042 -231.448622) (xy 101.756206 -231.498856) (xy 101.756718 -231.524302)
			(xy 102.075246 -231.524302) (xy 102.079206 -231.475248) (xy 102.090983 -231.427464) (xy 102.110274 -231.382188)
			(xy 102.136577 -231.340592) (xy 102.169212 -231.303755) (xy 102.207333 -231.27263) (xy 102.249954 -231.248023)
			(xy 102.29597 -231.230571) (xy 102.344189 -231.220727) (xy 102.393364 -231.218746) (xy 102.442219 -231.224678)
			(xy 102.48949 -231.23837) (xy 102.533952 -231.259468) (xy 102.574455 -231.287424) (xy 102.609948 -231.321516)
			(xy 102.639513 -231.36086) (xy 102.662384 -231.404437) (xy 102.677968 -231.451118) (xy 102.685863 -231.499695)
			(xy 102.686358 -231.524302) (xy 103.004869 -231.524302) (xy 103.008964 -231.473574) (xy 103.021143 -231.42416)
			(xy 103.041091 -231.37734) (xy 103.068292 -231.334326) (xy 103.10204 -231.296232) (xy 103.141462 -231.264045)
			(xy 103.185536 -231.238599) (xy 103.233122 -231.220552) (xy 103.282986 -231.210372) (xy 103.333838 -231.208323)
			(xy 103.384359 -231.214457) (xy 103.433243 -231.228617) (xy 103.479222 -231.250434) (xy 103.521106 -231.279344)
			(xy 103.55781 -231.314599) (xy 103.588383 -231.355285) (xy 103.612034 -231.400348) (xy 103.62815 -231.448622)
			(xy 103.636314 -231.498856) (xy 103.636826 -231.524302) (xy 103.944923 -231.524302) (xy 103.949018 -231.473574)
			(xy 103.961197 -231.42416) (xy 103.981145 -231.37734) (xy 104.008346 -231.334326) (xy 104.042094 -231.296232)
			(xy 104.081516 -231.264045) (xy 104.12559 -231.238599) (xy 104.173176 -231.220552) (xy 104.22304 -231.210372)
			(xy 104.273892 -231.208323) (xy 104.324413 -231.214457) (xy 104.373297 -231.228617) (xy 104.419276 -231.250434)
			(xy 104.46116 -231.279344) (xy 104.497864 -231.314599) (xy 104.528437 -231.355285) (xy 104.552088 -231.400348)
			(xy 104.568204 -231.448622) (xy 104.576368 -231.498856) (xy 104.57688 -231.524302) (xy 104.895154 -231.524302)
			(xy 104.899114 -231.475248) (xy 104.910891 -231.427464) (xy 104.930182 -231.382188) (xy 104.956485 -231.340592)
			(xy 104.98912 -231.303755) (xy 105.027241 -231.27263) (xy 105.069862 -231.248023) (xy 105.115878 -231.230571)
			(xy 105.164097 -231.220727) (xy 105.213272 -231.218746) (xy 105.262127 -231.224678) (xy 105.309398 -231.23837)
			(xy 105.35386 -231.259468) (xy 105.394363 -231.287424) (xy 105.429856 -231.321516) (xy 105.459421 -231.36086)
			(xy 105.482292 -231.404437) (xy 105.497876 -231.451118) (xy 105.505771 -231.499695) (xy 105.506266 -231.524302)
			(xy 105.824777 -231.524302) (xy 105.828872 -231.473574) (xy 105.841051 -231.42416) (xy 105.860999 -231.37734)
			(xy 105.8882 -231.334326) (xy 105.921948 -231.296232) (xy 105.96137 -231.264045) (xy 106.005444 -231.238599)
			(xy 106.05303 -231.220552) (xy 106.102894 -231.210372) (xy 106.153746 -231.208323) (xy 106.204267 -231.214457)
			(xy 106.253151 -231.228617) (xy 106.29913 -231.250434) (xy 106.341014 -231.279344) (xy 106.377718 -231.314599)
			(xy 106.408291 -231.355285) (xy 106.431942 -231.400348) (xy 106.448058 -231.448622) (xy 106.456222 -231.498856)
			(xy 106.456734 -231.524302) (xy 106.764831 -231.524302) (xy 106.768926 -231.473574) (xy 106.781105 -231.42416)
			(xy 106.801053 -231.37734) (xy 106.828254 -231.334326) (xy 106.862002 -231.296232) (xy 106.901424 -231.264045)
			(xy 106.945498 -231.238599) (xy 106.993084 -231.220552) (xy 107.042948 -231.210372) (xy 107.0938 -231.208323)
			(xy 107.144321 -231.214457) (xy 107.193205 -231.228617) (xy 107.239184 -231.250434) (xy 107.281068 -231.279344)
			(xy 107.317772 -231.314599) (xy 107.348345 -231.355285) (xy 107.371996 -231.400348) (xy 107.388112 -231.448622)
			(xy 107.396276 -231.498856) (xy 107.396788 -231.524302) (xy 107.715316 -231.524302) (xy 107.719276 -231.475248)
			(xy 107.731053 -231.427464) (xy 107.750344 -231.382188) (xy 107.776647 -231.340592) (xy 107.809282 -231.303755)
			(xy 107.847403 -231.27263) (xy 107.890024 -231.248023) (xy 107.93604 -231.230571) (xy 107.984259 -231.220727)
			(xy 108.033434 -231.218746) (xy 108.082289 -231.224678) (xy 108.12956 -231.23837) (xy 108.174022 -231.259468)
			(xy 108.214525 -231.287424) (xy 108.250018 -231.321516) (xy 108.279583 -231.36086) (xy 108.302454 -231.404437)
			(xy 108.318038 -231.451118) (xy 108.325933 -231.499695) (xy 108.326428 -231.524302) (xy 108.325933 -231.548909)
			(xy 108.318038 -231.597486) (xy 108.302454 -231.644167) (xy 108.279583 -231.687744) (xy 108.250018 -231.727088)
			(xy 108.214525 -231.76118) (xy 108.174022 -231.789136) (xy 108.12956 -231.810234) (xy 108.082289 -231.823926)
			(xy 108.033434 -231.829858) (xy 107.984259 -231.827877) (xy 107.93604 -231.818033) (xy 107.890024 -231.800581)
			(xy 107.847403 -231.775974) (xy 107.809282 -231.744849) (xy 107.776647 -231.708012) (xy 107.750344 -231.666416)
			(xy 107.731053 -231.62114) (xy 107.719276 -231.573356) (xy 107.715316 -231.524302) (xy 107.396788 -231.524302)
			(xy 107.396276 -231.549748) (xy 107.388112 -231.599982) (xy 107.371996 -231.648256) (xy 107.348345 -231.693319)
			(xy 107.317772 -231.734005) (xy 107.281068 -231.76926) (xy 107.239184 -231.79817) (xy 107.193205 -231.819987)
			(xy 107.144321 -231.834147) (xy 107.0938 -231.840281) (xy 107.042948 -231.838232) (xy 106.993084 -231.828052)
			(xy 106.945498 -231.810005) (xy 106.901424 -231.784559) (xy 106.862002 -231.752372) (xy 106.828254 -231.714278)
			(xy 106.801053 -231.671264) (xy 106.781105 -231.624444) (xy 106.768926 -231.57503) (xy 106.764831 -231.524302)
			(xy 106.456734 -231.524302) (xy 106.456222 -231.549748) (xy 106.448058 -231.599982) (xy 106.431942 -231.648256)
			(xy 106.408291 -231.693319) (xy 106.377718 -231.734005) (xy 106.341014 -231.76926) (xy 106.29913 -231.79817)
			(xy 106.253151 -231.819987) (xy 106.204267 -231.834147) (xy 106.153746 -231.840281) (xy 106.102894 -231.838232)
			(xy 106.05303 -231.828052) (xy 106.005444 -231.810005) (xy 105.96137 -231.784559) (xy 105.921948 -231.752372)
			(xy 105.8882 -231.714278) (xy 105.860999 -231.671264) (xy 105.841051 -231.624444) (xy 105.828872 -231.57503)
			(xy 105.824777 -231.524302) (xy 105.506266 -231.524302) (xy 105.505771 -231.548909) (xy 105.497876 -231.597486)
			(xy 105.482292 -231.644167) (xy 105.459421 -231.687744) (xy 105.429856 -231.727088) (xy 105.394363 -231.76118)
			(xy 105.35386 -231.789136) (xy 105.309398 -231.810234) (xy 105.262127 -231.823926) (xy 105.213272 -231.829858)
			(xy 105.164097 -231.827877) (xy 105.115878 -231.818033) (xy 105.069862 -231.800581) (xy 105.027241 -231.775974)
			(xy 104.98912 -231.744849) (xy 104.956485 -231.708012) (xy 104.930182 -231.666416) (xy 104.910891 -231.62114)
			(xy 104.899114 -231.573356) (xy 104.895154 -231.524302) (xy 104.57688 -231.524302) (xy 104.576368 -231.549748)
			(xy 104.568204 -231.599982) (xy 104.552088 -231.648256) (xy 104.528437 -231.693319) (xy 104.497864 -231.734005)
			(xy 104.46116 -231.76926) (xy 104.419276 -231.79817) (xy 104.373297 -231.819987) (xy 104.324413 -231.834147)
			(xy 104.273892 -231.840281) (xy 104.22304 -231.838232) (xy 104.173176 -231.828052) (xy 104.12559 -231.810005)
			(xy 104.081516 -231.784559) (xy 104.042094 -231.752372) (xy 104.008346 -231.714278) (xy 103.981145 -231.671264)
			(xy 103.961197 -231.624444) (xy 103.949018 -231.57503) (xy 103.944923 -231.524302) (xy 103.636826 -231.524302)
			(xy 103.636314 -231.549748) (xy 103.62815 -231.599982) (xy 103.612034 -231.648256) (xy 103.588383 -231.693319)
			(xy 103.55781 -231.734005) (xy 103.521106 -231.76926) (xy 103.479222 -231.79817) (xy 103.433243 -231.819987)
			(xy 103.384359 -231.834147) (xy 103.333838 -231.840281) (xy 103.282986 -231.838232) (xy 103.233122 -231.828052)
			(xy 103.185536 -231.810005) (xy 103.141462 -231.784559) (xy 103.10204 -231.752372) (xy 103.068292 -231.714278)
			(xy 103.041091 -231.671264) (xy 103.021143 -231.624444) (xy 103.008964 -231.57503) (xy 103.004869 -231.524302)
			(xy 102.686358 -231.524302) (xy 102.685863 -231.548909) (xy 102.677968 -231.597486) (xy 102.662384 -231.644167)
			(xy 102.639513 -231.687744) (xy 102.609948 -231.727088) (xy 102.574455 -231.76118) (xy 102.533952 -231.789136)
			(xy 102.48949 -231.810234) (xy 102.442219 -231.823926) (xy 102.393364 -231.829858) (xy 102.344189 -231.827877)
			(xy 102.29597 -231.818033) (xy 102.249954 -231.800581) (xy 102.207333 -231.775974) (xy 102.169212 -231.744849)
			(xy 102.136577 -231.708012) (xy 102.110274 -231.666416) (xy 102.090983 -231.62114) (xy 102.079206 -231.573356)
			(xy 102.075246 -231.524302) (xy 101.756718 -231.524302) (xy 101.756206 -231.549748) (xy 101.748042 -231.599982)
			(xy 101.731926 -231.648256) (xy 101.708275 -231.693319) (xy 101.677702 -231.734005) (xy 101.640998 -231.76926)
			(xy 101.599114 -231.79817) (xy 101.553135 -231.819987) (xy 101.504251 -231.834147) (xy 101.45373 -231.840281)
			(xy 101.402878 -231.838232) (xy 101.353014 -231.828052) (xy 101.305428 -231.810005) (xy 101.261354 -231.784559)
			(xy 101.221932 -231.752372) (xy 101.188184 -231.714278) (xy 101.160983 -231.671264) (xy 101.141035 -231.624444)
			(xy 101.128856 -231.57503) (xy 101.124761 -231.524302) (xy 100.816664 -231.524302) (xy 100.816152 -231.549748)
			(xy 100.807988 -231.599982) (xy 100.791872 -231.648256) (xy 100.768221 -231.693319) (xy 100.737648 -231.734005)
			(xy 100.700944 -231.76926) (xy 100.65906 -231.79817) (xy 100.613081 -231.819987) (xy 100.564197 -231.834147)
			(xy 100.513676 -231.840281) (xy 100.462824 -231.838232) (xy 100.41296 -231.828052) (xy 100.365374 -231.810005)
			(xy 100.3213 -231.784559) (xy 100.281878 -231.752372) (xy 100.24813 -231.714278) (xy 100.220929 -231.671264)
			(xy 100.200981 -231.624444) (xy 100.188802 -231.57503) (xy 100.184707 -231.524302) (xy 99.86645 -231.524302)
			(xy 99.865955 -231.548909) (xy 99.85806 -231.597486) (xy 99.842476 -231.644167) (xy 99.819605 -231.687744)
			(xy 99.79004 -231.727088) (xy 99.754547 -231.76118) (xy 99.714044 -231.789136) (xy 99.669582 -231.810234)
			(xy 99.622311 -231.823926) (xy 99.573456 -231.829858) (xy 99.524281 -231.827877) (xy 99.476062 -231.818033)
			(xy 99.430046 -231.800581) (xy 99.387425 -231.775974) (xy 99.349304 -231.744849) (xy 99.316669 -231.708012)
			(xy 99.290366 -231.666416) (xy 99.271075 -231.62114) (xy 99.259298 -231.573356) (xy 99.255338 -231.524302)
			(xy 98.93681 -231.524302) (xy 98.936298 -231.549748) (xy 98.928134 -231.599982) (xy 98.912018 -231.648256)
			(xy 98.888367 -231.693319) (xy 98.857794 -231.734005) (xy 98.82109 -231.76926) (xy 98.779206 -231.79817)
			(xy 98.733227 -231.819987) (xy 98.684343 -231.834147) (xy 98.633822 -231.840281) (xy 98.58297 -231.838232)
			(xy 98.533106 -231.828052) (xy 98.48552 -231.810005) (xy 98.441446 -231.784559) (xy 98.402024 -231.752372)
			(xy 98.368276 -231.714278) (xy 98.341075 -231.671264) (xy 98.321127 -231.624444) (xy 98.308948 -231.57503)
			(xy 98.304853 -231.524302) (xy 97.996756 -231.524302) (xy 97.996244 -231.549748) (xy 97.98808 -231.599982)
			(xy 97.971964 -231.648256) (xy 97.948313 -231.693319) (xy 97.91774 -231.734005) (xy 97.881036 -231.76926)
			(xy 97.839152 -231.79817) (xy 97.793173 -231.819987) (xy 97.744289 -231.834147) (xy 97.693768 -231.840281)
			(xy 97.642916 -231.838232) (xy 97.593052 -231.828052) (xy 97.545466 -231.810005) (xy 97.501392 -231.784559)
			(xy 97.46197 -231.752372) (xy 97.428222 -231.714278) (xy 97.401021 -231.671264) (xy 97.381073 -231.624444)
			(xy 97.368894 -231.57503) (xy 97.364799 -231.524302) (xy 97.046288 -231.524302) (xy 97.045793 -231.548909)
			(xy 97.037898 -231.597486) (xy 97.022314 -231.644167) (xy 96.999443 -231.687744) (xy 96.969878 -231.727088)
			(xy 96.934385 -231.76118) (xy 96.893882 -231.789136) (xy 96.84942 -231.810234) (xy 96.802149 -231.823926)
			(xy 96.753294 -231.829858) (xy 96.704119 -231.827877) (xy 96.6559 -231.818033) (xy 96.609884 -231.800581)
			(xy 96.567263 -231.775974) (xy 96.529142 -231.744849) (xy 96.496507 -231.708012) (xy 96.470204 -231.666416)
			(xy 96.450913 -231.62114) (xy 96.439136 -231.573356) (xy 96.435176 -231.524302) (xy 96.116648 -231.524302)
			(xy 96.116136 -231.549748) (xy 96.107972 -231.599982) (xy 96.091856 -231.648256) (xy 96.068205 -231.693319)
			(xy 96.037632 -231.734005) (xy 96.000928 -231.76926) (xy 95.959044 -231.79817) (xy 95.913065 -231.819987)
			(xy 95.864181 -231.834147) (xy 95.81366 -231.840281) (xy 95.762808 -231.838232) (xy 95.712944 -231.828052)
			(xy 95.665358 -231.810005) (xy 95.621284 -231.784559) (xy 95.581862 -231.752372) (xy 95.548114 -231.714278)
			(xy 95.520913 -231.671264) (xy 95.500965 -231.624444) (xy 95.488786 -231.57503) (xy 95.484691 -231.524302)
			(xy 95.166434 -231.524302) (xy 95.165939 -231.548909) (xy 95.158044 -231.597486) (xy 95.14246 -231.644167)
			(xy 95.119589 -231.687744) (xy 95.090024 -231.727088) (xy 95.054531 -231.76118) (xy 95.014028 -231.789136)
			(xy 94.969566 -231.810234) (xy 94.922295 -231.823926) (xy 94.87344 -231.829858) (xy 94.824265 -231.827877)
			(xy 94.776046 -231.818033) (xy 94.73003 -231.800581) (xy 94.687409 -231.775974) (xy 94.649288 -231.744849)
			(xy 94.616653 -231.708012) (xy 94.59035 -231.666416) (xy 94.571059 -231.62114) (xy 94.559282 -231.573356)
			(xy 94.555322 -231.524302) (xy 94.236794 -231.524302) (xy 94.236282 -231.549748) (xy 94.228118 -231.599982)
			(xy 94.212002 -231.648256) (xy 94.188351 -231.693319) (xy 94.157778 -231.734005) (xy 94.121074 -231.76926)
			(xy 94.07919 -231.79817) (xy 94.033211 -231.819987) (xy 93.984327 -231.834147) (xy 93.933806 -231.840281)
			(xy 93.882954 -231.838232) (xy 93.83309 -231.828052) (xy 93.785504 -231.810005) (xy 93.74143 -231.784559)
			(xy 93.702008 -231.752372) (xy 93.66826 -231.714278) (xy 93.641059 -231.671264) (xy 93.621111 -231.624444)
			(xy 93.608932 -231.57503) (xy 93.604837 -231.524302) (xy 93.286326 -231.524302) (xy 93.285831 -231.548909)
			(xy 93.277936 -231.597486) (xy 93.262352 -231.644167) (xy 93.239481 -231.687744) (xy 93.209916 -231.727088)
			(xy 93.174423 -231.76118) (xy 93.13392 -231.789136) (xy 93.089458 -231.810234) (xy 93.042187 -231.823926)
			(xy 92.993332 -231.829858) (xy 92.944157 -231.827877) (xy 92.895938 -231.818033) (xy 92.849922 -231.800581)
			(xy 92.807301 -231.775974) (xy 92.76918 -231.744849) (xy 92.736545 -231.708012) (xy 92.710242 -231.666416)
			(xy 92.690951 -231.62114) (xy 92.679174 -231.573356) (xy 92.675214 -231.524302) (xy 92.356686 -231.524302)
			(xy 92.356174 -231.549748) (xy 92.34801 -231.599982) (xy 92.331894 -231.648256) (xy 92.308243 -231.693319)
			(xy 92.27767 -231.734005) (xy 92.240966 -231.76926) (xy 92.199082 -231.79817) (xy 92.153103 -231.819987)
			(xy 92.104219 -231.834147) (xy 92.053698 -231.840281) (xy 92.002846 -231.838232) (xy 91.952982 -231.828052)
			(xy 91.905396 -231.810005) (xy 91.861322 -231.784559) (xy 91.8219 -231.752372) (xy 91.788152 -231.714278)
			(xy 91.760951 -231.671264) (xy 91.741003 -231.624444) (xy 91.728824 -231.57503) (xy 91.724729 -231.524302)
			(xy 91.416632 -231.524302) (xy 91.41612 -231.549748) (xy 91.407956 -231.599982) (xy 91.39184 -231.648256)
			(xy 91.368189 -231.693319) (xy 91.337616 -231.734005) (xy 91.300912 -231.76926) (xy 91.259028 -231.79817)
			(xy 91.213049 -231.819987) (xy 91.164165 -231.834147) (xy 91.113644 -231.840281) (xy 91.062792 -231.838232)
			(xy 91.012928 -231.828052) (xy 90.965342 -231.810005) (xy 90.921268 -231.784559) (xy 90.881846 -231.752372)
			(xy 90.848098 -231.714278) (xy 90.820897 -231.671264) (xy 90.800949 -231.624444) (xy 90.78877 -231.57503)
			(xy 90.784675 -231.524302) (xy 90.466929 -231.524302) (xy 90.462758 -231.574637) (xy 90.450359 -231.623601)
			(xy 90.43007 -231.669856) (xy 90.402445 -231.712141) (xy 90.368236 -231.749302) (xy 90.328378 -231.780326)
			(xy 90.283957 -231.804367) (xy 90.236185 -231.820769) (xy 90.186365 -231.829084) (xy 90.16111 -231.82961)
			(xy 90.148347 -231.829473) (xy 90.122912 -231.827315) (xy 90.11031 -231.825292) (xy 90.11031 -231.825546)
			(xy 90.086856 -231.821119) (xy 90.041602 -231.805957) (xy 89.99925 -231.783954) (xy 89.960827 -231.755643)
			(xy 89.927265 -231.72171) (xy 89.912952 -231.70261) (xy 89.904824 -231.69118) (xy 89.87917 -231.680004)
			(xy 89.762838 -231.69499) (xy 89.741248 -231.712008) (xy 89.736168 -231.725216) (xy 89.728021 -231.745539)
			(xy 89.70895 -231.784957) (xy 89.698068 -231.803956) (xy 89.694766 -231.809544) (xy 89.692734 -231.816148)
			(xy 89.690956 -231.82961) (xy 89.690956 -232.000806) (xy 89.715594 -232.029254) (xy 89.73439 -232.032048)
			(xy 89.75832 -232.035954) (xy 89.80462 -232.050341) (xy 89.848066 -232.071864) (xy 89.887564 -232.099982)
			(xy 89.922122 -232.133988) (xy 89.950873 -232.173028) (xy 89.973093 -232.216121) (xy 89.988223 -232.262184)
			(xy 89.995885 -232.310059) (xy 89.995885 -232.334308) (xy 90.314775 -232.334308) (xy 90.31887 -232.28358)
			(xy 90.331049 -232.234166) (xy 90.350997 -232.187346) (xy 90.378198 -232.144332) (xy 90.411946 -232.106238)
			(xy 90.451368 -232.074051) (xy 90.495442 -232.048605) (xy 90.543028 -232.030558) (xy 90.592892 -232.020378)
			(xy 90.643744 -232.018329) (xy 90.694265 -232.024463) (xy 90.743149 -232.038623) (xy 90.789128 -232.06044)
			(xy 90.831012 -232.08935) (xy 90.867716 -232.124605) (xy 90.898289 -232.165291) (xy 90.92194 -232.210354)
			(xy 90.938056 -232.258628) (xy 90.94622 -232.308862) (xy 90.946732 -232.334308) (xy 91.26526 -232.334308)
			(xy 91.26922 -232.285254) (xy 91.280997 -232.23747) (xy 91.300288 -232.192194) (xy 91.326591 -232.150598)
			(xy 91.359226 -232.113761) (xy 91.397347 -232.082636) (xy 91.439968 -232.058029) (xy 91.485984 -232.040577)
			(xy 91.534203 -232.030733) (xy 91.583378 -232.028752) (xy 91.632233 -232.034684) (xy 91.679504 -232.048376)
			(xy 91.723966 -232.069474) (xy 91.764469 -232.09743) (xy 91.799962 -232.131522) (xy 91.829527 -232.170866)
			(xy 91.852398 -232.214443) (xy 91.867982 -232.261124) (xy 91.875877 -232.309701) (xy 91.876372 -232.334308)
			(xy 92.194883 -232.334308) (xy 92.198978 -232.28358) (xy 92.211157 -232.234166) (xy 92.231105 -232.187346)
			(xy 92.258306 -232.144332) (xy 92.292054 -232.106238) (xy 92.331476 -232.074051) (xy 92.37555 -232.048605)
			(xy 92.423136 -232.030558) (xy 92.473 -232.020378) (xy 92.523852 -232.018329) (xy 92.574373 -232.024463)
			(xy 92.623257 -232.038623) (xy 92.669236 -232.06044) (xy 92.71112 -232.08935) (xy 92.747824 -232.124605)
			(xy 92.778397 -232.165291) (xy 92.802048 -232.210354) (xy 92.818164 -232.258628) (xy 92.826328 -232.308862)
			(xy 92.82684 -232.334308) (xy 93.145114 -232.334308) (xy 93.149074 -232.285254) (xy 93.160851 -232.23747)
			(xy 93.180142 -232.192194) (xy 93.206445 -232.150598) (xy 93.23908 -232.113761) (xy 93.277201 -232.082636)
			(xy 93.319822 -232.058029) (xy 93.365838 -232.040577) (xy 93.414057 -232.030733) (xy 93.463232 -232.028752)
			(xy 93.512087 -232.034684) (xy 93.559358 -232.048376) (xy 93.60382 -232.069474) (xy 93.644323 -232.09743)
			(xy 93.679816 -232.131522) (xy 93.709381 -232.170866) (xy 93.732252 -232.214443) (xy 93.747836 -232.261124)
			(xy 93.755731 -232.309701) (xy 93.756226 -232.334308) (xy 94.074737 -232.334308) (xy 94.078832 -232.28358)
			(xy 94.091011 -232.234166) (xy 94.110959 -232.187346) (xy 94.13816 -232.144332) (xy 94.171908 -232.106238)
			(xy 94.21133 -232.074051) (xy 94.255404 -232.048605) (xy 94.30299 -232.030558) (xy 94.352854 -232.020378)
			(xy 94.403706 -232.018329) (xy 94.454227 -232.024463) (xy 94.503111 -232.038623) (xy 94.54909 -232.06044)
			(xy 94.590974 -232.08935) (xy 94.627678 -232.124605) (xy 94.658251 -232.165291) (xy 94.681902 -232.210354)
			(xy 94.698018 -232.258628) (xy 94.706182 -232.308862) (xy 94.706694 -232.334308) (xy 95.014791 -232.334308)
			(xy 95.018886 -232.28358) (xy 95.031065 -232.234166) (xy 95.051013 -232.187346) (xy 95.078214 -232.144332)
			(xy 95.111962 -232.106238) (xy 95.151384 -232.074051) (xy 95.195458 -232.048605) (xy 95.243044 -232.030558)
			(xy 95.292908 -232.020378) (xy 95.34376 -232.018329) (xy 95.394281 -232.024463) (xy 95.443165 -232.038623)
			(xy 95.489144 -232.06044) (xy 95.531028 -232.08935) (xy 95.567732 -232.124605) (xy 95.598305 -232.165291)
			(xy 95.621956 -232.210354) (xy 95.638072 -232.258628) (xy 95.646236 -232.308862) (xy 95.646748 -232.334308)
			(xy 95.965276 -232.334308) (xy 95.969236 -232.285254) (xy 95.981013 -232.23747) (xy 96.000304 -232.192194)
			(xy 96.026607 -232.150598) (xy 96.059242 -232.113761) (xy 96.097363 -232.082636) (xy 96.139984 -232.058029)
			(xy 96.186 -232.040577) (xy 96.234219 -232.030733) (xy 96.283394 -232.028752) (xy 96.332249 -232.034684)
			(xy 96.37952 -232.048376) (xy 96.423982 -232.069474) (xy 96.464485 -232.09743) (xy 96.499978 -232.131522)
			(xy 96.529543 -232.170866) (xy 96.552414 -232.214443) (xy 96.567998 -232.261124) (xy 96.575893 -232.309701)
			(xy 96.576388 -232.334308) (xy 96.90533 -232.334308) (xy 96.90929 -232.285254) (xy 96.921067 -232.23747)
			(xy 96.940358 -232.192194) (xy 96.966661 -232.150598) (xy 96.999296 -232.113761) (xy 97.037417 -232.082636)
			(xy 97.080038 -232.058029) (xy 97.126054 -232.040577) (xy 97.174273 -232.030733) (xy 97.223448 -232.028752)
			(xy 97.272303 -232.034684) (xy 97.319574 -232.048376) (xy 97.364036 -232.069474) (xy 97.404539 -232.09743)
			(xy 97.440032 -232.131522) (xy 97.469597 -232.170866) (xy 97.492468 -232.214443) (xy 97.508052 -232.261124)
			(xy 97.515947 -232.309701) (xy 97.516442 -232.334308) (xy 97.84513 -232.334308) (xy 97.84909 -232.285254)
			(xy 97.860867 -232.23747) (xy 97.880158 -232.192194) (xy 97.906461 -232.150598) (xy 97.939096 -232.113761)
			(xy 97.977217 -232.082636) (xy 98.019838 -232.058029) (xy 98.065854 -232.040577) (xy 98.114073 -232.030733)
			(xy 98.163248 -232.028752) (xy 98.212103 -232.034684) (xy 98.259374 -232.048376) (xy 98.303836 -232.069474)
			(xy 98.344339 -232.09743) (xy 98.379832 -232.131522) (xy 98.409397 -232.170866) (xy 98.432268 -232.214443)
			(xy 98.447852 -232.261124) (xy 98.455747 -232.309701) (xy 98.456242 -232.334308) (xy 98.785184 -232.334308)
			(xy 98.789144 -232.285254) (xy 98.800921 -232.23747) (xy 98.820212 -232.192194) (xy 98.846515 -232.150598)
			(xy 98.87915 -232.113761) (xy 98.917271 -232.082636) (xy 98.959892 -232.058029) (xy 99.005908 -232.040577)
			(xy 99.054127 -232.030733) (xy 99.103302 -232.028752) (xy 99.152157 -232.034684) (xy 99.199428 -232.048376)
			(xy 99.24389 -232.069474) (xy 99.284393 -232.09743) (xy 99.319886 -232.131522) (xy 99.349451 -232.170866)
			(xy 99.372322 -232.214443) (xy 99.387906 -232.261124) (xy 99.395801 -232.309701) (xy 99.396296 -232.334308)
			(xy 99.725238 -232.334308) (xy 99.729198 -232.285254) (xy 99.740975 -232.23747) (xy 99.760266 -232.192194)
			(xy 99.786569 -232.150598) (xy 99.819204 -232.113761) (xy 99.857325 -232.082636) (xy 99.899946 -232.058029)
			(xy 99.945962 -232.040577) (xy 99.994181 -232.030733) (xy 100.043356 -232.028752) (xy 100.092211 -232.034684)
			(xy 100.139482 -232.048376) (xy 100.183944 -232.069474) (xy 100.224447 -232.09743) (xy 100.25994 -232.131522)
			(xy 100.289505 -232.170866) (xy 100.312376 -232.214443) (xy 100.32796 -232.261124) (xy 100.335855 -232.309701)
			(xy 100.33635 -232.334308) (xy 100.665292 -232.334308) (xy 100.669252 -232.285254) (xy 100.681029 -232.23747)
			(xy 100.70032 -232.192194) (xy 100.726623 -232.150598) (xy 100.759258 -232.113761) (xy 100.797379 -232.082636)
			(xy 100.84 -232.058029) (xy 100.886016 -232.040577) (xy 100.934235 -232.030733) (xy 100.98341 -232.028752)
			(xy 101.032265 -232.034684) (xy 101.079536 -232.048376) (xy 101.123998 -232.069474) (xy 101.164501 -232.09743)
			(xy 101.199994 -232.131522) (xy 101.229559 -232.170866) (xy 101.25243 -232.214443) (xy 101.268014 -232.261124)
			(xy 101.275909 -232.309701) (xy 101.276404 -232.334308) (xy 101.605346 -232.334308) (xy 101.609306 -232.285254)
			(xy 101.621083 -232.23747) (xy 101.640374 -232.192194) (xy 101.666677 -232.150598) (xy 101.699312 -232.113761)
			(xy 101.737433 -232.082636) (xy 101.780054 -232.058029) (xy 101.82607 -232.040577) (xy 101.874289 -232.030733)
			(xy 101.923464 -232.028752) (xy 101.972319 -232.034684) (xy 102.01959 -232.048376) (xy 102.064052 -232.069474)
			(xy 102.104555 -232.09743) (xy 102.140048 -232.131522) (xy 102.169613 -232.170866) (xy 102.192484 -232.214443)
			(xy 102.208068 -232.261124) (xy 102.215963 -232.309701) (xy 102.216458 -232.334308) (xy 102.545146 -232.334308)
			(xy 102.549106 -232.285254) (xy 102.560883 -232.23747) (xy 102.580174 -232.192194) (xy 102.606477 -232.150598)
			(xy 102.639112 -232.113761) (xy 102.677233 -232.082636) (xy 102.719854 -232.058029) (xy 102.76587 -232.040577)
			(xy 102.814089 -232.030733) (xy 102.863264 -232.028752) (xy 102.912119 -232.034684) (xy 102.95939 -232.048376)
			(xy 103.003852 -232.069474) (xy 103.044355 -232.09743) (xy 103.079848 -232.131522) (xy 103.109413 -232.170866)
			(xy 103.132284 -232.214443) (xy 103.147868 -232.261124) (xy 103.155763 -232.309701) (xy 103.156258 -232.334308)
			(xy 103.4852 -232.334308) (xy 103.48916 -232.285254) (xy 103.500937 -232.23747) (xy 103.520228 -232.192194)
			(xy 103.546531 -232.150598) (xy 103.579166 -232.113761) (xy 103.617287 -232.082636) (xy 103.659908 -232.058029)
			(xy 103.705924 -232.040577) (xy 103.754143 -232.030733) (xy 103.803318 -232.028752) (xy 103.852173 -232.034684)
			(xy 103.899444 -232.048376) (xy 103.943906 -232.069474) (xy 103.984409 -232.09743) (xy 104.019902 -232.131522)
			(xy 104.049467 -232.170866) (xy 104.072338 -232.214443) (xy 104.087922 -232.261124) (xy 104.095817 -232.309701)
			(xy 104.096312 -232.334308) (xy 104.425254 -232.334308) (xy 104.429214 -232.285254) (xy 104.440991 -232.23747)
			(xy 104.460282 -232.192194) (xy 104.486585 -232.150598) (xy 104.51922 -232.113761) (xy 104.557341 -232.082636)
			(xy 104.599962 -232.058029) (xy 104.645978 -232.040577) (xy 104.694197 -232.030733) (xy 104.743372 -232.028752)
			(xy 104.792227 -232.034684) (xy 104.839498 -232.048376) (xy 104.88396 -232.069474) (xy 104.924463 -232.09743)
			(xy 104.959956 -232.131522) (xy 104.989521 -232.170866) (xy 105.012392 -232.214443) (xy 105.027976 -232.261124)
			(xy 105.035871 -232.309701) (xy 105.036366 -232.334308) (xy 105.365308 -232.334308) (xy 105.369268 -232.285254)
			(xy 105.381045 -232.23747) (xy 105.400336 -232.192194) (xy 105.426639 -232.150598) (xy 105.459274 -232.113761)
			(xy 105.497395 -232.082636) (xy 105.540016 -232.058029) (xy 105.586032 -232.040577) (xy 105.634251 -232.030733)
			(xy 105.683426 -232.028752) (xy 105.732281 -232.034684) (xy 105.779552 -232.048376) (xy 105.824014 -232.069474)
			(xy 105.864517 -232.09743) (xy 105.90001 -232.131522) (xy 105.929575 -232.170866) (xy 105.952446 -232.214443)
			(xy 105.96803 -232.261124) (xy 105.975925 -232.309701) (xy 105.97642 -232.334308) (xy 106.305362 -232.334308)
			(xy 106.309322 -232.285254) (xy 106.321099 -232.23747) (xy 106.34039 -232.192194) (xy 106.366693 -232.150598)
			(xy 106.399328 -232.113761) (xy 106.437449 -232.082636) (xy 106.48007 -232.058029) (xy 106.526086 -232.040577)
			(xy 106.574305 -232.030733) (xy 106.62348 -232.028752) (xy 106.672335 -232.034684) (xy 106.719606 -232.048376)
			(xy 106.764068 -232.069474) (xy 106.804571 -232.09743) (xy 106.840064 -232.131522) (xy 106.869629 -232.170866)
			(xy 106.8925 -232.214443) (xy 106.908084 -232.261124) (xy 106.915979 -232.309701) (xy 106.916474 -232.334308)
			(xy 107.245162 -232.334308) (xy 107.249122 -232.285254) (xy 107.260899 -232.23747) (xy 107.28019 -232.192194)
			(xy 107.306493 -232.150598) (xy 107.339128 -232.113761) (xy 107.377249 -232.082636) (xy 107.41987 -232.058029)
			(xy 107.465886 -232.040577) (xy 107.514105 -232.030733) (xy 107.56328 -232.028752) (xy 107.612135 -232.034684)
			(xy 107.659406 -232.048376) (xy 107.703868 -232.069474) (xy 107.744371 -232.09743) (xy 107.779864 -232.131522)
			(xy 107.809429 -232.170866) (xy 107.8323 -232.214443) (xy 107.847884 -232.261124) (xy 107.855779 -232.309701)
			(xy 107.856274 -232.334308) (xy 108.174785 -232.334308) (xy 108.17888 -232.28358) (xy 108.191059 -232.234166)
			(xy 108.211007 -232.187346) (xy 108.238208 -232.144332) (xy 108.271956 -232.106238) (xy 108.311378 -232.074051)
			(xy 108.355452 -232.048605) (xy 108.403038 -232.030558) (xy 108.452902 -232.020378) (xy 108.503754 -232.018329)
			(xy 108.554275 -232.024463) (xy 108.603159 -232.038623) (xy 108.649138 -232.06044) (xy 108.691022 -232.08935)
			(xy 108.727726 -232.124605) (xy 108.758299 -232.165291) (xy 108.78195 -232.210354) (xy 108.798066 -232.258628)
			(xy 108.80623 -232.308862) (xy 108.806742 -232.334308) (xy 109.114839 -232.334308) (xy 109.118934 -232.28358)
			(xy 109.131113 -232.234166) (xy 109.151061 -232.187346) (xy 109.178262 -232.144332) (xy 109.21201 -232.106238)
			(xy 109.251432 -232.074051) (xy 109.295506 -232.048605) (xy 109.343092 -232.030558) (xy 109.392956 -232.020378)
			(xy 109.443808 -232.018329) (xy 109.494329 -232.024463) (xy 109.543213 -232.038623) (xy 109.589192 -232.06044)
			(xy 109.631076 -232.08935) (xy 109.66778 -232.124605) (xy 109.698353 -232.165291) (xy 109.722004 -232.210354)
			(xy 109.73812 -232.258628) (xy 109.746284 -232.308862) (xy 109.746796 -232.334308) (xy 110.065324 -232.334308)
			(xy 110.069284 -232.285254) (xy 110.081061 -232.23747) (xy 110.100352 -232.192194) (xy 110.126655 -232.150598)
			(xy 110.15929 -232.113761) (xy 110.197411 -232.082636) (xy 110.240032 -232.058029) (xy 110.286048 -232.040577)
			(xy 110.334267 -232.030733) (xy 110.383442 -232.028752) (xy 110.432297 -232.034684) (xy 110.479568 -232.048376)
			(xy 110.52403 -232.069474) (xy 110.564533 -232.09743) (xy 110.600026 -232.131522) (xy 110.629591 -232.170866)
			(xy 110.652462 -232.214443) (xy 110.668046 -232.261124) (xy 110.675941 -232.309701) (xy 110.676436 -232.334308)
			(xy 110.675941 -232.358915) (xy 110.668046 -232.407492) (xy 110.652462 -232.454173) (xy 110.629591 -232.49775)
			(xy 110.600026 -232.537094) (xy 110.564533 -232.571186) (xy 110.52403 -232.599142) (xy 110.479568 -232.62024)
			(xy 110.432297 -232.633932) (xy 110.383442 -232.639864) (xy 110.334267 -232.637883) (xy 110.286048 -232.628039)
			(xy 110.240032 -232.610587) (xy 110.197411 -232.58598) (xy 110.15929 -232.554855) (xy 110.126655 -232.518018)
			(xy 110.100352 -232.476422) (xy 110.081061 -232.431146) (xy 110.069284 -232.383362) (xy 110.065324 -232.334308)
			(xy 109.746796 -232.334308) (xy 109.746284 -232.359754) (xy 109.73812 -232.409988) (xy 109.722004 -232.458262)
			(xy 109.698353 -232.503325) (xy 109.66778 -232.544011) (xy 109.631076 -232.579266) (xy 109.589192 -232.608176)
			(xy 109.543213 -232.629993) (xy 109.494329 -232.644153) (xy 109.443808 -232.650287) (xy 109.392956 -232.648238)
			(xy 109.343092 -232.638058) (xy 109.295506 -232.620011) (xy 109.251432 -232.594565) (xy 109.21201 -232.562378)
			(xy 109.178262 -232.524284) (xy 109.151061 -232.48127) (xy 109.131113 -232.43445) (xy 109.118934 -232.385036)
			(xy 109.114839 -232.334308) (xy 108.806742 -232.334308) (xy 108.80623 -232.359754) (xy 108.798066 -232.409988)
			(xy 108.78195 -232.458262) (xy 108.758299 -232.503325) (xy 108.727726 -232.544011) (xy 108.691022 -232.579266)
			(xy 108.649138 -232.608176) (xy 108.603159 -232.629993) (xy 108.554275 -232.644153) (xy 108.503754 -232.650287)
			(xy 108.452902 -232.648238) (xy 108.403038 -232.638058) (xy 108.355452 -232.620011) (xy 108.311378 -232.594565)
			(xy 108.271956 -232.562378) (xy 108.238208 -232.524284) (xy 108.211007 -232.48127) (xy 108.191059 -232.43445)
			(xy 108.17888 -232.385036) (xy 108.174785 -232.334308) (xy 107.856274 -232.334308) (xy 107.855779 -232.358915)
			(xy 107.847884 -232.407492) (xy 107.8323 -232.454173) (xy 107.809429 -232.49775) (xy 107.779864 -232.537094)
			(xy 107.744371 -232.571186) (xy 107.703868 -232.599142) (xy 107.659406 -232.62024) (xy 107.612135 -232.633932)
			(xy 107.56328 -232.639864) (xy 107.514105 -232.637883) (xy 107.465886 -232.628039) (xy 107.41987 -232.610587)
			(xy 107.377249 -232.58598) (xy 107.339128 -232.554855) (xy 107.306493 -232.518018) (xy 107.28019 -232.476422)
			(xy 107.260899 -232.431146) (xy 107.249122 -232.383362) (xy 107.245162 -232.334308) (xy 106.916474 -232.334308)
			(xy 106.915979 -232.358915) (xy 106.908084 -232.407492) (xy 106.8925 -232.454173) (xy 106.869629 -232.49775)
			(xy 106.840064 -232.537094) (xy 106.804571 -232.571186) (xy 106.764068 -232.599142) (xy 106.719606 -232.62024)
			(xy 106.672335 -232.633932) (xy 106.62348 -232.639864) (xy 106.574305 -232.637883) (xy 106.526086 -232.628039)
			(xy 106.48007 -232.610587) (xy 106.437449 -232.58598) (xy 106.399328 -232.554855) (xy 106.366693 -232.518018)
			(xy 106.34039 -232.476422) (xy 106.321099 -232.431146) (xy 106.309322 -232.383362) (xy 106.305362 -232.334308)
			(xy 105.97642 -232.334308) (xy 105.975925 -232.358915) (xy 105.96803 -232.407492) (xy 105.952446 -232.454173)
			(xy 105.929575 -232.49775) (xy 105.90001 -232.537094) (xy 105.864517 -232.571186) (xy 105.824014 -232.599142)
			(xy 105.779552 -232.62024) (xy 105.732281 -232.633932) (xy 105.683426 -232.639864) (xy 105.634251 -232.637883)
			(xy 105.586032 -232.628039) (xy 105.540016 -232.610587) (xy 105.497395 -232.58598) (xy 105.459274 -232.554855)
			(xy 105.426639 -232.518018) (xy 105.400336 -232.476422) (xy 105.381045 -232.431146) (xy 105.369268 -232.383362)
			(xy 105.365308 -232.334308) (xy 105.036366 -232.334308) (xy 105.035871 -232.358915) (xy 105.027976 -232.407492)
			(xy 105.012392 -232.454173) (xy 104.989521 -232.49775) (xy 104.959956 -232.537094) (xy 104.924463 -232.571186)
			(xy 104.88396 -232.599142) (xy 104.839498 -232.62024) (xy 104.792227 -232.633932) (xy 104.743372 -232.639864)
			(xy 104.694197 -232.637883) (xy 104.645978 -232.628039) (xy 104.599962 -232.610587) (xy 104.557341 -232.58598)
			(xy 104.51922 -232.554855) (xy 104.486585 -232.518018) (xy 104.460282 -232.476422) (xy 104.440991 -232.431146)
			(xy 104.429214 -232.383362) (xy 104.425254 -232.334308) (xy 104.096312 -232.334308) (xy 104.095817 -232.358915)
			(xy 104.087922 -232.407492) (xy 104.072338 -232.454173) (xy 104.049467 -232.49775) (xy 104.019902 -232.537094)
			(xy 103.984409 -232.571186) (xy 103.943906 -232.599142) (xy 103.899444 -232.62024) (xy 103.852173 -232.633932)
			(xy 103.803318 -232.639864) (xy 103.754143 -232.637883) (xy 103.705924 -232.628039) (xy 103.659908 -232.610587)
			(xy 103.617287 -232.58598) (xy 103.579166 -232.554855) (xy 103.546531 -232.518018) (xy 103.520228 -232.476422)
			(xy 103.500937 -232.431146) (xy 103.48916 -232.383362) (xy 103.4852 -232.334308) (xy 103.156258 -232.334308)
			(xy 103.155763 -232.358915) (xy 103.147868 -232.407492) (xy 103.132284 -232.454173) (xy 103.109413 -232.49775)
			(xy 103.079848 -232.537094) (xy 103.044355 -232.571186) (xy 103.003852 -232.599142) (xy 102.95939 -232.62024)
			(xy 102.912119 -232.633932) (xy 102.863264 -232.639864) (xy 102.814089 -232.637883) (xy 102.76587 -232.628039)
			(xy 102.719854 -232.610587) (xy 102.677233 -232.58598) (xy 102.639112 -232.554855) (xy 102.606477 -232.518018)
			(xy 102.580174 -232.476422) (xy 102.560883 -232.431146) (xy 102.549106 -232.383362) (xy 102.545146 -232.334308)
			(xy 102.216458 -232.334308) (xy 102.215963 -232.358915) (xy 102.208068 -232.407492) (xy 102.192484 -232.454173)
			(xy 102.169613 -232.49775) (xy 102.140048 -232.537094) (xy 102.104555 -232.571186) (xy 102.064052 -232.599142)
			(xy 102.01959 -232.62024) (xy 101.972319 -232.633932) (xy 101.923464 -232.639864) (xy 101.874289 -232.637883)
			(xy 101.82607 -232.628039) (xy 101.780054 -232.610587) (xy 101.737433 -232.58598) (xy 101.699312 -232.554855)
			(xy 101.666677 -232.518018) (xy 101.640374 -232.476422) (xy 101.621083 -232.431146) (xy 101.609306 -232.383362)
			(xy 101.605346 -232.334308) (xy 101.276404 -232.334308) (xy 101.275909 -232.358915) (xy 101.268014 -232.407492)
			(xy 101.25243 -232.454173) (xy 101.229559 -232.49775) (xy 101.199994 -232.537094) (xy 101.164501 -232.571186)
			(xy 101.123998 -232.599142) (xy 101.079536 -232.62024) (xy 101.032265 -232.633932) (xy 100.98341 -232.639864)
			(xy 100.934235 -232.637883) (xy 100.886016 -232.628039) (xy 100.84 -232.610587) (xy 100.797379 -232.58598)
			(xy 100.759258 -232.554855) (xy 100.726623 -232.518018) (xy 100.70032 -232.476422) (xy 100.681029 -232.431146)
			(xy 100.669252 -232.383362) (xy 100.665292 -232.334308) (xy 100.33635 -232.334308) (xy 100.335855 -232.358915)
			(xy 100.32796 -232.407492) (xy 100.312376 -232.454173) (xy 100.289505 -232.49775) (xy 100.25994 -232.537094)
			(xy 100.224447 -232.571186) (xy 100.183944 -232.599142) (xy 100.139482 -232.62024) (xy 100.092211 -232.633932)
			(xy 100.043356 -232.639864) (xy 99.994181 -232.637883) (xy 99.945962 -232.628039) (xy 99.899946 -232.610587)
			(xy 99.857325 -232.58598) (xy 99.819204 -232.554855) (xy 99.786569 -232.518018) (xy 99.760266 -232.476422)
			(xy 99.740975 -232.431146) (xy 99.729198 -232.383362) (xy 99.725238 -232.334308) (xy 99.396296 -232.334308)
			(xy 99.395801 -232.358915) (xy 99.387906 -232.407492) (xy 99.372322 -232.454173) (xy 99.349451 -232.49775)
			(xy 99.319886 -232.537094) (xy 99.284393 -232.571186) (xy 99.24389 -232.599142) (xy 99.199428 -232.62024)
			(xy 99.152157 -232.633932) (xy 99.103302 -232.639864) (xy 99.054127 -232.637883) (xy 99.005908 -232.628039)
			(xy 98.959892 -232.610587) (xy 98.917271 -232.58598) (xy 98.87915 -232.554855) (xy 98.846515 -232.518018)
			(xy 98.820212 -232.476422) (xy 98.800921 -232.431146) (xy 98.789144 -232.383362) (xy 98.785184 -232.334308)
			(xy 98.456242 -232.334308) (xy 98.455747 -232.358915) (xy 98.447852 -232.407492) (xy 98.432268 -232.454173)
			(xy 98.409397 -232.49775) (xy 98.379832 -232.537094) (xy 98.344339 -232.571186) (xy 98.303836 -232.599142)
			(xy 98.259374 -232.62024) (xy 98.212103 -232.633932) (xy 98.163248 -232.639864) (xy 98.114073 -232.637883)
			(xy 98.065854 -232.628039) (xy 98.019838 -232.610587) (xy 97.977217 -232.58598) (xy 97.939096 -232.554855)
			(xy 97.906461 -232.518018) (xy 97.880158 -232.476422) (xy 97.860867 -232.431146) (xy 97.84909 -232.383362)
			(xy 97.84513 -232.334308) (xy 97.516442 -232.334308) (xy 97.515947 -232.358915) (xy 97.508052 -232.407492)
			(xy 97.492468 -232.454173) (xy 97.469597 -232.49775) (xy 97.440032 -232.537094) (xy 97.404539 -232.571186)
			(xy 97.364036 -232.599142) (xy 97.319574 -232.62024) (xy 97.272303 -232.633932) (xy 97.223448 -232.639864)
			(xy 97.174273 -232.637883) (xy 97.126054 -232.628039) (xy 97.080038 -232.610587) (xy 97.037417 -232.58598)
			(xy 96.999296 -232.554855) (xy 96.966661 -232.518018) (xy 96.940358 -232.476422) (xy 96.921067 -232.431146)
			(xy 96.90929 -232.383362) (xy 96.90533 -232.334308) (xy 96.576388 -232.334308) (xy 96.575893 -232.358915)
			(xy 96.567998 -232.407492) (xy 96.552414 -232.454173) (xy 96.529543 -232.49775) (xy 96.499978 -232.537094)
			(xy 96.464485 -232.571186) (xy 96.423982 -232.599142) (xy 96.37952 -232.62024) (xy 96.332249 -232.633932)
			(xy 96.283394 -232.639864) (xy 96.234219 -232.637883) (xy 96.186 -232.628039) (xy 96.139984 -232.610587)
			(xy 96.097363 -232.58598) (xy 96.059242 -232.554855) (xy 96.026607 -232.518018) (xy 96.000304 -232.476422)
			(xy 95.981013 -232.431146) (xy 95.969236 -232.383362) (xy 95.965276 -232.334308) (xy 95.646748 -232.334308)
			(xy 95.646236 -232.359754) (xy 95.638072 -232.409988) (xy 95.621956 -232.458262) (xy 95.598305 -232.503325)
			(xy 95.567732 -232.544011) (xy 95.531028 -232.579266) (xy 95.489144 -232.608176) (xy 95.443165 -232.629993)
			(xy 95.394281 -232.644153) (xy 95.34376 -232.650287) (xy 95.292908 -232.648238) (xy 95.243044 -232.638058)
			(xy 95.195458 -232.620011) (xy 95.151384 -232.594565) (xy 95.111962 -232.562378) (xy 95.078214 -232.524284)
			(xy 95.051013 -232.48127) (xy 95.031065 -232.43445) (xy 95.018886 -232.385036) (xy 95.014791 -232.334308)
			(xy 94.706694 -232.334308) (xy 94.706182 -232.359754) (xy 94.698018 -232.409988) (xy 94.681902 -232.458262)
			(xy 94.658251 -232.503325) (xy 94.627678 -232.544011) (xy 94.590974 -232.579266) (xy 94.54909 -232.608176)
			(xy 94.503111 -232.629993) (xy 94.454227 -232.644153) (xy 94.403706 -232.650287) (xy 94.352854 -232.648238)
			(xy 94.30299 -232.638058) (xy 94.255404 -232.620011) (xy 94.21133 -232.594565) (xy 94.171908 -232.562378)
			(xy 94.13816 -232.524284) (xy 94.110959 -232.48127) (xy 94.091011 -232.43445) (xy 94.078832 -232.385036)
			(xy 94.074737 -232.334308) (xy 93.756226 -232.334308) (xy 93.755731 -232.358915) (xy 93.747836 -232.407492)
			(xy 93.732252 -232.454173) (xy 93.709381 -232.49775) (xy 93.679816 -232.537094) (xy 93.644323 -232.571186)
			(xy 93.60382 -232.599142) (xy 93.559358 -232.62024) (xy 93.512087 -232.633932) (xy 93.463232 -232.639864)
			(xy 93.414057 -232.637883) (xy 93.365838 -232.628039) (xy 93.319822 -232.610587) (xy 93.277201 -232.58598)
			(xy 93.23908 -232.554855) (xy 93.206445 -232.518018) (xy 93.180142 -232.476422) (xy 93.160851 -232.431146)
			(xy 93.149074 -232.383362) (xy 93.145114 -232.334308) (xy 92.82684 -232.334308) (xy 92.826328 -232.359754)
			(xy 92.818164 -232.409988) (xy 92.802048 -232.458262) (xy 92.778397 -232.503325) (xy 92.747824 -232.544011)
			(xy 92.71112 -232.579266) (xy 92.669236 -232.608176) (xy 92.623257 -232.629993) (xy 92.574373 -232.644153)
			(xy 92.523852 -232.650287) (xy 92.473 -232.648238) (xy 92.423136 -232.638058) (xy 92.37555 -232.620011)
			(xy 92.331476 -232.594565) (xy 92.292054 -232.562378) (xy 92.258306 -232.524284) (xy 92.231105 -232.48127)
			(xy 92.211157 -232.43445) (xy 92.198978 -232.385036) (xy 92.194883 -232.334308) (xy 91.876372 -232.334308)
			(xy 91.875877 -232.358915) (xy 91.867982 -232.407492) (xy 91.852398 -232.454173) (xy 91.829527 -232.49775)
			(xy 91.799962 -232.537094) (xy 91.764469 -232.571186) (xy 91.723966 -232.599142) (xy 91.679504 -232.62024)
			(xy 91.632233 -232.633932) (xy 91.583378 -232.639864) (xy 91.534203 -232.637883) (xy 91.485984 -232.628039)
			(xy 91.439968 -232.610587) (xy 91.397347 -232.58598) (xy 91.359226 -232.554855) (xy 91.326591 -232.518018)
			(xy 91.300288 -232.476422) (xy 91.280997 -232.431146) (xy 91.26922 -232.383362) (xy 91.26526 -232.334308)
			(xy 90.946732 -232.334308) (xy 90.94622 -232.359754) (xy 90.938056 -232.409988) (xy 90.92194 -232.458262)
			(xy 90.898289 -232.503325) (xy 90.867716 -232.544011) (xy 90.831012 -232.579266) (xy 90.789128 -232.608176)
			(xy 90.743149 -232.629993) (xy 90.694265 -232.644153) (xy 90.643744 -232.650287) (xy 90.592892 -232.648238)
			(xy 90.543028 -232.638058) (xy 90.495442 -232.620011) (xy 90.451368 -232.594565) (xy 90.411946 -232.562378)
			(xy 90.378198 -232.524284) (xy 90.350997 -232.48127) (xy 90.331049 -232.43445) (xy 90.31887 -232.385036)
			(xy 90.314775 -232.334308) (xy 89.995885 -232.334308) (xy 89.995885 -232.358543) (xy 89.988223 -232.406418)
			(xy 89.973092 -232.452481) (xy 89.950872 -232.495574) (xy 89.922121 -232.534614) (xy 89.887562 -232.56862)
			(xy 89.848064 -232.596737) (xy 89.804618 -232.61826) (xy 89.758318 -232.632647) (xy 89.73439 -232.636568)
			(xy 89.715594 -232.639362) (xy 89.690956 -232.66781) (xy 89.690956 -232.832656) (xy 89.691126 -232.839388)
			(xy 89.694601 -232.852392) (xy 89.697814 -232.85831) (xy 89.702132 -232.865422) (xy 89.708342 -232.876305)
			(xy 89.719902 -232.898539) (xy 89.725246 -232.909872) (xy 89.738454 -232.94086) (xy 89.743534 -232.953814)
			(xy 89.765378 -232.970832) (xy 89.867486 -232.98404) (xy 89.874224 -232.984622) (xy 89.887607 -232.982701)
			(xy 89.893902 -232.98023) (xy 89.900506 -232.977436) (xy 89.91092 -232.969308) (xy 89.914984 -232.96372)
			(xy 89.929478 -232.944748) (xy 89.963367 -232.911123) (xy 90.002075 -232.883181) (xy 90.04466 -232.861602)
			(xy 90.090084 -232.846913) (xy 90.13724 -232.83947) (xy 90.16111 -232.839006) (xy 90.186364 -232.839528)
			(xy 90.236182 -232.847843) (xy 90.283952 -232.864244) (xy 90.328371 -232.888284) (xy 90.368228 -232.919307)
			(xy 90.402435 -232.956467) (xy 90.43006 -232.99875) (xy 90.450348 -233.045003) (xy 90.462746 -233.093965)
			(xy 90.466917 -233.1443) (xy 90.466916 -233.144314) (xy 90.784675 -233.144314) (xy 90.78877 -233.093586)
			(xy 90.800949 -233.044172) (xy 90.820897 -232.997352) (xy 90.848098 -232.954338) (xy 90.881846 -232.916244)
			(xy 90.921268 -232.884057) (xy 90.965342 -232.858611) (xy 91.012928 -232.840564) (xy 91.062792 -232.830384)
			(xy 91.113644 -232.828335) (xy 91.164165 -232.834469) (xy 91.213049 -232.848629) (xy 91.259028 -232.870446)
			(xy 91.300912 -232.899356) (xy 91.337616 -232.934611) (xy 91.368189 -232.975297) (xy 91.39184 -233.02036)
			(xy 91.407956 -233.068634) (xy 91.41612 -233.118868) (xy 91.416632 -233.144314) (xy 91.724729 -233.144314)
			(xy 91.728824 -233.093586) (xy 91.741003 -233.044172) (xy 91.760951 -232.997352) (xy 91.788152 -232.954338)
			(xy 91.8219 -232.916244) (xy 91.861322 -232.884057) (xy 91.905396 -232.858611) (xy 91.952982 -232.840564)
			(xy 92.002846 -232.830384) (xy 92.053698 -232.828335) (xy 92.104219 -232.834469) (xy 92.153103 -232.848629)
			(xy 92.199082 -232.870446) (xy 92.240966 -232.899356) (xy 92.27767 -232.934611) (xy 92.308243 -232.975297)
			(xy 92.331894 -233.02036) (xy 92.34801 -233.068634) (xy 92.356174 -233.118868) (xy 92.356686 -233.144314)
			(xy 92.675214 -233.144314) (xy 92.679174 -233.09526) (xy 92.690951 -233.047476) (xy 92.710242 -233.0022)
			(xy 92.736545 -232.960604) (xy 92.76918 -232.923767) (xy 92.807301 -232.892642) (xy 92.849922 -232.868035)
			(xy 92.895938 -232.850583) (xy 92.944157 -232.840739) (xy 92.993332 -232.838758) (xy 93.042187 -232.84469)
			(xy 93.089458 -232.858382) (xy 93.13392 -232.87948) (xy 93.174423 -232.907436) (xy 93.209916 -232.941528)
			(xy 93.239481 -232.980872) (xy 93.262352 -233.024449) (xy 93.277936 -233.07113) (xy 93.285831 -233.119707)
			(xy 93.286326 -233.144314) (xy 93.604837 -233.144314) (xy 93.608932 -233.093586) (xy 93.621111 -233.044172)
			(xy 93.641059 -232.997352) (xy 93.66826 -232.954338) (xy 93.702008 -232.916244) (xy 93.74143 -232.884057)
			(xy 93.785504 -232.858611) (xy 93.83309 -232.840564) (xy 93.882954 -232.830384) (xy 93.933806 -232.828335)
			(xy 93.984327 -232.834469) (xy 94.033211 -232.848629) (xy 94.07919 -232.870446) (xy 94.121074 -232.899356)
			(xy 94.157778 -232.934611) (xy 94.188351 -232.975297) (xy 94.212002 -233.02036) (xy 94.228118 -233.068634)
			(xy 94.236282 -233.118868) (xy 94.236794 -233.144314) (xy 94.555322 -233.144314) (xy 94.559282 -233.09526)
			(xy 94.571059 -233.047476) (xy 94.59035 -233.0022) (xy 94.616653 -232.960604) (xy 94.649288 -232.923767)
			(xy 94.687409 -232.892642) (xy 94.73003 -232.868035) (xy 94.776046 -232.850583) (xy 94.824265 -232.840739)
			(xy 94.87344 -232.838758) (xy 94.922295 -232.84469) (xy 94.969566 -232.858382) (xy 95.014028 -232.87948)
			(xy 95.054531 -232.907436) (xy 95.090024 -232.941528) (xy 95.119589 -232.980872) (xy 95.14246 -233.024449)
			(xy 95.158044 -233.07113) (xy 95.165939 -233.119707) (xy 95.166434 -233.144314) (xy 95.484691 -233.144314)
			(xy 95.488786 -233.093586) (xy 95.500965 -233.044172) (xy 95.520913 -232.997352) (xy 95.548114 -232.954338)
			(xy 95.581862 -232.916244) (xy 95.621284 -232.884057) (xy 95.665358 -232.858611) (xy 95.712944 -232.840564)
			(xy 95.762808 -232.830384) (xy 95.81366 -232.828335) (xy 95.864181 -232.834469) (xy 95.913065 -232.848629)
			(xy 95.959044 -232.870446) (xy 96.000928 -232.899356) (xy 96.037632 -232.934611) (xy 96.068205 -232.975297)
			(xy 96.091856 -233.02036) (xy 96.107972 -233.068634) (xy 96.116136 -233.118868) (xy 96.116648 -233.144314)
			(xy 96.435176 -233.144314) (xy 96.439136 -233.09526) (xy 96.450913 -233.047476) (xy 96.470204 -233.0022)
			(xy 96.496507 -232.960604) (xy 96.529142 -232.923767) (xy 96.567263 -232.892642) (xy 96.609884 -232.868035)
			(xy 96.6559 -232.850583) (xy 96.704119 -232.840739) (xy 96.753294 -232.838758) (xy 96.802149 -232.84469)
			(xy 96.84942 -232.858382) (xy 96.893882 -232.87948) (xy 96.934385 -232.907436) (xy 96.969878 -232.941528)
			(xy 96.999443 -232.980872) (xy 97.022314 -233.024449) (xy 97.037898 -233.07113) (xy 97.045793 -233.119707)
			(xy 97.046288 -233.144314) (xy 97.364799 -233.144314) (xy 97.368894 -233.093586) (xy 97.381073 -233.044172)
			(xy 97.401021 -232.997352) (xy 97.428222 -232.954338) (xy 97.46197 -232.916244) (xy 97.501392 -232.884057)
			(xy 97.545466 -232.858611) (xy 97.593052 -232.840564) (xy 97.642916 -232.830384) (xy 97.693768 -232.828335)
			(xy 97.744289 -232.834469) (xy 97.793173 -232.848629) (xy 97.839152 -232.870446) (xy 97.881036 -232.899356)
			(xy 97.91774 -232.934611) (xy 97.948313 -232.975297) (xy 97.971964 -233.02036) (xy 97.98808 -233.068634)
			(xy 97.996244 -233.118868) (xy 97.996756 -233.144314) (xy 98.304853 -233.144314) (xy 98.308948 -233.093586)
			(xy 98.321127 -233.044172) (xy 98.341075 -232.997352) (xy 98.368276 -232.954338) (xy 98.402024 -232.916244)
			(xy 98.441446 -232.884057) (xy 98.48552 -232.858611) (xy 98.533106 -232.840564) (xy 98.58297 -232.830384)
			(xy 98.633822 -232.828335) (xy 98.684343 -232.834469) (xy 98.733227 -232.848629) (xy 98.779206 -232.870446)
			(xy 98.82109 -232.899356) (xy 98.857794 -232.934611) (xy 98.888367 -232.975297) (xy 98.912018 -233.02036)
			(xy 98.928134 -233.068634) (xy 98.936298 -233.118868) (xy 98.93681 -233.144314) (xy 99.255338 -233.144314)
			(xy 99.259298 -233.09526) (xy 99.271075 -233.047476) (xy 99.290366 -233.0022) (xy 99.316669 -232.960604)
			(xy 99.349304 -232.923767) (xy 99.387425 -232.892642) (xy 99.430046 -232.868035) (xy 99.476062 -232.850583)
			(xy 99.524281 -232.840739) (xy 99.573456 -232.838758) (xy 99.622311 -232.84469) (xy 99.669582 -232.858382)
			(xy 99.714044 -232.87948) (xy 99.754547 -232.907436) (xy 99.79004 -232.941528) (xy 99.819605 -232.980872)
			(xy 99.842476 -233.024449) (xy 99.85806 -233.07113) (xy 99.865955 -233.119707) (xy 99.86645 -233.144314)
			(xy 100.184707 -233.144314) (xy 100.188802 -233.093586) (xy 100.200981 -233.044172) (xy 100.220929 -232.997352)
			(xy 100.24813 -232.954338) (xy 100.281878 -232.916244) (xy 100.3213 -232.884057) (xy 100.365374 -232.858611)
			(xy 100.41296 -232.840564) (xy 100.462824 -232.830384) (xy 100.513676 -232.828335) (xy 100.564197 -232.834469)
			(xy 100.613081 -232.848629) (xy 100.65906 -232.870446) (xy 100.700944 -232.899356) (xy 100.737648 -232.934611)
			(xy 100.768221 -232.975297) (xy 100.791872 -233.02036) (xy 100.807988 -233.068634) (xy 100.816152 -233.118868)
			(xy 100.816664 -233.144314) (xy 101.124761 -233.144314) (xy 101.128856 -233.093586) (xy 101.141035 -233.044172)
			(xy 101.160983 -232.997352) (xy 101.188184 -232.954338) (xy 101.221932 -232.916244) (xy 101.261354 -232.884057)
			(xy 101.305428 -232.858611) (xy 101.353014 -232.840564) (xy 101.402878 -232.830384) (xy 101.45373 -232.828335)
			(xy 101.504251 -232.834469) (xy 101.553135 -232.848629) (xy 101.599114 -232.870446) (xy 101.640998 -232.899356)
			(xy 101.677702 -232.934611) (xy 101.708275 -232.975297) (xy 101.731926 -233.02036) (xy 101.748042 -233.068634)
			(xy 101.756206 -233.118868) (xy 101.756718 -233.144314) (xy 102.075246 -233.144314) (xy 102.079206 -233.09526)
			(xy 102.090983 -233.047476) (xy 102.110274 -233.0022) (xy 102.136577 -232.960604) (xy 102.169212 -232.923767)
			(xy 102.207333 -232.892642) (xy 102.249954 -232.868035) (xy 102.29597 -232.850583) (xy 102.344189 -232.840739)
			(xy 102.393364 -232.838758) (xy 102.442219 -232.84469) (xy 102.48949 -232.858382) (xy 102.533952 -232.87948)
			(xy 102.574455 -232.907436) (xy 102.609948 -232.941528) (xy 102.639513 -232.980872) (xy 102.662384 -233.024449)
			(xy 102.677968 -233.07113) (xy 102.685863 -233.119707) (xy 102.686358 -233.144314) (xy 103.004869 -233.144314)
			(xy 103.008964 -233.093586) (xy 103.021143 -233.044172) (xy 103.041091 -232.997352) (xy 103.068292 -232.954338)
			(xy 103.10204 -232.916244) (xy 103.141462 -232.884057) (xy 103.185536 -232.858611) (xy 103.233122 -232.840564)
			(xy 103.282986 -232.830384) (xy 103.333838 -232.828335) (xy 103.384359 -232.834469) (xy 103.433243 -232.848629)
			(xy 103.479222 -232.870446) (xy 103.521106 -232.899356) (xy 103.55781 -232.934611) (xy 103.588383 -232.975297)
			(xy 103.612034 -233.02036) (xy 103.62815 -233.068634) (xy 103.636314 -233.118868) (xy 103.636826 -233.144314)
			(xy 103.944923 -233.144314) (xy 103.949018 -233.093586) (xy 103.961197 -233.044172) (xy 103.981145 -232.997352)
			(xy 104.008346 -232.954338) (xy 104.042094 -232.916244) (xy 104.081516 -232.884057) (xy 104.12559 -232.858611)
			(xy 104.173176 -232.840564) (xy 104.22304 -232.830384) (xy 104.273892 -232.828335) (xy 104.324413 -232.834469)
			(xy 104.373297 -232.848629) (xy 104.419276 -232.870446) (xy 104.46116 -232.899356) (xy 104.497864 -232.934611)
			(xy 104.528437 -232.975297) (xy 104.552088 -233.02036) (xy 104.568204 -233.068634) (xy 104.576368 -233.118868)
			(xy 104.57688 -233.144314) (xy 104.895154 -233.144314) (xy 104.899114 -233.09526) (xy 104.910891 -233.047476)
			(xy 104.930182 -233.0022) (xy 104.956485 -232.960604) (xy 104.98912 -232.923767) (xy 105.027241 -232.892642)
			(xy 105.069862 -232.868035) (xy 105.115878 -232.850583) (xy 105.164097 -232.840739) (xy 105.213272 -232.838758)
			(xy 105.262127 -232.84469) (xy 105.309398 -232.858382) (xy 105.35386 -232.87948) (xy 105.394363 -232.907436)
			(xy 105.429856 -232.941528) (xy 105.459421 -232.980872) (xy 105.482292 -233.024449) (xy 105.497876 -233.07113)
			(xy 105.505771 -233.119707) (xy 105.506266 -233.144314) (xy 105.824777 -233.144314) (xy 105.828872 -233.093586)
			(xy 105.841051 -233.044172) (xy 105.860999 -232.997352) (xy 105.8882 -232.954338) (xy 105.921948 -232.916244)
			(xy 105.96137 -232.884057) (xy 106.005444 -232.858611) (xy 106.05303 -232.840564) (xy 106.102894 -232.830384)
			(xy 106.153746 -232.828335) (xy 106.204267 -232.834469) (xy 106.253151 -232.848629) (xy 106.29913 -232.870446)
			(xy 106.341014 -232.899356) (xy 106.377718 -232.934611) (xy 106.408291 -232.975297) (xy 106.431942 -233.02036)
			(xy 106.448058 -233.068634) (xy 106.456222 -233.118868) (xy 106.456734 -233.144314) (xy 106.764831 -233.144314)
			(xy 106.768926 -233.093586) (xy 106.781105 -233.044172) (xy 106.801053 -232.997352) (xy 106.828254 -232.954338)
			(xy 106.862002 -232.916244) (xy 106.901424 -232.884057) (xy 106.945498 -232.858611) (xy 106.993084 -232.840564)
			(xy 107.042948 -232.830384) (xy 107.0938 -232.828335) (xy 107.144321 -232.834469) (xy 107.193205 -232.848629)
			(xy 107.239184 -232.870446) (xy 107.281068 -232.899356) (xy 107.317772 -232.934611) (xy 107.348345 -232.975297)
			(xy 107.371996 -233.02036) (xy 107.388112 -233.068634) (xy 107.396276 -233.118868) (xy 107.396788 -233.144314)
			(xy 107.715316 -233.144314) (xy 107.719276 -233.09526) (xy 107.731053 -233.047476) (xy 107.750344 -233.0022)
			(xy 107.776647 -232.960604) (xy 107.809282 -232.923767) (xy 107.847403 -232.892642) (xy 107.890024 -232.868035)
			(xy 107.93604 -232.850583) (xy 107.984259 -232.840739) (xy 108.033434 -232.838758) (xy 108.082289 -232.84469)
			(xy 108.12956 -232.858382) (xy 108.174022 -232.87948) (xy 108.214525 -232.907436) (xy 108.250018 -232.941528)
			(xy 108.279583 -232.980872) (xy 108.302454 -233.024449) (xy 108.318038 -233.07113) (xy 108.325933 -233.119707)
			(xy 108.326428 -233.144314) (xy 108.65537 -233.144314) (xy 108.65933 -233.09526) (xy 108.671107 -233.047476)
			(xy 108.690398 -233.0022) (xy 108.716701 -232.960604) (xy 108.749336 -232.923767) (xy 108.787457 -232.892642)
			(xy 108.830078 -232.868035) (xy 108.876094 -232.850583) (xy 108.924313 -232.840739) (xy 108.973488 -232.838758)
			(xy 109.022343 -232.84469) (xy 109.069614 -232.858382) (xy 109.114076 -232.87948) (xy 109.154579 -232.907436)
			(xy 109.190072 -232.941528) (xy 109.219637 -232.980872) (xy 109.242508 -233.024449) (xy 109.258092 -233.07113)
			(xy 109.265987 -233.119707) (xy 109.266482 -233.144314) (xy 109.59517 -233.144314) (xy 109.59913 -233.09526)
			(xy 109.610907 -233.047476) (xy 109.630198 -233.0022) (xy 109.656501 -232.960604) (xy 109.689136 -232.923767)
			(xy 109.727257 -232.892642) (xy 109.769878 -232.868035) (xy 109.815894 -232.850583) (xy 109.864113 -232.840739)
			(xy 109.913288 -232.838758) (xy 109.962143 -232.84469) (xy 110.009414 -232.858382) (xy 110.053876 -232.87948)
			(xy 110.094379 -232.907436) (xy 110.129872 -232.941528) (xy 110.159437 -232.980872) (xy 110.182308 -233.024449)
			(xy 110.197892 -233.07113) (xy 110.205787 -233.119707) (xy 110.206282 -233.144314) (xy 110.205787 -233.168921)
			(xy 110.197892 -233.217498) (xy 110.182308 -233.264179) (xy 110.159437 -233.307756) (xy 110.129872 -233.3471)
			(xy 110.094379 -233.381192) (xy 110.053876 -233.409148) (xy 110.009414 -233.430246) (xy 109.962143 -233.443938)
			(xy 109.913288 -233.44987) (xy 109.864113 -233.447889) (xy 109.815894 -233.438045) (xy 109.769878 -233.420593)
			(xy 109.727257 -233.395986) (xy 109.689136 -233.364861) (xy 109.656501 -233.328024) (xy 109.630198 -233.286428)
			(xy 109.610907 -233.241152) (xy 109.59913 -233.193368) (xy 109.59517 -233.144314) (xy 109.266482 -233.144314)
			(xy 109.265987 -233.168921) (xy 109.258092 -233.217498) (xy 109.242508 -233.264179) (xy 109.219637 -233.307756)
			(xy 109.190072 -233.3471) (xy 109.154579 -233.381192) (xy 109.114076 -233.409148) (xy 109.069614 -233.430246)
			(xy 109.022343 -233.443938) (xy 108.973488 -233.44987) (xy 108.924313 -233.447889) (xy 108.876094 -233.438045)
			(xy 108.830078 -233.420593) (xy 108.787457 -233.395986) (xy 108.749336 -233.364861) (xy 108.716701 -233.328024)
			(xy 108.690398 -233.286428) (xy 108.671107 -233.241152) (xy 108.65933 -233.193368) (xy 108.65537 -233.144314)
			(xy 108.326428 -233.144314) (xy 108.325933 -233.168921) (xy 108.318038 -233.217498) (xy 108.302454 -233.264179)
			(xy 108.279583 -233.307756) (xy 108.250018 -233.3471) (xy 108.214525 -233.381192) (xy 108.174022 -233.409148)
			(xy 108.12956 -233.430246) (xy 108.082289 -233.443938) (xy 108.033434 -233.44987) (xy 107.984259 -233.447889)
			(xy 107.93604 -233.438045) (xy 107.890024 -233.420593) (xy 107.847403 -233.395986) (xy 107.809282 -233.364861)
			(xy 107.776647 -233.328024) (xy 107.750344 -233.286428) (xy 107.731053 -233.241152) (xy 107.719276 -233.193368)
			(xy 107.715316 -233.144314) (xy 107.396788 -233.144314) (xy 107.396276 -233.16976) (xy 107.388112 -233.219994)
			(xy 107.371996 -233.268268) (xy 107.348345 -233.313331) (xy 107.317772 -233.354017) (xy 107.281068 -233.389272)
			(xy 107.239184 -233.418182) (xy 107.193205 -233.439999) (xy 107.144321 -233.454159) (xy 107.0938 -233.460293)
			(xy 107.042948 -233.458244) (xy 106.993084 -233.448064) (xy 106.945498 -233.430017) (xy 106.901424 -233.404571)
			(xy 106.862002 -233.372384) (xy 106.828254 -233.33429) (xy 106.801053 -233.291276) (xy 106.781105 -233.244456)
			(xy 106.768926 -233.195042) (xy 106.764831 -233.144314) (xy 106.456734 -233.144314) (xy 106.456222 -233.16976)
			(xy 106.448058 -233.219994) (xy 106.431942 -233.268268) (xy 106.408291 -233.313331) (xy 106.377718 -233.354017)
			(xy 106.341014 -233.389272) (xy 106.29913 -233.418182) (xy 106.253151 -233.439999) (xy 106.204267 -233.454159)
			(xy 106.153746 -233.460293) (xy 106.102894 -233.458244) (xy 106.05303 -233.448064) (xy 106.005444 -233.430017)
			(xy 105.96137 -233.404571) (xy 105.921948 -233.372384) (xy 105.8882 -233.33429) (xy 105.860999 -233.291276)
			(xy 105.841051 -233.244456) (xy 105.828872 -233.195042) (xy 105.824777 -233.144314) (xy 105.506266 -233.144314)
			(xy 105.505771 -233.168921) (xy 105.497876 -233.217498) (xy 105.482292 -233.264179) (xy 105.459421 -233.307756)
			(xy 105.429856 -233.3471) (xy 105.394363 -233.381192) (xy 105.35386 -233.409148) (xy 105.309398 -233.430246)
			(xy 105.262127 -233.443938) (xy 105.213272 -233.44987) (xy 105.164097 -233.447889) (xy 105.115878 -233.438045)
			(xy 105.069862 -233.420593) (xy 105.027241 -233.395986) (xy 104.98912 -233.364861) (xy 104.956485 -233.328024)
			(xy 104.930182 -233.286428) (xy 104.910891 -233.241152) (xy 104.899114 -233.193368) (xy 104.895154 -233.144314)
			(xy 104.57688 -233.144314) (xy 104.576368 -233.16976) (xy 104.568204 -233.219994) (xy 104.552088 -233.268268)
			(xy 104.528437 -233.313331) (xy 104.497864 -233.354017) (xy 104.46116 -233.389272) (xy 104.419276 -233.418182)
			(xy 104.373297 -233.439999) (xy 104.324413 -233.454159) (xy 104.273892 -233.460293) (xy 104.22304 -233.458244)
			(xy 104.173176 -233.448064) (xy 104.12559 -233.430017) (xy 104.081516 -233.404571) (xy 104.042094 -233.372384)
			(xy 104.008346 -233.33429) (xy 103.981145 -233.291276) (xy 103.961197 -233.244456) (xy 103.949018 -233.195042)
			(xy 103.944923 -233.144314) (xy 103.636826 -233.144314) (xy 103.636314 -233.16976) (xy 103.62815 -233.219994)
			(xy 103.612034 -233.268268) (xy 103.588383 -233.313331) (xy 103.55781 -233.354017) (xy 103.521106 -233.389272)
			(xy 103.479222 -233.418182) (xy 103.433243 -233.439999) (xy 103.384359 -233.454159) (xy 103.333838 -233.460293)
			(xy 103.282986 -233.458244) (xy 103.233122 -233.448064) (xy 103.185536 -233.430017) (xy 103.141462 -233.404571)
			(xy 103.10204 -233.372384) (xy 103.068292 -233.33429) (xy 103.041091 -233.291276) (xy 103.021143 -233.244456)
			(xy 103.008964 -233.195042) (xy 103.004869 -233.144314) (xy 102.686358 -233.144314) (xy 102.685863 -233.168921)
			(xy 102.677968 -233.217498) (xy 102.662384 -233.264179) (xy 102.639513 -233.307756) (xy 102.609948 -233.3471)
			(xy 102.574455 -233.381192) (xy 102.533952 -233.409148) (xy 102.48949 -233.430246) (xy 102.442219 -233.443938)
			(xy 102.393364 -233.44987) (xy 102.344189 -233.447889) (xy 102.29597 -233.438045) (xy 102.249954 -233.420593)
			(xy 102.207333 -233.395986) (xy 102.169212 -233.364861) (xy 102.136577 -233.328024) (xy 102.110274 -233.286428)
			(xy 102.090983 -233.241152) (xy 102.079206 -233.193368) (xy 102.075246 -233.144314) (xy 101.756718 -233.144314)
			(xy 101.756206 -233.16976) (xy 101.748042 -233.219994) (xy 101.731926 -233.268268) (xy 101.708275 -233.313331)
			(xy 101.677702 -233.354017) (xy 101.640998 -233.389272) (xy 101.599114 -233.418182) (xy 101.553135 -233.439999)
			(xy 101.504251 -233.454159) (xy 101.45373 -233.460293) (xy 101.402878 -233.458244) (xy 101.353014 -233.448064)
			(xy 101.305428 -233.430017) (xy 101.261354 -233.404571) (xy 101.221932 -233.372384) (xy 101.188184 -233.33429)
			(xy 101.160983 -233.291276) (xy 101.141035 -233.244456) (xy 101.128856 -233.195042) (xy 101.124761 -233.144314)
			(xy 100.816664 -233.144314) (xy 100.816152 -233.16976) (xy 100.807988 -233.219994) (xy 100.791872 -233.268268)
			(xy 100.768221 -233.313331) (xy 100.737648 -233.354017) (xy 100.700944 -233.389272) (xy 100.65906 -233.418182)
			(xy 100.613081 -233.439999) (xy 100.564197 -233.454159) (xy 100.513676 -233.460293) (xy 100.462824 -233.458244)
			(xy 100.41296 -233.448064) (xy 100.365374 -233.430017) (xy 100.3213 -233.404571) (xy 100.281878 -233.372384)
			(xy 100.24813 -233.33429) (xy 100.220929 -233.291276) (xy 100.200981 -233.244456) (xy 100.188802 -233.195042)
			(xy 100.184707 -233.144314) (xy 99.86645 -233.144314) (xy 99.865955 -233.168921) (xy 99.85806 -233.217498)
			(xy 99.842476 -233.264179) (xy 99.819605 -233.307756) (xy 99.79004 -233.3471) (xy 99.754547 -233.381192)
			(xy 99.714044 -233.409148) (xy 99.669582 -233.430246) (xy 99.622311 -233.443938) (xy 99.573456 -233.44987)
			(xy 99.524281 -233.447889) (xy 99.476062 -233.438045) (xy 99.430046 -233.420593) (xy 99.387425 -233.395986)
			(xy 99.349304 -233.364861) (xy 99.316669 -233.328024) (xy 99.290366 -233.286428) (xy 99.271075 -233.241152)
			(xy 99.259298 -233.193368) (xy 99.255338 -233.144314) (xy 98.93681 -233.144314) (xy 98.936298 -233.16976)
			(xy 98.928134 -233.219994) (xy 98.912018 -233.268268) (xy 98.888367 -233.313331) (xy 98.857794 -233.354017)
			(xy 98.82109 -233.389272) (xy 98.779206 -233.418182) (xy 98.733227 -233.439999) (xy 98.684343 -233.454159)
			(xy 98.633822 -233.460293) (xy 98.58297 -233.458244) (xy 98.533106 -233.448064) (xy 98.48552 -233.430017)
			(xy 98.441446 -233.404571) (xy 98.402024 -233.372384) (xy 98.368276 -233.33429) (xy 98.341075 -233.291276)
			(xy 98.321127 -233.244456) (xy 98.308948 -233.195042) (xy 98.304853 -233.144314) (xy 97.996756 -233.144314)
			(xy 97.996244 -233.16976) (xy 97.98808 -233.219994) (xy 97.971964 -233.268268) (xy 97.948313 -233.313331)
			(xy 97.91774 -233.354017) (xy 97.881036 -233.389272) (xy 97.839152 -233.418182) (xy 97.793173 -233.439999)
			(xy 97.744289 -233.454159) (xy 97.693768 -233.460293) (xy 97.642916 -233.458244) (xy 97.593052 -233.448064)
			(xy 97.545466 -233.430017) (xy 97.501392 -233.404571) (xy 97.46197 -233.372384) (xy 97.428222 -233.33429)
			(xy 97.401021 -233.291276) (xy 97.381073 -233.244456) (xy 97.368894 -233.195042) (xy 97.364799 -233.144314)
			(xy 97.046288 -233.144314) (xy 97.045793 -233.168921) (xy 97.037898 -233.217498) (xy 97.022314 -233.264179)
			(xy 96.999443 -233.307756) (xy 96.969878 -233.3471) (xy 96.934385 -233.381192) (xy 96.893882 -233.409148)
			(xy 96.84942 -233.430246) (xy 96.802149 -233.443938) (xy 96.753294 -233.44987) (xy 96.704119 -233.447889)
			(xy 96.6559 -233.438045) (xy 96.609884 -233.420593) (xy 96.567263 -233.395986) (xy 96.529142 -233.364861)
			(xy 96.496507 -233.328024) (xy 96.470204 -233.286428) (xy 96.450913 -233.241152) (xy 96.439136 -233.193368)
			(xy 96.435176 -233.144314) (xy 96.116648 -233.144314) (xy 96.116136 -233.16976) (xy 96.107972 -233.219994)
			(xy 96.091856 -233.268268) (xy 96.068205 -233.313331) (xy 96.037632 -233.354017) (xy 96.000928 -233.389272)
			(xy 95.959044 -233.418182) (xy 95.913065 -233.439999) (xy 95.864181 -233.454159) (xy 95.81366 -233.460293)
			(xy 95.762808 -233.458244) (xy 95.712944 -233.448064) (xy 95.665358 -233.430017) (xy 95.621284 -233.404571)
			(xy 95.581862 -233.372384) (xy 95.548114 -233.33429) (xy 95.520913 -233.291276) (xy 95.500965 -233.244456)
			(xy 95.488786 -233.195042) (xy 95.484691 -233.144314) (xy 95.166434 -233.144314) (xy 95.165939 -233.168921)
			(xy 95.158044 -233.217498) (xy 95.14246 -233.264179) (xy 95.119589 -233.307756) (xy 95.090024 -233.3471)
			(xy 95.054531 -233.381192) (xy 95.014028 -233.409148) (xy 94.969566 -233.430246) (xy 94.922295 -233.443938)
			(xy 94.87344 -233.44987) (xy 94.824265 -233.447889) (xy 94.776046 -233.438045) (xy 94.73003 -233.420593)
			(xy 94.687409 -233.395986) (xy 94.649288 -233.364861) (xy 94.616653 -233.328024) (xy 94.59035 -233.286428)
			(xy 94.571059 -233.241152) (xy 94.559282 -233.193368) (xy 94.555322 -233.144314) (xy 94.236794 -233.144314)
			(xy 94.236282 -233.16976) (xy 94.228118 -233.219994) (xy 94.212002 -233.268268) (xy 94.188351 -233.313331)
			(xy 94.157778 -233.354017) (xy 94.121074 -233.389272) (xy 94.07919 -233.418182) (xy 94.033211 -233.439999)
			(xy 93.984327 -233.454159) (xy 93.933806 -233.460293) (xy 93.882954 -233.458244) (xy 93.83309 -233.448064)
			(xy 93.785504 -233.430017) (xy 93.74143 -233.404571) (xy 93.702008 -233.372384) (xy 93.66826 -233.33429)
			(xy 93.641059 -233.291276) (xy 93.621111 -233.244456) (xy 93.608932 -233.195042) (xy 93.604837 -233.144314)
			(xy 93.286326 -233.144314) (xy 93.285831 -233.168921) (xy 93.277936 -233.217498) (xy 93.262352 -233.264179)
			(xy 93.239481 -233.307756) (xy 93.209916 -233.3471) (xy 93.174423 -233.381192) (xy 93.13392 -233.409148)
			(xy 93.089458 -233.430246) (xy 93.042187 -233.443938) (xy 92.993332 -233.44987) (xy 92.944157 -233.447889)
			(xy 92.895938 -233.438045) (xy 92.849922 -233.420593) (xy 92.807301 -233.395986) (xy 92.76918 -233.364861)
			(xy 92.736545 -233.328024) (xy 92.710242 -233.286428) (xy 92.690951 -233.241152) (xy 92.679174 -233.193368)
			(xy 92.675214 -233.144314) (xy 92.356686 -233.144314) (xy 92.356174 -233.16976) (xy 92.34801 -233.219994)
			(xy 92.331894 -233.268268) (xy 92.308243 -233.313331) (xy 92.27767 -233.354017) (xy 92.240966 -233.389272)
			(xy 92.199082 -233.418182) (xy 92.153103 -233.439999) (xy 92.104219 -233.454159) (xy 92.053698 -233.460293)
			(xy 92.002846 -233.458244) (xy 91.952982 -233.448064) (xy 91.905396 -233.430017) (xy 91.861322 -233.404571)
			(xy 91.8219 -233.372384) (xy 91.788152 -233.33429) (xy 91.760951 -233.291276) (xy 91.741003 -233.244456)
			(xy 91.728824 -233.195042) (xy 91.724729 -233.144314) (xy 91.416632 -233.144314) (xy 91.41612 -233.16976)
			(xy 91.407956 -233.219994) (xy 91.39184 -233.268268) (xy 91.368189 -233.313331) (xy 91.337616 -233.354017)
			(xy 91.300912 -233.389272) (xy 91.259028 -233.418182) (xy 91.213049 -233.439999) (xy 91.164165 -233.454159)
			(xy 91.113644 -233.460293) (xy 91.062792 -233.458244) (xy 91.012928 -233.448064) (xy 90.965342 -233.430017)
			(xy 90.921268 -233.404571) (xy 90.881846 -233.372384) (xy 90.848098 -233.33429) (xy 90.820897 -233.291276)
			(xy 90.800949 -233.244456) (xy 90.78877 -233.195042) (xy 90.784675 -233.144314) (xy 90.466916 -233.144314)
			(xy 90.462746 -233.194635) (xy 90.450348 -233.243597) (xy 90.43006 -233.28985) (xy 90.402435 -233.332133)
			(xy 90.368228 -233.369293) (xy 90.328371 -233.400316) (xy 90.283952 -233.424356) (xy 90.236182 -233.440757)
			(xy 90.186364 -233.449072) (xy 90.16111 -233.449622) (xy 90.13724 -233.449161) (xy 90.090082 -233.441727)
			(xy 90.044657 -233.427039) (xy 90.002074 -233.405456) (xy 89.963372 -233.377505) (xy 89.929496 -233.343867)
			(xy 89.914984 -233.324908) (xy 89.91092 -233.31932) (xy 89.900506 -233.311192) (xy 89.893902 -233.308398)
			(xy 89.887618 -233.305883) (xy 89.874226 -233.303963) (xy 89.867486 -233.304588) (xy 89.765378 -233.317796)
			(xy 89.743534 -233.334814) (xy 89.738454 -233.347768) (xy 89.729853 -233.368982) (xy 89.709637 -233.410057)
			(xy 89.698068 -233.42981) (xy 89.694512 -233.435652) (xy 89.690956 -233.44886) (xy 89.690956 -233.620818)
			(xy 89.715594 -233.649266) (xy 89.73439 -233.65206) (xy 89.758319 -233.655966) (xy 89.804618 -233.670352)
			(xy 89.848061 -233.691875) (xy 89.887557 -233.719992) (xy 89.922114 -233.753997) (xy 89.950864 -233.793036)
			(xy 89.973082 -233.836127) (xy 89.988212 -233.882188) (xy 89.995873 -233.930062) (xy 89.995873 -233.95432)
			(xy 90.314775 -233.95432) (xy 90.31887 -233.903592) (xy 90.331049 -233.854178) (xy 90.350997 -233.807358)
			(xy 90.378198 -233.764344) (xy 90.411946 -233.72625) (xy 90.451368 -233.694063) (xy 90.495442 -233.668617)
			(xy 90.543028 -233.65057) (xy 90.592892 -233.64039) (xy 90.643744 -233.638341) (xy 90.694265 -233.644475)
			(xy 90.743149 -233.658635) (xy 90.789128 -233.680452) (xy 90.831012 -233.709362) (xy 90.867716 -233.744617)
			(xy 90.898289 -233.785303) (xy 90.92194 -233.830366) (xy 90.938056 -233.87864) (xy 90.94622 -233.928874)
			(xy 90.946732 -233.95432) (xy 91.26526 -233.95432) (xy 91.26922 -233.905266) (xy 91.280997 -233.857482)
			(xy 91.300288 -233.812206) (xy 91.326591 -233.77061) (xy 91.359226 -233.733773) (xy 91.397347 -233.702648)
			(xy 91.439968 -233.678041) (xy 91.485984 -233.660589) (xy 91.534203 -233.650745) (xy 91.583378 -233.648764)
			(xy 91.632233 -233.654696) (xy 91.679504 -233.668388) (xy 91.723966 -233.689486) (xy 91.764469 -233.717442)
			(xy 91.799962 -233.751534) (xy 91.829527 -233.790878) (xy 91.852398 -233.834455) (xy 91.867982 -233.881136)
			(xy 91.875877 -233.929713) (xy 91.876372 -233.95432) (xy 92.194883 -233.95432) (xy 92.198978 -233.903592)
			(xy 92.211157 -233.854178) (xy 92.231105 -233.807358) (xy 92.258306 -233.764344) (xy 92.292054 -233.72625)
			(xy 92.331476 -233.694063) (xy 92.37555 -233.668617) (xy 92.423136 -233.65057) (xy 92.473 -233.64039)
			(xy 92.523852 -233.638341) (xy 92.574373 -233.644475) (xy 92.623257 -233.658635) (xy 92.669236 -233.680452)
			(xy 92.71112 -233.709362) (xy 92.747824 -233.744617) (xy 92.778397 -233.785303) (xy 92.802048 -233.830366)
			(xy 92.818164 -233.87864) (xy 92.826328 -233.928874) (xy 92.82684 -233.95432) (xy 93.145114 -233.95432)
			(xy 93.149074 -233.905266) (xy 93.160851 -233.857482) (xy 93.180142 -233.812206) (xy 93.206445 -233.77061)
			(xy 93.23908 -233.733773) (xy 93.277201 -233.702648) (xy 93.319822 -233.678041) (xy 93.365838 -233.660589)
			(xy 93.414057 -233.650745) (xy 93.463232 -233.648764) (xy 93.512087 -233.654696) (xy 93.559358 -233.668388)
			(xy 93.60382 -233.689486) (xy 93.644323 -233.717442) (xy 93.679816 -233.751534) (xy 93.709381 -233.790878)
			(xy 93.732252 -233.834455) (xy 93.747836 -233.881136) (xy 93.755731 -233.929713) (xy 93.756226 -233.95432)
			(xy 94.074737 -233.95432) (xy 94.078832 -233.903592) (xy 94.091011 -233.854178) (xy 94.110959 -233.807358)
			(xy 94.13816 -233.764344) (xy 94.171908 -233.72625) (xy 94.21133 -233.694063) (xy 94.255404 -233.668617)
			(xy 94.30299 -233.65057) (xy 94.352854 -233.64039) (xy 94.403706 -233.638341) (xy 94.454227 -233.644475)
			(xy 94.503111 -233.658635) (xy 94.54909 -233.680452) (xy 94.590974 -233.709362) (xy 94.627678 -233.744617)
			(xy 94.658251 -233.785303) (xy 94.681902 -233.830366) (xy 94.698018 -233.87864) (xy 94.706182 -233.928874)
			(xy 94.706694 -233.95432) (xy 95.014791 -233.95432) (xy 95.018886 -233.903592) (xy 95.031065 -233.854178)
			(xy 95.051013 -233.807358) (xy 95.078214 -233.764344) (xy 95.111962 -233.72625) (xy 95.151384 -233.694063)
			(xy 95.195458 -233.668617) (xy 95.243044 -233.65057) (xy 95.292908 -233.64039) (xy 95.34376 -233.638341)
			(xy 95.394281 -233.644475) (xy 95.443165 -233.658635) (xy 95.489144 -233.680452) (xy 95.531028 -233.709362)
			(xy 95.567732 -233.744617) (xy 95.598305 -233.785303) (xy 95.621956 -233.830366) (xy 95.638072 -233.87864)
			(xy 95.646236 -233.928874) (xy 95.646748 -233.95432) (xy 95.965276 -233.95432) (xy 95.969236 -233.905266)
			(xy 95.981013 -233.857482) (xy 96.000304 -233.812206) (xy 96.026607 -233.77061) (xy 96.059242 -233.733773)
			(xy 96.097363 -233.702648) (xy 96.139984 -233.678041) (xy 96.186 -233.660589) (xy 96.234219 -233.650745)
			(xy 96.283394 -233.648764) (xy 96.332249 -233.654696) (xy 96.37952 -233.668388) (xy 96.423982 -233.689486)
			(xy 96.464485 -233.717442) (xy 96.499978 -233.751534) (xy 96.529543 -233.790878) (xy 96.552414 -233.834455)
			(xy 96.567998 -233.881136) (xy 96.575893 -233.929713) (xy 96.576388 -233.95432) (xy 98.785184 -233.95432)
			(xy 98.789144 -233.905266) (xy 98.800921 -233.857482) (xy 98.820212 -233.812206) (xy 98.846515 -233.77061)
			(xy 98.87915 -233.733773) (xy 98.917271 -233.702648) (xy 98.959892 -233.678041) (xy 99.005908 -233.660589)
			(xy 99.054127 -233.650745) (xy 99.103302 -233.648764) (xy 99.152157 -233.654696) (xy 99.199428 -233.668388)
			(xy 99.24389 -233.689486) (xy 99.284393 -233.717442) (xy 99.319886 -233.751534) (xy 99.349451 -233.790878)
			(xy 99.372322 -233.834455) (xy 99.387906 -233.881136) (xy 99.395801 -233.929713) (xy 99.396296 -233.95432)
			(xy 101.605346 -233.95432) (xy 101.609306 -233.905266) (xy 101.621083 -233.857482) (xy 101.640374 -233.812206)
			(xy 101.666677 -233.77061) (xy 101.699312 -233.733773) (xy 101.737433 -233.702648) (xy 101.780054 -233.678041)
			(xy 101.82607 -233.660589) (xy 101.874289 -233.650745) (xy 101.923464 -233.648764) (xy 101.972319 -233.654696)
			(xy 102.01959 -233.668388) (xy 102.064052 -233.689486) (xy 102.104555 -233.717442) (xy 102.140048 -233.751534)
			(xy 102.169613 -233.790878) (xy 102.192484 -233.834455) (xy 102.208068 -233.881136) (xy 102.215963 -233.929713)
			(xy 102.216458 -233.95432) (xy 104.425254 -233.95432) (xy 104.429214 -233.905266) (xy 104.440991 -233.857482)
			(xy 104.460282 -233.812206) (xy 104.486585 -233.77061) (xy 104.51922 -233.733773) (xy 104.557341 -233.702648)
			(xy 104.599962 -233.678041) (xy 104.645978 -233.660589) (xy 104.694197 -233.650745) (xy 104.743372 -233.648764)
			(xy 104.792227 -233.654696) (xy 104.839498 -233.668388) (xy 104.88396 -233.689486) (xy 104.924463 -233.717442)
			(xy 104.959956 -233.751534) (xy 104.989521 -233.790878) (xy 105.012392 -233.834455) (xy 105.027976 -233.881136)
			(xy 105.035871 -233.929713) (xy 105.036366 -233.95432) (xy 107.245162 -233.95432) (xy 107.249122 -233.905266)
			(xy 107.260899 -233.857482) (xy 107.28019 -233.812206) (xy 107.306493 -233.77061) (xy 107.339128 -233.733773)
			(xy 107.377249 -233.702648) (xy 107.41987 -233.678041) (xy 107.465886 -233.660589) (xy 107.514105 -233.650745)
			(xy 107.56328 -233.648764) (xy 107.612135 -233.654696) (xy 107.659406 -233.668388) (xy 107.703868 -233.689486)
			(xy 107.744371 -233.717442) (xy 107.779864 -233.751534) (xy 107.809429 -233.790878) (xy 107.8323 -233.834455)
			(xy 107.847884 -233.881136) (xy 107.855779 -233.929713) (xy 107.856274 -233.95432) (xy 108.174785 -233.95432)
			(xy 108.17888 -233.903592) (xy 108.191059 -233.854178) (xy 108.211007 -233.807358) (xy 108.238208 -233.764344)
			(xy 108.271956 -233.72625) (xy 108.311378 -233.694063) (xy 108.355452 -233.668617) (xy 108.403038 -233.65057)
			(xy 108.452902 -233.64039) (xy 108.503754 -233.638341) (xy 108.554275 -233.644475) (xy 108.603159 -233.658635)
			(xy 108.649138 -233.680452) (xy 108.691022 -233.709362) (xy 108.727726 -233.744617) (xy 108.758299 -233.785303)
			(xy 108.78195 -233.830366) (xy 108.798066 -233.87864) (xy 108.80623 -233.928874) (xy 108.806742 -233.95432)
			(xy 109.114839 -233.95432) (xy 109.118934 -233.903592) (xy 109.131113 -233.854178) (xy 109.151061 -233.807358)
			(xy 109.178262 -233.764344) (xy 109.21201 -233.72625) (xy 109.251432 -233.694063) (xy 109.295506 -233.668617)
			(xy 109.343092 -233.65057) (xy 109.392956 -233.64039) (xy 109.443808 -233.638341) (xy 109.494329 -233.644475)
			(xy 109.543213 -233.658635) (xy 109.589192 -233.680452) (xy 109.631076 -233.709362) (xy 109.66778 -233.744617)
			(xy 109.698353 -233.785303) (xy 109.722004 -233.830366) (xy 109.73812 -233.87864) (xy 109.746284 -233.928874)
			(xy 109.746796 -233.95432) (xy 110.065324 -233.95432) (xy 110.069284 -233.905266) (xy 110.081061 -233.857482)
			(xy 110.100352 -233.812206) (xy 110.126655 -233.77061) (xy 110.15929 -233.733773) (xy 110.197411 -233.702648)
			(xy 110.240032 -233.678041) (xy 110.286048 -233.660589) (xy 110.334267 -233.650745) (xy 110.383442 -233.648764)
			(xy 110.432297 -233.654696) (xy 110.479568 -233.668388) (xy 110.52403 -233.689486) (xy 110.564533 -233.717442)
			(xy 110.600026 -233.751534) (xy 110.629591 -233.790878) (xy 110.652462 -233.834455) (xy 110.668046 -233.881136)
			(xy 110.675941 -233.929713) (xy 110.676436 -233.95432) (xy 110.675941 -233.978927) (xy 110.668046 -234.027504)
			(xy 110.652462 -234.074185) (xy 110.629591 -234.117762) (xy 110.600026 -234.157106) (xy 110.564533 -234.191198)
			(xy 110.52403 -234.219154) (xy 110.479568 -234.240252) (xy 110.432297 -234.253944) (xy 110.383442 -234.259876)
			(xy 110.334267 -234.257895) (xy 110.286048 -234.248051) (xy 110.240032 -234.230599) (xy 110.197411 -234.205992)
			(xy 110.15929 -234.174867) (xy 110.126655 -234.13803) (xy 110.100352 -234.096434) (xy 110.081061 -234.051158)
			(xy 110.069284 -234.003374) (xy 110.065324 -233.95432) (xy 109.746796 -233.95432) (xy 109.746284 -233.979766)
			(xy 109.73812 -234.03) (xy 109.722004 -234.078274) (xy 109.698353 -234.123337) (xy 109.66778 -234.164023)
			(xy 109.631076 -234.199278) (xy 109.589192 -234.228188) (xy 109.543213 -234.250005) (xy 109.494329 -234.264165)
			(xy 109.443808 -234.270299) (xy 109.392956 -234.26825) (xy 109.343092 -234.25807) (xy 109.295506 -234.240023)
			(xy 109.251432 -234.214577) (xy 109.21201 -234.18239) (xy 109.178262 -234.144296) (xy 109.151061 -234.101282)
			(xy 109.131113 -234.054462) (xy 109.118934 -234.005048) (xy 109.114839 -233.95432) (xy 108.806742 -233.95432)
			(xy 108.80623 -233.979766) (xy 108.798066 -234.03) (xy 108.78195 -234.078274) (xy 108.758299 -234.123337)
			(xy 108.727726 -234.164023) (xy 108.691022 -234.199278) (xy 108.649138 -234.228188) (xy 108.603159 -234.250005)
			(xy 108.554275 -234.264165) (xy 108.503754 -234.270299) (xy 108.452902 -234.26825) (xy 108.403038 -234.25807)
			(xy 108.355452 -234.240023) (xy 108.311378 -234.214577) (xy 108.271956 -234.18239) (xy 108.238208 -234.144296)
			(xy 108.211007 -234.101282) (xy 108.191059 -234.054462) (xy 108.17888 -234.005048) (xy 108.174785 -233.95432)
			(xy 107.856274 -233.95432) (xy 107.855779 -233.978927) (xy 107.847884 -234.027504) (xy 107.8323 -234.074185)
			(xy 107.809429 -234.117762) (xy 107.779864 -234.157106) (xy 107.744371 -234.191198) (xy 107.703868 -234.219154)
			(xy 107.659406 -234.240252) (xy 107.612135 -234.253944) (xy 107.56328 -234.259876) (xy 107.514105 -234.257895)
			(xy 107.465886 -234.248051) (xy 107.41987 -234.230599) (xy 107.377249 -234.205992) (xy 107.339128 -234.174867)
			(xy 107.306493 -234.13803) (xy 107.28019 -234.096434) (xy 107.260899 -234.051158) (xy 107.249122 -234.003374)
			(xy 107.245162 -233.95432) (xy 105.036366 -233.95432) (xy 105.035871 -233.978927) (xy 105.027976 -234.027504)
			(xy 105.012392 -234.074185) (xy 104.989521 -234.117762) (xy 104.959956 -234.157106) (xy 104.924463 -234.191198)
			(xy 104.88396 -234.219154) (xy 104.839498 -234.240252) (xy 104.792227 -234.253944) (xy 104.743372 -234.259876)
			(xy 104.694197 -234.257895) (xy 104.645978 -234.248051) (xy 104.599962 -234.230599) (xy 104.557341 -234.205992)
			(xy 104.51922 -234.174867) (xy 104.486585 -234.13803) (xy 104.460282 -234.096434) (xy 104.440991 -234.051158)
			(xy 104.429214 -234.003374) (xy 104.425254 -233.95432) (xy 102.216458 -233.95432) (xy 102.215963 -233.978927)
			(xy 102.208068 -234.027504) (xy 102.192484 -234.074185) (xy 102.169613 -234.117762) (xy 102.140048 -234.157106)
			(xy 102.104555 -234.191198) (xy 102.064052 -234.219154) (xy 102.01959 -234.240252) (xy 101.972319 -234.253944)
			(xy 101.923464 -234.259876) (xy 101.874289 -234.257895) (xy 101.82607 -234.248051) (xy 101.780054 -234.230599)
			(xy 101.737433 -234.205992) (xy 101.699312 -234.174867) (xy 101.666677 -234.13803) (xy 101.640374 -234.096434)
			(xy 101.621083 -234.051158) (xy 101.609306 -234.003374) (xy 101.605346 -233.95432) (xy 99.396296 -233.95432)
			(xy 99.395801 -233.978927) (xy 99.387906 -234.027504) (xy 99.372322 -234.074185) (xy 99.349451 -234.117762)
			(xy 99.319886 -234.157106) (xy 99.284393 -234.191198) (xy 99.24389 -234.219154) (xy 99.199428 -234.240252)
			(xy 99.152157 -234.253944) (xy 99.103302 -234.259876) (xy 99.054127 -234.257895) (xy 99.005908 -234.248051)
			(xy 98.959892 -234.230599) (xy 98.917271 -234.205992) (xy 98.87915 -234.174867) (xy 98.846515 -234.13803)
			(xy 98.820212 -234.096434) (xy 98.800921 -234.051158) (xy 98.789144 -234.003374) (xy 98.785184 -233.95432)
			(xy 96.576388 -233.95432) (xy 96.575893 -233.978927) (xy 96.567998 -234.027504) (xy 96.552414 -234.074185)
			(xy 96.529543 -234.117762) (xy 96.499978 -234.157106) (xy 96.464485 -234.191198) (xy 96.423982 -234.219154)
			(xy 96.37952 -234.240252) (xy 96.332249 -234.253944) (xy 96.283394 -234.259876) (xy 96.234219 -234.257895)
			(xy 96.186 -234.248051) (xy 96.139984 -234.230599) (xy 96.097363 -234.205992) (xy 96.059242 -234.174867)
			(xy 96.026607 -234.13803) (xy 96.000304 -234.096434) (xy 95.981013 -234.051158) (xy 95.969236 -234.003374)
			(xy 95.965276 -233.95432) (xy 95.646748 -233.95432) (xy 95.646236 -233.979766) (xy 95.638072 -234.03)
			(xy 95.621956 -234.078274) (xy 95.598305 -234.123337) (xy 95.567732 -234.164023) (xy 95.531028 -234.199278)
			(xy 95.489144 -234.228188) (xy 95.443165 -234.250005) (xy 95.394281 -234.264165) (xy 95.34376 -234.270299)
			(xy 95.292908 -234.26825) (xy 95.243044 -234.25807) (xy 95.195458 -234.240023) (xy 95.151384 -234.214577)
			(xy 95.111962 -234.18239) (xy 95.078214 -234.144296) (xy 95.051013 -234.101282) (xy 95.031065 -234.054462)
			(xy 95.018886 -234.005048) (xy 95.014791 -233.95432) (xy 94.706694 -233.95432) (xy 94.706182 -233.979766)
			(xy 94.698018 -234.03) (xy 94.681902 -234.078274) (xy 94.658251 -234.123337) (xy 94.627678 -234.164023)
			(xy 94.590974 -234.199278) (xy 94.54909 -234.228188) (xy 94.503111 -234.250005) (xy 94.454227 -234.264165)
			(xy 94.403706 -234.270299) (xy 94.352854 -234.26825) (xy 94.30299 -234.25807) (xy 94.255404 -234.240023)
			(xy 94.21133 -234.214577) (xy 94.171908 -234.18239) (xy 94.13816 -234.144296) (xy 94.110959 -234.101282)
			(xy 94.091011 -234.054462) (xy 94.078832 -234.005048) (xy 94.074737 -233.95432) (xy 93.756226 -233.95432)
			(xy 93.755731 -233.978927) (xy 93.747836 -234.027504) (xy 93.732252 -234.074185) (xy 93.709381 -234.117762)
			(xy 93.679816 -234.157106) (xy 93.644323 -234.191198) (xy 93.60382 -234.219154) (xy 93.559358 -234.240252)
			(xy 93.512087 -234.253944) (xy 93.463232 -234.259876) (xy 93.414057 -234.257895) (xy 93.365838 -234.248051)
			(xy 93.319822 -234.230599) (xy 93.277201 -234.205992) (xy 93.23908 -234.174867) (xy 93.206445 -234.13803)
			(xy 93.180142 -234.096434) (xy 93.160851 -234.051158) (xy 93.149074 -234.003374) (xy 93.145114 -233.95432)
			(xy 92.82684 -233.95432) (xy 92.826328 -233.979766) (xy 92.818164 -234.03) (xy 92.802048 -234.078274)
			(xy 92.778397 -234.123337) (xy 92.747824 -234.164023) (xy 92.71112 -234.199278) (xy 92.669236 -234.228188)
			(xy 92.623257 -234.250005) (xy 92.574373 -234.264165) (xy 92.523852 -234.270299) (xy 92.473 -234.26825)
			(xy 92.423136 -234.25807) (xy 92.37555 -234.240023) (xy 92.331476 -234.214577) (xy 92.292054 -234.18239)
			(xy 92.258306 -234.144296) (xy 92.231105 -234.101282) (xy 92.211157 -234.054462) (xy 92.198978 -234.005048)
			(xy 92.194883 -233.95432) (xy 91.876372 -233.95432) (xy 91.875877 -233.978927) (xy 91.867982 -234.027504)
			(xy 91.852398 -234.074185) (xy 91.829527 -234.117762) (xy 91.799962 -234.157106) (xy 91.764469 -234.191198)
			(xy 91.723966 -234.219154) (xy 91.679504 -234.240252) (xy 91.632233 -234.253944) (xy 91.583378 -234.259876)
			(xy 91.534203 -234.257895) (xy 91.485984 -234.248051) (xy 91.439968 -234.230599) (xy 91.397347 -234.205992)
			(xy 91.359226 -234.174867) (xy 91.326591 -234.13803) (xy 91.300288 -234.096434) (xy 91.280997 -234.051158)
			(xy 91.26922 -234.003374) (xy 91.26526 -233.95432) (xy 90.946732 -233.95432) (xy 90.94622 -233.979766)
			(xy 90.938056 -234.03) (xy 90.92194 -234.078274) (xy 90.898289 -234.123337) (xy 90.867716 -234.164023)
			(xy 90.831012 -234.199278) (xy 90.789128 -234.228188) (xy 90.743149 -234.250005) (xy 90.694265 -234.264165)
			(xy 90.643744 -234.270299) (xy 90.592892 -234.26825) (xy 90.543028 -234.25807) (xy 90.495442 -234.240023)
			(xy 90.451368 -234.214577) (xy 90.411946 -234.18239) (xy 90.378198 -234.144296) (xy 90.350997 -234.101282)
			(xy 90.331049 -234.054462) (xy 90.31887 -234.005048) (xy 90.314775 -233.95432) (xy 89.995873 -233.95432)
			(xy 89.995873 -233.978544) (xy 89.988211 -234.026417) (xy 89.97308 -234.072478) (xy 89.950861 -234.115569)
			(xy 89.922111 -234.154607) (xy 89.887553 -234.188612) (xy 89.848056 -234.216728) (xy 89.804612 -234.23825)
			(xy 89.758313 -234.252635) (xy 89.73439 -234.25658) (xy 89.715594 -234.259374) (xy 89.690956 -234.287822)
			(xy 89.690956 -234.459018) (xy 89.691219 -234.465906) (xy 89.694949 -234.47917) (xy 89.698322 -234.48518)
			(xy 89.699338 -234.486958) (xy 89.707629 -234.501532) (xy 89.722626 -234.531525) (xy 89.72931 -234.546902)
			(xy 89.736168 -234.563412) (xy 89.741248 -234.57662) (xy 89.762838 -234.593638) (xy 89.879424 -234.608624)
			(xy 89.905078 -234.597448) (xy 89.913206 -234.586018) (xy 89.927671 -234.566719) (xy 89.961659 -234.532502)
			(xy 90.000599 -234.504048) (xy 90.043524 -234.482061) (xy 90.089369 -234.467089) (xy 90.136996 -234.459501)
			(xy 90.16111 -234.459018) (xy 90.186363 -234.45954) (xy 90.236179 -234.467855) (xy 90.283947 -234.484255)
			(xy 90.328365 -234.508294) (xy 90.36822 -234.539316) (xy 90.402426 -234.576474) (xy 90.430049 -234.618756)
			(xy 90.450336 -234.665007) (xy 90.462734 -234.713967) (xy 90.466905 -234.7643) (xy 90.466903 -234.764326)
			(xy 90.784675 -234.764326) (xy 90.78877 -234.713598) (xy 90.800949 -234.664184) (xy 90.820897 -234.617364)
			(xy 90.848098 -234.57435) (xy 90.881846 -234.536256) (xy 90.921268 -234.504069) (xy 90.965342 -234.478623)
			(xy 91.012928 -234.460576) (xy 91.062792 -234.450396) (xy 91.113644 -234.448347) (xy 91.164165 -234.454481)
			(xy 91.213049 -234.468641) (xy 91.259028 -234.490458) (xy 91.300912 -234.519368) (xy 91.337616 -234.554623)
			(xy 91.368189 -234.595309) (xy 91.39184 -234.640372) (xy 91.407956 -234.688646) (xy 91.41612 -234.73888)
			(xy 91.416632 -234.764326) (xy 91.724729 -234.764326) (xy 91.728824 -234.713598) (xy 91.741003 -234.664184)
			(xy 91.760951 -234.617364) (xy 91.788152 -234.57435) (xy 91.8219 -234.536256) (xy 91.861322 -234.504069)
			(xy 91.905396 -234.478623) (xy 91.952982 -234.460576) (xy 92.002846 -234.450396) (xy 92.053698 -234.448347)
			(xy 92.104219 -234.454481) (xy 92.153103 -234.468641) (xy 92.199082 -234.490458) (xy 92.240966 -234.519368)
			(xy 92.27767 -234.554623) (xy 92.308243 -234.595309) (xy 92.331894 -234.640372) (xy 92.34801 -234.688646)
			(xy 92.356174 -234.73888) (xy 92.356686 -234.764326) (xy 92.675214 -234.764326) (xy 92.679174 -234.715272)
			(xy 92.690951 -234.667488) (xy 92.710242 -234.622212) (xy 92.736545 -234.580616) (xy 92.76918 -234.543779)
			(xy 92.807301 -234.512654) (xy 92.849922 -234.488047) (xy 92.895938 -234.470595) (xy 92.944157 -234.460751)
			(xy 92.993332 -234.45877) (xy 93.042187 -234.464702) (xy 93.089458 -234.478394) (xy 93.13392 -234.499492)
			(xy 93.174423 -234.527448) (xy 93.209916 -234.56154) (xy 93.239481 -234.600884) (xy 93.262352 -234.644461)
			(xy 93.277936 -234.691142) (xy 93.285831 -234.739719) (xy 93.286326 -234.764326) (xy 93.604837 -234.764326)
			(xy 93.608932 -234.713598) (xy 93.621111 -234.664184) (xy 93.641059 -234.617364) (xy 93.66826 -234.57435)
			(xy 93.702008 -234.536256) (xy 93.74143 -234.504069) (xy 93.785504 -234.478623) (xy 93.83309 -234.460576)
			(xy 93.882954 -234.450396) (xy 93.933806 -234.448347) (xy 93.984327 -234.454481) (xy 94.033211 -234.468641)
			(xy 94.07919 -234.490458) (xy 94.121074 -234.519368) (xy 94.157778 -234.554623) (xy 94.188351 -234.595309)
			(xy 94.212002 -234.640372) (xy 94.228118 -234.688646) (xy 94.236282 -234.73888) (xy 94.236794 -234.764326)
			(xy 94.555322 -234.764326) (xy 94.559282 -234.715272) (xy 94.571059 -234.667488) (xy 94.59035 -234.622212)
			(xy 94.616653 -234.580616) (xy 94.649288 -234.543779) (xy 94.687409 -234.512654) (xy 94.73003 -234.488047)
			(xy 94.776046 -234.470595) (xy 94.824265 -234.460751) (xy 94.87344 -234.45877) (xy 94.922295 -234.464702)
			(xy 94.969566 -234.478394) (xy 95.014028 -234.499492) (xy 95.054531 -234.527448) (xy 95.090024 -234.56154)
			(xy 95.119589 -234.600884) (xy 95.14246 -234.644461) (xy 95.158044 -234.691142) (xy 95.165939 -234.739719)
			(xy 95.166434 -234.764326) (xy 95.484691 -234.764326) (xy 95.488786 -234.713598) (xy 95.500965 -234.664184)
			(xy 95.520913 -234.617364) (xy 95.548114 -234.57435) (xy 95.581862 -234.536256) (xy 95.621284 -234.504069)
			(xy 95.665358 -234.478623) (xy 95.712944 -234.460576) (xy 95.762808 -234.450396) (xy 95.81366 -234.448347)
			(xy 95.864181 -234.454481) (xy 95.913065 -234.468641) (xy 95.959044 -234.490458) (xy 96.000928 -234.519368)
			(xy 96.037632 -234.554623) (xy 96.068205 -234.595309) (xy 96.091856 -234.640372) (xy 96.107972 -234.688646)
			(xy 96.116136 -234.73888) (xy 96.116648 -234.764326) (xy 96.435176 -234.764326) (xy 96.439136 -234.715272)
			(xy 96.450913 -234.667488) (xy 96.470204 -234.622212) (xy 96.496507 -234.580616) (xy 96.529142 -234.543779)
			(xy 96.567263 -234.512654) (xy 96.609884 -234.488047) (xy 96.6559 -234.470595) (xy 96.704119 -234.460751)
			(xy 96.753294 -234.45877) (xy 96.802149 -234.464702) (xy 96.84942 -234.478394) (xy 96.893882 -234.499492)
			(xy 96.934385 -234.527448) (xy 96.969878 -234.56154) (xy 96.999443 -234.600884) (xy 97.022314 -234.644461)
			(xy 97.037898 -234.691142) (xy 97.045793 -234.739719) (xy 97.046288 -234.764326) (xy 97.364799 -234.764326)
			(xy 97.368894 -234.713598) (xy 97.381073 -234.664184) (xy 97.401021 -234.617364) (xy 97.428222 -234.57435)
			(xy 97.46197 -234.536256) (xy 97.501392 -234.504069) (xy 97.545466 -234.478623) (xy 97.593052 -234.460576)
			(xy 97.642916 -234.450396) (xy 97.693768 -234.448347) (xy 97.744289 -234.454481) (xy 97.793173 -234.468641)
			(xy 97.839152 -234.490458) (xy 97.881036 -234.519368) (xy 97.91774 -234.554623) (xy 97.948313 -234.595309)
			(xy 97.971964 -234.640372) (xy 97.98808 -234.688646) (xy 97.996244 -234.73888) (xy 97.996756 -234.764326)
			(xy 98.304853 -234.764326) (xy 98.308948 -234.713598) (xy 98.321127 -234.664184) (xy 98.341075 -234.617364)
			(xy 98.368276 -234.57435) (xy 98.402024 -234.536256) (xy 98.441446 -234.504069) (xy 98.48552 -234.478623)
			(xy 98.533106 -234.460576) (xy 98.58297 -234.450396) (xy 98.633822 -234.448347) (xy 98.684343 -234.454481)
			(xy 98.733227 -234.468641) (xy 98.779206 -234.490458) (xy 98.82109 -234.519368) (xy 98.857794 -234.554623)
			(xy 98.888367 -234.595309) (xy 98.912018 -234.640372) (xy 98.928134 -234.688646) (xy 98.936298 -234.73888)
			(xy 98.93681 -234.764326) (xy 99.255338 -234.764326) (xy 99.259298 -234.715272) (xy 99.271075 -234.667488)
			(xy 99.290366 -234.622212) (xy 99.316669 -234.580616) (xy 99.349304 -234.543779) (xy 99.387425 -234.512654)
			(xy 99.430046 -234.488047) (xy 99.476062 -234.470595) (xy 99.524281 -234.460751) (xy 99.573456 -234.45877)
			(xy 99.622311 -234.464702) (xy 99.669582 -234.478394) (xy 99.714044 -234.499492) (xy 99.754547 -234.527448)
			(xy 99.79004 -234.56154) (xy 99.819605 -234.600884) (xy 99.842476 -234.644461) (xy 99.85806 -234.691142)
			(xy 99.865955 -234.739719) (xy 99.86645 -234.764326) (xy 100.184707 -234.764326) (xy 100.188802 -234.713598)
			(xy 100.200981 -234.664184) (xy 100.220929 -234.617364) (xy 100.24813 -234.57435) (xy 100.281878 -234.536256)
			(xy 100.3213 -234.504069) (xy 100.365374 -234.478623) (xy 100.41296 -234.460576) (xy 100.462824 -234.450396)
			(xy 100.513676 -234.448347) (xy 100.564197 -234.454481) (xy 100.613081 -234.468641) (xy 100.65906 -234.490458)
			(xy 100.700944 -234.519368) (xy 100.737648 -234.554623) (xy 100.768221 -234.595309) (xy 100.791872 -234.640372)
			(xy 100.807988 -234.688646) (xy 100.816152 -234.73888) (xy 100.816664 -234.764326) (xy 101.124761 -234.764326)
			(xy 101.128856 -234.713598) (xy 101.141035 -234.664184) (xy 101.160983 -234.617364) (xy 101.188184 -234.57435)
			(xy 101.221932 -234.536256) (xy 101.261354 -234.504069) (xy 101.305428 -234.478623) (xy 101.353014 -234.460576)
			(xy 101.402878 -234.450396) (xy 101.45373 -234.448347) (xy 101.504251 -234.454481) (xy 101.553135 -234.468641)
			(xy 101.599114 -234.490458) (xy 101.640998 -234.519368) (xy 101.677702 -234.554623) (xy 101.708275 -234.595309)
			(xy 101.731926 -234.640372) (xy 101.748042 -234.688646) (xy 101.756206 -234.73888) (xy 101.756718 -234.764326)
			(xy 102.075246 -234.764326) (xy 102.079206 -234.715272) (xy 102.090983 -234.667488) (xy 102.110274 -234.622212)
			(xy 102.136577 -234.580616) (xy 102.169212 -234.543779) (xy 102.207333 -234.512654) (xy 102.249954 -234.488047)
			(xy 102.29597 -234.470595) (xy 102.344189 -234.460751) (xy 102.393364 -234.45877) (xy 102.442219 -234.464702)
			(xy 102.48949 -234.478394) (xy 102.533952 -234.499492) (xy 102.574455 -234.527448) (xy 102.609948 -234.56154)
			(xy 102.639513 -234.600884) (xy 102.662384 -234.644461) (xy 102.677968 -234.691142) (xy 102.685863 -234.739719)
			(xy 102.686358 -234.764326) (xy 103.004869 -234.764326) (xy 103.008964 -234.713598) (xy 103.021143 -234.664184)
			(xy 103.041091 -234.617364) (xy 103.068292 -234.57435) (xy 103.10204 -234.536256) (xy 103.141462 -234.504069)
			(xy 103.185536 -234.478623) (xy 103.233122 -234.460576) (xy 103.282986 -234.450396) (xy 103.333838 -234.448347)
			(xy 103.384359 -234.454481) (xy 103.433243 -234.468641) (xy 103.479222 -234.490458) (xy 103.521106 -234.519368)
			(xy 103.55781 -234.554623) (xy 103.588383 -234.595309) (xy 103.612034 -234.640372) (xy 103.62815 -234.688646)
			(xy 103.636314 -234.73888) (xy 103.636826 -234.764326) (xy 103.944923 -234.764326) (xy 103.949018 -234.713598)
			(xy 103.961197 -234.664184) (xy 103.981145 -234.617364) (xy 104.008346 -234.57435) (xy 104.042094 -234.536256)
			(xy 104.081516 -234.504069) (xy 104.12559 -234.478623) (xy 104.173176 -234.460576) (xy 104.22304 -234.450396)
			(xy 104.273892 -234.448347) (xy 104.324413 -234.454481) (xy 104.373297 -234.468641) (xy 104.419276 -234.490458)
			(xy 104.46116 -234.519368) (xy 104.497864 -234.554623) (xy 104.528437 -234.595309) (xy 104.552088 -234.640372)
			(xy 104.568204 -234.688646) (xy 104.576368 -234.73888) (xy 104.57688 -234.764326) (xy 104.895154 -234.764326)
			(xy 104.899114 -234.715272) (xy 104.910891 -234.667488) (xy 104.930182 -234.622212) (xy 104.956485 -234.580616)
			(xy 104.98912 -234.543779) (xy 105.027241 -234.512654) (xy 105.069862 -234.488047) (xy 105.115878 -234.470595)
			(xy 105.164097 -234.460751) (xy 105.213272 -234.45877) (xy 105.262127 -234.464702) (xy 105.309398 -234.478394)
			(xy 105.35386 -234.499492) (xy 105.394363 -234.527448) (xy 105.429856 -234.56154) (xy 105.459421 -234.600884)
			(xy 105.482292 -234.644461) (xy 105.497876 -234.691142) (xy 105.505771 -234.739719) (xy 105.506266 -234.764326)
			(xy 105.824777 -234.764326) (xy 105.828872 -234.713598) (xy 105.841051 -234.664184) (xy 105.860999 -234.617364)
			(xy 105.8882 -234.57435) (xy 105.921948 -234.536256) (xy 105.96137 -234.504069) (xy 106.005444 -234.478623)
			(xy 106.05303 -234.460576) (xy 106.102894 -234.450396) (xy 106.153746 -234.448347) (xy 106.204267 -234.454481)
			(xy 106.253151 -234.468641) (xy 106.29913 -234.490458) (xy 106.341014 -234.519368) (xy 106.377718 -234.554623)
			(xy 106.408291 -234.595309) (xy 106.431942 -234.640372) (xy 106.448058 -234.688646) (xy 106.456222 -234.73888)
			(xy 106.456734 -234.764326) (xy 106.764831 -234.764326) (xy 106.768926 -234.713598) (xy 106.781105 -234.664184)
			(xy 106.801053 -234.617364) (xy 106.828254 -234.57435) (xy 106.862002 -234.536256) (xy 106.901424 -234.504069)
			(xy 106.945498 -234.478623) (xy 106.993084 -234.460576) (xy 107.042948 -234.450396) (xy 107.0938 -234.448347)
			(xy 107.144321 -234.454481) (xy 107.193205 -234.468641) (xy 107.239184 -234.490458) (xy 107.281068 -234.519368)
			(xy 107.317772 -234.554623) (xy 107.348345 -234.595309) (xy 107.371996 -234.640372) (xy 107.388112 -234.688646)
			(xy 107.396276 -234.73888) (xy 107.396788 -234.764326) (xy 107.715316 -234.764326) (xy 107.719276 -234.715272)
			(xy 107.731053 -234.667488) (xy 107.750344 -234.622212) (xy 107.776647 -234.580616) (xy 107.809282 -234.543779)
			(xy 107.847403 -234.512654) (xy 107.890024 -234.488047) (xy 107.93604 -234.470595) (xy 107.984259 -234.460751)
			(xy 108.033434 -234.45877) (xy 108.082289 -234.464702) (xy 108.12956 -234.478394) (xy 108.174022 -234.499492)
			(xy 108.214525 -234.527448) (xy 108.250018 -234.56154) (xy 108.279583 -234.600884) (xy 108.302454 -234.644461)
			(xy 108.318038 -234.691142) (xy 108.325933 -234.739719) (xy 108.326428 -234.764326) (xy 108.325933 -234.788933)
			(xy 108.318038 -234.83751) (xy 108.302454 -234.884191) (xy 108.279583 -234.927768) (xy 108.250018 -234.967112)
			(xy 108.214525 -235.001204) (xy 108.174022 -235.02916) (xy 108.12956 -235.050258) (xy 108.082289 -235.06395)
			(xy 108.033434 -235.069882) (xy 107.984259 -235.067901) (xy 107.93604 -235.058057) (xy 107.890024 -235.040605)
			(xy 107.847403 -235.015998) (xy 107.809282 -234.984873) (xy 107.776647 -234.948036) (xy 107.750344 -234.90644)
			(xy 107.731053 -234.861164) (xy 107.719276 -234.81338) (xy 107.715316 -234.764326) (xy 107.396788 -234.764326)
			(xy 107.396276 -234.789772) (xy 107.388112 -234.840006) (xy 107.371996 -234.88828) (xy 107.348345 -234.933343)
			(xy 107.317772 -234.974029) (xy 107.281068 -235.009284) (xy 107.239184 -235.038194) (xy 107.193205 -235.060011)
			(xy 107.144321 -235.074171) (xy 107.0938 -235.080305) (xy 107.042948 -235.078256) (xy 106.993084 -235.068076)
			(xy 106.945498 -235.050029) (xy 106.901424 -235.024583) (xy 106.862002 -234.992396) (xy 106.828254 -234.954302)
			(xy 106.801053 -234.911288) (xy 106.781105 -234.864468) (xy 106.768926 -234.815054) (xy 106.764831 -234.764326)
			(xy 106.456734 -234.764326) (xy 106.456222 -234.789772) (xy 106.448058 -234.840006) (xy 106.431942 -234.88828)
			(xy 106.408291 -234.933343) (xy 106.377718 -234.974029) (xy 106.341014 -235.009284) (xy 106.29913 -235.038194)
			(xy 106.253151 -235.060011) (xy 106.204267 -235.074171) (xy 106.153746 -235.080305) (xy 106.102894 -235.078256)
			(xy 106.05303 -235.068076) (xy 106.005444 -235.050029) (xy 105.96137 -235.024583) (xy 105.921948 -234.992396)
			(xy 105.8882 -234.954302) (xy 105.860999 -234.911288) (xy 105.841051 -234.864468) (xy 105.828872 -234.815054)
			(xy 105.824777 -234.764326) (xy 105.506266 -234.764326) (xy 105.505771 -234.788933) (xy 105.497876 -234.83751)
			(xy 105.482292 -234.884191) (xy 105.459421 -234.927768) (xy 105.429856 -234.967112) (xy 105.394363 -235.001204)
			(xy 105.35386 -235.02916) (xy 105.309398 -235.050258) (xy 105.262127 -235.06395) (xy 105.213272 -235.069882)
			(xy 105.164097 -235.067901) (xy 105.115878 -235.058057) (xy 105.069862 -235.040605) (xy 105.027241 -235.015998)
			(xy 104.98912 -234.984873) (xy 104.956485 -234.948036) (xy 104.930182 -234.90644) (xy 104.910891 -234.861164)
			(xy 104.899114 -234.81338) (xy 104.895154 -234.764326) (xy 104.57688 -234.764326) (xy 104.576368 -234.789772)
			(xy 104.568204 -234.840006) (xy 104.552088 -234.88828) (xy 104.528437 -234.933343) (xy 104.497864 -234.974029)
			(xy 104.46116 -235.009284) (xy 104.419276 -235.038194) (xy 104.373297 -235.060011) (xy 104.324413 -235.074171)
			(xy 104.273892 -235.080305) (xy 104.22304 -235.078256) (xy 104.173176 -235.068076) (xy 104.12559 -235.050029)
			(xy 104.081516 -235.024583) (xy 104.042094 -234.992396) (xy 104.008346 -234.954302) (xy 103.981145 -234.911288)
			(xy 103.961197 -234.864468) (xy 103.949018 -234.815054) (xy 103.944923 -234.764326) (xy 103.636826 -234.764326)
			(xy 103.636314 -234.789772) (xy 103.62815 -234.840006) (xy 103.612034 -234.88828) (xy 103.588383 -234.933343)
			(xy 103.55781 -234.974029) (xy 103.521106 -235.009284) (xy 103.479222 -235.038194) (xy 103.433243 -235.060011)
			(xy 103.384359 -235.074171) (xy 103.333838 -235.080305) (xy 103.282986 -235.078256) (xy 103.233122 -235.068076)
			(xy 103.185536 -235.050029) (xy 103.141462 -235.024583) (xy 103.10204 -234.992396) (xy 103.068292 -234.954302)
			(xy 103.041091 -234.911288) (xy 103.021143 -234.864468) (xy 103.008964 -234.815054) (xy 103.004869 -234.764326)
			(xy 102.686358 -234.764326) (xy 102.685863 -234.788933) (xy 102.677968 -234.83751) (xy 102.662384 -234.884191)
			(xy 102.639513 -234.927768) (xy 102.609948 -234.967112) (xy 102.574455 -235.001204) (xy 102.533952 -235.02916)
			(xy 102.48949 -235.050258) (xy 102.442219 -235.06395) (xy 102.393364 -235.069882) (xy 102.344189 -235.067901)
			(xy 102.29597 -235.058057) (xy 102.249954 -235.040605) (xy 102.207333 -235.015998) (xy 102.169212 -234.984873)
			(xy 102.136577 -234.948036) (xy 102.110274 -234.90644) (xy 102.090983 -234.861164) (xy 102.079206 -234.81338)
			(xy 102.075246 -234.764326) (xy 101.756718 -234.764326) (xy 101.756206 -234.789772) (xy 101.748042 -234.840006)
			(xy 101.731926 -234.88828) (xy 101.708275 -234.933343) (xy 101.677702 -234.974029) (xy 101.640998 -235.009284)
			(xy 101.599114 -235.038194) (xy 101.553135 -235.060011) (xy 101.504251 -235.074171) (xy 101.45373 -235.080305)
			(xy 101.402878 -235.078256) (xy 101.353014 -235.068076) (xy 101.305428 -235.050029) (xy 101.261354 -235.024583)
			(xy 101.221932 -234.992396) (xy 101.188184 -234.954302) (xy 101.160983 -234.911288) (xy 101.141035 -234.864468)
			(xy 101.128856 -234.815054) (xy 101.124761 -234.764326) (xy 100.816664 -234.764326) (xy 100.816152 -234.789772)
			(xy 100.807988 -234.840006) (xy 100.791872 -234.88828) (xy 100.768221 -234.933343) (xy 100.737648 -234.974029)
			(xy 100.700944 -235.009284) (xy 100.65906 -235.038194) (xy 100.613081 -235.060011) (xy 100.564197 -235.074171)
			(xy 100.513676 -235.080305) (xy 100.462824 -235.078256) (xy 100.41296 -235.068076) (xy 100.365374 -235.050029)
			(xy 100.3213 -235.024583) (xy 100.281878 -234.992396) (xy 100.24813 -234.954302) (xy 100.220929 -234.911288)
			(xy 100.200981 -234.864468) (xy 100.188802 -234.815054) (xy 100.184707 -234.764326) (xy 99.86645 -234.764326)
			(xy 99.865955 -234.788933) (xy 99.85806 -234.83751) (xy 99.842476 -234.884191) (xy 99.819605 -234.927768)
			(xy 99.79004 -234.967112) (xy 99.754547 -235.001204) (xy 99.714044 -235.02916) (xy 99.669582 -235.050258)
			(xy 99.622311 -235.06395) (xy 99.573456 -235.069882) (xy 99.524281 -235.067901) (xy 99.476062 -235.058057)
			(xy 99.430046 -235.040605) (xy 99.387425 -235.015998) (xy 99.349304 -234.984873) (xy 99.316669 -234.948036)
			(xy 99.290366 -234.90644) (xy 99.271075 -234.861164) (xy 99.259298 -234.81338) (xy 99.255338 -234.764326)
			(xy 98.93681 -234.764326) (xy 98.936298 -234.789772) (xy 98.928134 -234.840006) (xy 98.912018 -234.88828)
			(xy 98.888367 -234.933343) (xy 98.857794 -234.974029) (xy 98.82109 -235.009284) (xy 98.779206 -235.038194)
			(xy 98.733227 -235.060011) (xy 98.684343 -235.074171) (xy 98.633822 -235.080305) (xy 98.58297 -235.078256)
			(xy 98.533106 -235.068076) (xy 98.48552 -235.050029) (xy 98.441446 -235.024583) (xy 98.402024 -234.992396)
			(xy 98.368276 -234.954302) (xy 98.341075 -234.911288) (xy 98.321127 -234.864468) (xy 98.308948 -234.815054)
			(xy 98.304853 -234.764326) (xy 97.996756 -234.764326) (xy 97.996244 -234.789772) (xy 97.98808 -234.840006)
			(xy 97.971964 -234.88828) (xy 97.948313 -234.933343) (xy 97.91774 -234.974029) (xy 97.881036 -235.009284)
			(xy 97.839152 -235.038194) (xy 97.793173 -235.060011) (xy 97.744289 -235.074171) (xy 97.693768 -235.080305)
			(xy 97.642916 -235.078256) (xy 97.593052 -235.068076) (xy 97.545466 -235.050029) (xy 97.501392 -235.024583)
			(xy 97.46197 -234.992396) (xy 97.428222 -234.954302) (xy 97.401021 -234.911288) (xy 97.381073 -234.864468)
			(xy 97.368894 -234.815054) (xy 97.364799 -234.764326) (xy 97.046288 -234.764326) (xy 97.045793 -234.788933)
			(xy 97.037898 -234.83751) (xy 97.022314 -234.884191) (xy 96.999443 -234.927768) (xy 96.969878 -234.967112)
			(xy 96.934385 -235.001204) (xy 96.893882 -235.02916) (xy 96.84942 -235.050258) (xy 96.802149 -235.06395)
			(xy 96.753294 -235.069882) (xy 96.704119 -235.067901) (xy 96.6559 -235.058057) (xy 96.609884 -235.040605)
			(xy 96.567263 -235.015998) (xy 96.529142 -234.984873) (xy 96.496507 -234.948036) (xy 96.470204 -234.90644)
			(xy 96.450913 -234.861164) (xy 96.439136 -234.81338) (xy 96.435176 -234.764326) (xy 96.116648 -234.764326)
			(xy 96.116136 -234.789772) (xy 96.107972 -234.840006) (xy 96.091856 -234.88828) (xy 96.068205 -234.933343)
			(xy 96.037632 -234.974029) (xy 96.000928 -235.009284) (xy 95.959044 -235.038194) (xy 95.913065 -235.060011)
			(xy 95.864181 -235.074171) (xy 95.81366 -235.080305) (xy 95.762808 -235.078256) (xy 95.712944 -235.068076)
			(xy 95.665358 -235.050029) (xy 95.621284 -235.024583) (xy 95.581862 -234.992396) (xy 95.548114 -234.954302)
			(xy 95.520913 -234.911288) (xy 95.500965 -234.864468) (xy 95.488786 -234.815054) (xy 95.484691 -234.764326)
			(xy 95.166434 -234.764326) (xy 95.165939 -234.788933) (xy 95.158044 -234.83751) (xy 95.14246 -234.884191)
			(xy 95.119589 -234.927768) (xy 95.090024 -234.967112) (xy 95.054531 -235.001204) (xy 95.014028 -235.02916)
			(xy 94.969566 -235.050258) (xy 94.922295 -235.06395) (xy 94.87344 -235.069882) (xy 94.824265 -235.067901)
			(xy 94.776046 -235.058057) (xy 94.73003 -235.040605) (xy 94.687409 -235.015998) (xy 94.649288 -234.984873)
			(xy 94.616653 -234.948036) (xy 94.59035 -234.90644) (xy 94.571059 -234.861164) (xy 94.559282 -234.81338)
			(xy 94.555322 -234.764326) (xy 94.236794 -234.764326) (xy 94.236282 -234.789772) (xy 94.228118 -234.840006)
			(xy 94.212002 -234.88828) (xy 94.188351 -234.933343) (xy 94.157778 -234.974029) (xy 94.121074 -235.009284)
			(xy 94.07919 -235.038194) (xy 94.033211 -235.060011) (xy 93.984327 -235.074171) (xy 93.933806 -235.080305)
			(xy 93.882954 -235.078256) (xy 93.83309 -235.068076) (xy 93.785504 -235.050029) (xy 93.74143 -235.024583)
			(xy 93.702008 -234.992396) (xy 93.66826 -234.954302) (xy 93.641059 -234.911288) (xy 93.621111 -234.864468)
			(xy 93.608932 -234.815054) (xy 93.604837 -234.764326) (xy 93.286326 -234.764326) (xy 93.285831 -234.788933)
			(xy 93.277936 -234.83751) (xy 93.262352 -234.884191) (xy 93.239481 -234.927768) (xy 93.209916 -234.967112)
			(xy 93.174423 -235.001204) (xy 93.13392 -235.02916) (xy 93.089458 -235.050258) (xy 93.042187 -235.06395)
			(xy 92.993332 -235.069882) (xy 92.944157 -235.067901) (xy 92.895938 -235.058057) (xy 92.849922 -235.040605)
			(xy 92.807301 -235.015998) (xy 92.76918 -234.984873) (xy 92.736545 -234.948036) (xy 92.710242 -234.90644)
			(xy 92.690951 -234.861164) (xy 92.679174 -234.81338) (xy 92.675214 -234.764326) (xy 92.356686 -234.764326)
			(xy 92.356174 -234.789772) (xy 92.34801 -234.840006) (xy 92.331894 -234.88828) (xy 92.308243 -234.933343)
			(xy 92.27767 -234.974029) (xy 92.240966 -235.009284) (xy 92.199082 -235.038194) (xy 92.153103 -235.060011)
			(xy 92.104219 -235.074171) (xy 92.053698 -235.080305) (xy 92.002846 -235.078256) (xy 91.952982 -235.068076)
			(xy 91.905396 -235.050029) (xy 91.861322 -235.024583) (xy 91.8219 -234.992396) (xy 91.788152 -234.954302)
			(xy 91.760951 -234.911288) (xy 91.741003 -234.864468) (xy 91.728824 -234.815054) (xy 91.724729 -234.764326)
			(xy 91.416632 -234.764326) (xy 91.41612 -234.789772) (xy 91.407956 -234.840006) (xy 91.39184 -234.88828)
			(xy 91.368189 -234.933343) (xy 91.337616 -234.974029) (xy 91.300912 -235.009284) (xy 91.259028 -235.038194)
			(xy 91.213049 -235.060011) (xy 91.164165 -235.074171) (xy 91.113644 -235.080305) (xy 91.062792 -235.078256)
			(xy 91.012928 -235.068076) (xy 90.965342 -235.050029) (xy 90.921268 -235.024583) (xy 90.881846 -234.992396)
			(xy 90.848098 -234.954302) (xy 90.820897 -234.911288) (xy 90.800949 -234.864468) (xy 90.78877 -234.815054)
			(xy 90.784675 -234.764326) (xy 90.466903 -234.764326) (xy 90.462734 -234.814633) (xy 90.450336 -234.863593)
			(xy 90.430049 -234.909844) (xy 90.402426 -234.952126) (xy 90.36822 -234.989284) (xy 90.328365 -235.020306)
			(xy 90.283947 -235.044345) (xy 90.236179 -235.060745) (xy 90.186363 -235.06906) (xy 90.16111 -235.069634)
			(xy 90.148347 -235.069497) (xy 90.122912 -235.067339) (xy 90.11031 -235.065316) (xy 90.11031 -235.06557)
			(xy 90.086856 -235.061143) (xy 90.041601 -235.045982) (xy 89.999247 -235.02398) (xy 89.960823 -234.99567)
			(xy 89.927259 -234.961739) (xy 89.912952 -234.942634) (xy 89.904824 -234.931204) (xy 89.87917 -234.920028)
			(xy 89.762838 -234.935014) (xy 89.741248 -234.952032) (xy 89.736168 -234.96524) (xy 89.728021 -234.985563)
			(xy 89.708948 -235.024979) (xy 89.698068 -235.04398) (xy 89.694766 -235.049568) (xy 89.692734 -235.056172)
			(xy 89.690956 -235.069634) (xy 89.690956 -235.24083) (xy 89.715594 -235.269278) (xy 89.73439 -235.272072)
			(xy 89.758318 -235.275978) (xy 89.804615 -235.290364) (xy 89.848056 -235.311886) (xy 89.887551 -235.340002)
			(xy 89.922107 -235.374006) (xy 89.950854 -235.413044) (xy 89.973072 -235.456133) (xy 89.988201 -235.502193)
			(xy 89.995861 -235.550064) (xy 89.995861 -235.574332) (xy 90.314775 -235.574332) (xy 90.31887 -235.523604)
			(xy 90.331049 -235.47419) (xy 90.350997 -235.42737) (xy 90.378198 -235.384356) (xy 90.411946 -235.346262)
			(xy 90.451368 -235.314075) (xy 90.495442 -235.288629) (xy 90.543028 -235.270582) (xy 90.592892 -235.260402)
			(xy 90.643744 -235.258353) (xy 90.694265 -235.264487) (xy 90.743149 -235.278647) (xy 90.789128 -235.300464)
			(xy 90.831012 -235.329374) (xy 90.867716 -235.364629) (xy 90.898289 -235.405315) (xy 90.92194 -235.450378)
			(xy 90.938056 -235.498652) (xy 90.94622 -235.548886) (xy 90.946732 -235.574332) (xy 91.26526 -235.574332)
			(xy 91.26922 -235.525278) (xy 91.280997 -235.477494) (xy 91.300288 -235.432218) (xy 91.326591 -235.390622)
			(xy 91.359226 -235.353785) (xy 91.397347 -235.32266) (xy 91.439968 -235.298053) (xy 91.485984 -235.280601)
			(xy 91.534203 -235.270757) (xy 91.583378 -235.268776) (xy 91.632233 -235.274708) (xy 91.679504 -235.2884)
			(xy 91.723966 -235.309498) (xy 91.764469 -235.337454) (xy 91.799962 -235.371546) (xy 91.829527 -235.41089)
			(xy 91.852398 -235.454467) (xy 91.867982 -235.501148) (xy 91.875877 -235.549725) (xy 91.876372 -235.574332)
			(xy 92.194883 -235.574332) (xy 92.198978 -235.523604) (xy 92.211157 -235.47419) (xy 92.231105 -235.42737)
			(xy 92.258306 -235.384356) (xy 92.292054 -235.346262) (xy 92.331476 -235.314075) (xy 92.37555 -235.288629)
			(xy 92.423136 -235.270582) (xy 92.473 -235.260402) (xy 92.523852 -235.258353) (xy 92.574373 -235.264487)
			(xy 92.623257 -235.278647) (xy 92.669236 -235.300464) (xy 92.71112 -235.329374) (xy 92.747824 -235.364629)
			(xy 92.778397 -235.405315) (xy 92.802048 -235.450378) (xy 92.818164 -235.498652) (xy 92.826328 -235.548886)
			(xy 92.82684 -235.574332) (xy 93.145114 -235.574332) (xy 93.149074 -235.525278) (xy 93.160851 -235.477494)
			(xy 93.180142 -235.432218) (xy 93.206445 -235.390622) (xy 93.23908 -235.353785) (xy 93.277201 -235.32266)
			(xy 93.319822 -235.298053) (xy 93.365838 -235.280601) (xy 93.414057 -235.270757) (xy 93.463232 -235.268776)
			(xy 93.512087 -235.274708) (xy 93.559358 -235.2884) (xy 93.60382 -235.309498) (xy 93.644323 -235.337454)
			(xy 93.679816 -235.371546) (xy 93.709381 -235.41089) (xy 93.732252 -235.454467) (xy 93.747836 -235.501148)
			(xy 93.755731 -235.549725) (xy 93.756226 -235.574332) (xy 94.074737 -235.574332) (xy 94.078832 -235.523604)
			(xy 94.091011 -235.47419) (xy 94.110959 -235.42737) (xy 94.13816 -235.384356) (xy 94.171908 -235.346262)
			(xy 94.21133 -235.314075) (xy 94.255404 -235.288629) (xy 94.30299 -235.270582) (xy 94.352854 -235.260402)
			(xy 94.403706 -235.258353) (xy 94.454227 -235.264487) (xy 94.503111 -235.278647) (xy 94.54909 -235.300464)
			(xy 94.590974 -235.329374) (xy 94.627678 -235.364629) (xy 94.658251 -235.405315) (xy 94.681902 -235.450378)
			(xy 94.698018 -235.498652) (xy 94.706182 -235.548886) (xy 94.706694 -235.574332) (xy 95.014791 -235.574332)
			(xy 95.018886 -235.523604) (xy 95.031065 -235.47419) (xy 95.051013 -235.42737) (xy 95.078214 -235.384356)
			(xy 95.111962 -235.346262) (xy 95.151384 -235.314075) (xy 95.195458 -235.288629) (xy 95.243044 -235.270582)
			(xy 95.292908 -235.260402) (xy 95.34376 -235.258353) (xy 95.394281 -235.264487) (xy 95.443165 -235.278647)
			(xy 95.489144 -235.300464) (xy 95.531028 -235.329374) (xy 95.567732 -235.364629) (xy 95.598305 -235.405315)
			(xy 95.621956 -235.450378) (xy 95.638072 -235.498652) (xy 95.646236 -235.548886) (xy 95.646748 -235.574332)
			(xy 95.965276 -235.574332) (xy 95.969236 -235.525278) (xy 95.981013 -235.477494) (xy 96.000304 -235.432218)
			(xy 96.026607 -235.390622) (xy 96.059242 -235.353785) (xy 96.097363 -235.32266) (xy 96.139984 -235.298053)
			(xy 96.186 -235.280601) (xy 96.234219 -235.270757) (xy 96.283394 -235.268776) (xy 96.332249 -235.274708)
			(xy 96.37952 -235.2884) (xy 96.423982 -235.309498) (xy 96.464485 -235.337454) (xy 96.499978 -235.371546)
			(xy 96.529543 -235.41089) (xy 96.552414 -235.454467) (xy 96.567998 -235.501148) (xy 96.575893 -235.549725)
			(xy 96.576388 -235.574332) (xy 96.90533 -235.574332) (xy 96.90929 -235.525278) (xy 96.921067 -235.477494)
			(xy 96.940358 -235.432218) (xy 96.966661 -235.390622) (xy 96.999296 -235.353785) (xy 97.037417 -235.32266)
			(xy 97.080038 -235.298053) (xy 97.126054 -235.280601) (xy 97.174273 -235.270757) (xy 97.223448 -235.268776)
			(xy 97.272303 -235.274708) (xy 97.319574 -235.2884) (xy 97.364036 -235.309498) (xy 97.404539 -235.337454)
			(xy 97.440032 -235.371546) (xy 97.469597 -235.41089) (xy 97.492468 -235.454467) (xy 97.508052 -235.501148)
			(xy 97.515947 -235.549725) (xy 97.516442 -235.574332) (xy 97.84513 -235.574332) (xy 97.84909 -235.525278)
			(xy 97.860867 -235.477494) (xy 97.880158 -235.432218) (xy 97.906461 -235.390622) (xy 97.939096 -235.353785)
			(xy 97.977217 -235.32266) (xy 98.019838 -235.298053) (xy 98.065854 -235.280601) (xy 98.114073 -235.270757)
			(xy 98.163248 -235.268776) (xy 98.212103 -235.274708) (xy 98.259374 -235.2884) (xy 98.303836 -235.309498)
			(xy 98.344339 -235.337454) (xy 98.379832 -235.371546) (xy 98.409397 -235.41089) (xy 98.432268 -235.454467)
			(xy 98.447852 -235.501148) (xy 98.455747 -235.549725) (xy 98.456242 -235.574332) (xy 98.785184 -235.574332)
			(xy 98.789144 -235.525278) (xy 98.800921 -235.477494) (xy 98.820212 -235.432218) (xy 98.846515 -235.390622)
			(xy 98.87915 -235.353785) (xy 98.917271 -235.32266) (xy 98.959892 -235.298053) (xy 99.005908 -235.280601)
			(xy 99.054127 -235.270757) (xy 99.103302 -235.268776) (xy 99.152157 -235.274708) (xy 99.199428 -235.2884)
			(xy 99.24389 -235.309498) (xy 99.284393 -235.337454) (xy 99.319886 -235.371546) (xy 99.349451 -235.41089)
			(xy 99.372322 -235.454467) (xy 99.387906 -235.501148) (xy 99.395801 -235.549725) (xy 99.396296 -235.574332)
			(xy 99.725238 -235.574332) (xy 99.729198 -235.525278) (xy 99.740975 -235.477494) (xy 99.760266 -235.432218)
			(xy 99.786569 -235.390622) (xy 99.819204 -235.353785) (xy 99.857325 -235.32266) (xy 99.899946 -235.298053)
			(xy 99.945962 -235.280601) (xy 99.994181 -235.270757) (xy 100.043356 -235.268776) (xy 100.092211 -235.274708)
			(xy 100.139482 -235.2884) (xy 100.183944 -235.309498) (xy 100.224447 -235.337454) (xy 100.25994 -235.371546)
			(xy 100.289505 -235.41089) (xy 100.312376 -235.454467) (xy 100.32796 -235.501148) (xy 100.335855 -235.549725)
			(xy 100.33635 -235.574332) (xy 100.665292 -235.574332) (xy 100.669252 -235.525278) (xy 100.681029 -235.477494)
			(xy 100.70032 -235.432218) (xy 100.726623 -235.390622) (xy 100.759258 -235.353785) (xy 100.797379 -235.32266)
			(xy 100.84 -235.298053) (xy 100.886016 -235.280601) (xy 100.934235 -235.270757) (xy 100.98341 -235.268776)
			(xy 101.032265 -235.274708) (xy 101.079536 -235.2884) (xy 101.123998 -235.309498) (xy 101.164501 -235.337454)
			(xy 101.199994 -235.371546) (xy 101.229559 -235.41089) (xy 101.25243 -235.454467) (xy 101.268014 -235.501148)
			(xy 101.275909 -235.549725) (xy 101.276404 -235.574332) (xy 101.605346 -235.574332) (xy 101.609306 -235.525278)
			(xy 101.621083 -235.477494) (xy 101.640374 -235.432218) (xy 101.666677 -235.390622) (xy 101.699312 -235.353785)
			(xy 101.737433 -235.32266) (xy 101.780054 -235.298053) (xy 101.82607 -235.280601) (xy 101.874289 -235.270757)
			(xy 101.923464 -235.268776) (xy 101.972319 -235.274708) (xy 102.01959 -235.2884) (xy 102.064052 -235.309498)
			(xy 102.104555 -235.337454) (xy 102.140048 -235.371546) (xy 102.169613 -235.41089) (xy 102.192484 -235.454467)
			(xy 102.208068 -235.501148) (xy 102.215963 -235.549725) (xy 102.216458 -235.574332) (xy 102.545146 -235.574332)
			(xy 102.549106 -235.525278) (xy 102.560883 -235.477494) (xy 102.580174 -235.432218) (xy 102.606477 -235.390622)
			(xy 102.639112 -235.353785) (xy 102.677233 -235.32266) (xy 102.719854 -235.298053) (xy 102.76587 -235.280601)
			(xy 102.814089 -235.270757) (xy 102.863264 -235.268776) (xy 102.912119 -235.274708) (xy 102.95939 -235.2884)
			(xy 103.003852 -235.309498) (xy 103.044355 -235.337454) (xy 103.079848 -235.371546) (xy 103.109413 -235.41089)
			(xy 103.132284 -235.454467) (xy 103.147868 -235.501148) (xy 103.155763 -235.549725) (xy 103.156258 -235.574332)
			(xy 103.4852 -235.574332) (xy 103.48916 -235.525278) (xy 103.500937 -235.477494) (xy 103.520228 -235.432218)
			(xy 103.546531 -235.390622) (xy 103.579166 -235.353785) (xy 103.617287 -235.32266) (xy 103.659908 -235.298053)
			(xy 103.705924 -235.280601) (xy 103.754143 -235.270757) (xy 103.803318 -235.268776) (xy 103.852173 -235.274708)
			(xy 103.899444 -235.2884) (xy 103.943906 -235.309498) (xy 103.984409 -235.337454) (xy 104.019902 -235.371546)
			(xy 104.049467 -235.41089) (xy 104.072338 -235.454467) (xy 104.087922 -235.501148) (xy 104.095817 -235.549725)
			(xy 104.096312 -235.574332) (xy 104.425254 -235.574332) (xy 104.429214 -235.525278) (xy 104.440991 -235.477494)
			(xy 104.460282 -235.432218) (xy 104.486585 -235.390622) (xy 104.51922 -235.353785) (xy 104.557341 -235.32266)
			(xy 104.599962 -235.298053) (xy 104.645978 -235.280601) (xy 104.694197 -235.270757) (xy 104.743372 -235.268776)
			(xy 104.792227 -235.274708) (xy 104.839498 -235.2884) (xy 104.88396 -235.309498) (xy 104.924463 -235.337454)
			(xy 104.959956 -235.371546) (xy 104.989521 -235.41089) (xy 105.012392 -235.454467) (xy 105.027976 -235.501148)
			(xy 105.035871 -235.549725) (xy 105.036366 -235.574332) (xy 105.365308 -235.574332) (xy 105.369268 -235.525278)
			(xy 105.381045 -235.477494) (xy 105.400336 -235.432218) (xy 105.426639 -235.390622) (xy 105.459274 -235.353785)
			(xy 105.497395 -235.32266) (xy 105.540016 -235.298053) (xy 105.586032 -235.280601) (xy 105.634251 -235.270757)
			(xy 105.683426 -235.268776) (xy 105.732281 -235.274708) (xy 105.779552 -235.2884) (xy 105.824014 -235.309498)
			(xy 105.864517 -235.337454) (xy 105.90001 -235.371546) (xy 105.929575 -235.41089) (xy 105.952446 -235.454467)
			(xy 105.96803 -235.501148) (xy 105.975925 -235.549725) (xy 105.97642 -235.574332) (xy 106.305362 -235.574332)
			(xy 106.309322 -235.525278) (xy 106.321099 -235.477494) (xy 106.34039 -235.432218) (xy 106.366693 -235.390622)
			(xy 106.399328 -235.353785) (xy 106.437449 -235.32266) (xy 106.48007 -235.298053) (xy 106.526086 -235.280601)
			(xy 106.574305 -235.270757) (xy 106.62348 -235.268776) (xy 106.672335 -235.274708) (xy 106.719606 -235.2884)
			(xy 106.764068 -235.309498) (xy 106.804571 -235.337454) (xy 106.840064 -235.371546) (xy 106.869629 -235.41089)
			(xy 106.8925 -235.454467) (xy 106.908084 -235.501148) (xy 106.915979 -235.549725) (xy 106.916474 -235.574332)
			(xy 107.245162 -235.574332) (xy 107.249122 -235.525278) (xy 107.260899 -235.477494) (xy 107.28019 -235.432218)
			(xy 107.306493 -235.390622) (xy 107.339128 -235.353785) (xy 107.377249 -235.32266) (xy 107.41987 -235.298053)
			(xy 107.465886 -235.280601) (xy 107.514105 -235.270757) (xy 107.56328 -235.268776) (xy 107.612135 -235.274708)
			(xy 107.659406 -235.2884) (xy 107.703868 -235.309498) (xy 107.744371 -235.337454) (xy 107.779864 -235.371546)
			(xy 107.809429 -235.41089) (xy 107.8323 -235.454467) (xy 107.847884 -235.501148) (xy 107.855779 -235.549725)
			(xy 107.856274 -235.574332) (xy 108.174785 -235.574332) (xy 108.17888 -235.523604) (xy 108.191059 -235.47419)
			(xy 108.211007 -235.42737) (xy 108.238208 -235.384356) (xy 108.271956 -235.346262) (xy 108.311378 -235.314075)
			(xy 108.355452 -235.288629) (xy 108.403038 -235.270582) (xy 108.452902 -235.260402) (xy 108.503754 -235.258353)
			(xy 108.554275 -235.264487) (xy 108.603159 -235.278647) (xy 108.649138 -235.300464) (xy 108.691022 -235.329374)
			(xy 108.727726 -235.364629) (xy 108.758299 -235.405315) (xy 108.78195 -235.450378) (xy 108.798066 -235.498652)
			(xy 108.80623 -235.548886) (xy 108.806742 -235.574332) (xy 109.114839 -235.574332) (xy 109.118934 -235.523604)
			(xy 109.131113 -235.47419) (xy 109.151061 -235.42737) (xy 109.178262 -235.384356) (xy 109.21201 -235.346262)
			(xy 109.251432 -235.314075) (xy 109.295506 -235.288629) (xy 109.343092 -235.270582) (xy 109.392956 -235.260402)
			(xy 109.443808 -235.258353) (xy 109.494329 -235.264487) (xy 109.543213 -235.278647) (xy 109.589192 -235.300464)
			(xy 109.631076 -235.329374) (xy 109.66778 -235.364629) (xy 109.698353 -235.405315) (xy 109.722004 -235.450378)
			(xy 109.73812 -235.498652) (xy 109.746284 -235.548886) (xy 109.746796 -235.574332) (xy 110.065324 -235.574332)
			(xy 110.069284 -235.525278) (xy 110.081061 -235.477494) (xy 110.100352 -235.432218) (xy 110.126655 -235.390622)
			(xy 110.15929 -235.353785) (xy 110.197411 -235.32266) (xy 110.240032 -235.298053) (xy 110.286048 -235.280601)
			(xy 110.334267 -235.270757) (xy 110.383442 -235.268776) (xy 110.432297 -235.274708) (xy 110.479568 -235.2884)
			(xy 110.52403 -235.309498) (xy 110.564533 -235.337454) (xy 110.600026 -235.371546) (xy 110.629591 -235.41089)
			(xy 110.652462 -235.454467) (xy 110.668046 -235.501148) (xy 110.675941 -235.549725) (xy 110.676436 -235.574332)
			(xy 110.675941 -235.598939) (xy 110.668046 -235.647516) (xy 110.652462 -235.694197) (xy 110.629591 -235.737774)
			(xy 110.600026 -235.777118) (xy 110.564533 -235.81121) (xy 110.52403 -235.839166) (xy 110.479568 -235.860264)
			(xy 110.432297 -235.873956) (xy 110.383442 -235.879888) (xy 110.334267 -235.877907) (xy 110.286048 -235.868063)
			(xy 110.240032 -235.850611) (xy 110.197411 -235.826004) (xy 110.15929 -235.794879) (xy 110.126655 -235.758042)
			(xy 110.100352 -235.716446) (xy 110.081061 -235.67117) (xy 110.069284 -235.623386) (xy 110.065324 -235.574332)
			(xy 109.746796 -235.574332) (xy 109.746284 -235.599778) (xy 109.73812 -235.650012) (xy 109.722004 -235.698286)
			(xy 109.698353 -235.743349) (xy 109.66778 -235.784035) (xy 109.631076 -235.81929) (xy 109.589192 -235.8482)
			(xy 109.543213 -235.870017) (xy 109.494329 -235.884177) (xy 109.443808 -235.890311) (xy 109.392956 -235.888262)
			(xy 109.343092 -235.878082) (xy 109.295506 -235.860035) (xy 109.251432 -235.834589) (xy 109.21201 -235.802402)
			(xy 109.178262 -235.764308) (xy 109.151061 -235.721294) (xy 109.131113 -235.674474) (xy 109.118934 -235.62506)
			(xy 109.114839 -235.574332) (xy 108.806742 -235.574332) (xy 108.80623 -235.599778) (xy 108.798066 -235.650012)
			(xy 108.78195 -235.698286) (xy 108.758299 -235.743349) (xy 108.727726 -235.784035) (xy 108.691022 -235.81929)
			(xy 108.649138 -235.8482) (xy 108.603159 -235.870017) (xy 108.554275 -235.884177) (xy 108.503754 -235.890311)
			(xy 108.452902 -235.888262) (xy 108.403038 -235.878082) (xy 108.355452 -235.860035) (xy 108.311378 -235.834589)
			(xy 108.271956 -235.802402) (xy 108.238208 -235.764308) (xy 108.211007 -235.721294) (xy 108.191059 -235.674474)
			(xy 108.17888 -235.62506) (xy 108.174785 -235.574332) (xy 107.856274 -235.574332) (xy 107.855779 -235.598939)
			(xy 107.847884 -235.647516) (xy 107.8323 -235.694197) (xy 107.809429 -235.737774) (xy 107.779864 -235.777118)
			(xy 107.744371 -235.81121) (xy 107.703868 -235.839166) (xy 107.659406 -235.860264) (xy 107.612135 -235.873956)
			(xy 107.56328 -235.879888) (xy 107.514105 -235.877907) (xy 107.465886 -235.868063) (xy 107.41987 -235.850611)
			(xy 107.377249 -235.826004) (xy 107.339128 -235.794879) (xy 107.306493 -235.758042) (xy 107.28019 -235.716446)
			(xy 107.260899 -235.67117) (xy 107.249122 -235.623386) (xy 107.245162 -235.574332) (xy 106.916474 -235.574332)
			(xy 106.915979 -235.598939) (xy 106.908084 -235.647516) (xy 106.8925 -235.694197) (xy 106.869629 -235.737774)
			(xy 106.840064 -235.777118) (xy 106.804571 -235.81121) (xy 106.764068 -235.839166) (xy 106.719606 -235.860264)
			(xy 106.672335 -235.873956) (xy 106.62348 -235.879888) (xy 106.574305 -235.877907) (xy 106.526086 -235.868063)
			(xy 106.48007 -235.850611) (xy 106.437449 -235.826004) (xy 106.399328 -235.794879) (xy 106.366693 -235.758042)
			(xy 106.34039 -235.716446) (xy 106.321099 -235.67117) (xy 106.309322 -235.623386) (xy 106.305362 -235.574332)
			(xy 105.97642 -235.574332) (xy 105.975925 -235.598939) (xy 105.96803 -235.647516) (xy 105.952446 -235.694197)
			(xy 105.929575 -235.737774) (xy 105.90001 -235.777118) (xy 105.864517 -235.81121) (xy 105.824014 -235.839166)
			(xy 105.779552 -235.860264) (xy 105.732281 -235.873956) (xy 105.683426 -235.879888) (xy 105.634251 -235.877907)
			(xy 105.586032 -235.868063) (xy 105.540016 -235.850611) (xy 105.497395 -235.826004) (xy 105.459274 -235.794879)
			(xy 105.426639 -235.758042) (xy 105.400336 -235.716446) (xy 105.381045 -235.67117) (xy 105.369268 -235.623386)
			(xy 105.365308 -235.574332) (xy 105.036366 -235.574332) (xy 105.035871 -235.598939) (xy 105.027976 -235.647516)
			(xy 105.012392 -235.694197) (xy 104.989521 -235.737774) (xy 104.959956 -235.777118) (xy 104.924463 -235.81121)
			(xy 104.88396 -235.839166) (xy 104.839498 -235.860264) (xy 104.792227 -235.873956) (xy 104.743372 -235.879888)
			(xy 104.694197 -235.877907) (xy 104.645978 -235.868063) (xy 104.599962 -235.850611) (xy 104.557341 -235.826004)
			(xy 104.51922 -235.794879) (xy 104.486585 -235.758042) (xy 104.460282 -235.716446) (xy 104.440991 -235.67117)
			(xy 104.429214 -235.623386) (xy 104.425254 -235.574332) (xy 104.096312 -235.574332) (xy 104.095817 -235.598939)
			(xy 104.087922 -235.647516) (xy 104.072338 -235.694197) (xy 104.049467 -235.737774) (xy 104.019902 -235.777118)
			(xy 103.984409 -235.81121) (xy 103.943906 -235.839166) (xy 103.899444 -235.860264) (xy 103.852173 -235.873956)
			(xy 103.803318 -235.879888) (xy 103.754143 -235.877907) (xy 103.705924 -235.868063) (xy 103.659908 -235.850611)
			(xy 103.617287 -235.826004) (xy 103.579166 -235.794879) (xy 103.546531 -235.758042) (xy 103.520228 -235.716446)
			(xy 103.500937 -235.67117) (xy 103.48916 -235.623386) (xy 103.4852 -235.574332) (xy 103.156258 -235.574332)
			(xy 103.155763 -235.598939) (xy 103.147868 -235.647516) (xy 103.132284 -235.694197) (xy 103.109413 -235.737774)
			(xy 103.079848 -235.777118) (xy 103.044355 -235.81121) (xy 103.003852 -235.839166) (xy 102.95939 -235.860264)
			(xy 102.912119 -235.873956) (xy 102.863264 -235.879888) (xy 102.814089 -235.877907) (xy 102.76587 -235.868063)
			(xy 102.719854 -235.850611) (xy 102.677233 -235.826004) (xy 102.639112 -235.794879) (xy 102.606477 -235.758042)
			(xy 102.580174 -235.716446) (xy 102.560883 -235.67117) (xy 102.549106 -235.623386) (xy 102.545146 -235.574332)
			(xy 102.216458 -235.574332) (xy 102.215963 -235.598939) (xy 102.208068 -235.647516) (xy 102.192484 -235.694197)
			(xy 102.169613 -235.737774) (xy 102.140048 -235.777118) (xy 102.104555 -235.81121) (xy 102.064052 -235.839166)
			(xy 102.01959 -235.860264) (xy 101.972319 -235.873956) (xy 101.923464 -235.879888) (xy 101.874289 -235.877907)
			(xy 101.82607 -235.868063) (xy 101.780054 -235.850611) (xy 101.737433 -235.826004) (xy 101.699312 -235.794879)
			(xy 101.666677 -235.758042) (xy 101.640374 -235.716446) (xy 101.621083 -235.67117) (xy 101.609306 -235.623386)
			(xy 101.605346 -235.574332) (xy 101.276404 -235.574332) (xy 101.275909 -235.598939) (xy 101.268014 -235.647516)
			(xy 101.25243 -235.694197) (xy 101.229559 -235.737774) (xy 101.199994 -235.777118) (xy 101.164501 -235.81121)
			(xy 101.123998 -235.839166) (xy 101.079536 -235.860264) (xy 101.032265 -235.873956) (xy 100.98341 -235.879888)
			(xy 100.934235 -235.877907) (xy 100.886016 -235.868063) (xy 100.84 -235.850611) (xy 100.797379 -235.826004)
			(xy 100.759258 -235.794879) (xy 100.726623 -235.758042) (xy 100.70032 -235.716446) (xy 100.681029 -235.67117)
			(xy 100.669252 -235.623386) (xy 100.665292 -235.574332) (xy 100.33635 -235.574332) (xy 100.335855 -235.598939)
			(xy 100.32796 -235.647516) (xy 100.312376 -235.694197) (xy 100.289505 -235.737774) (xy 100.25994 -235.777118)
			(xy 100.224447 -235.81121) (xy 100.183944 -235.839166) (xy 100.139482 -235.860264) (xy 100.092211 -235.873956)
			(xy 100.043356 -235.879888) (xy 99.994181 -235.877907) (xy 99.945962 -235.868063) (xy 99.899946 -235.850611)
			(xy 99.857325 -235.826004) (xy 99.819204 -235.794879) (xy 99.786569 -235.758042) (xy 99.760266 -235.716446)
			(xy 99.740975 -235.67117) (xy 99.729198 -235.623386) (xy 99.725238 -235.574332) (xy 99.396296 -235.574332)
			(xy 99.395801 -235.598939) (xy 99.387906 -235.647516) (xy 99.372322 -235.694197) (xy 99.349451 -235.737774)
			(xy 99.319886 -235.777118) (xy 99.284393 -235.81121) (xy 99.24389 -235.839166) (xy 99.199428 -235.860264)
			(xy 99.152157 -235.873956) (xy 99.103302 -235.879888) (xy 99.054127 -235.877907) (xy 99.005908 -235.868063)
			(xy 98.959892 -235.850611) (xy 98.917271 -235.826004) (xy 98.87915 -235.794879) (xy 98.846515 -235.758042)
			(xy 98.820212 -235.716446) (xy 98.800921 -235.67117) (xy 98.789144 -235.623386) (xy 98.785184 -235.574332)
			(xy 98.456242 -235.574332) (xy 98.455747 -235.598939) (xy 98.447852 -235.647516) (xy 98.432268 -235.694197)
			(xy 98.409397 -235.737774) (xy 98.379832 -235.777118) (xy 98.344339 -235.81121) (xy 98.303836 -235.839166)
			(xy 98.259374 -235.860264) (xy 98.212103 -235.873956) (xy 98.163248 -235.879888) (xy 98.114073 -235.877907)
			(xy 98.065854 -235.868063) (xy 98.019838 -235.850611) (xy 97.977217 -235.826004) (xy 97.939096 -235.794879)
			(xy 97.906461 -235.758042) (xy 97.880158 -235.716446) (xy 97.860867 -235.67117) (xy 97.84909 -235.623386)
			(xy 97.84513 -235.574332) (xy 97.516442 -235.574332) (xy 97.515947 -235.598939) (xy 97.508052 -235.647516)
			(xy 97.492468 -235.694197) (xy 97.469597 -235.737774) (xy 97.440032 -235.777118) (xy 97.404539 -235.81121)
			(xy 97.364036 -235.839166) (xy 97.319574 -235.860264) (xy 97.272303 -235.873956) (xy 97.223448 -235.879888)
			(xy 97.174273 -235.877907) (xy 97.126054 -235.868063) (xy 97.080038 -235.850611) (xy 97.037417 -235.826004)
			(xy 96.999296 -235.794879) (xy 96.966661 -235.758042) (xy 96.940358 -235.716446) (xy 96.921067 -235.67117)
			(xy 96.90929 -235.623386) (xy 96.90533 -235.574332) (xy 96.576388 -235.574332) (xy 96.575893 -235.598939)
			(xy 96.567998 -235.647516) (xy 96.552414 -235.694197) (xy 96.529543 -235.737774) (xy 96.499978 -235.777118)
			(xy 96.464485 -235.81121) (xy 96.423982 -235.839166) (xy 96.37952 -235.860264) (xy 96.332249 -235.873956)
			(xy 96.283394 -235.879888) (xy 96.234219 -235.877907) (xy 96.186 -235.868063) (xy 96.139984 -235.850611)
			(xy 96.097363 -235.826004) (xy 96.059242 -235.794879) (xy 96.026607 -235.758042) (xy 96.000304 -235.716446)
			(xy 95.981013 -235.67117) (xy 95.969236 -235.623386) (xy 95.965276 -235.574332) (xy 95.646748 -235.574332)
			(xy 95.646236 -235.599778) (xy 95.638072 -235.650012) (xy 95.621956 -235.698286) (xy 95.598305 -235.743349)
			(xy 95.567732 -235.784035) (xy 95.531028 -235.81929) (xy 95.489144 -235.8482) (xy 95.443165 -235.870017)
			(xy 95.394281 -235.884177) (xy 95.34376 -235.890311) (xy 95.292908 -235.888262) (xy 95.243044 -235.878082)
			(xy 95.195458 -235.860035) (xy 95.151384 -235.834589) (xy 95.111962 -235.802402) (xy 95.078214 -235.764308)
			(xy 95.051013 -235.721294) (xy 95.031065 -235.674474) (xy 95.018886 -235.62506) (xy 95.014791 -235.574332)
			(xy 94.706694 -235.574332) (xy 94.706182 -235.599778) (xy 94.698018 -235.650012) (xy 94.681902 -235.698286)
			(xy 94.658251 -235.743349) (xy 94.627678 -235.784035) (xy 94.590974 -235.81929) (xy 94.54909 -235.8482)
			(xy 94.503111 -235.870017) (xy 94.454227 -235.884177) (xy 94.403706 -235.890311) (xy 94.352854 -235.888262)
			(xy 94.30299 -235.878082) (xy 94.255404 -235.860035) (xy 94.21133 -235.834589) (xy 94.171908 -235.802402)
			(xy 94.13816 -235.764308) (xy 94.110959 -235.721294) (xy 94.091011 -235.674474) (xy 94.078832 -235.62506)
			(xy 94.074737 -235.574332) (xy 93.756226 -235.574332) (xy 93.755731 -235.598939) (xy 93.747836 -235.647516)
			(xy 93.732252 -235.694197) (xy 93.709381 -235.737774) (xy 93.679816 -235.777118) (xy 93.644323 -235.81121)
			(xy 93.60382 -235.839166) (xy 93.559358 -235.860264) (xy 93.512087 -235.873956) (xy 93.463232 -235.879888)
			(xy 93.414057 -235.877907) (xy 93.365838 -235.868063) (xy 93.319822 -235.850611) (xy 93.277201 -235.826004)
			(xy 93.23908 -235.794879) (xy 93.206445 -235.758042) (xy 93.180142 -235.716446) (xy 93.160851 -235.67117)
			(xy 93.149074 -235.623386) (xy 93.145114 -235.574332) (xy 92.82684 -235.574332) (xy 92.826328 -235.599778)
			(xy 92.818164 -235.650012) (xy 92.802048 -235.698286) (xy 92.778397 -235.743349) (xy 92.747824 -235.784035)
			(xy 92.71112 -235.81929) (xy 92.669236 -235.8482) (xy 92.623257 -235.870017) (xy 92.574373 -235.884177)
			(xy 92.523852 -235.890311) (xy 92.473 -235.888262) (xy 92.423136 -235.878082) (xy 92.37555 -235.860035)
			(xy 92.331476 -235.834589) (xy 92.292054 -235.802402) (xy 92.258306 -235.764308) (xy 92.231105 -235.721294)
			(xy 92.211157 -235.674474) (xy 92.198978 -235.62506) (xy 92.194883 -235.574332) (xy 91.876372 -235.574332)
			(xy 91.875877 -235.598939) (xy 91.867982 -235.647516) (xy 91.852398 -235.694197) (xy 91.829527 -235.737774)
			(xy 91.799962 -235.777118) (xy 91.764469 -235.81121) (xy 91.723966 -235.839166) (xy 91.679504 -235.860264)
			(xy 91.632233 -235.873956) (xy 91.583378 -235.879888) (xy 91.534203 -235.877907) (xy 91.485984 -235.868063)
			(xy 91.439968 -235.850611) (xy 91.397347 -235.826004) (xy 91.359226 -235.794879) (xy 91.326591 -235.758042)
			(xy 91.300288 -235.716446) (xy 91.280997 -235.67117) (xy 91.26922 -235.623386) (xy 91.26526 -235.574332)
			(xy 90.946732 -235.574332) (xy 90.94622 -235.599778) (xy 90.938056 -235.650012) (xy 90.92194 -235.698286)
			(xy 90.898289 -235.743349) (xy 90.867716 -235.784035) (xy 90.831012 -235.81929) (xy 90.789128 -235.8482)
			(xy 90.743149 -235.870017) (xy 90.694265 -235.884177) (xy 90.643744 -235.890311) (xy 90.592892 -235.888262)
			(xy 90.543028 -235.878082) (xy 90.495442 -235.860035) (xy 90.451368 -235.834589) (xy 90.411946 -235.802402)
			(xy 90.378198 -235.764308) (xy 90.350997 -235.721294) (xy 90.331049 -235.674474) (xy 90.31887 -235.62506)
			(xy 90.314775 -235.574332) (xy 89.995861 -235.574332) (xy 89.995861 -235.598545) (xy 89.988199 -235.646416)
			(xy 89.973068 -235.692475) (xy 89.95085 -235.735564) (xy 89.922101 -235.774601) (xy 89.887544 -235.808604)
			(xy 89.848049 -235.836719) (xy 89.804606 -235.858239) (xy 89.758309 -235.872624) (xy 89.73439 -235.876592)
			(xy 89.715594 -235.879386) (xy 89.690956 -235.907834) (xy 89.690956 -236.07903) (xy 89.691221 -236.085917)
			(xy 89.694953 -236.09918) (xy 89.698322 -236.105192) (xy 89.699338 -236.10697) (xy 89.707628 -236.121544)
			(xy 89.722625 -236.151537) (xy 89.72931 -236.166914) (xy 89.736168 -236.183424) (xy 89.741248 -236.196632)
			(xy 89.762838 -236.21365) (xy 89.879424 -236.228636) (xy 89.905078 -236.21746) (xy 89.913206 -236.20603)
			(xy 89.927674 -236.186735) (xy 89.961666 -236.152528) (xy 90.000607 -236.124082) (xy 90.043531 -236.102102)
			(xy 90.089374 -236.087134) (xy 90.136998 -236.079549) (xy 90.16111 -236.07903) (xy 90.186362 -236.079552)
			(xy 90.236176 -236.087866) (xy 90.283942 -236.104266) (xy 90.328358 -236.128304) (xy 90.368212 -236.159324)
			(xy 90.402416 -236.196481) (xy 90.430038 -236.238761) (xy 90.450325 -236.285011) (xy 90.462723 -236.333969)
			(xy 90.466893 -236.3843) (xy 90.46689 -236.384338) (xy 90.784675 -236.384338) (xy 90.78877 -236.33361)
			(xy 90.800949 -236.284196) (xy 90.820897 -236.237376) (xy 90.848098 -236.194362) (xy 90.881846 -236.156268)
			(xy 90.921268 -236.124081) (xy 90.965342 -236.098635) (xy 91.012928 -236.080588) (xy 91.062792 -236.070408)
			(xy 91.113644 -236.068359) (xy 91.164165 -236.074493) (xy 91.213049 -236.088653) (xy 91.259028 -236.11047)
			(xy 91.300912 -236.13938) (xy 91.337616 -236.174635) (xy 91.368189 -236.215321) (xy 91.39184 -236.260384)
			(xy 91.407956 -236.308658) (xy 91.41612 -236.358892) (xy 91.416632 -236.384338) (xy 91.724729 -236.384338)
			(xy 91.728824 -236.33361) (xy 91.741003 -236.284196) (xy 91.760951 -236.237376) (xy 91.788152 -236.194362)
			(xy 91.8219 -236.156268) (xy 91.861322 -236.124081) (xy 91.905396 -236.098635) (xy 91.952982 -236.080588)
			(xy 92.002846 -236.070408) (xy 92.053698 -236.068359) (xy 92.104219 -236.074493) (xy 92.153103 -236.088653)
			(xy 92.199082 -236.11047) (xy 92.240966 -236.13938) (xy 92.27767 -236.174635) (xy 92.308243 -236.215321)
			(xy 92.331894 -236.260384) (xy 92.34801 -236.308658) (xy 92.356174 -236.358892) (xy 92.356686 -236.384338)
			(xy 92.675214 -236.384338) (xy 92.679174 -236.335284) (xy 92.690951 -236.2875) (xy 92.710242 -236.242224)
			(xy 92.736545 -236.200628) (xy 92.76918 -236.163791) (xy 92.807301 -236.132666) (xy 92.849922 -236.108059)
			(xy 92.895938 -236.090607) (xy 92.944157 -236.080763) (xy 92.993332 -236.078782) (xy 93.042187 -236.084714)
			(xy 93.089458 -236.098406) (xy 93.13392 -236.119504) (xy 93.174423 -236.14746) (xy 93.209916 -236.181552)
			(xy 93.239481 -236.220896) (xy 93.262352 -236.264473) (xy 93.277936 -236.311154) (xy 93.285831 -236.359731)
			(xy 93.286326 -236.384338) (xy 93.604837 -236.384338) (xy 93.608932 -236.33361) (xy 93.621111 -236.284196)
			(xy 93.641059 -236.237376) (xy 93.66826 -236.194362) (xy 93.702008 -236.156268) (xy 93.74143 -236.124081)
			(xy 93.785504 -236.098635) (xy 93.83309 -236.080588) (xy 93.882954 -236.070408) (xy 93.933806 -236.068359)
			(xy 93.984327 -236.074493) (xy 94.033211 -236.088653) (xy 94.07919 -236.11047) (xy 94.121074 -236.13938)
			(xy 94.157778 -236.174635) (xy 94.188351 -236.215321) (xy 94.212002 -236.260384) (xy 94.228118 -236.308658)
			(xy 94.236282 -236.358892) (xy 94.236794 -236.384338) (xy 94.555322 -236.384338) (xy 94.559282 -236.335284)
			(xy 94.571059 -236.2875) (xy 94.59035 -236.242224) (xy 94.616653 -236.200628) (xy 94.649288 -236.163791)
			(xy 94.687409 -236.132666) (xy 94.73003 -236.108059) (xy 94.776046 -236.090607) (xy 94.824265 -236.080763)
			(xy 94.87344 -236.078782) (xy 94.922295 -236.084714) (xy 94.969566 -236.098406) (xy 95.014028 -236.119504)
			(xy 95.054531 -236.14746) (xy 95.090024 -236.181552) (xy 95.119589 -236.220896) (xy 95.14246 -236.264473)
			(xy 95.158044 -236.311154) (xy 95.165939 -236.359731) (xy 95.166434 -236.384338) (xy 95.484691 -236.384338)
			(xy 95.488786 -236.33361) (xy 95.500965 -236.284196) (xy 95.520913 -236.237376) (xy 95.548114 -236.194362)
			(xy 95.581862 -236.156268) (xy 95.621284 -236.124081) (xy 95.665358 -236.098635) (xy 95.712944 -236.080588)
			(xy 95.762808 -236.070408) (xy 95.81366 -236.068359) (xy 95.864181 -236.074493) (xy 95.913065 -236.088653)
			(xy 95.959044 -236.11047) (xy 96.000928 -236.13938) (xy 96.037632 -236.174635) (xy 96.068205 -236.215321)
			(xy 96.091856 -236.260384) (xy 96.107972 -236.308658) (xy 96.116136 -236.358892) (xy 96.116648 -236.384338)
			(xy 96.435176 -236.384338) (xy 96.439136 -236.335284) (xy 96.450913 -236.2875) (xy 96.470204 -236.242224)
			(xy 96.496507 -236.200628) (xy 96.529142 -236.163791) (xy 96.567263 -236.132666) (xy 96.609884 -236.108059)
			(xy 96.6559 -236.090607) (xy 96.704119 -236.080763) (xy 96.753294 -236.078782) (xy 96.802149 -236.084714)
			(xy 96.84942 -236.098406) (xy 96.893882 -236.119504) (xy 96.934385 -236.14746) (xy 96.969878 -236.181552)
			(xy 96.999443 -236.220896) (xy 97.022314 -236.264473) (xy 97.037898 -236.311154) (xy 97.045793 -236.359731)
			(xy 97.046288 -236.384338) (xy 97.364799 -236.384338) (xy 97.368894 -236.33361) (xy 97.381073 -236.284196)
			(xy 97.401021 -236.237376) (xy 97.428222 -236.194362) (xy 97.46197 -236.156268) (xy 97.501392 -236.124081)
			(xy 97.545466 -236.098635) (xy 97.593052 -236.080588) (xy 97.642916 -236.070408) (xy 97.693768 -236.068359)
			(xy 97.744289 -236.074493) (xy 97.793173 -236.088653) (xy 97.839152 -236.11047) (xy 97.881036 -236.13938)
			(xy 97.91774 -236.174635) (xy 97.948313 -236.215321) (xy 97.971964 -236.260384) (xy 97.98808 -236.308658)
			(xy 97.996244 -236.358892) (xy 97.996756 -236.384338) (xy 98.304853 -236.384338) (xy 98.308948 -236.33361)
			(xy 98.321127 -236.284196) (xy 98.341075 -236.237376) (xy 98.368276 -236.194362) (xy 98.402024 -236.156268)
			(xy 98.441446 -236.124081) (xy 98.48552 -236.098635) (xy 98.533106 -236.080588) (xy 98.58297 -236.070408)
			(xy 98.633822 -236.068359) (xy 98.684343 -236.074493) (xy 98.733227 -236.088653) (xy 98.779206 -236.11047)
			(xy 98.82109 -236.13938) (xy 98.857794 -236.174635) (xy 98.888367 -236.215321) (xy 98.912018 -236.260384)
			(xy 98.928134 -236.308658) (xy 98.936298 -236.358892) (xy 98.93681 -236.384338) (xy 99.255338 -236.384338)
			(xy 99.259298 -236.335284) (xy 99.271075 -236.2875) (xy 99.290366 -236.242224) (xy 99.316669 -236.200628)
			(xy 99.349304 -236.163791) (xy 99.387425 -236.132666) (xy 99.430046 -236.108059) (xy 99.476062 -236.090607)
			(xy 99.524281 -236.080763) (xy 99.573456 -236.078782) (xy 99.622311 -236.084714) (xy 99.669582 -236.098406)
			(xy 99.714044 -236.119504) (xy 99.754547 -236.14746) (xy 99.79004 -236.181552) (xy 99.819605 -236.220896)
			(xy 99.842476 -236.264473) (xy 99.85806 -236.311154) (xy 99.865955 -236.359731) (xy 99.86645 -236.384338)
			(xy 100.184707 -236.384338) (xy 100.188802 -236.33361) (xy 100.200981 -236.284196) (xy 100.220929 -236.237376)
			(xy 100.24813 -236.194362) (xy 100.281878 -236.156268) (xy 100.3213 -236.124081) (xy 100.365374 -236.098635)
			(xy 100.41296 -236.080588) (xy 100.462824 -236.070408) (xy 100.513676 -236.068359) (xy 100.564197 -236.074493)
			(xy 100.613081 -236.088653) (xy 100.65906 -236.11047) (xy 100.700944 -236.13938) (xy 100.737648 -236.174635)
			(xy 100.768221 -236.215321) (xy 100.791872 -236.260384) (xy 100.807988 -236.308658) (xy 100.816152 -236.358892)
			(xy 100.816664 -236.384338) (xy 101.124761 -236.384338) (xy 101.128856 -236.33361) (xy 101.141035 -236.284196)
			(xy 101.160983 -236.237376) (xy 101.188184 -236.194362) (xy 101.221932 -236.156268) (xy 101.261354 -236.124081)
			(xy 101.305428 -236.098635) (xy 101.353014 -236.080588) (xy 101.402878 -236.070408) (xy 101.45373 -236.068359)
			(xy 101.504251 -236.074493) (xy 101.553135 -236.088653) (xy 101.599114 -236.11047) (xy 101.640998 -236.13938)
			(xy 101.677702 -236.174635) (xy 101.708275 -236.215321) (xy 101.731926 -236.260384) (xy 101.748042 -236.308658)
			(xy 101.756206 -236.358892) (xy 101.756718 -236.384338) (xy 102.075246 -236.384338) (xy 102.079206 -236.335284)
			(xy 102.090983 -236.2875) (xy 102.110274 -236.242224) (xy 102.136577 -236.200628) (xy 102.169212 -236.163791)
			(xy 102.207333 -236.132666) (xy 102.249954 -236.108059) (xy 102.29597 -236.090607) (xy 102.344189 -236.080763)
			(xy 102.393364 -236.078782) (xy 102.442219 -236.084714) (xy 102.48949 -236.098406) (xy 102.533952 -236.119504)
			(xy 102.574455 -236.14746) (xy 102.609948 -236.181552) (xy 102.639513 -236.220896) (xy 102.662384 -236.264473)
			(xy 102.677968 -236.311154) (xy 102.685863 -236.359731) (xy 102.686358 -236.384338) (xy 104.895154 -236.384338)
			(xy 104.899114 -236.335284) (xy 104.910891 -236.2875) (xy 104.930182 -236.242224) (xy 104.956485 -236.200628)
			(xy 104.98912 -236.163791) (xy 105.027241 -236.132666) (xy 105.069862 -236.108059) (xy 105.115878 -236.090607)
			(xy 105.164097 -236.080763) (xy 105.213272 -236.078782) (xy 105.262127 -236.084714) (xy 105.309398 -236.098406)
			(xy 105.35386 -236.119504) (xy 105.394363 -236.14746) (xy 105.429856 -236.181552) (xy 105.459421 -236.220896)
			(xy 105.482292 -236.264473) (xy 105.497876 -236.311154) (xy 105.505771 -236.359731) (xy 105.506266 -236.384338)
			(xy 107.715316 -236.384338) (xy 107.719276 -236.335284) (xy 107.731053 -236.2875) (xy 107.750344 -236.242224)
			(xy 107.776647 -236.200628) (xy 107.809282 -236.163791) (xy 107.847403 -236.132666) (xy 107.890024 -236.108059)
			(xy 107.93604 -236.090607) (xy 107.984259 -236.080763) (xy 108.033434 -236.078782) (xy 108.082289 -236.084714)
			(xy 108.12956 -236.098406) (xy 108.174022 -236.119504) (xy 108.214525 -236.14746) (xy 108.250018 -236.181552)
			(xy 108.279583 -236.220896) (xy 108.302454 -236.264473) (xy 108.318038 -236.311154) (xy 108.325933 -236.359731)
			(xy 108.326428 -236.384338) (xy 108.65537 -236.384338) (xy 108.65933 -236.335284) (xy 108.671107 -236.2875)
			(xy 108.690398 -236.242224) (xy 108.716701 -236.200628) (xy 108.749336 -236.163791) (xy 108.787457 -236.132666)
			(xy 108.830078 -236.108059) (xy 108.876094 -236.090607) (xy 108.924313 -236.080763) (xy 108.973488 -236.078782)
			(xy 109.022343 -236.084714) (xy 109.069614 -236.098406) (xy 109.114076 -236.119504) (xy 109.154579 -236.14746)
			(xy 109.190072 -236.181552) (xy 109.219637 -236.220896) (xy 109.242508 -236.264473) (xy 109.258092 -236.311154)
			(xy 109.265987 -236.359731) (xy 109.266482 -236.384338) (xy 109.59517 -236.384338) (xy 109.59913 -236.335284)
			(xy 109.610907 -236.2875) (xy 109.630198 -236.242224) (xy 109.656501 -236.200628) (xy 109.689136 -236.163791)
			(xy 109.727257 -236.132666) (xy 109.769878 -236.108059) (xy 109.815894 -236.090607) (xy 109.864113 -236.080763)
			(xy 109.913288 -236.078782) (xy 109.962143 -236.084714) (xy 110.009414 -236.098406) (xy 110.053876 -236.119504)
			(xy 110.094379 -236.14746) (xy 110.129872 -236.181552) (xy 110.159437 -236.220896) (xy 110.182308 -236.264473)
			(xy 110.197892 -236.311154) (xy 110.205787 -236.359731) (xy 110.206282 -236.384338) (xy 110.205787 -236.408945)
			(xy 110.197892 -236.457522) (xy 110.182308 -236.504203) (xy 110.159437 -236.54778) (xy 110.129872 -236.587124)
			(xy 110.094379 -236.621216) (xy 110.053876 -236.649172) (xy 110.009414 -236.67027) (xy 109.962143 -236.683962)
			(xy 109.913288 -236.689894) (xy 109.864113 -236.687913) (xy 109.815894 -236.678069) (xy 109.769878 -236.660617)
			(xy 109.727257 -236.63601) (xy 109.689136 -236.604885) (xy 109.656501 -236.568048) (xy 109.630198 -236.526452)
			(xy 109.610907 -236.481176) (xy 109.59913 -236.433392) (xy 109.59517 -236.384338) (xy 109.266482 -236.384338)
			(xy 109.265987 -236.408945) (xy 109.258092 -236.457522) (xy 109.242508 -236.504203) (xy 109.219637 -236.54778)
			(xy 109.190072 -236.587124) (xy 109.154579 -236.621216) (xy 109.114076 -236.649172) (xy 109.069614 -236.67027)
			(xy 109.022343 -236.683962) (xy 108.973488 -236.689894) (xy 108.924313 -236.687913) (xy 108.876094 -236.678069)
			(xy 108.830078 -236.660617) (xy 108.787457 -236.63601) (xy 108.749336 -236.604885) (xy 108.716701 -236.568048)
			(xy 108.690398 -236.526452) (xy 108.671107 -236.481176) (xy 108.65933 -236.433392) (xy 108.65537 -236.384338)
			(xy 108.326428 -236.384338) (xy 108.325933 -236.408945) (xy 108.318038 -236.457522) (xy 108.302454 -236.504203)
			(xy 108.279583 -236.54778) (xy 108.250018 -236.587124) (xy 108.214525 -236.621216) (xy 108.174022 -236.649172)
			(xy 108.12956 -236.67027) (xy 108.082289 -236.683962) (xy 108.033434 -236.689894) (xy 107.984259 -236.687913)
			(xy 107.93604 -236.678069) (xy 107.890024 -236.660617) (xy 107.847403 -236.63601) (xy 107.809282 -236.604885)
			(xy 107.776647 -236.568048) (xy 107.750344 -236.526452) (xy 107.731053 -236.481176) (xy 107.719276 -236.433392)
			(xy 107.715316 -236.384338) (xy 105.506266 -236.384338) (xy 105.505771 -236.408945) (xy 105.497876 -236.457522)
			(xy 105.482292 -236.504203) (xy 105.459421 -236.54778) (xy 105.429856 -236.587124) (xy 105.394363 -236.621216)
			(xy 105.35386 -236.649172) (xy 105.309398 -236.67027) (xy 105.262127 -236.683962) (xy 105.213272 -236.689894)
			(xy 105.164097 -236.687913) (xy 105.115878 -236.678069) (xy 105.069862 -236.660617) (xy 105.027241 -236.63601)
			(xy 104.98912 -236.604885) (xy 104.956485 -236.568048) (xy 104.930182 -236.526452) (xy 104.910891 -236.481176)
			(xy 104.899114 -236.433392) (xy 104.895154 -236.384338) (xy 102.686358 -236.384338) (xy 102.685863 -236.408945)
			(xy 102.677968 -236.457522) (xy 102.662384 -236.504203) (xy 102.639513 -236.54778) (xy 102.609948 -236.587124)
			(xy 102.574455 -236.621216) (xy 102.533952 -236.649172) (xy 102.48949 -236.67027) (xy 102.442219 -236.683962)
			(xy 102.393364 -236.689894) (xy 102.344189 -236.687913) (xy 102.29597 -236.678069) (xy 102.249954 -236.660617)
			(xy 102.207333 -236.63601) (xy 102.169212 -236.604885) (xy 102.136577 -236.568048) (xy 102.110274 -236.526452)
			(xy 102.090983 -236.481176) (xy 102.079206 -236.433392) (xy 102.075246 -236.384338) (xy 101.756718 -236.384338)
			(xy 101.756206 -236.409784) (xy 101.748042 -236.460018) (xy 101.731926 -236.508292) (xy 101.708275 -236.553355)
			(xy 101.677702 -236.594041) (xy 101.640998 -236.629296) (xy 101.599114 -236.658206) (xy 101.553135 -236.680023)
			(xy 101.504251 -236.694183) (xy 101.45373 -236.700317) (xy 101.402878 -236.698268) (xy 101.353014 -236.688088)
			(xy 101.305428 -236.670041) (xy 101.261354 -236.644595) (xy 101.221932 -236.612408) (xy 101.188184 -236.574314)
			(xy 101.160983 -236.5313) (xy 101.141035 -236.48448) (xy 101.128856 -236.435066) (xy 101.124761 -236.384338)
			(xy 100.816664 -236.384338) (xy 100.816152 -236.409784) (xy 100.807988 -236.460018) (xy 100.791872 -236.508292)
			(xy 100.768221 -236.553355) (xy 100.737648 -236.594041) (xy 100.700944 -236.629296) (xy 100.65906 -236.658206)
			(xy 100.613081 -236.680023) (xy 100.564197 -236.694183) (xy 100.513676 -236.700317) (xy 100.462824 -236.698268)
			(xy 100.41296 -236.688088) (xy 100.365374 -236.670041) (xy 100.3213 -236.644595) (xy 100.281878 -236.612408)
			(xy 100.24813 -236.574314) (xy 100.220929 -236.5313) (xy 100.200981 -236.48448) (xy 100.188802 -236.435066)
			(xy 100.184707 -236.384338) (xy 99.86645 -236.384338) (xy 99.865955 -236.408945) (xy 99.85806 -236.457522)
			(xy 99.842476 -236.504203) (xy 99.819605 -236.54778) (xy 99.79004 -236.587124) (xy 99.754547 -236.621216)
			(xy 99.714044 -236.649172) (xy 99.669582 -236.67027) (xy 99.622311 -236.683962) (xy 99.573456 -236.689894)
			(xy 99.524281 -236.687913) (xy 99.476062 -236.678069) (xy 99.430046 -236.660617) (xy 99.387425 -236.63601)
			(xy 99.349304 -236.604885) (xy 99.316669 -236.568048) (xy 99.290366 -236.526452) (xy 99.271075 -236.481176)
			(xy 99.259298 -236.433392) (xy 99.255338 -236.384338) (xy 98.93681 -236.384338) (xy 98.936298 -236.409784)
			(xy 98.928134 -236.460018) (xy 98.912018 -236.508292) (xy 98.888367 -236.553355) (xy 98.857794 -236.594041)
			(xy 98.82109 -236.629296) (xy 98.779206 -236.658206) (xy 98.733227 -236.680023) (xy 98.684343 -236.694183)
			(xy 98.633822 -236.700317) (xy 98.58297 -236.698268) (xy 98.533106 -236.688088) (xy 98.48552 -236.670041)
			(xy 98.441446 -236.644595) (xy 98.402024 -236.612408) (xy 98.368276 -236.574314) (xy 98.341075 -236.5313)
			(xy 98.321127 -236.48448) (xy 98.308948 -236.435066) (xy 98.304853 -236.384338) (xy 97.996756 -236.384338)
			(xy 97.996244 -236.409784) (xy 97.98808 -236.460018) (xy 97.971964 -236.508292) (xy 97.948313 -236.553355)
			(xy 97.91774 -236.594041) (xy 97.881036 -236.629296) (xy 97.839152 -236.658206) (xy 97.793173 -236.680023)
			(xy 97.744289 -236.694183) (xy 97.693768 -236.700317) (xy 97.642916 -236.698268) (xy 97.593052 -236.688088)
			(xy 97.545466 -236.670041) (xy 97.501392 -236.644595) (xy 97.46197 -236.612408) (xy 97.428222 -236.574314)
			(xy 97.401021 -236.5313) (xy 97.381073 -236.48448) (xy 97.368894 -236.435066) (xy 97.364799 -236.384338)
			(xy 97.046288 -236.384338) (xy 97.045793 -236.408945) (xy 97.037898 -236.457522) (xy 97.022314 -236.504203)
			(xy 96.999443 -236.54778) (xy 96.969878 -236.587124) (xy 96.934385 -236.621216) (xy 96.893882 -236.649172)
			(xy 96.84942 -236.67027) (xy 96.802149 -236.683962) (xy 96.753294 -236.689894) (xy 96.704119 -236.687913)
			(xy 96.6559 -236.678069) (xy 96.609884 -236.660617) (xy 96.567263 -236.63601) (xy 96.529142 -236.604885)
			(xy 96.496507 -236.568048) (xy 96.470204 -236.526452) (xy 96.450913 -236.481176) (xy 96.439136 -236.433392)
			(xy 96.435176 -236.384338) (xy 96.116648 -236.384338) (xy 96.116136 -236.409784) (xy 96.107972 -236.460018)
			(xy 96.091856 -236.508292) (xy 96.068205 -236.553355) (xy 96.037632 -236.594041) (xy 96.000928 -236.629296)
			(xy 95.959044 -236.658206) (xy 95.913065 -236.680023) (xy 95.864181 -236.694183) (xy 95.81366 -236.700317)
			(xy 95.762808 -236.698268) (xy 95.712944 -236.688088) (xy 95.665358 -236.670041) (xy 95.621284 -236.644595)
			(xy 95.581862 -236.612408) (xy 95.548114 -236.574314) (xy 95.520913 -236.5313) (xy 95.500965 -236.48448)
			(xy 95.488786 -236.435066) (xy 95.484691 -236.384338) (xy 95.166434 -236.384338) (xy 95.165939 -236.408945)
			(xy 95.158044 -236.457522) (xy 95.14246 -236.504203) (xy 95.119589 -236.54778) (xy 95.090024 -236.587124)
			(xy 95.054531 -236.621216) (xy 95.014028 -236.649172) (xy 94.969566 -236.67027) (xy 94.922295 -236.683962)
			(xy 94.87344 -236.689894) (xy 94.824265 -236.687913) (xy 94.776046 -236.678069) (xy 94.73003 -236.660617)
			(xy 94.687409 -236.63601) (xy 94.649288 -236.604885) (xy 94.616653 -236.568048) (xy 94.59035 -236.526452)
			(xy 94.571059 -236.481176) (xy 94.559282 -236.433392) (xy 94.555322 -236.384338) (xy 94.236794 -236.384338)
			(xy 94.236282 -236.409784) (xy 94.228118 -236.460018) (xy 94.212002 -236.508292) (xy 94.188351 -236.553355)
			(xy 94.157778 -236.594041) (xy 94.121074 -236.629296) (xy 94.07919 -236.658206) (xy 94.033211 -236.680023)
			(xy 93.984327 -236.694183) (xy 93.933806 -236.700317) (xy 93.882954 -236.698268) (xy 93.83309 -236.688088)
			(xy 93.785504 -236.670041) (xy 93.74143 -236.644595) (xy 93.702008 -236.612408) (xy 93.66826 -236.574314)
			(xy 93.641059 -236.5313) (xy 93.621111 -236.48448) (xy 93.608932 -236.435066) (xy 93.604837 -236.384338)
			(xy 93.286326 -236.384338) (xy 93.285831 -236.408945) (xy 93.277936 -236.457522) (xy 93.262352 -236.504203)
			(xy 93.239481 -236.54778) (xy 93.209916 -236.587124) (xy 93.174423 -236.621216) (xy 93.13392 -236.649172)
			(xy 93.089458 -236.67027) (xy 93.042187 -236.683962) (xy 92.993332 -236.689894) (xy 92.944157 -236.687913)
			(xy 92.895938 -236.678069) (xy 92.849922 -236.660617) (xy 92.807301 -236.63601) (xy 92.76918 -236.604885)
			(xy 92.736545 -236.568048) (xy 92.710242 -236.526452) (xy 92.690951 -236.481176) (xy 92.679174 -236.433392)
			(xy 92.675214 -236.384338) (xy 92.356686 -236.384338) (xy 92.356174 -236.409784) (xy 92.34801 -236.460018)
			(xy 92.331894 -236.508292) (xy 92.308243 -236.553355) (xy 92.27767 -236.594041) (xy 92.240966 -236.629296)
			(xy 92.199082 -236.658206) (xy 92.153103 -236.680023) (xy 92.104219 -236.694183) (xy 92.053698 -236.700317)
			(xy 92.002846 -236.698268) (xy 91.952982 -236.688088) (xy 91.905396 -236.670041) (xy 91.861322 -236.644595)
			(xy 91.8219 -236.612408) (xy 91.788152 -236.574314) (xy 91.760951 -236.5313) (xy 91.741003 -236.48448)
			(xy 91.728824 -236.435066) (xy 91.724729 -236.384338) (xy 91.416632 -236.384338) (xy 91.41612 -236.409784)
			(xy 91.407956 -236.460018) (xy 91.39184 -236.508292) (xy 91.368189 -236.553355) (xy 91.337616 -236.594041)
			(xy 91.300912 -236.629296) (xy 91.259028 -236.658206) (xy 91.213049 -236.680023) (xy 91.164165 -236.694183)
			(xy 91.113644 -236.700317) (xy 91.062792 -236.698268) (xy 91.012928 -236.688088) (xy 90.965342 -236.670041)
			(xy 90.921268 -236.644595) (xy 90.881846 -236.612408) (xy 90.848098 -236.574314) (xy 90.820897 -236.5313)
			(xy 90.800949 -236.48448) (xy 90.78877 -236.435066) (xy 90.784675 -236.384338) (xy 90.46689 -236.384338)
			(xy 90.462723 -236.434631) (xy 90.450325 -236.483589) (xy 90.430038 -236.529839) (xy 90.402416 -236.572119)
			(xy 90.368212 -236.609276) (xy 90.328358 -236.640296) (xy 90.283942 -236.664334) (xy 90.236176 -236.680734)
			(xy 90.186362 -236.689048) (xy 90.16111 -236.689646) (xy 90.148347 -236.689509) (xy 90.122912 -236.687351)
			(xy 90.11031 -236.685328) (xy 90.11031 -236.685582) (xy 90.086856 -236.681155) (xy 90.0416 -236.665995)
			(xy 89.999246 -236.643993) (xy 89.960821 -236.615684) (xy 89.927256 -236.581753) (xy 89.912952 -236.562646)
			(xy 89.904824 -236.551216) (xy 89.87917 -236.54004) (xy 89.762838 -236.555026) (xy 89.741248 -236.572044)
			(xy 89.736168 -236.585252) (xy 89.72802 -236.605575) (xy 89.708947 -236.644991) (xy 89.698068 -236.663992)
			(xy 89.694766 -236.66958) (xy 89.692734 -236.676184) (xy 89.690956 -236.689646) (xy 89.690956 -236.860842)
			(xy 89.715594 -236.88929) (xy 89.73439 -236.892084) (xy 89.758317 -236.89599) (xy 89.804612 -236.910376)
			(xy 89.848052 -236.931897) (xy 89.887545 -236.960012) (xy 89.922099 -236.994015) (xy 89.950845 -237.033051)
			(xy 89.973062 -237.07614) (xy 89.98819 -237.122197) (xy 89.99585 -237.170067) (xy 89.995849 -237.194344)
			(xy 90.314775 -237.194344) (xy 90.31887 -237.143616) (xy 90.331049 -237.094202) (xy 90.350997 -237.047382)
			(xy 90.378198 -237.004368) (xy 90.411946 -236.966274) (xy 90.451368 -236.934087) (xy 90.495442 -236.908641)
			(xy 90.543028 -236.890594) (xy 90.592892 -236.880414) (xy 90.643744 -236.878365) (xy 90.694265 -236.884499)
			(xy 90.743149 -236.898659) (xy 90.789128 -236.920476) (xy 90.831012 -236.949386) (xy 90.867716 -236.984641)
			(xy 90.898289 -237.025327) (xy 90.92194 -237.07039) (xy 90.938056 -237.118664) (xy 90.94622 -237.168898)
			(xy 90.946732 -237.194344) (xy 91.26526 -237.194344) (xy 91.26922 -237.14529) (xy 91.280997 -237.097506)
			(xy 91.300288 -237.05223) (xy 91.326591 -237.010634) (xy 91.359226 -236.973797) (xy 91.397347 -236.942672)
			(xy 91.439968 -236.918065) (xy 91.485984 -236.900613) (xy 91.534203 -236.890769) (xy 91.583378 -236.888788)
			(xy 91.632233 -236.89472) (xy 91.679504 -236.908412) (xy 91.723966 -236.92951) (xy 91.764469 -236.957466)
			(xy 91.799962 -236.991558) (xy 91.829527 -237.030902) (xy 91.852398 -237.074479) (xy 91.867982 -237.12116)
			(xy 91.875877 -237.169737) (xy 91.876372 -237.194344) (xy 92.194883 -237.194344) (xy 92.198978 -237.143616)
			(xy 92.211157 -237.094202) (xy 92.231105 -237.047382) (xy 92.258306 -237.004368) (xy 92.292054 -236.966274)
			(xy 92.331476 -236.934087) (xy 92.37555 -236.908641) (xy 92.423136 -236.890594) (xy 92.473 -236.880414)
			(xy 92.523852 -236.878365) (xy 92.574373 -236.884499) (xy 92.623257 -236.898659) (xy 92.669236 -236.920476)
			(xy 92.71112 -236.949386) (xy 92.747824 -236.984641) (xy 92.778397 -237.025327) (xy 92.802048 -237.07039)
			(xy 92.818164 -237.118664) (xy 92.826328 -237.168898) (xy 92.82684 -237.194344) (xy 93.145114 -237.194344)
			(xy 93.149074 -237.14529) (xy 93.160851 -237.097506) (xy 93.180142 -237.05223) (xy 93.206445 -237.010634)
			(xy 93.23908 -236.973797) (xy 93.277201 -236.942672) (xy 93.319822 -236.918065) (xy 93.365838 -236.900613)
			(xy 93.414057 -236.890769) (xy 93.463232 -236.888788) (xy 93.512087 -236.89472) (xy 93.559358 -236.908412)
			(xy 93.60382 -236.92951) (xy 93.644323 -236.957466) (xy 93.679816 -236.991558) (xy 93.709381 -237.030902)
			(xy 93.732252 -237.074479) (xy 93.747836 -237.12116) (xy 93.755731 -237.169737) (xy 93.756226 -237.194344)
			(xy 94.074737 -237.194344) (xy 94.078832 -237.143616) (xy 94.091011 -237.094202) (xy 94.110959 -237.047382)
			(xy 94.13816 -237.004368) (xy 94.171908 -236.966274) (xy 94.21133 -236.934087) (xy 94.255404 -236.908641)
			(xy 94.30299 -236.890594) (xy 94.352854 -236.880414) (xy 94.403706 -236.878365) (xy 94.454227 -236.884499)
			(xy 94.503111 -236.898659) (xy 94.54909 -236.920476) (xy 94.590974 -236.949386) (xy 94.627678 -236.984641)
			(xy 94.658251 -237.025327) (xy 94.681902 -237.07039) (xy 94.698018 -237.118664) (xy 94.706182 -237.168898)
			(xy 94.706694 -237.194344) (xy 95.014791 -237.194344) (xy 95.018886 -237.143616) (xy 95.031065 -237.094202)
			(xy 95.051013 -237.047382) (xy 95.078214 -237.004368) (xy 95.111962 -236.966274) (xy 95.151384 -236.934087)
			(xy 95.195458 -236.908641) (xy 95.243044 -236.890594) (xy 95.292908 -236.880414) (xy 95.34376 -236.878365)
			(xy 95.394281 -236.884499) (xy 95.443165 -236.898659) (xy 95.489144 -236.920476) (xy 95.531028 -236.949386)
			(xy 95.567732 -236.984641) (xy 95.598305 -237.025327) (xy 95.621956 -237.07039) (xy 95.638072 -237.118664)
			(xy 95.646236 -237.168898) (xy 95.646748 -237.194344) (xy 95.965276 -237.194344) (xy 95.969236 -237.14529)
			(xy 95.981013 -237.097506) (xy 96.000304 -237.05223) (xy 96.026607 -237.010634) (xy 96.059242 -236.973797)
			(xy 96.097363 -236.942672) (xy 96.139984 -236.918065) (xy 96.186 -236.900613) (xy 96.234219 -236.890769)
			(xy 96.283394 -236.888788) (xy 96.332249 -236.89472) (xy 96.37952 -236.908412) (xy 96.423982 -236.92951)
			(xy 96.464485 -236.957466) (xy 96.499978 -236.991558) (xy 96.529543 -237.030902) (xy 96.552414 -237.074479)
			(xy 96.567998 -237.12116) (xy 96.575893 -237.169737) (xy 96.576388 -237.194344) (xy 96.90533 -237.194344)
			(xy 96.90929 -237.14529) (xy 96.921067 -237.097506) (xy 96.940358 -237.05223) (xy 96.966661 -237.010634)
			(xy 96.999296 -236.973797) (xy 97.037417 -236.942672) (xy 97.080038 -236.918065) (xy 97.126054 -236.900613)
			(xy 97.174273 -236.890769) (xy 97.223448 -236.888788) (xy 97.272303 -236.89472) (xy 97.319574 -236.908412)
			(xy 97.364036 -236.92951) (xy 97.404539 -236.957466) (xy 97.440032 -236.991558) (xy 97.469597 -237.030902)
			(xy 97.492468 -237.074479) (xy 97.508052 -237.12116) (xy 97.515947 -237.169737) (xy 97.516442 -237.194344)
			(xy 97.84513 -237.194344) (xy 97.84909 -237.14529) (xy 97.860867 -237.097506) (xy 97.880158 -237.05223)
			(xy 97.906461 -237.010634) (xy 97.939096 -236.973797) (xy 97.977217 -236.942672) (xy 98.019838 -236.918065)
			(xy 98.065854 -236.900613) (xy 98.114073 -236.890769) (xy 98.163248 -236.888788) (xy 98.212103 -236.89472)
			(xy 98.259374 -236.908412) (xy 98.303836 -236.92951) (xy 98.344339 -236.957466) (xy 98.379832 -236.991558)
			(xy 98.409397 -237.030902) (xy 98.432268 -237.074479) (xy 98.447852 -237.12116) (xy 98.455747 -237.169737)
			(xy 98.456242 -237.194344) (xy 98.785184 -237.194344) (xy 98.789144 -237.14529) (xy 98.800921 -237.097506)
			(xy 98.820212 -237.05223) (xy 98.846515 -237.010634) (xy 98.87915 -236.973797) (xy 98.917271 -236.942672)
			(xy 98.959892 -236.918065) (xy 99.005908 -236.900613) (xy 99.054127 -236.890769) (xy 99.103302 -236.888788)
			(xy 99.152157 -236.89472) (xy 99.199428 -236.908412) (xy 99.24389 -236.92951) (xy 99.284393 -236.957466)
			(xy 99.319886 -236.991558) (xy 99.349451 -237.030902) (xy 99.372322 -237.074479) (xy 99.387906 -237.12116)
			(xy 99.395801 -237.169737) (xy 99.396296 -237.194344) (xy 99.725238 -237.194344) (xy 99.729198 -237.14529)
			(xy 99.740975 -237.097506) (xy 99.760266 -237.05223) (xy 99.786569 -237.010634) (xy 99.819204 -236.973797)
			(xy 99.857325 -236.942672) (xy 99.899946 -236.918065) (xy 99.945962 -236.900613) (xy 99.994181 -236.890769)
			(xy 100.043356 -236.888788) (xy 100.092211 -236.89472) (xy 100.139482 -236.908412) (xy 100.183944 -236.92951)
			(xy 100.224447 -236.957466) (xy 100.25994 -236.991558) (xy 100.289505 -237.030902) (xy 100.312376 -237.074479)
			(xy 100.32796 -237.12116) (xy 100.335855 -237.169737) (xy 100.33635 -237.194344) (xy 100.665292 -237.194344)
			(xy 100.669252 -237.14529) (xy 100.681029 -237.097506) (xy 100.70032 -237.05223) (xy 100.726623 -237.010634)
			(xy 100.759258 -236.973797) (xy 100.797379 -236.942672) (xy 100.84 -236.918065) (xy 100.886016 -236.900613)
			(xy 100.934235 -236.890769) (xy 100.98341 -236.888788) (xy 101.032265 -236.89472) (xy 101.079536 -236.908412)
			(xy 101.123998 -236.92951) (xy 101.164501 -236.957466) (xy 101.199994 -236.991558) (xy 101.229559 -237.030902)
			(xy 101.25243 -237.074479) (xy 101.268014 -237.12116) (xy 101.275909 -237.169737) (xy 101.276404 -237.194344)
			(xy 101.605346 -237.194344) (xy 101.609306 -237.14529) (xy 101.621083 -237.097506) (xy 101.640374 -237.05223)
			(xy 101.666677 -237.010634) (xy 101.699312 -236.973797) (xy 101.737433 -236.942672) (xy 101.780054 -236.918065)
			(xy 101.82607 -236.900613) (xy 101.874289 -236.890769) (xy 101.923464 -236.888788) (xy 101.972319 -236.89472)
			(xy 102.01959 -236.908412) (xy 102.064052 -236.92951) (xy 102.104555 -236.957466) (xy 102.140048 -236.991558)
			(xy 102.169613 -237.030902) (xy 102.192484 -237.074479) (xy 102.208068 -237.12116) (xy 102.215963 -237.169737)
			(xy 102.216458 -237.194344) (xy 102.545146 -237.194344) (xy 102.549106 -237.14529) (xy 102.560883 -237.097506)
			(xy 102.580174 -237.05223) (xy 102.606477 -237.010634) (xy 102.639112 -236.973797) (xy 102.677233 -236.942672)
			(xy 102.719854 -236.918065) (xy 102.76587 -236.900613) (xy 102.814089 -236.890769) (xy 102.863264 -236.888788)
			(xy 102.912119 -236.89472) (xy 102.95939 -236.908412) (xy 103.003852 -236.92951) (xy 103.044355 -236.957466)
			(xy 103.079848 -236.991558) (xy 103.109413 -237.030902) (xy 103.132284 -237.074479) (xy 103.147868 -237.12116)
			(xy 103.155763 -237.169737) (xy 103.156258 -237.194344) (xy 103.4852 -237.194344) (xy 103.48916 -237.14529)
			(xy 103.500937 -237.097506) (xy 103.520228 -237.05223) (xy 103.546531 -237.010634) (xy 103.579166 -236.973797)
			(xy 103.617287 -236.942672) (xy 103.659908 -236.918065) (xy 103.705924 -236.900613) (xy 103.754143 -236.890769)
			(xy 103.803318 -236.888788) (xy 103.852173 -236.89472) (xy 103.899444 -236.908412) (xy 103.943906 -236.92951)
			(xy 103.984409 -236.957466) (xy 104.019902 -236.991558) (xy 104.049467 -237.030902) (xy 104.072338 -237.074479)
			(xy 104.087922 -237.12116) (xy 104.095817 -237.169737) (xy 104.096312 -237.194344) (xy 104.425254 -237.194344)
			(xy 104.429214 -237.14529) (xy 104.440991 -237.097506) (xy 104.460282 -237.05223) (xy 104.486585 -237.010634)
			(xy 104.51922 -236.973797) (xy 104.557341 -236.942672) (xy 104.599962 -236.918065) (xy 104.645978 -236.900613)
			(xy 104.694197 -236.890769) (xy 104.743372 -236.888788) (xy 104.792227 -236.89472) (xy 104.839498 -236.908412)
			(xy 104.88396 -236.92951) (xy 104.924463 -236.957466) (xy 104.959956 -236.991558) (xy 104.989521 -237.030902)
			(xy 105.012392 -237.074479) (xy 105.027976 -237.12116) (xy 105.035871 -237.169737) (xy 105.036366 -237.194344)
			(xy 105.365308 -237.194344) (xy 105.369268 -237.14529) (xy 105.381045 -237.097506) (xy 105.400336 -237.05223)
			(xy 105.426639 -237.010634) (xy 105.459274 -236.973797) (xy 105.497395 -236.942672) (xy 105.540016 -236.918065)
			(xy 105.586032 -236.900613) (xy 105.634251 -236.890769) (xy 105.683426 -236.888788) (xy 105.732281 -236.89472)
			(xy 105.779552 -236.908412) (xy 105.824014 -236.92951) (xy 105.864517 -236.957466) (xy 105.90001 -236.991558)
			(xy 105.929575 -237.030902) (xy 105.952446 -237.074479) (xy 105.96803 -237.12116) (xy 105.975925 -237.169737)
			(xy 105.97642 -237.194344) (xy 106.305362 -237.194344) (xy 106.309322 -237.14529) (xy 106.321099 -237.097506)
			(xy 106.34039 -237.05223) (xy 106.366693 -237.010634) (xy 106.399328 -236.973797) (xy 106.437449 -236.942672)
			(xy 106.48007 -236.918065) (xy 106.526086 -236.900613) (xy 106.574305 -236.890769) (xy 106.62348 -236.888788)
			(xy 106.672335 -236.89472) (xy 106.719606 -236.908412) (xy 106.764068 -236.92951) (xy 106.804571 -236.957466)
			(xy 106.840064 -236.991558) (xy 106.869629 -237.030902) (xy 106.8925 -237.074479) (xy 106.908084 -237.12116)
			(xy 106.915979 -237.169737) (xy 106.916474 -237.194344) (xy 107.245162 -237.194344) (xy 107.249122 -237.14529)
			(xy 107.260899 -237.097506) (xy 107.28019 -237.05223) (xy 107.306493 -237.010634) (xy 107.339128 -236.973797)
			(xy 107.377249 -236.942672) (xy 107.41987 -236.918065) (xy 107.465886 -236.900613) (xy 107.514105 -236.890769)
			(xy 107.56328 -236.888788) (xy 107.612135 -236.89472) (xy 107.659406 -236.908412) (xy 107.703868 -236.92951)
			(xy 107.744371 -236.957466) (xy 107.779864 -236.991558) (xy 107.809429 -237.030902) (xy 107.8323 -237.074479)
			(xy 107.847884 -237.12116) (xy 107.855779 -237.169737) (xy 107.856274 -237.194344) (xy 110.065324 -237.194344)
			(xy 110.069284 -237.14529) (xy 110.081061 -237.097506) (xy 110.100352 -237.05223) (xy 110.126655 -237.010634)
			(xy 110.15929 -236.973797) (xy 110.197411 -236.942672) (xy 110.240032 -236.918065) (xy 110.286048 -236.900613)
			(xy 110.334267 -236.890769) (xy 110.383442 -236.888788) (xy 110.432297 -236.89472) (xy 110.479568 -236.908412)
			(xy 110.52403 -236.92951) (xy 110.564533 -236.957466) (xy 110.600026 -236.991558) (xy 110.629591 -237.030902)
			(xy 110.652462 -237.074479) (xy 110.668046 -237.12116) (xy 110.675941 -237.169737) (xy 110.676436 -237.194344)
			(xy 110.675941 -237.218951) (xy 110.668046 -237.267528) (xy 110.652462 -237.314209) (xy 110.629591 -237.357786)
			(xy 110.600026 -237.39713) (xy 110.564533 -237.431222) (xy 110.52403 -237.459178) (xy 110.479568 -237.480276)
			(xy 110.432297 -237.493968) (xy 110.383442 -237.4999) (xy 110.334267 -237.497919) (xy 110.286048 -237.488075)
			(xy 110.240032 -237.470623) (xy 110.197411 -237.446016) (xy 110.15929 -237.414891) (xy 110.126655 -237.378054)
			(xy 110.100352 -237.336458) (xy 110.081061 -237.291182) (xy 110.069284 -237.243398) (xy 110.065324 -237.194344)
			(xy 107.856274 -237.194344) (xy 107.855779 -237.218951) (xy 107.847884 -237.267528) (xy 107.8323 -237.314209)
			(xy 107.809429 -237.357786) (xy 107.779864 -237.39713) (xy 107.744371 -237.431222) (xy 107.703868 -237.459178)
			(xy 107.659406 -237.480276) (xy 107.612135 -237.493968) (xy 107.56328 -237.4999) (xy 107.514105 -237.497919)
			(xy 107.465886 -237.488075) (xy 107.41987 -237.470623) (xy 107.377249 -237.446016) (xy 107.339128 -237.414891)
			(xy 107.306493 -237.378054) (xy 107.28019 -237.336458) (xy 107.260899 -237.291182) (xy 107.249122 -237.243398)
			(xy 107.245162 -237.194344) (xy 106.916474 -237.194344) (xy 106.915979 -237.218951) (xy 106.908084 -237.267528)
			(xy 106.8925 -237.314209) (xy 106.869629 -237.357786) (xy 106.840064 -237.39713) (xy 106.804571 -237.431222)
			(xy 106.764068 -237.459178) (xy 106.719606 -237.480276) (xy 106.672335 -237.493968) (xy 106.62348 -237.4999)
			(xy 106.574305 -237.497919) (xy 106.526086 -237.488075) (xy 106.48007 -237.470623) (xy 106.437449 -237.446016)
			(xy 106.399328 -237.414891) (xy 106.366693 -237.378054) (xy 106.34039 -237.336458) (xy 106.321099 -237.291182)
			(xy 106.309322 -237.243398) (xy 106.305362 -237.194344) (xy 105.97642 -237.194344) (xy 105.975925 -237.218951)
			(xy 105.96803 -237.267528) (xy 105.952446 -237.314209) (xy 105.929575 -237.357786) (xy 105.90001 -237.39713)
			(xy 105.864517 -237.431222) (xy 105.824014 -237.459178) (xy 105.779552 -237.480276) (xy 105.732281 -237.493968)
			(xy 105.683426 -237.4999) (xy 105.634251 -237.497919) (xy 105.586032 -237.488075) (xy 105.540016 -237.470623)
			(xy 105.497395 -237.446016) (xy 105.459274 -237.414891) (xy 105.426639 -237.378054) (xy 105.400336 -237.336458)
			(xy 105.381045 -237.291182) (xy 105.369268 -237.243398) (xy 105.365308 -237.194344) (xy 105.036366 -237.194344)
			(xy 105.035871 -237.218951) (xy 105.027976 -237.267528) (xy 105.012392 -237.314209) (xy 104.989521 -237.357786)
			(xy 104.959956 -237.39713) (xy 104.924463 -237.431222) (xy 104.88396 -237.459178) (xy 104.839498 -237.480276)
			(xy 104.792227 -237.493968) (xy 104.743372 -237.4999) (xy 104.694197 -237.497919) (xy 104.645978 -237.488075)
			(xy 104.599962 -237.470623) (xy 104.557341 -237.446016) (xy 104.51922 -237.414891) (xy 104.486585 -237.378054)
			(xy 104.460282 -237.336458) (xy 104.440991 -237.291182) (xy 104.429214 -237.243398) (xy 104.425254 -237.194344)
			(xy 104.096312 -237.194344) (xy 104.095817 -237.218951) (xy 104.087922 -237.267528) (xy 104.072338 -237.314209)
			(xy 104.049467 -237.357786) (xy 104.019902 -237.39713) (xy 103.984409 -237.431222) (xy 103.943906 -237.459178)
			(xy 103.899444 -237.480276) (xy 103.852173 -237.493968) (xy 103.803318 -237.4999) (xy 103.754143 -237.497919)
			(xy 103.705924 -237.488075) (xy 103.659908 -237.470623) (xy 103.617287 -237.446016) (xy 103.579166 -237.414891)
			(xy 103.546531 -237.378054) (xy 103.520228 -237.336458) (xy 103.500937 -237.291182) (xy 103.48916 -237.243398)
			(xy 103.4852 -237.194344) (xy 103.156258 -237.194344) (xy 103.155763 -237.218951) (xy 103.147868 -237.267528)
			(xy 103.132284 -237.314209) (xy 103.109413 -237.357786) (xy 103.079848 -237.39713) (xy 103.044355 -237.431222)
			(xy 103.003852 -237.459178) (xy 102.95939 -237.480276) (xy 102.912119 -237.493968) (xy 102.863264 -237.4999)
			(xy 102.814089 -237.497919) (xy 102.76587 -237.488075) (xy 102.719854 -237.470623) (xy 102.677233 -237.446016)
			(xy 102.639112 -237.414891) (xy 102.606477 -237.378054) (xy 102.580174 -237.336458) (xy 102.560883 -237.291182)
			(xy 102.549106 -237.243398) (xy 102.545146 -237.194344) (xy 102.216458 -237.194344) (xy 102.215963 -237.218951)
			(xy 102.208068 -237.267528) (xy 102.192484 -237.314209) (xy 102.169613 -237.357786) (xy 102.140048 -237.39713)
			(xy 102.104555 -237.431222) (xy 102.064052 -237.459178) (xy 102.01959 -237.480276) (xy 101.972319 -237.493968)
			(xy 101.923464 -237.4999) (xy 101.874289 -237.497919) (xy 101.82607 -237.488075) (xy 101.780054 -237.470623)
			(xy 101.737433 -237.446016) (xy 101.699312 -237.414891) (xy 101.666677 -237.378054) (xy 101.640374 -237.336458)
			(xy 101.621083 -237.291182) (xy 101.609306 -237.243398) (xy 101.605346 -237.194344) (xy 101.276404 -237.194344)
			(xy 101.275909 -237.218951) (xy 101.268014 -237.267528) (xy 101.25243 -237.314209) (xy 101.229559 -237.357786)
			(xy 101.199994 -237.39713) (xy 101.164501 -237.431222) (xy 101.123998 -237.459178) (xy 101.079536 -237.480276)
			(xy 101.032265 -237.493968) (xy 100.98341 -237.4999) (xy 100.934235 -237.497919) (xy 100.886016 -237.488075)
			(xy 100.84 -237.470623) (xy 100.797379 -237.446016) (xy 100.759258 -237.414891) (xy 100.726623 -237.378054)
			(xy 100.70032 -237.336458) (xy 100.681029 -237.291182) (xy 100.669252 -237.243398) (xy 100.665292 -237.194344)
			(xy 100.33635 -237.194344) (xy 100.335855 -237.218951) (xy 100.32796 -237.267528) (xy 100.312376 -237.314209)
			(xy 100.289505 -237.357786) (xy 100.25994 -237.39713) (xy 100.224447 -237.431222) (xy 100.183944 -237.459178)
			(xy 100.139482 -237.480276) (xy 100.092211 -237.493968) (xy 100.043356 -237.4999) (xy 99.994181 -237.497919)
			(xy 99.945962 -237.488075) (xy 99.899946 -237.470623) (xy 99.857325 -237.446016) (xy 99.819204 -237.414891)
			(xy 99.786569 -237.378054) (xy 99.760266 -237.336458) (xy 99.740975 -237.291182) (xy 99.729198 -237.243398)
			(xy 99.725238 -237.194344) (xy 99.396296 -237.194344) (xy 99.395801 -237.218951) (xy 99.387906 -237.267528)
			(xy 99.372322 -237.314209) (xy 99.349451 -237.357786) (xy 99.319886 -237.39713) (xy 99.284393 -237.431222)
			(xy 99.24389 -237.459178) (xy 99.199428 -237.480276) (xy 99.152157 -237.493968) (xy 99.103302 -237.4999)
			(xy 99.054127 -237.497919) (xy 99.005908 -237.488075) (xy 98.959892 -237.470623) (xy 98.917271 -237.446016)
			(xy 98.87915 -237.414891) (xy 98.846515 -237.378054) (xy 98.820212 -237.336458) (xy 98.800921 -237.291182)
			(xy 98.789144 -237.243398) (xy 98.785184 -237.194344) (xy 98.456242 -237.194344) (xy 98.455747 -237.218951)
			(xy 98.447852 -237.267528) (xy 98.432268 -237.314209) (xy 98.409397 -237.357786) (xy 98.379832 -237.39713)
			(xy 98.344339 -237.431222) (xy 98.303836 -237.459178) (xy 98.259374 -237.480276) (xy 98.212103 -237.493968)
			(xy 98.163248 -237.4999) (xy 98.114073 -237.497919) (xy 98.065854 -237.488075) (xy 98.019838 -237.470623)
			(xy 97.977217 -237.446016) (xy 97.939096 -237.414891) (xy 97.906461 -237.378054) (xy 97.880158 -237.336458)
			(xy 97.860867 -237.291182) (xy 97.84909 -237.243398) (xy 97.84513 -237.194344) (xy 97.516442 -237.194344)
			(xy 97.515947 -237.218951) (xy 97.508052 -237.267528) (xy 97.492468 -237.314209) (xy 97.469597 -237.357786)
			(xy 97.440032 -237.39713) (xy 97.404539 -237.431222) (xy 97.364036 -237.459178) (xy 97.319574 -237.480276)
			(xy 97.272303 -237.493968) (xy 97.223448 -237.4999) (xy 97.174273 -237.497919) (xy 97.126054 -237.488075)
			(xy 97.080038 -237.470623) (xy 97.037417 -237.446016) (xy 96.999296 -237.414891) (xy 96.966661 -237.378054)
			(xy 96.940358 -237.336458) (xy 96.921067 -237.291182) (xy 96.90929 -237.243398) (xy 96.90533 -237.194344)
			(xy 96.576388 -237.194344) (xy 96.575893 -237.218951) (xy 96.567998 -237.267528) (xy 96.552414 -237.314209)
			(xy 96.529543 -237.357786) (xy 96.499978 -237.39713) (xy 96.464485 -237.431222) (xy 96.423982 -237.459178)
			(xy 96.37952 -237.480276) (xy 96.332249 -237.493968) (xy 96.283394 -237.4999) (xy 96.234219 -237.497919)
			(xy 96.186 -237.488075) (xy 96.139984 -237.470623) (xy 96.097363 -237.446016) (xy 96.059242 -237.414891)
			(xy 96.026607 -237.378054) (xy 96.000304 -237.336458) (xy 95.981013 -237.291182) (xy 95.969236 -237.243398)
			(xy 95.965276 -237.194344) (xy 95.646748 -237.194344) (xy 95.646236 -237.21979) (xy 95.638072 -237.270024)
			(xy 95.621956 -237.318298) (xy 95.598305 -237.363361) (xy 95.567732 -237.404047) (xy 95.531028 -237.439302)
			(xy 95.489144 -237.468212) (xy 95.443165 -237.490029) (xy 95.394281 -237.504189) (xy 95.34376 -237.510323)
			(xy 95.292908 -237.508274) (xy 95.243044 -237.498094) (xy 95.195458 -237.480047) (xy 95.151384 -237.454601)
			(xy 95.111962 -237.422414) (xy 95.078214 -237.38432) (xy 95.051013 -237.341306) (xy 95.031065 -237.294486)
			(xy 95.018886 -237.245072) (xy 95.014791 -237.194344) (xy 94.706694 -237.194344) (xy 94.706182 -237.21979)
			(xy 94.698018 -237.270024) (xy 94.681902 -237.318298) (xy 94.658251 -237.363361) (xy 94.627678 -237.404047)
			(xy 94.590974 -237.439302) (xy 94.54909 -237.468212) (xy 94.503111 -237.490029) (xy 94.454227 -237.504189)
			(xy 94.403706 -237.510323) (xy 94.352854 -237.508274) (xy 94.30299 -237.498094) (xy 94.255404 -237.480047)
			(xy 94.21133 -237.454601) (xy 94.171908 -237.422414) (xy 94.13816 -237.38432) (xy 94.110959 -237.341306)
			(xy 94.091011 -237.294486) (xy 94.078832 -237.245072) (xy 94.074737 -237.194344) (xy 93.756226 -237.194344)
			(xy 93.755731 -237.218951) (xy 93.747836 -237.267528) (xy 93.732252 -237.314209) (xy 93.709381 -237.357786)
			(xy 93.679816 -237.39713) (xy 93.644323 -237.431222) (xy 93.60382 -237.459178) (xy 93.559358 -237.480276)
			(xy 93.512087 -237.493968) (xy 93.463232 -237.4999) (xy 93.414057 -237.497919) (xy 93.365838 -237.488075)
			(xy 93.319822 -237.470623) (xy 93.277201 -237.446016) (xy 93.23908 -237.414891) (xy 93.206445 -237.378054)
			(xy 93.180142 -237.336458) (xy 93.160851 -237.291182) (xy 93.149074 -237.243398) (xy 93.145114 -237.194344)
			(xy 92.82684 -237.194344) (xy 92.826328 -237.21979) (xy 92.818164 -237.270024) (xy 92.802048 -237.318298)
			(xy 92.778397 -237.363361) (xy 92.747824 -237.404047) (xy 92.71112 -237.439302) (xy 92.669236 -237.468212)
			(xy 92.623257 -237.490029) (xy 92.574373 -237.504189) (xy 92.523852 -237.510323) (xy 92.473 -237.508274)
			(xy 92.423136 -237.498094) (xy 92.37555 -237.480047) (xy 92.331476 -237.454601) (xy 92.292054 -237.422414)
			(xy 92.258306 -237.38432) (xy 92.231105 -237.341306) (xy 92.211157 -237.294486) (xy 92.198978 -237.245072)
			(xy 92.194883 -237.194344) (xy 91.876372 -237.194344) (xy 91.875877 -237.218951) (xy 91.867982 -237.267528)
			(xy 91.852398 -237.314209) (xy 91.829527 -237.357786) (xy 91.799962 -237.39713) (xy 91.764469 -237.431222)
			(xy 91.723966 -237.459178) (xy 91.679504 -237.480276) (xy 91.632233 -237.493968) (xy 91.583378 -237.4999)
			(xy 91.534203 -237.497919) (xy 91.485984 -237.488075) (xy 91.439968 -237.470623) (xy 91.397347 -237.446016)
			(xy 91.359226 -237.414891) (xy 91.326591 -237.378054) (xy 91.300288 -237.336458) (xy 91.280997 -237.291182)
			(xy 91.26922 -237.243398) (xy 91.26526 -237.194344) (xy 90.946732 -237.194344) (xy 90.94622 -237.21979)
			(xy 90.938056 -237.270024) (xy 90.92194 -237.318298) (xy 90.898289 -237.363361) (xy 90.867716 -237.404047)
			(xy 90.831012 -237.439302) (xy 90.789128 -237.468212) (xy 90.743149 -237.490029) (xy 90.694265 -237.504189)
			(xy 90.643744 -237.510323) (xy 90.592892 -237.508274) (xy 90.543028 -237.498094) (xy 90.495442 -237.480047)
			(xy 90.451368 -237.454601) (xy 90.411946 -237.422414) (xy 90.378198 -237.38432) (xy 90.350997 -237.341306)
			(xy 90.331049 -237.294486) (xy 90.31887 -237.245072) (xy 90.314775 -237.194344) (xy 89.995849 -237.194344)
			(xy 89.995849 -237.218546) (xy 89.988187 -237.266415) (xy 89.973057 -237.312472) (xy 89.950839 -237.355559)
			(xy 89.922091 -237.394594) (xy 89.887535 -237.428596) (xy 89.848041 -237.45671) (xy 89.8046 -237.478229)
			(xy 89.758305 -237.492613) (xy 89.73439 -237.496604) (xy 89.715594 -237.499398) (xy 89.690956 -237.527846)
			(xy 89.690956 -237.692692) (xy 89.691131 -237.699422) (xy 89.694614 -237.712422) (xy 89.697814 -237.718346)
			(xy 89.702132 -237.725458) (xy 89.708343 -237.73634) (xy 89.719905 -237.758573) (xy 89.725246 -237.769908)
			(xy 89.738454 -237.800896) (xy 89.743534 -237.81385) (xy 89.765378 -237.830868) (xy 89.867486 -237.844076)
			(xy 89.874224 -237.844658) (xy 89.887606 -237.842735) (xy 89.893902 -237.840266) (xy 89.900506 -237.837472)
			(xy 89.91092 -237.829344) (xy 89.914984 -237.823756) (xy 89.92948 -237.804788) (xy 89.963372 -237.771169)
			(xy 90.002081 -237.743233) (xy 90.044665 -237.721659) (xy 90.090088 -237.706973) (xy 90.137241 -237.699532)
			(xy 90.16111 -237.699042) (xy 90.186361 -237.699564) (xy 90.236173 -237.707878) (xy 90.283938 -237.724277)
			(xy 90.328352 -237.748314) (xy 90.368204 -237.779333) (xy 90.402407 -237.816489) (xy 90.430028 -237.858767)
			(xy 90.450314 -237.905015) (xy 90.462711 -237.953971) (xy 90.466881 -238.0043) (xy 90.466877 -238.00435)
			(xy 90.784675 -238.00435) (xy 90.78877 -237.953622) (xy 90.800949 -237.904208) (xy 90.820897 -237.857388)
			(xy 90.848098 -237.814374) (xy 90.881846 -237.77628) (xy 90.921268 -237.744093) (xy 90.965342 -237.718647)
			(xy 91.012928 -237.7006) (xy 91.062792 -237.69042) (xy 91.113644 -237.688371) (xy 91.164165 -237.694505)
			(xy 91.213049 -237.708665) (xy 91.259028 -237.730482) (xy 91.300912 -237.759392) (xy 91.337616 -237.794647)
			(xy 91.368189 -237.835333) (xy 91.39184 -237.880396) (xy 91.407956 -237.92867) (xy 91.41612 -237.978904)
			(xy 91.416632 -238.00435) (xy 91.724729 -238.00435) (xy 91.728824 -237.953622) (xy 91.741003 -237.904208)
			(xy 91.760951 -237.857388) (xy 91.788152 -237.814374) (xy 91.8219 -237.77628) (xy 91.861322 -237.744093)
			(xy 91.905396 -237.718647) (xy 91.952982 -237.7006) (xy 92.002846 -237.69042) (xy 92.053698 -237.688371)
			(xy 92.104219 -237.694505) (xy 92.153103 -237.708665) (xy 92.199082 -237.730482) (xy 92.240966 -237.759392)
			(xy 92.27767 -237.794647) (xy 92.308243 -237.835333) (xy 92.331894 -237.880396) (xy 92.34801 -237.92867)
			(xy 92.356174 -237.978904) (xy 92.356686 -238.00435) (xy 92.675214 -238.00435) (xy 92.679174 -237.955296)
			(xy 92.690951 -237.907512) (xy 92.710242 -237.862236) (xy 92.736545 -237.82064) (xy 92.76918 -237.783803)
			(xy 92.807301 -237.752678) (xy 92.849922 -237.728071) (xy 92.895938 -237.710619) (xy 92.944157 -237.700775)
			(xy 92.993332 -237.698794) (xy 93.042187 -237.704726) (xy 93.089458 -237.718418) (xy 93.13392 -237.739516)
			(xy 93.174423 -237.767472) (xy 93.209916 -237.801564) (xy 93.239481 -237.840908) (xy 93.262352 -237.884485)
			(xy 93.277936 -237.931166) (xy 93.285831 -237.979743) (xy 93.286326 -238.00435) (xy 93.604837 -238.00435)
			(xy 93.608932 -237.953622) (xy 93.621111 -237.904208) (xy 93.641059 -237.857388) (xy 93.66826 -237.814374)
			(xy 93.702008 -237.77628) (xy 93.74143 -237.744093) (xy 93.785504 -237.718647) (xy 93.83309 -237.7006)
			(xy 93.882954 -237.69042) (xy 93.933806 -237.688371) (xy 93.984327 -237.694505) (xy 94.033211 -237.708665)
			(xy 94.07919 -237.730482) (xy 94.121074 -237.759392) (xy 94.157778 -237.794647) (xy 94.188351 -237.835333)
			(xy 94.212002 -237.880396) (xy 94.228118 -237.92867) (xy 94.236282 -237.978904) (xy 94.236794 -238.00435)
			(xy 94.555322 -238.00435) (xy 94.559282 -237.955296) (xy 94.571059 -237.907512) (xy 94.59035 -237.862236)
			(xy 94.616653 -237.82064) (xy 94.649288 -237.783803) (xy 94.687409 -237.752678) (xy 94.73003 -237.728071)
			(xy 94.776046 -237.710619) (xy 94.824265 -237.700775) (xy 94.87344 -237.698794) (xy 94.922295 -237.704726)
			(xy 94.969566 -237.718418) (xy 95.014028 -237.739516) (xy 95.054531 -237.767472) (xy 95.090024 -237.801564)
			(xy 95.119589 -237.840908) (xy 95.14246 -237.884485) (xy 95.158044 -237.931166) (xy 95.165939 -237.979743)
			(xy 95.166434 -238.00435) (xy 95.484691 -238.00435) (xy 95.488786 -237.953622) (xy 95.500965 -237.904208)
			(xy 95.520913 -237.857388) (xy 95.548114 -237.814374) (xy 95.581862 -237.77628) (xy 95.621284 -237.744093)
			(xy 95.665358 -237.718647) (xy 95.712944 -237.7006) (xy 95.762808 -237.69042) (xy 95.81366 -237.688371)
			(xy 95.864181 -237.694505) (xy 95.913065 -237.708665) (xy 95.959044 -237.730482) (xy 96.000928 -237.759392)
			(xy 96.037632 -237.794647) (xy 96.068205 -237.835333) (xy 96.091856 -237.880396) (xy 96.107972 -237.92867)
			(xy 96.116136 -237.978904) (xy 96.116648 -238.00435) (xy 96.435176 -238.00435) (xy 96.439136 -237.955296)
			(xy 96.450913 -237.907512) (xy 96.470204 -237.862236) (xy 96.496507 -237.82064) (xy 96.529142 -237.783803)
			(xy 96.567263 -237.752678) (xy 96.609884 -237.728071) (xy 96.6559 -237.710619) (xy 96.704119 -237.700775)
			(xy 96.753294 -237.698794) (xy 96.802149 -237.704726) (xy 96.84942 -237.718418) (xy 96.893882 -237.739516)
			(xy 96.934385 -237.767472) (xy 96.969878 -237.801564) (xy 96.999443 -237.840908) (xy 97.022314 -237.884485)
			(xy 97.037898 -237.931166) (xy 97.045793 -237.979743) (xy 97.046288 -238.00435) (xy 97.37523 -238.00435)
			(xy 97.37919 -237.955296) (xy 97.390967 -237.907512) (xy 97.410258 -237.862236) (xy 97.436561 -237.82064)
			(xy 97.469196 -237.783803) (xy 97.507317 -237.752678) (xy 97.549938 -237.728071) (xy 97.595954 -237.710619)
			(xy 97.644173 -237.700775) (xy 97.693348 -237.698794) (xy 97.742203 -237.704726) (xy 97.789474 -237.718418)
			(xy 97.833936 -237.739516) (xy 97.874439 -237.767472) (xy 97.909932 -237.801564) (xy 97.939497 -237.840908)
			(xy 97.962368 -237.884485) (xy 97.977952 -237.931166) (xy 97.985847 -237.979743) (xy 97.986342 -238.00435)
			(xy 98.315284 -238.00435) (xy 98.319244 -237.955296) (xy 98.331021 -237.907512) (xy 98.350312 -237.862236)
			(xy 98.376615 -237.82064) (xy 98.40925 -237.783803) (xy 98.447371 -237.752678) (xy 98.489992 -237.728071)
			(xy 98.536008 -237.710619) (xy 98.584227 -237.700775) (xy 98.633402 -237.698794) (xy 98.682257 -237.704726)
			(xy 98.729528 -237.718418) (xy 98.77399 -237.739516) (xy 98.814493 -237.767472) (xy 98.849986 -237.801564)
			(xy 98.879551 -237.840908) (xy 98.902422 -237.884485) (xy 98.918006 -237.931166) (xy 98.925901 -237.979743)
			(xy 98.926396 -238.00435) (xy 99.255338 -238.00435) (xy 99.259298 -237.955296) (xy 99.271075 -237.907512)
			(xy 99.290366 -237.862236) (xy 99.316669 -237.82064) (xy 99.349304 -237.783803) (xy 99.387425 -237.752678)
			(xy 99.430046 -237.728071) (xy 99.476062 -237.710619) (xy 99.524281 -237.700775) (xy 99.573456 -237.698794)
			(xy 99.622311 -237.704726) (xy 99.669582 -237.718418) (xy 99.714044 -237.739516) (xy 99.754547 -237.767472)
			(xy 99.79004 -237.801564) (xy 99.819605 -237.840908) (xy 99.842476 -237.884485) (xy 99.85806 -237.931166)
			(xy 99.865955 -237.979743) (xy 99.86645 -238.00435) (xy 100.195138 -238.00435) (xy 100.199098 -237.955296)
			(xy 100.210875 -237.907512) (xy 100.230166 -237.862236) (xy 100.256469 -237.82064) (xy 100.289104 -237.783803)
			(xy 100.327225 -237.752678) (xy 100.369846 -237.728071) (xy 100.415862 -237.710619) (xy 100.464081 -237.700775)
			(xy 100.513256 -237.698794) (xy 100.562111 -237.704726) (xy 100.609382 -237.718418) (xy 100.653844 -237.739516)
			(xy 100.694347 -237.767472) (xy 100.72984 -237.801564) (xy 100.759405 -237.840908) (xy 100.782276 -237.884485)
			(xy 100.79786 -237.931166) (xy 100.805755 -237.979743) (xy 100.80625 -238.00435) (xy 101.135192 -238.00435)
			(xy 101.139152 -237.955296) (xy 101.150929 -237.907512) (xy 101.17022 -237.862236) (xy 101.196523 -237.82064)
			(xy 101.229158 -237.783803) (xy 101.267279 -237.752678) (xy 101.3099 -237.728071) (xy 101.355916 -237.710619)
			(xy 101.404135 -237.700775) (xy 101.45331 -237.698794) (xy 101.502165 -237.704726) (xy 101.549436 -237.718418)
			(xy 101.593898 -237.739516) (xy 101.634401 -237.767472) (xy 101.669894 -237.801564) (xy 101.699459 -237.840908)
			(xy 101.72233 -237.884485) (xy 101.737914 -237.931166) (xy 101.745809 -237.979743) (xy 101.746304 -238.00435)
			(xy 102.075246 -238.00435) (xy 102.079206 -237.955296) (xy 102.090983 -237.907512) (xy 102.110274 -237.862236)
			(xy 102.136577 -237.82064) (xy 102.169212 -237.783803) (xy 102.207333 -237.752678) (xy 102.249954 -237.728071)
			(xy 102.29597 -237.710619) (xy 102.344189 -237.700775) (xy 102.393364 -237.698794) (xy 102.442219 -237.704726)
			(xy 102.48949 -237.718418) (xy 102.533952 -237.739516) (xy 102.574455 -237.767472) (xy 102.609948 -237.801564)
			(xy 102.639513 -237.840908) (xy 102.662384 -237.884485) (xy 102.677968 -237.931166) (xy 102.685863 -237.979743)
			(xy 102.686358 -238.00435) (xy 103.0153 -238.00435) (xy 103.01926 -237.955296) (xy 103.031037 -237.907512)
			(xy 103.050328 -237.862236) (xy 103.076631 -237.82064) (xy 103.109266 -237.783803) (xy 103.147387 -237.752678)
			(xy 103.190008 -237.728071) (xy 103.236024 -237.710619) (xy 103.284243 -237.700775) (xy 103.333418 -237.698794)
			(xy 103.382273 -237.704726) (xy 103.429544 -237.718418) (xy 103.474006 -237.739516) (xy 103.514509 -237.767472)
			(xy 103.550002 -237.801564) (xy 103.579567 -237.840908) (xy 103.602438 -237.884485) (xy 103.618022 -237.931166)
			(xy 103.625917 -237.979743) (xy 103.626412 -238.00435) (xy 103.955354 -238.00435) (xy 103.959314 -237.955296)
			(xy 103.971091 -237.907512) (xy 103.990382 -237.862236) (xy 104.016685 -237.82064) (xy 104.04932 -237.783803)
			(xy 104.087441 -237.752678) (xy 104.130062 -237.728071) (xy 104.176078 -237.710619) (xy 104.224297 -237.700775)
			(xy 104.273472 -237.698794) (xy 104.322327 -237.704726) (xy 104.369598 -237.718418) (xy 104.41406 -237.739516)
			(xy 104.454563 -237.767472) (xy 104.490056 -237.801564) (xy 104.519621 -237.840908) (xy 104.542492 -237.884485)
			(xy 104.558076 -237.931166) (xy 104.565971 -237.979743) (xy 104.566466 -238.00435) (xy 104.895154 -238.00435)
			(xy 104.899114 -237.955296) (xy 104.910891 -237.907512) (xy 104.930182 -237.862236) (xy 104.956485 -237.82064)
			(xy 104.98912 -237.783803) (xy 105.027241 -237.752678) (xy 105.069862 -237.728071) (xy 105.115878 -237.710619)
			(xy 105.164097 -237.700775) (xy 105.213272 -237.698794) (xy 105.262127 -237.704726) (xy 105.309398 -237.718418)
			(xy 105.35386 -237.739516) (xy 105.394363 -237.767472) (xy 105.429856 -237.801564) (xy 105.459421 -237.840908)
			(xy 105.482292 -237.884485) (xy 105.497876 -237.931166) (xy 105.505771 -237.979743) (xy 105.506266 -238.00435)
			(xy 105.824777 -238.00435) (xy 105.828872 -237.953622) (xy 105.841051 -237.904208) (xy 105.860999 -237.857388)
			(xy 105.8882 -237.814374) (xy 105.921948 -237.77628) (xy 105.96137 -237.744093) (xy 106.005444 -237.718647)
			(xy 106.05303 -237.7006) (xy 106.102894 -237.69042) (xy 106.153746 -237.688371) (xy 106.204267 -237.694505)
			(xy 106.253151 -237.708665) (xy 106.29913 -237.730482) (xy 106.341014 -237.759392) (xy 106.377718 -237.794647)
			(xy 106.408291 -237.835333) (xy 106.431942 -237.880396) (xy 106.448058 -237.92867) (xy 106.456222 -237.978904)
			(xy 106.456734 -238.00435) (xy 106.764831 -238.00435) (xy 106.768926 -237.953622) (xy 106.781105 -237.904208)
			(xy 106.801053 -237.857388) (xy 106.828254 -237.814374) (xy 106.862002 -237.77628) (xy 106.901424 -237.744093)
			(xy 106.945498 -237.718647) (xy 106.993084 -237.7006) (xy 107.042948 -237.69042) (xy 107.0938 -237.688371)
			(xy 107.144321 -237.694505) (xy 107.193205 -237.708665) (xy 107.239184 -237.730482) (xy 107.281068 -237.759392)
			(xy 107.317772 -237.794647) (xy 107.348345 -237.835333) (xy 107.371996 -237.880396) (xy 107.388112 -237.92867)
			(xy 107.396276 -237.978904) (xy 107.396788 -238.00435) (xy 107.715316 -238.00435) (xy 107.719276 -237.955296)
			(xy 107.731053 -237.907512) (xy 107.750344 -237.862236) (xy 107.776647 -237.82064) (xy 107.809282 -237.783803)
			(xy 107.847403 -237.752678) (xy 107.890024 -237.728071) (xy 107.93604 -237.710619) (xy 107.984259 -237.700775)
			(xy 108.033434 -237.698794) (xy 108.082289 -237.704726) (xy 108.12956 -237.718418) (xy 108.174022 -237.739516)
			(xy 108.214525 -237.767472) (xy 108.250018 -237.801564) (xy 108.279583 -237.840908) (xy 108.302454 -237.884485)
			(xy 108.318038 -237.931166) (xy 108.325933 -237.979743) (xy 108.326428 -238.00435) (xy 108.65537 -238.00435)
			(xy 108.65933 -237.955296) (xy 108.671107 -237.907512) (xy 108.690398 -237.862236) (xy 108.716701 -237.82064)
			(xy 108.749336 -237.783803) (xy 108.787457 -237.752678) (xy 108.830078 -237.728071) (xy 108.876094 -237.710619)
			(xy 108.924313 -237.700775) (xy 108.973488 -237.698794) (xy 109.022343 -237.704726) (xy 109.069614 -237.718418)
			(xy 109.114076 -237.739516) (xy 109.154579 -237.767472) (xy 109.190072 -237.801564) (xy 109.219637 -237.840908)
			(xy 109.242508 -237.884485) (xy 109.258092 -237.931166) (xy 109.265987 -237.979743) (xy 109.266482 -238.00435)
			(xy 109.59517 -238.00435) (xy 109.59913 -237.955296) (xy 109.610907 -237.907512) (xy 109.630198 -237.862236)
			(xy 109.656501 -237.82064) (xy 109.689136 -237.783803) (xy 109.727257 -237.752678) (xy 109.769878 -237.728071)
			(xy 109.815894 -237.710619) (xy 109.864113 -237.700775) (xy 109.913288 -237.698794) (xy 109.962143 -237.704726)
			(xy 110.009414 -237.718418) (xy 110.053876 -237.739516) (xy 110.094379 -237.767472) (xy 110.129872 -237.801564)
			(xy 110.159437 -237.840908) (xy 110.182308 -237.884485) (xy 110.197892 -237.931166) (xy 110.205787 -237.979743)
			(xy 110.206282 -238.00435) (xy 110.205787 -238.028957) (xy 110.197892 -238.077534) (xy 110.182308 -238.124215)
			(xy 110.159437 -238.167792) (xy 110.129872 -238.207136) (xy 110.094379 -238.241228) (xy 110.053876 -238.269184)
			(xy 110.009414 -238.290282) (xy 109.962143 -238.303974) (xy 109.913288 -238.309906) (xy 109.864113 -238.307925)
			(xy 109.815894 -238.298081) (xy 109.769878 -238.280629) (xy 109.727257 -238.256022) (xy 109.689136 -238.224897)
			(xy 109.656501 -238.18806) (xy 109.630198 -238.146464) (xy 109.610907 -238.101188) (xy 109.59913 -238.053404)
			(xy 109.59517 -238.00435) (xy 109.266482 -238.00435) (xy 109.265987 -238.028957) (xy 109.258092 -238.077534)
			(xy 109.242508 -238.124215) (xy 109.219637 -238.167792) (xy 109.190072 -238.207136) (xy 109.154579 -238.241228)
			(xy 109.114076 -238.269184) (xy 109.069614 -238.290282) (xy 109.022343 -238.303974) (xy 108.973488 -238.309906)
			(xy 108.924313 -238.307925) (xy 108.876094 -238.298081) (xy 108.830078 -238.280629) (xy 108.787457 -238.256022)
			(xy 108.749336 -238.224897) (xy 108.716701 -238.18806) (xy 108.690398 -238.146464) (xy 108.671107 -238.101188)
			(xy 108.65933 -238.053404) (xy 108.65537 -238.00435) (xy 108.326428 -238.00435) (xy 108.325933 -238.028957)
			(xy 108.318038 -238.077534) (xy 108.302454 -238.124215) (xy 108.279583 -238.167792) (xy 108.250018 -238.207136)
			(xy 108.214525 -238.241228) (xy 108.174022 -238.269184) (xy 108.12956 -238.290282) (xy 108.082289 -238.303974)
			(xy 108.033434 -238.309906) (xy 107.984259 -238.307925) (xy 107.93604 -238.298081) (xy 107.890024 -238.280629)
			(xy 107.847403 -238.256022) (xy 107.809282 -238.224897) (xy 107.776647 -238.18806) (xy 107.750344 -238.146464)
			(xy 107.731053 -238.101188) (xy 107.719276 -238.053404) (xy 107.715316 -238.00435) (xy 107.396788 -238.00435)
			(xy 107.396276 -238.029796) (xy 107.388112 -238.08003) (xy 107.371996 -238.128304) (xy 107.348345 -238.173367)
			(xy 107.317772 -238.214053) (xy 107.281068 -238.249308) (xy 107.239184 -238.278218) (xy 107.193205 -238.300035)
			(xy 107.144321 -238.314195) (xy 107.0938 -238.320329) (xy 107.042948 -238.31828) (xy 106.993084 -238.3081)
			(xy 106.945498 -238.290053) (xy 106.901424 -238.264607) (xy 106.862002 -238.23242) (xy 106.828254 -238.194326)
			(xy 106.801053 -238.151312) (xy 106.781105 -238.104492) (xy 106.768926 -238.055078) (xy 106.764831 -238.00435)
			(xy 106.456734 -238.00435) (xy 106.456222 -238.029796) (xy 106.448058 -238.08003) (xy 106.431942 -238.128304)
			(xy 106.408291 -238.173367) (xy 106.377718 -238.214053) (xy 106.341014 -238.249308) (xy 106.29913 -238.278218)
			(xy 106.253151 -238.300035) (xy 106.204267 -238.314195) (xy 106.153746 -238.320329) (xy 106.102894 -238.31828)
			(xy 106.05303 -238.3081) (xy 106.005444 -238.290053) (xy 105.96137 -238.264607) (xy 105.921948 -238.23242)
			(xy 105.8882 -238.194326) (xy 105.860999 -238.151312) (xy 105.841051 -238.104492) (xy 105.828872 -238.055078)
			(xy 105.824777 -238.00435) (xy 105.506266 -238.00435) (xy 105.505771 -238.028957) (xy 105.497876 -238.077534)
			(xy 105.482292 -238.124215) (xy 105.459421 -238.167792) (xy 105.429856 -238.207136) (xy 105.394363 -238.241228)
			(xy 105.35386 -238.269184) (xy 105.309398 -238.290282) (xy 105.262127 -238.303974) (xy 105.213272 -238.309906)
			(xy 105.164097 -238.307925) (xy 105.115878 -238.298081) (xy 105.069862 -238.280629) (xy 105.027241 -238.256022)
			(xy 104.98912 -238.224897) (xy 104.956485 -238.18806) (xy 104.930182 -238.146464) (xy 104.910891 -238.101188)
			(xy 104.899114 -238.053404) (xy 104.895154 -238.00435) (xy 104.566466 -238.00435) (xy 104.565971 -238.028957)
			(xy 104.558076 -238.077534) (xy 104.542492 -238.124215) (xy 104.519621 -238.167792) (xy 104.490056 -238.207136)
			(xy 104.454563 -238.241228) (xy 104.41406 -238.269184) (xy 104.369598 -238.290282) (xy 104.322327 -238.303974)
			(xy 104.273472 -238.309906) (xy 104.224297 -238.307925) (xy 104.176078 -238.298081) (xy 104.130062 -238.280629)
			(xy 104.087441 -238.256022) (xy 104.04932 -238.224897) (xy 104.016685 -238.18806) (xy 103.990382 -238.146464)
			(xy 103.971091 -238.101188) (xy 103.959314 -238.053404) (xy 103.955354 -238.00435) (xy 103.626412 -238.00435)
			(xy 103.625917 -238.028957) (xy 103.618022 -238.077534) (xy 103.602438 -238.124215) (xy 103.579567 -238.167792)
			(xy 103.550002 -238.207136) (xy 103.514509 -238.241228) (xy 103.474006 -238.269184) (xy 103.429544 -238.290282)
			(xy 103.382273 -238.303974) (xy 103.333418 -238.309906) (xy 103.284243 -238.307925) (xy 103.236024 -238.298081)
			(xy 103.190008 -238.280629) (xy 103.147387 -238.256022) (xy 103.109266 -238.224897) (xy 103.076631 -238.18806)
			(xy 103.050328 -238.146464) (xy 103.031037 -238.101188) (xy 103.01926 -238.053404) (xy 103.0153 -238.00435)
			(xy 102.686358 -238.00435) (xy 102.685863 -238.028957) (xy 102.677968 -238.077534) (xy 102.662384 -238.124215)
			(xy 102.639513 -238.167792) (xy 102.609948 -238.207136) (xy 102.574455 -238.241228) (xy 102.533952 -238.269184)
			(xy 102.48949 -238.290282) (xy 102.442219 -238.303974) (xy 102.393364 -238.309906) (xy 102.344189 -238.307925)
			(xy 102.29597 -238.298081) (xy 102.249954 -238.280629) (xy 102.207333 -238.256022) (xy 102.169212 -238.224897)
			(xy 102.136577 -238.18806) (xy 102.110274 -238.146464) (xy 102.090983 -238.101188) (xy 102.079206 -238.053404)
			(xy 102.075246 -238.00435) (xy 101.746304 -238.00435) (xy 101.745809 -238.028957) (xy 101.737914 -238.077534)
			(xy 101.72233 -238.124215) (xy 101.699459 -238.167792) (xy 101.669894 -238.207136) (xy 101.634401 -238.241228)
			(xy 101.593898 -238.269184) (xy 101.549436 -238.290282) (xy 101.502165 -238.303974) (xy 101.45331 -238.309906)
			(xy 101.404135 -238.307925) (xy 101.355916 -238.298081) (xy 101.3099 -238.280629) (xy 101.267279 -238.256022)
			(xy 101.229158 -238.224897) (xy 101.196523 -238.18806) (xy 101.17022 -238.146464) (xy 101.150929 -238.101188)
			(xy 101.139152 -238.053404) (xy 101.135192 -238.00435) (xy 100.80625 -238.00435) (xy 100.805755 -238.028957)
			(xy 100.79786 -238.077534) (xy 100.782276 -238.124215) (xy 100.759405 -238.167792) (xy 100.72984 -238.207136)
			(xy 100.694347 -238.241228) (xy 100.653844 -238.269184) (xy 100.609382 -238.290282) (xy 100.562111 -238.303974)
			(xy 100.513256 -238.309906) (xy 100.464081 -238.307925) (xy 100.415862 -238.298081) (xy 100.369846 -238.280629)
			(xy 100.327225 -238.256022) (xy 100.289104 -238.224897) (xy 100.256469 -238.18806) (xy 100.230166 -238.146464)
			(xy 100.210875 -238.101188) (xy 100.199098 -238.053404) (xy 100.195138 -238.00435) (xy 99.86645 -238.00435)
			(xy 99.865955 -238.028957) (xy 99.85806 -238.077534) (xy 99.842476 -238.124215) (xy 99.819605 -238.167792)
			(xy 99.79004 -238.207136) (xy 99.754547 -238.241228) (xy 99.714044 -238.269184) (xy 99.669582 -238.290282)
			(xy 99.622311 -238.303974) (xy 99.573456 -238.309906) (xy 99.524281 -238.307925) (xy 99.476062 -238.298081)
			(xy 99.430046 -238.280629) (xy 99.387425 -238.256022) (xy 99.349304 -238.224897) (xy 99.316669 -238.18806)
			(xy 99.290366 -238.146464) (xy 99.271075 -238.101188) (xy 99.259298 -238.053404) (xy 99.255338 -238.00435)
			(xy 98.926396 -238.00435) (xy 98.925901 -238.028957) (xy 98.918006 -238.077534) (xy 98.902422 -238.124215)
			(xy 98.879551 -238.167792) (xy 98.849986 -238.207136) (xy 98.814493 -238.241228) (xy 98.77399 -238.269184)
			(xy 98.729528 -238.290282) (xy 98.682257 -238.303974) (xy 98.633402 -238.309906) (xy 98.584227 -238.307925)
			(xy 98.536008 -238.298081) (xy 98.489992 -238.280629) (xy 98.447371 -238.256022) (xy 98.40925 -238.224897)
			(xy 98.376615 -238.18806) (xy 98.350312 -238.146464) (xy 98.331021 -238.101188) (xy 98.319244 -238.053404)
			(xy 98.315284 -238.00435) (xy 97.986342 -238.00435) (xy 97.985847 -238.028957) (xy 97.977952 -238.077534)
			(xy 97.962368 -238.124215) (xy 97.939497 -238.167792) (xy 97.909932 -238.207136) (xy 97.874439 -238.241228)
			(xy 97.833936 -238.269184) (xy 97.789474 -238.290282) (xy 97.742203 -238.303974) (xy 97.693348 -238.309906)
			(xy 97.644173 -238.307925) (xy 97.595954 -238.298081) (xy 97.549938 -238.280629) (xy 97.507317 -238.256022)
			(xy 97.469196 -238.224897) (xy 97.436561 -238.18806) (xy 97.410258 -238.146464) (xy 97.390967 -238.101188)
			(xy 97.37919 -238.053404) (xy 97.37523 -238.00435) (xy 97.046288 -238.00435) (xy 97.045793 -238.028957)
			(xy 97.037898 -238.077534) (xy 97.022314 -238.124215) (xy 96.999443 -238.167792) (xy 96.969878 -238.207136)
			(xy 96.934385 -238.241228) (xy 96.893882 -238.269184) (xy 96.84942 -238.290282) (xy 96.802149 -238.303974)
			(xy 96.753294 -238.309906) (xy 96.704119 -238.307925) (xy 96.6559 -238.298081) (xy 96.609884 -238.280629)
			(xy 96.567263 -238.256022) (xy 96.529142 -238.224897) (xy 96.496507 -238.18806) (xy 96.470204 -238.146464)
			(xy 96.450913 -238.101188) (xy 96.439136 -238.053404) (xy 96.435176 -238.00435) (xy 96.116648 -238.00435)
			(xy 96.116136 -238.029796) (xy 96.107972 -238.08003) (xy 96.091856 -238.128304) (xy 96.068205 -238.173367)
			(xy 96.037632 -238.214053) (xy 96.000928 -238.249308) (xy 95.959044 -238.278218) (xy 95.913065 -238.300035)
			(xy 95.864181 -238.314195) (xy 95.81366 -238.320329) (xy 95.762808 -238.31828) (xy 95.712944 -238.3081)
			(xy 95.665358 -238.290053) (xy 95.621284 -238.264607) (xy 95.581862 -238.23242) (xy 95.548114 -238.194326)
			(xy 95.520913 -238.151312) (xy 95.500965 -238.104492) (xy 95.488786 -238.055078) (xy 95.484691 -238.00435)
			(xy 95.166434 -238.00435) (xy 95.165939 -238.028957) (xy 95.158044 -238.077534) (xy 95.14246 -238.124215)
			(xy 95.119589 -238.167792) (xy 95.090024 -238.207136) (xy 95.054531 -238.241228) (xy 95.014028 -238.269184)
			(xy 94.969566 -238.290282) (xy 94.922295 -238.303974) (xy 94.87344 -238.309906) (xy 94.824265 -238.307925)
			(xy 94.776046 -238.298081) (xy 94.73003 -238.280629) (xy 94.687409 -238.256022) (xy 94.649288 -238.224897)
			(xy 94.616653 -238.18806) (xy 94.59035 -238.146464) (xy 94.571059 -238.101188) (xy 94.559282 -238.053404)
			(xy 94.555322 -238.00435) (xy 94.236794 -238.00435) (xy 94.236282 -238.029796) (xy 94.228118 -238.08003)
			(xy 94.212002 -238.128304) (xy 94.188351 -238.173367) (xy 94.157778 -238.214053) (xy 94.121074 -238.249308)
			(xy 94.07919 -238.278218) (xy 94.033211 -238.300035) (xy 93.984327 -238.314195) (xy 93.933806 -238.320329)
			(xy 93.882954 -238.31828) (xy 93.83309 -238.3081) (xy 93.785504 -238.290053) (xy 93.74143 -238.264607)
			(xy 93.702008 -238.23242) (xy 93.66826 -238.194326) (xy 93.641059 -238.151312) (xy 93.621111 -238.104492)
			(xy 93.608932 -238.055078) (xy 93.604837 -238.00435) (xy 93.286326 -238.00435) (xy 93.285831 -238.028957)
			(xy 93.277936 -238.077534) (xy 93.262352 -238.124215) (xy 93.239481 -238.167792) (xy 93.209916 -238.207136)
			(xy 93.174423 -238.241228) (xy 93.13392 -238.269184) (xy 93.089458 -238.290282) (xy 93.042187 -238.303974)
			(xy 92.993332 -238.309906) (xy 92.944157 -238.307925) (xy 92.895938 -238.298081) (xy 92.849922 -238.280629)
			(xy 92.807301 -238.256022) (xy 92.76918 -238.224897) (xy 92.736545 -238.18806) (xy 92.710242 -238.146464)
			(xy 92.690951 -238.101188) (xy 92.679174 -238.053404) (xy 92.675214 -238.00435) (xy 92.356686 -238.00435)
			(xy 92.356174 -238.029796) (xy 92.34801 -238.08003) (xy 92.331894 -238.128304) (xy 92.308243 -238.173367)
			(xy 92.27767 -238.214053) (xy 92.240966 -238.249308) (xy 92.199082 -238.278218) (xy 92.153103 -238.300035)
			(xy 92.104219 -238.314195) (xy 92.053698 -238.320329) (xy 92.002846 -238.31828) (xy 91.952982 -238.3081)
			(xy 91.905396 -238.290053) (xy 91.861322 -238.264607) (xy 91.8219 -238.23242) (xy 91.788152 -238.194326)
			(xy 91.760951 -238.151312) (xy 91.741003 -238.104492) (xy 91.728824 -238.055078) (xy 91.724729 -238.00435)
			(xy 91.416632 -238.00435) (xy 91.41612 -238.029796) (xy 91.407956 -238.08003) (xy 91.39184 -238.128304)
			(xy 91.368189 -238.173367) (xy 91.337616 -238.214053) (xy 91.300912 -238.249308) (xy 91.259028 -238.278218)
			(xy 91.213049 -238.300035) (xy 91.164165 -238.314195) (xy 91.113644 -238.320329) (xy 91.062792 -238.31828)
			(xy 91.012928 -238.3081) (xy 90.965342 -238.290053) (xy 90.921268 -238.264607) (xy 90.881846 -238.23242)
			(xy 90.848098 -238.194326) (xy 90.820897 -238.151312) (xy 90.800949 -238.104492) (xy 90.78877 -238.055078)
			(xy 90.784675 -238.00435) (xy 90.466877 -238.00435) (xy 90.462711 -238.054629) (xy 90.450314 -238.103585)
			(xy 90.430028 -238.149833) (xy 90.402407 -238.192111) (xy 90.368204 -238.229267) (xy 90.328352 -238.260286)
			(xy 90.283938 -238.284323) (xy 90.236173 -238.300722) (xy 90.186361 -238.309036) (xy 90.16111 -238.309658)
			(xy 90.137239 -238.309197) (xy 90.090081 -238.301764) (xy 90.044655 -238.287078) (xy 90.00207 -238.265496)
			(xy 89.963365 -238.237547) (xy 89.929486 -238.203911) (xy 89.914984 -238.184944) (xy 89.91092 -238.179356)
			(xy 89.900506 -238.171228) (xy 89.893902 -238.168434) (xy 89.887618 -238.165922) (xy 89.874226 -238.164004)
			(xy 89.867486 -238.164624) (xy 89.765378 -238.177832) (xy 89.743534 -238.19485) (xy 89.738454 -238.207804)
			(xy 89.729852 -238.229017) (xy 89.709633 -238.270091) (xy 89.698068 -238.289846) (xy 89.694512 -238.295688)
			(xy 89.690956 -238.308896) (xy 89.690956 -238.480854) (xy 89.715594 -238.509302) (xy 89.73439 -238.512096)
			(xy 89.758324 -238.516001) (xy 89.804633 -238.53039) (xy 89.848086 -238.551915) (xy 89.887592 -238.580037)
			(xy 89.922157 -238.614048) (xy 89.950913 -238.653094) (xy 89.973138 -238.696194) (xy 89.988272 -238.742264)
			(xy 89.995936 -238.790148) (xy 89.995936 -238.814356) (xy 90.314775 -238.814356) (xy 90.31887 -238.763628)
			(xy 90.331049 -238.714214) (xy 90.350997 -238.667394) (xy 90.378198 -238.62438) (xy 90.411946 -238.586286)
			(xy 90.451368 -238.554099) (xy 90.495442 -238.528653) (xy 90.543028 -238.510606) (xy 90.592892 -238.500426)
			(xy 90.643744 -238.498377) (xy 90.694265 -238.504511) (xy 90.743149 -238.518671) (xy 90.789128 -238.540488)
			(xy 90.831012 -238.569398) (xy 90.867716 -238.604653) (xy 90.898289 -238.645339) (xy 90.92194 -238.690402)
			(xy 90.938056 -238.738676) (xy 90.94622 -238.78891) (xy 90.946732 -238.814356) (xy 91.26526 -238.814356)
			(xy 91.26922 -238.765302) (xy 91.280997 -238.717518) (xy 91.300288 -238.672242) (xy 91.326591 -238.630646)
			(xy 91.359226 -238.593809) (xy 91.397347 -238.562684) (xy 91.439968 -238.538077) (xy 91.485984 -238.520625)
			(xy 91.534203 -238.510781) (xy 91.583378 -238.5088) (xy 91.632233 -238.514732) (xy 91.679504 -238.528424)
			(xy 91.723966 -238.549522) (xy 91.764469 -238.577478) (xy 91.799962 -238.61157) (xy 91.829527 -238.650914)
			(xy 91.852398 -238.694491) (xy 91.867982 -238.741172) (xy 91.875877 -238.789749) (xy 91.876372 -238.814356)
			(xy 92.194883 -238.814356) (xy 92.198978 -238.763628) (xy 92.211157 -238.714214) (xy 92.231105 -238.667394)
			(xy 92.258306 -238.62438) (xy 92.292054 -238.586286) (xy 92.331476 -238.554099) (xy 92.37555 -238.528653)
			(xy 92.423136 -238.510606) (xy 92.473 -238.500426) (xy 92.523852 -238.498377) (xy 92.574373 -238.504511)
			(xy 92.623257 -238.518671) (xy 92.669236 -238.540488) (xy 92.71112 -238.569398) (xy 92.747824 -238.604653)
			(xy 92.778397 -238.645339) (xy 92.802048 -238.690402) (xy 92.818164 -238.738676) (xy 92.826328 -238.78891)
			(xy 92.82684 -238.814356) (xy 93.145114 -238.814356) (xy 93.149074 -238.765302) (xy 93.160851 -238.717518)
			(xy 93.180142 -238.672242) (xy 93.206445 -238.630646) (xy 93.23908 -238.593809) (xy 93.277201 -238.562684)
			(xy 93.319822 -238.538077) (xy 93.365838 -238.520625) (xy 93.414057 -238.510781) (xy 93.463232 -238.5088)
			(xy 93.512087 -238.514732) (xy 93.559358 -238.528424) (xy 93.60382 -238.549522) (xy 93.644323 -238.577478)
			(xy 93.679816 -238.61157) (xy 93.709381 -238.650914) (xy 93.732252 -238.694491) (xy 93.747836 -238.741172)
			(xy 93.755731 -238.789749) (xy 93.756226 -238.814356) (xy 94.074737 -238.814356) (xy 94.078832 -238.763628)
			(xy 94.091011 -238.714214) (xy 94.110959 -238.667394) (xy 94.13816 -238.62438) (xy 94.171908 -238.586286)
			(xy 94.21133 -238.554099) (xy 94.255404 -238.528653) (xy 94.30299 -238.510606) (xy 94.352854 -238.500426)
			(xy 94.403706 -238.498377) (xy 94.454227 -238.504511) (xy 94.503111 -238.518671) (xy 94.54909 -238.540488)
			(xy 94.590974 -238.569398) (xy 94.627678 -238.604653) (xy 94.658251 -238.645339) (xy 94.681902 -238.690402)
			(xy 94.698018 -238.738676) (xy 94.706182 -238.78891) (xy 94.706694 -238.814356) (xy 95.014791 -238.814356)
			(xy 95.018886 -238.763628) (xy 95.031065 -238.714214) (xy 95.051013 -238.667394) (xy 95.078214 -238.62438)
			(xy 95.111962 -238.586286) (xy 95.151384 -238.554099) (xy 95.195458 -238.528653) (xy 95.243044 -238.510606)
			(xy 95.292908 -238.500426) (xy 95.34376 -238.498377) (xy 95.394281 -238.504511) (xy 95.443165 -238.518671)
			(xy 95.489144 -238.540488) (xy 95.531028 -238.569398) (xy 95.567732 -238.604653) (xy 95.598305 -238.645339)
			(xy 95.621956 -238.690402) (xy 95.638072 -238.738676) (xy 95.646236 -238.78891) (xy 95.646748 -238.814356)
			(xy 95.965276 -238.814356) (xy 95.969236 -238.765302) (xy 95.981013 -238.717518) (xy 96.000304 -238.672242)
			(xy 96.026607 -238.630646) (xy 96.059242 -238.593809) (xy 96.097363 -238.562684) (xy 96.139984 -238.538077)
			(xy 96.186 -238.520625) (xy 96.234219 -238.510781) (xy 96.283394 -238.5088) (xy 96.332249 -238.514732)
			(xy 96.37952 -238.528424) (xy 96.423982 -238.549522) (xy 96.464485 -238.577478) (xy 96.499978 -238.61157)
			(xy 96.529543 -238.650914) (xy 96.552414 -238.694491) (xy 96.567998 -238.741172) (xy 96.575893 -238.789749)
			(xy 96.576388 -238.814356) (xy 98.785184 -238.814356) (xy 98.789144 -238.765302) (xy 98.800921 -238.717518)
			(xy 98.820212 -238.672242) (xy 98.846515 -238.630646) (xy 98.87915 -238.593809) (xy 98.917271 -238.562684)
			(xy 98.959892 -238.538077) (xy 99.005908 -238.520625) (xy 99.054127 -238.510781) (xy 99.103302 -238.5088)
			(xy 99.152157 -238.514732) (xy 99.199428 -238.528424) (xy 99.24389 -238.549522) (xy 99.284393 -238.577478)
			(xy 99.319886 -238.61157) (xy 99.349451 -238.650914) (xy 99.372322 -238.694491) (xy 99.387906 -238.741172)
			(xy 99.395801 -238.789749) (xy 99.396296 -238.814356) (xy 101.605346 -238.814356) (xy 101.609306 -238.765302)
			(xy 101.621083 -238.717518) (xy 101.640374 -238.672242) (xy 101.666677 -238.630646) (xy 101.699312 -238.593809)
			(xy 101.737433 -238.562684) (xy 101.780054 -238.538077) (xy 101.82607 -238.520625) (xy 101.874289 -238.510781)
			(xy 101.923464 -238.5088) (xy 101.972319 -238.514732) (xy 102.01959 -238.528424) (xy 102.064052 -238.549522)
			(xy 102.104555 -238.577478) (xy 102.140048 -238.61157) (xy 102.169613 -238.650914) (xy 102.192484 -238.694491)
			(xy 102.208068 -238.741172) (xy 102.215963 -238.789749) (xy 102.216458 -238.814356) (xy 104.425254 -238.814356)
			(xy 104.429214 -238.765302) (xy 104.440991 -238.717518) (xy 104.460282 -238.672242) (xy 104.486585 -238.630646)
			(xy 104.51922 -238.593809) (xy 104.557341 -238.562684) (xy 104.599962 -238.538077) (xy 104.645978 -238.520625)
			(xy 104.694197 -238.510781) (xy 104.743372 -238.5088) (xy 104.792227 -238.514732) (xy 104.839498 -238.528424)
			(xy 104.88396 -238.549522) (xy 104.924463 -238.577478) (xy 104.959956 -238.61157) (xy 104.989521 -238.650914)
			(xy 105.012392 -238.694491) (xy 105.027976 -238.741172) (xy 105.035871 -238.789749) (xy 105.036366 -238.814356)
			(xy 107.245162 -238.814356) (xy 107.249122 -238.765302) (xy 107.260899 -238.717518) (xy 107.28019 -238.672242)
			(xy 107.306493 -238.630646) (xy 107.339128 -238.593809) (xy 107.377249 -238.562684) (xy 107.41987 -238.538077)
			(xy 107.465886 -238.520625) (xy 107.514105 -238.510781) (xy 107.56328 -238.5088) (xy 107.612135 -238.514732)
			(xy 107.659406 -238.528424) (xy 107.703868 -238.549522) (xy 107.744371 -238.577478) (xy 107.779864 -238.61157)
			(xy 107.809429 -238.650914) (xy 107.8323 -238.694491) (xy 107.847884 -238.741172) (xy 107.855779 -238.789749)
			(xy 107.856274 -238.814356) (xy 108.174785 -238.814356) (xy 108.17888 -238.763628) (xy 108.191059 -238.714214)
			(xy 108.211007 -238.667394) (xy 108.238208 -238.62438) (xy 108.271956 -238.586286) (xy 108.311378 -238.554099)
			(xy 108.355452 -238.528653) (xy 108.403038 -238.510606) (xy 108.452902 -238.500426) (xy 108.503754 -238.498377)
			(xy 108.554275 -238.504511) (xy 108.603159 -238.518671) (xy 108.649138 -238.540488) (xy 108.691022 -238.569398)
			(xy 108.727726 -238.604653) (xy 108.758299 -238.645339) (xy 108.78195 -238.690402) (xy 108.798066 -238.738676)
			(xy 108.80623 -238.78891) (xy 108.806742 -238.814356) (xy 109.114839 -238.814356) (xy 109.118934 -238.763628)
			(xy 109.131113 -238.714214) (xy 109.151061 -238.667394) (xy 109.178262 -238.62438) (xy 109.21201 -238.586286)
			(xy 109.251432 -238.554099) (xy 109.295506 -238.528653) (xy 109.343092 -238.510606) (xy 109.392956 -238.500426)
			(xy 109.443808 -238.498377) (xy 109.494329 -238.504511) (xy 109.543213 -238.518671) (xy 109.589192 -238.540488)
			(xy 109.631076 -238.569398) (xy 109.66778 -238.604653) (xy 109.698353 -238.645339) (xy 109.722004 -238.690402)
			(xy 109.73812 -238.738676) (xy 109.746284 -238.78891) (xy 109.746796 -238.814356) (xy 110.065324 -238.814356)
			(xy 110.069284 -238.765302) (xy 110.081061 -238.717518) (xy 110.100352 -238.672242) (xy 110.126655 -238.630646)
			(xy 110.15929 -238.593809) (xy 110.197411 -238.562684) (xy 110.240032 -238.538077) (xy 110.286048 -238.520625)
			(xy 110.334267 -238.510781) (xy 110.383442 -238.5088) (xy 110.432297 -238.514732) (xy 110.479568 -238.528424)
			(xy 110.52403 -238.549522) (xy 110.564533 -238.577478) (xy 110.600026 -238.61157) (xy 110.629591 -238.650914)
			(xy 110.652462 -238.694491) (xy 110.668046 -238.741172) (xy 110.675941 -238.789749) (xy 110.676436 -238.814356)
			(xy 110.675941 -238.838963) (xy 110.668046 -238.88754) (xy 110.652462 -238.934221) (xy 110.629591 -238.977798)
			(xy 110.600026 -239.017142) (xy 110.564533 -239.051234) (xy 110.52403 -239.07919) (xy 110.479568 -239.100288)
			(xy 110.432297 -239.11398) (xy 110.383442 -239.119912) (xy 110.334267 -239.117931) (xy 110.286048 -239.108087)
			(xy 110.240032 -239.090635) (xy 110.197411 -239.066028) (xy 110.15929 -239.034903) (xy 110.126655 -238.998066)
			(xy 110.100352 -238.95647) (xy 110.081061 -238.911194) (xy 110.069284 -238.86341) (xy 110.065324 -238.814356)
			(xy 109.746796 -238.814356) (xy 109.746284 -238.839802) (xy 109.73812 -238.890036) (xy 109.722004 -238.93831)
			(xy 109.698353 -238.983373) (xy 109.66778 -239.024059) (xy 109.631076 -239.059314) (xy 109.589192 -239.088224)
			(xy 109.543213 -239.110041) (xy 109.494329 -239.124201) (xy 109.443808 -239.130335) (xy 109.392956 -239.128286)
			(xy 109.343092 -239.118106) (xy 109.295506 -239.100059) (xy 109.251432 -239.074613) (xy 109.21201 -239.042426)
			(xy 109.178262 -239.004332) (xy 109.151061 -238.961318) (xy 109.131113 -238.914498) (xy 109.118934 -238.865084)
			(xy 109.114839 -238.814356) (xy 108.806742 -238.814356) (xy 108.80623 -238.839802) (xy 108.798066 -238.890036)
			(xy 108.78195 -238.93831) (xy 108.758299 -238.983373) (xy 108.727726 -239.024059) (xy 108.691022 -239.059314)
			(xy 108.649138 -239.088224) (xy 108.603159 -239.110041) (xy 108.554275 -239.124201) (xy 108.503754 -239.130335)
			(xy 108.452902 -239.128286) (xy 108.403038 -239.118106) (xy 108.355452 -239.100059) (xy 108.311378 -239.074613)
			(xy 108.271956 -239.042426) (xy 108.238208 -239.004332) (xy 108.211007 -238.961318) (xy 108.191059 -238.914498)
			(xy 108.17888 -238.865084) (xy 108.174785 -238.814356) (xy 107.856274 -238.814356) (xy 107.855779 -238.838963)
			(xy 107.847884 -238.88754) (xy 107.8323 -238.934221) (xy 107.809429 -238.977798) (xy 107.779864 -239.017142)
			(xy 107.744371 -239.051234) (xy 107.703868 -239.07919) (xy 107.659406 -239.100288) (xy 107.612135 -239.11398)
			(xy 107.56328 -239.119912) (xy 107.514105 -239.117931) (xy 107.465886 -239.108087) (xy 107.41987 -239.090635)
			(xy 107.377249 -239.066028) (xy 107.339128 -239.034903) (xy 107.306493 -238.998066) (xy 107.28019 -238.95647)
			(xy 107.260899 -238.911194) (xy 107.249122 -238.86341) (xy 107.245162 -238.814356) (xy 105.036366 -238.814356)
			(xy 105.035871 -238.838963) (xy 105.027976 -238.88754) (xy 105.012392 -238.934221) (xy 104.989521 -238.977798)
			(xy 104.959956 -239.017142) (xy 104.924463 -239.051234) (xy 104.88396 -239.07919) (xy 104.839498 -239.100288)
			(xy 104.792227 -239.11398) (xy 104.743372 -239.119912) (xy 104.694197 -239.117931) (xy 104.645978 -239.108087)
			(xy 104.599962 -239.090635) (xy 104.557341 -239.066028) (xy 104.51922 -239.034903) (xy 104.486585 -238.998066)
			(xy 104.460282 -238.95647) (xy 104.440991 -238.911194) (xy 104.429214 -238.86341) (xy 104.425254 -238.814356)
			(xy 102.216458 -238.814356) (xy 102.215963 -238.838963) (xy 102.208068 -238.88754) (xy 102.192484 -238.934221)
			(xy 102.169613 -238.977798) (xy 102.140048 -239.017142) (xy 102.104555 -239.051234) (xy 102.064052 -239.07919)
			(xy 102.01959 -239.100288) (xy 101.972319 -239.11398) (xy 101.923464 -239.119912) (xy 101.874289 -239.117931)
			(xy 101.82607 -239.108087) (xy 101.780054 -239.090635) (xy 101.737433 -239.066028) (xy 101.699312 -239.034903)
			(xy 101.666677 -238.998066) (xy 101.640374 -238.95647) (xy 101.621083 -238.911194) (xy 101.609306 -238.86341)
			(xy 101.605346 -238.814356) (xy 99.396296 -238.814356) (xy 99.395801 -238.838963) (xy 99.387906 -238.88754)
			(xy 99.372322 -238.934221) (xy 99.349451 -238.977798) (xy 99.319886 -239.017142) (xy 99.284393 -239.051234)
			(xy 99.24389 -239.07919) (xy 99.199428 -239.100288) (xy 99.152157 -239.11398) (xy 99.103302 -239.119912)
			(xy 99.054127 -239.117931) (xy 99.005908 -239.108087) (xy 98.959892 -239.090635) (xy 98.917271 -239.066028)
			(xy 98.87915 -239.034903) (xy 98.846515 -238.998066) (xy 98.820212 -238.95647) (xy 98.800921 -238.911194)
			(xy 98.789144 -238.86341) (xy 98.785184 -238.814356) (xy 96.576388 -238.814356) (xy 96.575893 -238.838963)
			(xy 96.567998 -238.88754) (xy 96.552414 -238.934221) (xy 96.529543 -238.977798) (xy 96.499978 -239.017142)
			(xy 96.464485 -239.051234) (xy 96.423982 -239.07919) (xy 96.37952 -239.100288) (xy 96.332249 -239.11398)
			(xy 96.283394 -239.119912) (xy 96.234219 -239.117931) (xy 96.186 -239.108087) (xy 96.139984 -239.090635)
			(xy 96.097363 -239.066028) (xy 96.059242 -239.034903) (xy 96.026607 -238.998066) (xy 96.000304 -238.95647)
			(xy 95.981013 -238.911194) (xy 95.969236 -238.86341) (xy 95.965276 -238.814356) (xy 95.646748 -238.814356)
			(xy 95.646236 -238.839802) (xy 95.638072 -238.890036) (xy 95.621956 -238.93831) (xy 95.598305 -238.983373)
			(xy 95.567732 -239.024059) (xy 95.531028 -239.059314) (xy 95.489144 -239.088224) (xy 95.443165 -239.110041)
			(xy 95.394281 -239.124201) (xy 95.34376 -239.130335) (xy 95.292908 -239.128286) (xy 95.243044 -239.118106)
			(xy 95.195458 -239.100059) (xy 95.151384 -239.074613) (xy 95.111962 -239.042426) (xy 95.078214 -239.004332)
			(xy 95.051013 -238.961318) (xy 95.031065 -238.914498) (xy 95.018886 -238.865084) (xy 95.014791 -238.814356)
			(xy 94.706694 -238.814356) (xy 94.706182 -238.839802) (xy 94.698018 -238.890036) (xy 94.681902 -238.93831)
			(xy 94.658251 -238.983373) (xy 94.627678 -239.024059) (xy 94.590974 -239.059314) (xy 94.54909 -239.088224)
			(xy 94.503111 -239.110041) (xy 94.454227 -239.124201) (xy 94.403706 -239.130335) (xy 94.352854 -239.128286)
			(xy 94.30299 -239.118106) (xy 94.255404 -239.100059) (xy 94.21133 -239.074613) (xy 94.171908 -239.042426)
			(xy 94.13816 -239.004332) (xy 94.110959 -238.961318) (xy 94.091011 -238.914498) (xy 94.078832 -238.865084)
			(xy 94.074737 -238.814356) (xy 93.756226 -238.814356) (xy 93.755731 -238.838963) (xy 93.747836 -238.88754)
			(xy 93.732252 -238.934221) (xy 93.709381 -238.977798) (xy 93.679816 -239.017142) (xy 93.644323 -239.051234)
			(xy 93.60382 -239.07919) (xy 93.559358 -239.100288) (xy 93.512087 -239.11398) (xy 93.463232 -239.119912)
			(xy 93.414057 -239.117931) (xy 93.365838 -239.108087) (xy 93.319822 -239.090635) (xy 93.277201 -239.066028)
			(xy 93.23908 -239.034903) (xy 93.206445 -238.998066) (xy 93.180142 -238.95647) (xy 93.160851 -238.911194)
			(xy 93.149074 -238.86341) (xy 93.145114 -238.814356) (xy 92.82684 -238.814356) (xy 92.826328 -238.839802)
			(xy 92.818164 -238.890036) (xy 92.802048 -238.93831) (xy 92.778397 -238.983373) (xy 92.747824 -239.024059)
			(xy 92.71112 -239.059314) (xy 92.669236 -239.088224) (xy 92.623257 -239.110041) (xy 92.574373 -239.124201)
			(xy 92.523852 -239.130335) (xy 92.473 -239.128286) (xy 92.423136 -239.118106) (xy 92.37555 -239.100059)
			(xy 92.331476 -239.074613) (xy 92.292054 -239.042426) (xy 92.258306 -239.004332) (xy 92.231105 -238.961318)
			(xy 92.211157 -238.914498) (xy 92.198978 -238.865084) (xy 92.194883 -238.814356) (xy 91.876372 -238.814356)
			(xy 91.875877 -238.838963) (xy 91.867982 -238.88754) (xy 91.852398 -238.934221) (xy 91.829527 -238.977798)
			(xy 91.799962 -239.017142) (xy 91.764469 -239.051234) (xy 91.723966 -239.07919) (xy 91.679504 -239.100288)
			(xy 91.632233 -239.11398) (xy 91.583378 -239.119912) (xy 91.534203 -239.117931) (xy 91.485984 -239.108087)
			(xy 91.439968 -239.090635) (xy 91.397347 -239.066028) (xy 91.359226 -239.034903) (xy 91.326591 -238.998066)
			(xy 91.300288 -238.95647) (xy 91.280997 -238.911194) (xy 91.26922 -238.86341) (xy 91.26526 -238.814356)
			(xy 90.946732 -238.814356) (xy 90.94622 -238.839802) (xy 90.938056 -238.890036) (xy 90.92194 -238.93831)
			(xy 90.898289 -238.983373) (xy 90.867716 -239.024059) (xy 90.831012 -239.059314) (xy 90.789128 -239.088224)
			(xy 90.743149 -239.110041) (xy 90.694265 -239.124201) (xy 90.643744 -239.130335) (xy 90.592892 -239.128286)
			(xy 90.543028 -239.118106) (xy 90.495442 -239.100059) (xy 90.451368 -239.074613) (xy 90.411946 -239.042426)
			(xy 90.378198 -239.004332) (xy 90.350997 -238.961318) (xy 90.331049 -238.914498) (xy 90.31887 -238.865084)
			(xy 90.314775 -238.814356) (xy 89.995936 -238.814356) (xy 89.995937 -238.83864) (xy 89.988275 -238.886523)
			(xy 89.973142 -238.932594) (xy 89.95092 -238.975695) (xy 89.922165 -239.014742) (xy 89.887601 -239.048755)
			(xy 89.848097 -239.076878) (xy 89.804645 -239.098406) (xy 89.758336 -239.112796) (xy 89.73439 -239.116616)
			(xy 89.715594 -239.11941) (xy 89.690956 -239.147858) (xy 89.690956 -239.319054) (xy 89.691224 -239.32594)
			(xy 89.694961 -239.339199) (xy 89.698322 -239.345216) (xy 89.699338 -239.346994) (xy 89.707628 -239.361568)
			(xy 89.722623 -239.391562) (xy 89.72931 -239.406938) (xy 89.736168 -239.423448) (xy 89.741248 -239.436656)
			(xy 89.762838 -239.453674) (xy 89.879424 -239.46866) (xy 89.905078 -239.457484) (xy 89.913206 -239.446054)
			(xy 89.927673 -239.426758) (xy 89.961664 -239.392548) (xy 90.000605 -239.3641) (xy 90.043529 -239.342118)
			(xy 90.089372 -239.327149) (xy 90.136997 -239.319563) (xy 90.16111 -239.319054) (xy 90.186368 -239.319576)
			(xy 90.236195 -239.327893) (xy 90.283973 -239.344296) (xy 90.3284 -239.36834) (xy 90.368263 -239.399368)
			(xy 90.402476 -239.436535) (xy 90.430105 -239.478825) (xy 90.450397 -239.525086) (xy 90.462798 -239.574057)
			(xy 90.466966 -239.624362) (xy 90.784675 -239.624362) (xy 90.78877 -239.573634) (xy 90.800949 -239.52422)
			(xy 90.820897 -239.4774) (xy 90.848098 -239.434386) (xy 90.881846 -239.396292) (xy 90.921268 -239.364105)
			(xy 90.965342 -239.338659) (xy 91.012928 -239.320612) (xy 91.062792 -239.310432) (xy 91.113644 -239.308383)
			(xy 91.164165 -239.314517) (xy 91.213049 -239.328677) (xy 91.259028 -239.350494) (xy 91.300912 -239.379404)
			(xy 91.337616 -239.414659) (xy 91.368189 -239.455345) (xy 91.39184 -239.500408) (xy 91.407956 -239.548682)
			(xy 91.41612 -239.598916) (xy 91.416632 -239.624362) (xy 91.724729 -239.624362) (xy 91.728824 -239.573634)
			(xy 91.741003 -239.52422) (xy 91.760951 -239.4774) (xy 91.788152 -239.434386) (xy 91.8219 -239.396292)
			(xy 91.861322 -239.364105) (xy 91.905396 -239.338659) (xy 91.952982 -239.320612) (xy 92.002846 -239.310432)
			(xy 92.053698 -239.308383) (xy 92.104219 -239.314517) (xy 92.153103 -239.328677) (xy 92.199082 -239.350494)
			(xy 92.240966 -239.379404) (xy 92.27767 -239.414659) (xy 92.308243 -239.455345) (xy 92.331894 -239.500408)
			(xy 92.34801 -239.548682) (xy 92.356174 -239.598916) (xy 92.356686 -239.624362) (xy 92.675214 -239.624362)
			(xy 92.679174 -239.575308) (xy 92.690951 -239.527524) (xy 92.710242 -239.482248) (xy 92.736545 -239.440652)
			(xy 92.76918 -239.403815) (xy 92.807301 -239.37269) (xy 92.849922 -239.348083) (xy 92.895938 -239.330631)
			(xy 92.944157 -239.320787) (xy 92.993332 -239.318806) (xy 93.042187 -239.324738) (xy 93.089458 -239.33843)
			(xy 93.13392 -239.359528) (xy 93.174423 -239.387484) (xy 93.209916 -239.421576) (xy 93.239481 -239.46092)
			(xy 93.262352 -239.504497) (xy 93.277936 -239.551178) (xy 93.285831 -239.599755) (xy 93.286326 -239.624362)
			(xy 93.604837 -239.624362) (xy 93.608932 -239.573634) (xy 93.621111 -239.52422) (xy 93.641059 -239.4774)
			(xy 93.66826 -239.434386) (xy 93.702008 -239.396292) (xy 93.74143 -239.364105) (xy 93.785504 -239.338659)
			(xy 93.83309 -239.320612) (xy 93.882954 -239.310432) (xy 93.933806 -239.308383) (xy 93.984327 -239.314517)
			(xy 94.033211 -239.328677) (xy 94.07919 -239.350494) (xy 94.121074 -239.379404) (xy 94.157778 -239.414659)
			(xy 94.188351 -239.455345) (xy 94.212002 -239.500408) (xy 94.228118 -239.548682) (xy 94.236282 -239.598916)
			(xy 94.236794 -239.624362) (xy 94.555322 -239.624362) (xy 94.559282 -239.575308) (xy 94.571059 -239.527524)
			(xy 94.59035 -239.482248) (xy 94.616653 -239.440652) (xy 94.649288 -239.403815) (xy 94.687409 -239.37269)
			(xy 94.73003 -239.348083) (xy 94.776046 -239.330631) (xy 94.824265 -239.320787) (xy 94.87344 -239.318806)
			(xy 94.922295 -239.324738) (xy 94.969566 -239.33843) (xy 95.014028 -239.359528) (xy 95.054531 -239.387484)
			(xy 95.090024 -239.421576) (xy 95.119589 -239.46092) (xy 95.14246 -239.504497) (xy 95.158044 -239.551178)
			(xy 95.165939 -239.599755) (xy 95.166434 -239.624362) (xy 95.484691 -239.624362) (xy 95.488786 -239.573634)
			(xy 95.500965 -239.52422) (xy 95.520913 -239.4774) (xy 95.548114 -239.434386) (xy 95.581862 -239.396292)
			(xy 95.621284 -239.364105) (xy 95.665358 -239.338659) (xy 95.712944 -239.320612) (xy 95.762808 -239.310432)
			(xy 95.81366 -239.308383) (xy 95.864181 -239.314517) (xy 95.913065 -239.328677) (xy 95.959044 -239.350494)
			(xy 96.000928 -239.379404) (xy 96.037632 -239.414659) (xy 96.068205 -239.455345) (xy 96.091856 -239.500408)
			(xy 96.107972 -239.548682) (xy 96.116136 -239.598916) (xy 96.116648 -239.624362) (xy 96.435176 -239.624362)
			(xy 96.439136 -239.575308) (xy 96.450913 -239.527524) (xy 96.470204 -239.482248) (xy 96.496507 -239.440652)
			(xy 96.529142 -239.403815) (xy 96.567263 -239.37269) (xy 96.609884 -239.348083) (xy 96.6559 -239.330631)
			(xy 96.704119 -239.320787) (xy 96.753294 -239.318806) (xy 96.802149 -239.324738) (xy 96.84942 -239.33843)
			(xy 96.893882 -239.359528) (xy 96.934385 -239.387484) (xy 96.969878 -239.421576) (xy 96.999443 -239.46092)
			(xy 97.022314 -239.504497) (xy 97.037898 -239.551178) (xy 97.045793 -239.599755) (xy 97.046288 -239.624362)
			(xy 97.364799 -239.624362) (xy 97.368894 -239.573634) (xy 97.381073 -239.52422) (xy 97.401021 -239.4774)
			(xy 97.428222 -239.434386) (xy 97.46197 -239.396292) (xy 97.501392 -239.364105) (xy 97.545466 -239.338659)
			(xy 97.593052 -239.320612) (xy 97.642916 -239.310432) (xy 97.693768 -239.308383) (xy 97.744289 -239.314517)
			(xy 97.793173 -239.328677) (xy 97.839152 -239.350494) (xy 97.881036 -239.379404) (xy 97.91774 -239.414659)
			(xy 97.948313 -239.455345) (xy 97.971964 -239.500408) (xy 97.98808 -239.548682) (xy 97.996244 -239.598916)
			(xy 97.996756 -239.624362) (xy 98.304853 -239.624362) (xy 98.308948 -239.573634) (xy 98.321127 -239.52422)
			(xy 98.341075 -239.4774) (xy 98.368276 -239.434386) (xy 98.402024 -239.396292) (xy 98.441446 -239.364105)
			(xy 98.48552 -239.338659) (xy 98.533106 -239.320612) (xy 98.58297 -239.310432) (xy 98.633822 -239.308383)
			(xy 98.684343 -239.314517) (xy 98.733227 -239.328677) (xy 98.779206 -239.350494) (xy 98.82109 -239.379404)
			(xy 98.857794 -239.414659) (xy 98.888367 -239.455345) (xy 98.912018 -239.500408) (xy 98.928134 -239.548682)
			(xy 98.936298 -239.598916) (xy 98.93681 -239.624362) (xy 99.255338 -239.624362) (xy 99.259298 -239.575308)
			(xy 99.271075 -239.527524) (xy 99.290366 -239.482248) (xy 99.316669 -239.440652) (xy 99.349304 -239.403815)
			(xy 99.387425 -239.37269) (xy 99.430046 -239.348083) (xy 99.476062 -239.330631) (xy 99.524281 -239.320787)
			(xy 99.573456 -239.318806) (xy 99.622311 -239.324738) (xy 99.669582 -239.33843) (xy 99.714044 -239.359528)
			(xy 99.754547 -239.387484) (xy 99.79004 -239.421576) (xy 99.819605 -239.46092) (xy 99.842476 -239.504497)
			(xy 99.85806 -239.551178) (xy 99.865955 -239.599755) (xy 99.86645 -239.624362) (xy 100.184707 -239.624362)
			(xy 100.188802 -239.573634) (xy 100.200981 -239.52422) (xy 100.220929 -239.4774) (xy 100.24813 -239.434386)
			(xy 100.281878 -239.396292) (xy 100.3213 -239.364105) (xy 100.365374 -239.338659) (xy 100.41296 -239.320612)
			(xy 100.462824 -239.310432) (xy 100.513676 -239.308383) (xy 100.564197 -239.314517) (xy 100.613081 -239.328677)
			(xy 100.65906 -239.350494) (xy 100.700944 -239.379404) (xy 100.737648 -239.414659) (xy 100.768221 -239.455345)
			(xy 100.791872 -239.500408) (xy 100.807988 -239.548682) (xy 100.816152 -239.598916) (xy 100.816664 -239.624362)
			(xy 101.124761 -239.624362) (xy 101.128856 -239.573634) (xy 101.141035 -239.52422) (xy 101.160983 -239.4774)
			(xy 101.188184 -239.434386) (xy 101.221932 -239.396292) (xy 101.261354 -239.364105) (xy 101.305428 -239.338659)
			(xy 101.353014 -239.320612) (xy 101.402878 -239.310432) (xy 101.45373 -239.308383) (xy 101.504251 -239.314517)
			(xy 101.553135 -239.328677) (xy 101.599114 -239.350494) (xy 101.640998 -239.379404) (xy 101.677702 -239.414659)
			(xy 101.708275 -239.455345) (xy 101.731926 -239.500408) (xy 101.748042 -239.548682) (xy 101.756206 -239.598916)
			(xy 101.756718 -239.624362) (xy 102.075246 -239.624362) (xy 102.079206 -239.575308) (xy 102.090983 -239.527524)
			(xy 102.110274 -239.482248) (xy 102.136577 -239.440652) (xy 102.169212 -239.403815) (xy 102.207333 -239.37269)
			(xy 102.249954 -239.348083) (xy 102.29597 -239.330631) (xy 102.344189 -239.320787) (xy 102.393364 -239.318806)
			(xy 102.442219 -239.324738) (xy 102.48949 -239.33843) (xy 102.533952 -239.359528) (xy 102.574455 -239.387484)
			(xy 102.609948 -239.421576) (xy 102.639513 -239.46092) (xy 102.662384 -239.504497) (xy 102.677968 -239.551178)
			(xy 102.685863 -239.599755) (xy 102.686358 -239.624362) (xy 103.004869 -239.624362) (xy 103.008964 -239.573634)
			(xy 103.021143 -239.52422) (xy 103.041091 -239.4774) (xy 103.068292 -239.434386) (xy 103.10204 -239.396292)
			(xy 103.141462 -239.364105) (xy 103.185536 -239.338659) (xy 103.233122 -239.320612) (xy 103.282986 -239.310432)
			(xy 103.333838 -239.308383) (xy 103.384359 -239.314517) (xy 103.433243 -239.328677) (xy 103.479222 -239.350494)
			(xy 103.521106 -239.379404) (xy 103.55781 -239.414659) (xy 103.588383 -239.455345) (xy 103.612034 -239.500408)
			(xy 103.62815 -239.548682) (xy 103.636314 -239.598916) (xy 103.636826 -239.624362) (xy 103.944923 -239.624362)
			(xy 103.949018 -239.573634) (xy 103.961197 -239.52422) (xy 103.981145 -239.4774) (xy 104.008346 -239.434386)
			(xy 104.042094 -239.396292) (xy 104.081516 -239.364105) (xy 104.12559 -239.338659) (xy 104.173176 -239.320612)
			(xy 104.22304 -239.310432) (xy 104.273892 -239.308383) (xy 104.324413 -239.314517) (xy 104.373297 -239.328677)
			(xy 104.419276 -239.350494) (xy 104.46116 -239.379404) (xy 104.497864 -239.414659) (xy 104.528437 -239.455345)
			(xy 104.552088 -239.500408) (xy 104.568204 -239.548682) (xy 104.576368 -239.598916) (xy 104.57688 -239.624362)
			(xy 104.895154 -239.624362) (xy 104.899114 -239.575308) (xy 104.910891 -239.527524) (xy 104.930182 -239.482248)
			(xy 104.956485 -239.440652) (xy 104.98912 -239.403815) (xy 105.027241 -239.37269) (xy 105.069862 -239.348083)
			(xy 105.115878 -239.330631) (xy 105.164097 -239.320787) (xy 105.213272 -239.318806) (xy 105.262127 -239.324738)
			(xy 105.309398 -239.33843) (xy 105.35386 -239.359528) (xy 105.394363 -239.387484) (xy 105.429856 -239.421576)
			(xy 105.459421 -239.46092) (xy 105.482292 -239.504497) (xy 105.497876 -239.551178) (xy 105.505771 -239.599755)
			(xy 105.506266 -239.624362) (xy 105.824777 -239.624362) (xy 105.828872 -239.573634) (xy 105.841051 -239.52422)
			(xy 105.860999 -239.4774) (xy 105.8882 -239.434386) (xy 105.921948 -239.396292) (xy 105.96137 -239.364105)
			(xy 106.005444 -239.338659) (xy 106.05303 -239.320612) (xy 106.102894 -239.310432) (xy 106.153746 -239.308383)
			(xy 106.204267 -239.314517) (xy 106.253151 -239.328677) (xy 106.29913 -239.350494) (xy 106.341014 -239.379404)
			(xy 106.377718 -239.414659) (xy 106.408291 -239.455345) (xy 106.431942 -239.500408) (xy 106.448058 -239.548682)
			(xy 106.456222 -239.598916) (xy 106.456734 -239.624362) (xy 106.764831 -239.624362) (xy 106.768926 -239.573634)
			(xy 106.781105 -239.52422) (xy 106.801053 -239.4774) (xy 106.828254 -239.434386) (xy 106.862002 -239.396292)
			(xy 106.901424 -239.364105) (xy 106.945498 -239.338659) (xy 106.993084 -239.320612) (xy 107.042948 -239.310432)
			(xy 107.0938 -239.308383) (xy 107.144321 -239.314517) (xy 107.193205 -239.328677) (xy 107.239184 -239.350494)
			(xy 107.281068 -239.379404) (xy 107.317772 -239.414659) (xy 107.348345 -239.455345) (xy 107.371996 -239.500408)
			(xy 107.388112 -239.548682) (xy 107.396276 -239.598916) (xy 107.396788 -239.624362) (xy 107.715316 -239.624362)
			(xy 107.719276 -239.575308) (xy 107.731053 -239.527524) (xy 107.750344 -239.482248) (xy 107.776647 -239.440652)
			(xy 107.809282 -239.403815) (xy 107.847403 -239.37269) (xy 107.890024 -239.348083) (xy 107.93604 -239.330631)
			(xy 107.984259 -239.320787) (xy 108.033434 -239.318806) (xy 108.082289 -239.324738) (xy 108.12956 -239.33843)
			(xy 108.174022 -239.359528) (xy 108.214525 -239.387484) (xy 108.250018 -239.421576) (xy 108.279583 -239.46092)
			(xy 108.302454 -239.504497) (xy 108.318038 -239.551178) (xy 108.325933 -239.599755) (xy 108.326428 -239.624362)
			(xy 108.325933 -239.648969) (xy 108.318038 -239.697546) (xy 108.302454 -239.744227) (xy 108.279583 -239.787804)
			(xy 108.250018 -239.827148) (xy 108.214525 -239.86124) (xy 108.174022 -239.889196) (xy 108.12956 -239.910294)
			(xy 108.082289 -239.923986) (xy 108.033434 -239.929918) (xy 107.984259 -239.927937) (xy 107.93604 -239.918093)
			(xy 107.890024 -239.900641) (xy 107.847403 -239.876034) (xy 107.809282 -239.844909) (xy 107.776647 -239.808072)
			(xy 107.750344 -239.766476) (xy 107.731053 -239.7212) (xy 107.719276 -239.673416) (xy 107.715316 -239.624362)
			(xy 107.396788 -239.624362) (xy 107.396276 -239.649808) (xy 107.388112 -239.700042) (xy 107.371996 -239.748316)
			(xy 107.348345 -239.793379) (xy 107.317772 -239.834065) (xy 107.281068 -239.86932) (xy 107.239184 -239.89823)
			(xy 107.193205 -239.920047) (xy 107.144321 -239.934207) (xy 107.0938 -239.940341) (xy 107.042948 -239.938292)
			(xy 106.993084 -239.928112) (xy 106.945498 -239.910065) (xy 106.901424 -239.884619) (xy 106.862002 -239.852432)
			(xy 106.828254 -239.814338) (xy 106.801053 -239.771324) (xy 106.781105 -239.724504) (xy 106.768926 -239.67509)
			(xy 106.764831 -239.624362) (xy 106.456734 -239.624362) (xy 106.456222 -239.649808) (xy 106.448058 -239.700042)
			(xy 106.431942 -239.748316) (xy 106.408291 -239.793379) (xy 106.377718 -239.834065) (xy 106.341014 -239.86932)
			(xy 106.29913 -239.89823) (xy 106.253151 -239.920047) (xy 106.204267 -239.934207) (xy 106.153746 -239.940341)
			(xy 106.102894 -239.938292) (xy 106.05303 -239.928112) (xy 106.005444 -239.910065) (xy 105.96137 -239.884619)
			(xy 105.921948 -239.852432) (xy 105.8882 -239.814338) (xy 105.860999 -239.771324) (xy 105.841051 -239.724504)
			(xy 105.828872 -239.67509) (xy 105.824777 -239.624362) (xy 105.506266 -239.624362) (xy 105.505771 -239.648969)
			(xy 105.497876 -239.697546) (xy 105.482292 -239.744227) (xy 105.459421 -239.787804) (xy 105.429856 -239.827148)
			(xy 105.394363 -239.86124) (xy 105.35386 -239.889196) (xy 105.309398 -239.910294) (xy 105.262127 -239.923986)
			(xy 105.213272 -239.929918) (xy 105.164097 -239.927937) (xy 105.115878 -239.918093) (xy 105.069862 -239.900641)
			(xy 105.027241 -239.876034) (xy 104.98912 -239.844909) (xy 104.956485 -239.808072) (xy 104.930182 -239.766476)
			(xy 104.910891 -239.7212) (xy 104.899114 -239.673416) (xy 104.895154 -239.624362) (xy 104.57688 -239.624362)
			(xy 104.576368 -239.649808) (xy 104.568204 -239.700042) (xy 104.552088 -239.748316) (xy 104.528437 -239.793379)
			(xy 104.497864 -239.834065) (xy 104.46116 -239.86932) (xy 104.419276 -239.89823) (xy 104.373297 -239.920047)
			(xy 104.324413 -239.934207) (xy 104.273892 -239.940341) (xy 104.22304 -239.938292) (xy 104.173176 -239.928112)
			(xy 104.12559 -239.910065) (xy 104.081516 -239.884619) (xy 104.042094 -239.852432) (xy 104.008346 -239.814338)
			(xy 103.981145 -239.771324) (xy 103.961197 -239.724504) (xy 103.949018 -239.67509) (xy 103.944923 -239.624362)
			(xy 103.636826 -239.624362) (xy 103.636314 -239.649808) (xy 103.62815 -239.700042) (xy 103.612034 -239.748316)
			(xy 103.588383 -239.793379) (xy 103.55781 -239.834065) (xy 103.521106 -239.86932) (xy 103.479222 -239.89823)
			(xy 103.433243 -239.920047) (xy 103.384359 -239.934207) (xy 103.333838 -239.940341) (xy 103.282986 -239.938292)
			(xy 103.233122 -239.928112) (xy 103.185536 -239.910065) (xy 103.141462 -239.884619) (xy 103.10204 -239.852432)
			(xy 103.068292 -239.814338) (xy 103.041091 -239.771324) (xy 103.021143 -239.724504) (xy 103.008964 -239.67509)
			(xy 103.004869 -239.624362) (xy 102.686358 -239.624362) (xy 102.685863 -239.648969) (xy 102.677968 -239.697546)
			(xy 102.662384 -239.744227) (xy 102.639513 -239.787804) (xy 102.609948 -239.827148) (xy 102.574455 -239.86124)
			(xy 102.533952 -239.889196) (xy 102.48949 -239.910294) (xy 102.442219 -239.923986) (xy 102.393364 -239.929918)
			(xy 102.344189 -239.927937) (xy 102.29597 -239.918093) (xy 102.249954 -239.900641) (xy 102.207333 -239.876034)
			(xy 102.169212 -239.844909) (xy 102.136577 -239.808072) (xy 102.110274 -239.766476) (xy 102.090983 -239.7212)
			(xy 102.079206 -239.673416) (xy 102.075246 -239.624362) (xy 101.756718 -239.624362) (xy 101.756206 -239.649808)
			(xy 101.748042 -239.700042) (xy 101.731926 -239.748316) (xy 101.708275 -239.793379) (xy 101.677702 -239.834065)
			(xy 101.640998 -239.86932) (xy 101.599114 -239.89823) (xy 101.553135 -239.920047) (xy 101.504251 -239.934207)
			(xy 101.45373 -239.940341) (xy 101.402878 -239.938292) (xy 101.353014 -239.928112) (xy 101.305428 -239.910065)
			(xy 101.261354 -239.884619) (xy 101.221932 -239.852432) (xy 101.188184 -239.814338) (xy 101.160983 -239.771324)
			(xy 101.141035 -239.724504) (xy 101.128856 -239.67509) (xy 101.124761 -239.624362) (xy 100.816664 -239.624362)
			(xy 100.816152 -239.649808) (xy 100.807988 -239.700042) (xy 100.791872 -239.748316) (xy 100.768221 -239.793379)
			(xy 100.737648 -239.834065) (xy 100.700944 -239.86932) (xy 100.65906 -239.89823) (xy 100.613081 -239.920047)
			(xy 100.564197 -239.934207) (xy 100.513676 -239.940341) (xy 100.462824 -239.938292) (xy 100.41296 -239.928112)
			(xy 100.365374 -239.910065) (xy 100.3213 -239.884619) (xy 100.281878 -239.852432) (xy 100.24813 -239.814338)
			(xy 100.220929 -239.771324) (xy 100.200981 -239.724504) (xy 100.188802 -239.67509) (xy 100.184707 -239.624362)
			(xy 99.86645 -239.624362) (xy 99.865955 -239.648969) (xy 99.85806 -239.697546) (xy 99.842476 -239.744227)
			(xy 99.819605 -239.787804) (xy 99.79004 -239.827148) (xy 99.754547 -239.86124) (xy 99.714044 -239.889196)
			(xy 99.669582 -239.910294) (xy 99.622311 -239.923986) (xy 99.573456 -239.929918) (xy 99.524281 -239.927937)
			(xy 99.476062 -239.918093) (xy 99.430046 -239.900641) (xy 99.387425 -239.876034) (xy 99.349304 -239.844909)
			(xy 99.316669 -239.808072) (xy 99.290366 -239.766476) (xy 99.271075 -239.7212) (xy 99.259298 -239.673416)
			(xy 99.255338 -239.624362) (xy 98.93681 -239.624362) (xy 98.936298 -239.649808) (xy 98.928134 -239.700042)
			(xy 98.912018 -239.748316) (xy 98.888367 -239.793379) (xy 98.857794 -239.834065) (xy 98.82109 -239.86932)
			(xy 98.779206 -239.89823) (xy 98.733227 -239.920047) (xy 98.684343 -239.934207) (xy 98.633822 -239.940341)
			(xy 98.58297 -239.938292) (xy 98.533106 -239.928112) (xy 98.48552 -239.910065) (xy 98.441446 -239.884619)
			(xy 98.402024 -239.852432) (xy 98.368276 -239.814338) (xy 98.341075 -239.771324) (xy 98.321127 -239.724504)
			(xy 98.308948 -239.67509) (xy 98.304853 -239.624362) (xy 97.996756 -239.624362) (xy 97.996244 -239.649808)
			(xy 97.98808 -239.700042) (xy 97.971964 -239.748316) (xy 97.948313 -239.793379) (xy 97.91774 -239.834065)
			(xy 97.881036 -239.86932) (xy 97.839152 -239.89823) (xy 97.793173 -239.920047) (xy 97.744289 -239.934207)
			(xy 97.693768 -239.940341) (xy 97.642916 -239.938292) (xy 97.593052 -239.928112) (xy 97.545466 -239.910065)
			(xy 97.501392 -239.884619) (xy 97.46197 -239.852432) (xy 97.428222 -239.814338) (xy 97.401021 -239.771324)
			(xy 97.381073 -239.724504) (xy 97.368894 -239.67509) (xy 97.364799 -239.624362) (xy 97.046288 -239.624362)
			(xy 97.045793 -239.648969) (xy 97.037898 -239.697546) (xy 97.022314 -239.744227) (xy 96.999443 -239.787804)
			(xy 96.969878 -239.827148) (xy 96.934385 -239.86124) (xy 96.893882 -239.889196) (xy 96.84942 -239.910294)
			(xy 96.802149 -239.923986) (xy 96.753294 -239.929918) (xy 96.704119 -239.927937) (xy 96.6559 -239.918093)
			(xy 96.609884 -239.900641) (xy 96.567263 -239.876034) (xy 96.529142 -239.844909) (xy 96.496507 -239.808072)
			(xy 96.470204 -239.766476) (xy 96.450913 -239.7212) (xy 96.439136 -239.673416) (xy 96.435176 -239.624362)
			(xy 96.116648 -239.624362) (xy 96.116136 -239.649808) (xy 96.107972 -239.700042) (xy 96.091856 -239.748316)
			(xy 96.068205 -239.793379) (xy 96.037632 -239.834065) (xy 96.000928 -239.86932) (xy 95.959044 -239.89823)
			(xy 95.913065 -239.920047) (xy 95.864181 -239.934207) (xy 95.81366 -239.940341) (xy 95.762808 -239.938292)
			(xy 95.712944 -239.928112) (xy 95.665358 -239.910065) (xy 95.621284 -239.884619) (xy 95.581862 -239.852432)
			(xy 95.548114 -239.814338) (xy 95.520913 -239.771324) (xy 95.500965 -239.724504) (xy 95.488786 -239.67509)
			(xy 95.484691 -239.624362) (xy 95.166434 -239.624362) (xy 95.165939 -239.648969) (xy 95.158044 -239.697546)
			(xy 95.14246 -239.744227) (xy 95.119589 -239.787804) (xy 95.090024 -239.827148) (xy 95.054531 -239.86124)
			(xy 95.014028 -239.889196) (xy 94.969566 -239.910294) (xy 94.922295 -239.923986) (xy 94.87344 -239.929918)
			(xy 94.824265 -239.927937) (xy 94.776046 -239.918093) (xy 94.73003 -239.900641) (xy 94.687409 -239.876034)
			(xy 94.649288 -239.844909) (xy 94.616653 -239.808072) (xy 94.59035 -239.766476) (xy 94.571059 -239.7212)
			(xy 94.559282 -239.673416) (xy 94.555322 -239.624362) (xy 94.236794 -239.624362) (xy 94.236282 -239.649808)
			(xy 94.228118 -239.700042) (xy 94.212002 -239.748316) (xy 94.188351 -239.793379) (xy 94.157778 -239.834065)
			(xy 94.121074 -239.86932) (xy 94.07919 -239.89823) (xy 94.033211 -239.920047) (xy 93.984327 -239.934207)
			(xy 93.933806 -239.940341) (xy 93.882954 -239.938292) (xy 93.83309 -239.928112) (xy 93.785504 -239.910065)
			(xy 93.74143 -239.884619) (xy 93.702008 -239.852432) (xy 93.66826 -239.814338) (xy 93.641059 -239.771324)
			(xy 93.621111 -239.724504) (xy 93.608932 -239.67509) (xy 93.604837 -239.624362) (xy 93.286326 -239.624362)
			(xy 93.285831 -239.648969) (xy 93.277936 -239.697546) (xy 93.262352 -239.744227) (xy 93.239481 -239.787804)
			(xy 93.209916 -239.827148) (xy 93.174423 -239.86124) (xy 93.13392 -239.889196) (xy 93.089458 -239.910294)
			(xy 93.042187 -239.923986) (xy 92.993332 -239.929918) (xy 92.944157 -239.927937) (xy 92.895938 -239.918093)
			(xy 92.849922 -239.900641) (xy 92.807301 -239.876034) (xy 92.76918 -239.844909) (xy 92.736545 -239.808072)
			(xy 92.710242 -239.766476) (xy 92.690951 -239.7212) (xy 92.679174 -239.673416) (xy 92.675214 -239.624362)
			(xy 92.356686 -239.624362) (xy 92.356174 -239.649808) (xy 92.34801 -239.700042) (xy 92.331894 -239.748316)
			(xy 92.308243 -239.793379) (xy 92.27767 -239.834065) (xy 92.240966 -239.86932) (xy 92.199082 -239.89823)
			(xy 92.153103 -239.920047) (xy 92.104219 -239.934207) (xy 92.053698 -239.940341) (xy 92.002846 -239.938292)
			(xy 91.952982 -239.928112) (xy 91.905396 -239.910065) (xy 91.861322 -239.884619) (xy 91.8219 -239.852432)
			(xy 91.788152 -239.814338) (xy 91.760951 -239.771324) (xy 91.741003 -239.724504) (xy 91.728824 -239.67509)
			(xy 91.724729 -239.624362) (xy 91.416632 -239.624362) (xy 91.41612 -239.649808) (xy 91.407956 -239.700042)
			(xy 91.39184 -239.748316) (xy 91.368189 -239.793379) (xy 91.337616 -239.834065) (xy 91.300912 -239.86932)
			(xy 91.259028 -239.89823) (xy 91.213049 -239.920047) (xy 91.164165 -239.934207) (xy 91.113644 -239.940341)
			(xy 91.062792 -239.938292) (xy 91.012928 -239.928112) (xy 90.965342 -239.910065) (xy 90.921268 -239.884619)
			(xy 90.881846 -239.852432) (xy 90.848098 -239.814338) (xy 90.820897 -239.771324) (xy 90.800949 -239.724504)
			(xy 90.78877 -239.67509) (xy 90.784675 -239.624362) (xy 90.466966 -239.624362) (xy 90.466969 -239.6244)
			(xy 90.462798 -239.674743) (xy 90.450397 -239.723714) (xy 90.430105 -239.769975) (xy 90.402476 -239.812265)
			(xy 90.368263 -239.849432) (xy 90.3284 -239.88046) (xy 90.283973 -239.904504) (xy 90.236195 -239.920907)
			(xy 90.186368 -239.929224) (xy 90.16111 -239.92967) (xy 90.148347 -239.929534) (xy 90.122912 -239.927375)
			(xy 90.11031 -239.925352) (xy 90.11031 -239.925606) (xy 90.086857 -239.921178) (xy 90.041604 -239.906015)
			(xy 89.999254 -239.88401) (xy 89.960834 -239.855697) (xy 89.927276 -239.821761) (xy 89.912952 -239.80267)
			(xy 89.904824 -239.79124) (xy 89.87917 -239.780064) (xy 89.762838 -239.79505) (xy 89.741248 -239.812068)
			(xy 89.736168 -239.825276) (xy 89.728019 -239.845598) (xy 89.708945 -239.885013) (xy 89.698068 -239.904016)
			(xy 89.694766 -239.909604) (xy 89.692734 -239.916208) (xy 89.690956 -239.92967) (xy 89.690956 -240.100866)
			(xy 89.715594 -240.129314) (xy 89.73439 -240.132108) (xy 89.758323 -240.136013) (xy 89.80463 -240.150401)
			(xy 89.848081 -240.171926) (xy 89.887585 -240.200047) (xy 89.922149 -240.234057) (xy 89.950904 -240.273102)
			(xy 89.973127 -240.3162) (xy 89.988261 -240.362269) (xy 89.995924 -240.41015) (xy 89.995924 -240.434368)
			(xy 90.314775 -240.434368) (xy 90.31887 -240.38364) (xy 90.331049 -240.334226) (xy 90.350997 -240.287406)
			(xy 90.378198 -240.244392) (xy 90.411946 -240.206298) (xy 90.451368 -240.174111) (xy 90.495442 -240.148665)
			(xy 90.543028 -240.130618) (xy 90.592892 -240.120438) (xy 90.643744 -240.118389) (xy 90.694265 -240.124523)
			(xy 90.743149 -240.138683) (xy 90.789128 -240.1605) (xy 90.831012 -240.18941) (xy 90.867716 -240.224665)
			(xy 90.898289 -240.265351) (xy 90.92194 -240.310414) (xy 90.938056 -240.358688) (xy 90.94622 -240.408922)
			(xy 90.946732 -240.434368) (xy 91.26526 -240.434368) (xy 91.26922 -240.385314) (xy 91.280997 -240.33753)
			(xy 91.300288 -240.292254) (xy 91.326591 -240.250658) (xy 91.359226 -240.213821) (xy 91.397347 -240.182696)
			(xy 91.439968 -240.158089) (xy 91.485984 -240.140637) (xy 91.534203 -240.130793) (xy 91.583378 -240.128812)
			(xy 91.632233 -240.134744) (xy 91.679504 -240.148436) (xy 91.723966 -240.169534) (xy 91.764469 -240.19749)
			(xy 91.799962 -240.231582) (xy 91.829527 -240.270926) (xy 91.852398 -240.314503) (xy 91.867982 -240.361184)
			(xy 91.875877 -240.409761) (xy 91.876372 -240.434368) (xy 92.194883 -240.434368) (xy 92.198978 -240.38364)
			(xy 92.211157 -240.334226) (xy 92.231105 -240.287406) (xy 92.258306 -240.244392) (xy 92.292054 -240.206298)
			(xy 92.331476 -240.174111) (xy 92.37555 -240.148665) (xy 92.423136 -240.130618) (xy 92.473 -240.120438)
			(xy 92.523852 -240.118389) (xy 92.574373 -240.124523) (xy 92.623257 -240.138683) (xy 92.669236 -240.1605)
			(xy 92.71112 -240.18941) (xy 92.747824 -240.224665) (xy 92.778397 -240.265351) (xy 92.802048 -240.310414)
			(xy 92.818164 -240.358688) (xy 92.826328 -240.408922) (xy 92.82684 -240.434368) (xy 93.145114 -240.434368)
			(xy 93.149074 -240.385314) (xy 93.160851 -240.33753) (xy 93.180142 -240.292254) (xy 93.206445 -240.250658)
			(xy 93.23908 -240.213821) (xy 93.277201 -240.182696) (xy 93.319822 -240.158089) (xy 93.365838 -240.140637)
			(xy 93.414057 -240.130793) (xy 93.463232 -240.128812) (xy 93.512087 -240.134744) (xy 93.559358 -240.148436)
			(xy 93.60382 -240.169534) (xy 93.644323 -240.19749) (xy 93.679816 -240.231582) (xy 93.709381 -240.270926)
			(xy 93.732252 -240.314503) (xy 93.747836 -240.361184) (xy 93.755731 -240.409761) (xy 93.756226 -240.434368)
			(xy 94.074737 -240.434368) (xy 94.078832 -240.38364) (xy 94.091011 -240.334226) (xy 94.110959 -240.287406)
			(xy 94.13816 -240.244392) (xy 94.171908 -240.206298) (xy 94.21133 -240.174111) (xy 94.255404 -240.148665)
			(xy 94.30299 -240.130618) (xy 94.352854 -240.120438) (xy 94.403706 -240.118389) (xy 94.454227 -240.124523)
			(xy 94.503111 -240.138683) (xy 94.54909 -240.1605) (xy 94.590974 -240.18941) (xy 94.627678 -240.224665)
			(xy 94.658251 -240.265351) (xy 94.681902 -240.310414) (xy 94.698018 -240.358688) (xy 94.706182 -240.408922)
			(xy 94.706694 -240.434368) (xy 95.014791 -240.434368) (xy 95.018886 -240.38364) (xy 95.031065 -240.334226)
			(xy 95.051013 -240.287406) (xy 95.078214 -240.244392) (xy 95.111962 -240.206298) (xy 95.151384 -240.174111)
			(xy 95.195458 -240.148665) (xy 95.243044 -240.130618) (xy 95.292908 -240.120438) (xy 95.34376 -240.118389)
			(xy 95.394281 -240.124523) (xy 95.443165 -240.138683) (xy 95.489144 -240.1605) (xy 95.531028 -240.18941)
			(xy 95.567732 -240.224665) (xy 95.598305 -240.265351) (xy 95.621956 -240.310414) (xy 95.638072 -240.358688)
			(xy 95.646236 -240.408922) (xy 95.646748 -240.434368) (xy 95.965276 -240.434368) (xy 95.969236 -240.385314)
			(xy 95.981013 -240.33753) (xy 96.000304 -240.292254) (xy 96.026607 -240.250658) (xy 96.059242 -240.213821)
			(xy 96.097363 -240.182696) (xy 96.139984 -240.158089) (xy 96.186 -240.140637) (xy 96.234219 -240.130793)
			(xy 96.283394 -240.128812) (xy 96.332249 -240.134744) (xy 96.37952 -240.148436) (xy 96.423982 -240.169534)
			(xy 96.464485 -240.19749) (xy 96.499978 -240.231582) (xy 96.529543 -240.270926) (xy 96.552414 -240.314503)
			(xy 96.567998 -240.361184) (xy 96.575893 -240.409761) (xy 96.576388 -240.434368) (xy 96.90533 -240.434368)
			(xy 96.90929 -240.385314) (xy 96.921067 -240.33753) (xy 96.940358 -240.292254) (xy 96.966661 -240.250658)
			(xy 96.999296 -240.213821) (xy 97.037417 -240.182696) (xy 97.080038 -240.158089) (xy 97.126054 -240.140637)
			(xy 97.174273 -240.130793) (xy 97.223448 -240.128812) (xy 97.272303 -240.134744) (xy 97.319574 -240.148436)
			(xy 97.364036 -240.169534) (xy 97.404539 -240.19749) (xy 97.440032 -240.231582) (xy 97.469597 -240.270926)
			(xy 97.492468 -240.314503) (xy 97.508052 -240.361184) (xy 97.515947 -240.409761) (xy 97.516442 -240.434368)
			(xy 97.84513 -240.434368) (xy 97.84909 -240.385314) (xy 97.860867 -240.33753) (xy 97.880158 -240.292254)
			(xy 97.906461 -240.250658) (xy 97.939096 -240.213821) (xy 97.977217 -240.182696) (xy 98.019838 -240.158089)
			(xy 98.065854 -240.140637) (xy 98.114073 -240.130793) (xy 98.163248 -240.128812) (xy 98.212103 -240.134744)
			(xy 98.259374 -240.148436) (xy 98.303836 -240.169534) (xy 98.344339 -240.19749) (xy 98.379832 -240.231582)
			(xy 98.409397 -240.270926) (xy 98.432268 -240.314503) (xy 98.447852 -240.361184) (xy 98.455747 -240.409761)
			(xy 98.456242 -240.434368) (xy 98.785184 -240.434368) (xy 98.789144 -240.385314) (xy 98.800921 -240.33753)
			(xy 98.820212 -240.292254) (xy 98.846515 -240.250658) (xy 98.87915 -240.213821) (xy 98.917271 -240.182696)
			(xy 98.959892 -240.158089) (xy 99.005908 -240.140637) (xy 99.054127 -240.130793) (xy 99.103302 -240.128812)
			(xy 99.152157 -240.134744) (xy 99.199428 -240.148436) (xy 99.24389 -240.169534) (xy 99.284393 -240.19749)
			(xy 99.319886 -240.231582) (xy 99.349451 -240.270926) (xy 99.372322 -240.314503) (xy 99.387906 -240.361184)
			(xy 99.395801 -240.409761) (xy 99.396296 -240.434368) (xy 99.725238 -240.434368) (xy 99.729198 -240.385314)
			(xy 99.740975 -240.33753) (xy 99.760266 -240.292254) (xy 99.786569 -240.250658) (xy 99.819204 -240.213821)
			(xy 99.857325 -240.182696) (xy 99.899946 -240.158089) (xy 99.945962 -240.140637) (xy 99.994181 -240.130793)
			(xy 100.043356 -240.128812) (xy 100.092211 -240.134744) (xy 100.139482 -240.148436) (xy 100.183944 -240.169534)
			(xy 100.224447 -240.19749) (xy 100.25994 -240.231582) (xy 100.289505 -240.270926) (xy 100.312376 -240.314503)
			(xy 100.32796 -240.361184) (xy 100.335855 -240.409761) (xy 100.33635 -240.434368) (xy 100.665292 -240.434368)
			(xy 100.669252 -240.385314) (xy 100.681029 -240.33753) (xy 100.70032 -240.292254) (xy 100.726623 -240.250658)
			(xy 100.759258 -240.213821) (xy 100.797379 -240.182696) (xy 100.84 -240.158089) (xy 100.886016 -240.140637)
			(xy 100.934235 -240.130793) (xy 100.98341 -240.128812) (xy 101.032265 -240.134744) (xy 101.079536 -240.148436)
			(xy 101.123998 -240.169534) (xy 101.164501 -240.19749) (xy 101.199994 -240.231582) (xy 101.229559 -240.270926)
			(xy 101.25243 -240.314503) (xy 101.268014 -240.361184) (xy 101.275909 -240.409761) (xy 101.276404 -240.434368)
			(xy 101.605346 -240.434368) (xy 101.609306 -240.385314) (xy 101.621083 -240.33753) (xy 101.640374 -240.292254)
			(xy 101.666677 -240.250658) (xy 101.699312 -240.213821) (xy 101.737433 -240.182696) (xy 101.780054 -240.158089)
			(xy 101.82607 -240.140637) (xy 101.874289 -240.130793) (xy 101.923464 -240.128812) (xy 101.972319 -240.134744)
			(xy 102.01959 -240.148436) (xy 102.064052 -240.169534) (xy 102.104555 -240.19749) (xy 102.140048 -240.231582)
			(xy 102.169613 -240.270926) (xy 102.192484 -240.314503) (xy 102.208068 -240.361184) (xy 102.215963 -240.409761)
			(xy 102.216458 -240.434368) (xy 102.545146 -240.434368) (xy 102.549106 -240.385314) (xy 102.560883 -240.33753)
			(xy 102.580174 -240.292254) (xy 102.606477 -240.250658) (xy 102.639112 -240.213821) (xy 102.677233 -240.182696)
			(xy 102.719854 -240.158089) (xy 102.76587 -240.140637) (xy 102.814089 -240.130793) (xy 102.863264 -240.128812)
			(xy 102.912119 -240.134744) (xy 102.95939 -240.148436) (xy 103.003852 -240.169534) (xy 103.044355 -240.19749)
			(xy 103.079848 -240.231582) (xy 103.109413 -240.270926) (xy 103.132284 -240.314503) (xy 103.147868 -240.361184)
			(xy 103.155763 -240.409761) (xy 103.156258 -240.434368) (xy 103.4852 -240.434368) (xy 103.48916 -240.385314)
			(xy 103.500937 -240.33753) (xy 103.520228 -240.292254) (xy 103.546531 -240.250658) (xy 103.579166 -240.213821)
			(xy 103.617287 -240.182696) (xy 103.659908 -240.158089) (xy 103.705924 -240.140637) (xy 103.754143 -240.130793)
			(xy 103.803318 -240.128812) (xy 103.852173 -240.134744) (xy 103.899444 -240.148436) (xy 103.943906 -240.169534)
			(xy 103.984409 -240.19749) (xy 104.019902 -240.231582) (xy 104.049467 -240.270926) (xy 104.072338 -240.314503)
			(xy 104.087922 -240.361184) (xy 104.095817 -240.409761) (xy 104.096312 -240.434368) (xy 104.425254 -240.434368)
			(xy 104.429214 -240.385314) (xy 104.440991 -240.33753) (xy 104.460282 -240.292254) (xy 104.486585 -240.250658)
			(xy 104.51922 -240.213821) (xy 104.557341 -240.182696) (xy 104.599962 -240.158089) (xy 104.645978 -240.140637)
			(xy 104.694197 -240.130793) (xy 104.743372 -240.128812) (xy 104.792227 -240.134744) (xy 104.839498 -240.148436)
			(xy 104.88396 -240.169534) (xy 104.924463 -240.19749) (xy 104.959956 -240.231582) (xy 104.989521 -240.270926)
			(xy 105.012392 -240.314503) (xy 105.027976 -240.361184) (xy 105.035871 -240.409761) (xy 105.036366 -240.434368)
			(xy 105.365308 -240.434368) (xy 105.369268 -240.385314) (xy 105.381045 -240.33753) (xy 105.400336 -240.292254)
			(xy 105.426639 -240.250658) (xy 105.459274 -240.213821) (xy 105.497395 -240.182696) (xy 105.540016 -240.158089)
			(xy 105.586032 -240.140637) (xy 105.634251 -240.130793) (xy 105.683426 -240.128812) (xy 105.732281 -240.134744)
			(xy 105.779552 -240.148436) (xy 105.824014 -240.169534) (xy 105.864517 -240.19749) (xy 105.90001 -240.231582)
			(xy 105.929575 -240.270926) (xy 105.952446 -240.314503) (xy 105.96803 -240.361184) (xy 105.975925 -240.409761)
			(xy 105.97642 -240.434368) (xy 106.305362 -240.434368) (xy 106.309322 -240.385314) (xy 106.321099 -240.33753)
			(xy 106.34039 -240.292254) (xy 106.366693 -240.250658) (xy 106.399328 -240.213821) (xy 106.437449 -240.182696)
			(xy 106.48007 -240.158089) (xy 106.526086 -240.140637) (xy 106.574305 -240.130793) (xy 106.62348 -240.128812)
			(xy 106.672335 -240.134744) (xy 106.719606 -240.148436) (xy 106.764068 -240.169534) (xy 106.804571 -240.19749)
			(xy 106.840064 -240.231582) (xy 106.869629 -240.270926) (xy 106.8925 -240.314503) (xy 106.908084 -240.361184)
			(xy 106.915979 -240.409761) (xy 106.916474 -240.434368) (xy 107.245162 -240.434368) (xy 107.249122 -240.385314)
			(xy 107.260899 -240.33753) (xy 107.28019 -240.292254) (xy 107.306493 -240.250658) (xy 107.339128 -240.213821)
			(xy 107.377249 -240.182696) (xy 107.41987 -240.158089) (xy 107.465886 -240.140637) (xy 107.514105 -240.130793)
			(xy 107.56328 -240.128812) (xy 107.612135 -240.134744) (xy 107.659406 -240.148436) (xy 107.703868 -240.169534)
			(xy 107.744371 -240.19749) (xy 107.779864 -240.231582) (xy 107.809429 -240.270926) (xy 107.8323 -240.314503)
			(xy 107.847884 -240.361184) (xy 107.855779 -240.409761) (xy 107.856274 -240.434368) (xy 108.174785 -240.434368)
			(xy 108.17888 -240.38364) (xy 108.191059 -240.334226) (xy 108.211007 -240.287406) (xy 108.238208 -240.244392)
			(xy 108.271956 -240.206298) (xy 108.311378 -240.174111) (xy 108.355452 -240.148665) (xy 108.403038 -240.130618)
			(xy 108.452902 -240.120438) (xy 108.503754 -240.118389) (xy 108.554275 -240.124523) (xy 108.603159 -240.138683)
			(xy 108.649138 -240.1605) (xy 108.691022 -240.18941) (xy 108.727726 -240.224665) (xy 108.758299 -240.265351)
			(xy 108.78195 -240.310414) (xy 108.798066 -240.358688) (xy 108.80623 -240.408922) (xy 108.806742 -240.434368)
			(xy 109.114839 -240.434368) (xy 109.118934 -240.38364) (xy 109.131113 -240.334226) (xy 109.151061 -240.287406)
			(xy 109.178262 -240.244392) (xy 109.21201 -240.206298) (xy 109.251432 -240.174111) (xy 109.295506 -240.148665)
			(xy 109.343092 -240.130618) (xy 109.392956 -240.120438) (xy 109.443808 -240.118389) (xy 109.494329 -240.124523)
			(xy 109.543213 -240.138683) (xy 109.589192 -240.1605) (xy 109.631076 -240.18941) (xy 109.66778 -240.224665)
			(xy 109.698353 -240.265351) (xy 109.722004 -240.310414) (xy 109.73812 -240.358688) (xy 109.746284 -240.408922)
			(xy 109.746796 -240.434368) (xy 110.065324 -240.434368) (xy 110.069284 -240.385314) (xy 110.081061 -240.33753)
			(xy 110.100352 -240.292254) (xy 110.126655 -240.250658) (xy 110.15929 -240.213821) (xy 110.197411 -240.182696)
			(xy 110.240032 -240.158089) (xy 110.286048 -240.140637) (xy 110.334267 -240.130793) (xy 110.383442 -240.128812)
			(xy 110.432297 -240.134744) (xy 110.479568 -240.148436) (xy 110.52403 -240.169534) (xy 110.564533 -240.19749)
			(xy 110.600026 -240.231582) (xy 110.629591 -240.270926) (xy 110.652462 -240.314503) (xy 110.668046 -240.361184)
			(xy 110.675941 -240.409761) (xy 110.676436 -240.434368) (xy 110.675941 -240.458975) (xy 110.668046 -240.507552)
			(xy 110.652462 -240.554233) (xy 110.629591 -240.59781) (xy 110.600026 -240.637154) (xy 110.564533 -240.671246)
			(xy 110.52403 -240.699202) (xy 110.479568 -240.7203) (xy 110.432297 -240.733992) (xy 110.383442 -240.739924)
			(xy 110.334267 -240.737943) (xy 110.286048 -240.728099) (xy 110.240032 -240.710647) (xy 110.197411 -240.68604)
			(xy 110.15929 -240.654915) (xy 110.126655 -240.618078) (xy 110.100352 -240.576482) (xy 110.081061 -240.531206)
			(xy 110.069284 -240.483422) (xy 110.065324 -240.434368) (xy 109.746796 -240.434368) (xy 109.746284 -240.459814)
			(xy 109.73812 -240.510048) (xy 109.722004 -240.558322) (xy 109.698353 -240.603385) (xy 109.66778 -240.644071)
			(xy 109.631076 -240.679326) (xy 109.589192 -240.708236) (xy 109.543213 -240.730053) (xy 109.494329 -240.744213)
			(xy 109.443808 -240.750347) (xy 109.392956 -240.748298) (xy 109.343092 -240.738118) (xy 109.295506 -240.720071)
			(xy 109.251432 -240.694625) (xy 109.21201 -240.662438) (xy 109.178262 -240.624344) (xy 109.151061 -240.58133)
			(xy 109.131113 -240.53451) (xy 109.118934 -240.485096) (xy 109.114839 -240.434368) (xy 108.806742 -240.434368)
			(xy 108.80623 -240.459814) (xy 108.798066 -240.510048) (xy 108.78195 -240.558322) (xy 108.758299 -240.603385)
			(xy 108.727726 -240.644071) (xy 108.691022 -240.679326) (xy 108.649138 -240.708236) (xy 108.603159 -240.730053)
			(xy 108.554275 -240.744213) (xy 108.503754 -240.750347) (xy 108.452902 -240.748298) (xy 108.403038 -240.738118)
			(xy 108.355452 -240.720071) (xy 108.311378 -240.694625) (xy 108.271956 -240.662438) (xy 108.238208 -240.624344)
			(xy 108.211007 -240.58133) (xy 108.191059 -240.53451) (xy 108.17888 -240.485096) (xy 108.174785 -240.434368)
			(xy 107.856274 -240.434368) (xy 107.855779 -240.458975) (xy 107.847884 -240.507552) (xy 107.8323 -240.554233)
			(xy 107.809429 -240.59781) (xy 107.779864 -240.637154) (xy 107.744371 -240.671246) (xy 107.703868 -240.699202)
			(xy 107.659406 -240.7203) (xy 107.612135 -240.733992) (xy 107.56328 -240.739924) (xy 107.514105 -240.737943)
			(xy 107.465886 -240.728099) (xy 107.41987 -240.710647) (xy 107.377249 -240.68604) (xy 107.339128 -240.654915)
			(xy 107.306493 -240.618078) (xy 107.28019 -240.576482) (xy 107.260899 -240.531206) (xy 107.249122 -240.483422)
			(xy 107.245162 -240.434368) (xy 106.916474 -240.434368) (xy 106.915979 -240.458975) (xy 106.908084 -240.507552)
			(xy 106.8925 -240.554233) (xy 106.869629 -240.59781) (xy 106.840064 -240.637154) (xy 106.804571 -240.671246)
			(xy 106.764068 -240.699202) (xy 106.719606 -240.7203) (xy 106.672335 -240.733992) (xy 106.62348 -240.739924)
			(xy 106.574305 -240.737943) (xy 106.526086 -240.728099) (xy 106.48007 -240.710647) (xy 106.437449 -240.68604)
			(xy 106.399328 -240.654915) (xy 106.366693 -240.618078) (xy 106.34039 -240.576482) (xy 106.321099 -240.531206)
			(xy 106.309322 -240.483422) (xy 106.305362 -240.434368) (xy 105.97642 -240.434368) (xy 105.975925 -240.458975)
			(xy 105.96803 -240.507552) (xy 105.952446 -240.554233) (xy 105.929575 -240.59781) (xy 105.90001 -240.637154)
			(xy 105.864517 -240.671246) (xy 105.824014 -240.699202) (xy 105.779552 -240.7203) (xy 105.732281 -240.733992)
			(xy 105.683426 -240.739924) (xy 105.634251 -240.737943) (xy 105.586032 -240.728099) (xy 105.540016 -240.710647)
			(xy 105.497395 -240.68604) (xy 105.459274 -240.654915) (xy 105.426639 -240.618078) (xy 105.400336 -240.576482)
			(xy 105.381045 -240.531206) (xy 105.369268 -240.483422) (xy 105.365308 -240.434368) (xy 105.036366 -240.434368)
			(xy 105.035871 -240.458975) (xy 105.027976 -240.507552) (xy 105.012392 -240.554233) (xy 104.989521 -240.59781)
			(xy 104.959956 -240.637154) (xy 104.924463 -240.671246) (xy 104.88396 -240.699202) (xy 104.839498 -240.7203)
			(xy 104.792227 -240.733992) (xy 104.743372 -240.739924) (xy 104.694197 -240.737943) (xy 104.645978 -240.728099)
			(xy 104.599962 -240.710647) (xy 104.557341 -240.68604) (xy 104.51922 -240.654915) (xy 104.486585 -240.618078)
			(xy 104.460282 -240.576482) (xy 104.440991 -240.531206) (xy 104.429214 -240.483422) (xy 104.425254 -240.434368)
			(xy 104.096312 -240.434368) (xy 104.095817 -240.458975) (xy 104.087922 -240.507552) (xy 104.072338 -240.554233)
			(xy 104.049467 -240.59781) (xy 104.019902 -240.637154) (xy 103.984409 -240.671246) (xy 103.943906 -240.699202)
			(xy 103.899444 -240.7203) (xy 103.852173 -240.733992) (xy 103.803318 -240.739924) (xy 103.754143 -240.737943)
			(xy 103.705924 -240.728099) (xy 103.659908 -240.710647) (xy 103.617287 -240.68604) (xy 103.579166 -240.654915)
			(xy 103.546531 -240.618078) (xy 103.520228 -240.576482) (xy 103.500937 -240.531206) (xy 103.48916 -240.483422)
			(xy 103.4852 -240.434368) (xy 103.156258 -240.434368) (xy 103.155763 -240.458975) (xy 103.147868 -240.507552)
			(xy 103.132284 -240.554233) (xy 103.109413 -240.59781) (xy 103.079848 -240.637154) (xy 103.044355 -240.671246)
			(xy 103.003852 -240.699202) (xy 102.95939 -240.7203) (xy 102.912119 -240.733992) (xy 102.863264 -240.739924)
			(xy 102.814089 -240.737943) (xy 102.76587 -240.728099) (xy 102.719854 -240.710647) (xy 102.677233 -240.68604)
			(xy 102.639112 -240.654915) (xy 102.606477 -240.618078) (xy 102.580174 -240.576482) (xy 102.560883 -240.531206)
			(xy 102.549106 -240.483422) (xy 102.545146 -240.434368) (xy 102.216458 -240.434368) (xy 102.215963 -240.458975)
			(xy 102.208068 -240.507552) (xy 102.192484 -240.554233) (xy 102.169613 -240.59781) (xy 102.140048 -240.637154)
			(xy 102.104555 -240.671246) (xy 102.064052 -240.699202) (xy 102.01959 -240.7203) (xy 101.972319 -240.733992)
			(xy 101.923464 -240.739924) (xy 101.874289 -240.737943) (xy 101.82607 -240.728099) (xy 101.780054 -240.710647)
			(xy 101.737433 -240.68604) (xy 101.699312 -240.654915) (xy 101.666677 -240.618078) (xy 101.640374 -240.576482)
			(xy 101.621083 -240.531206) (xy 101.609306 -240.483422) (xy 101.605346 -240.434368) (xy 101.276404 -240.434368)
			(xy 101.275909 -240.458975) (xy 101.268014 -240.507552) (xy 101.25243 -240.554233) (xy 101.229559 -240.59781)
			(xy 101.199994 -240.637154) (xy 101.164501 -240.671246) (xy 101.123998 -240.699202) (xy 101.079536 -240.7203)
			(xy 101.032265 -240.733992) (xy 100.98341 -240.739924) (xy 100.934235 -240.737943) (xy 100.886016 -240.728099)
			(xy 100.84 -240.710647) (xy 100.797379 -240.68604) (xy 100.759258 -240.654915) (xy 100.726623 -240.618078)
			(xy 100.70032 -240.576482) (xy 100.681029 -240.531206) (xy 100.669252 -240.483422) (xy 100.665292 -240.434368)
			(xy 100.33635 -240.434368) (xy 100.335855 -240.458975) (xy 100.32796 -240.507552) (xy 100.312376 -240.554233)
			(xy 100.289505 -240.59781) (xy 100.25994 -240.637154) (xy 100.224447 -240.671246) (xy 100.183944 -240.699202)
			(xy 100.139482 -240.7203) (xy 100.092211 -240.733992) (xy 100.043356 -240.739924) (xy 99.994181 -240.737943)
			(xy 99.945962 -240.728099) (xy 99.899946 -240.710647) (xy 99.857325 -240.68604) (xy 99.819204 -240.654915)
			(xy 99.786569 -240.618078) (xy 99.760266 -240.576482) (xy 99.740975 -240.531206) (xy 99.729198 -240.483422)
			(xy 99.725238 -240.434368) (xy 99.396296 -240.434368) (xy 99.395801 -240.458975) (xy 99.387906 -240.507552)
			(xy 99.372322 -240.554233) (xy 99.349451 -240.59781) (xy 99.319886 -240.637154) (xy 99.284393 -240.671246)
			(xy 99.24389 -240.699202) (xy 99.199428 -240.7203) (xy 99.152157 -240.733992) (xy 99.103302 -240.739924)
			(xy 99.054127 -240.737943) (xy 99.005908 -240.728099) (xy 98.959892 -240.710647) (xy 98.917271 -240.68604)
			(xy 98.87915 -240.654915) (xy 98.846515 -240.618078) (xy 98.820212 -240.576482) (xy 98.800921 -240.531206)
			(xy 98.789144 -240.483422) (xy 98.785184 -240.434368) (xy 98.456242 -240.434368) (xy 98.455747 -240.458975)
			(xy 98.447852 -240.507552) (xy 98.432268 -240.554233) (xy 98.409397 -240.59781) (xy 98.379832 -240.637154)
			(xy 98.344339 -240.671246) (xy 98.303836 -240.699202) (xy 98.259374 -240.7203) (xy 98.212103 -240.733992)
			(xy 98.163248 -240.739924) (xy 98.114073 -240.737943) (xy 98.065854 -240.728099) (xy 98.019838 -240.710647)
			(xy 97.977217 -240.68604) (xy 97.939096 -240.654915) (xy 97.906461 -240.618078) (xy 97.880158 -240.576482)
			(xy 97.860867 -240.531206) (xy 97.84909 -240.483422) (xy 97.84513 -240.434368) (xy 97.516442 -240.434368)
			(xy 97.515947 -240.458975) (xy 97.508052 -240.507552) (xy 97.492468 -240.554233) (xy 97.469597 -240.59781)
			(xy 97.440032 -240.637154) (xy 97.404539 -240.671246) (xy 97.364036 -240.699202) (xy 97.319574 -240.7203)
			(xy 97.272303 -240.733992) (xy 97.223448 -240.739924) (xy 97.174273 -240.737943) (xy 97.126054 -240.728099)
			(xy 97.080038 -240.710647) (xy 97.037417 -240.68604) (xy 96.999296 -240.654915) (xy 96.966661 -240.618078)
			(xy 96.940358 -240.576482) (xy 96.921067 -240.531206) (xy 96.90929 -240.483422) (xy 96.90533 -240.434368)
			(xy 96.576388 -240.434368) (xy 96.575893 -240.458975) (xy 96.567998 -240.507552) (xy 96.552414 -240.554233)
			(xy 96.529543 -240.59781) (xy 96.499978 -240.637154) (xy 96.464485 -240.671246) (xy 96.423982 -240.699202)
			(xy 96.37952 -240.7203) (xy 96.332249 -240.733992) (xy 96.283394 -240.739924) (xy 96.234219 -240.737943)
			(xy 96.186 -240.728099) (xy 96.139984 -240.710647) (xy 96.097363 -240.68604) (xy 96.059242 -240.654915)
			(xy 96.026607 -240.618078) (xy 96.000304 -240.576482) (xy 95.981013 -240.531206) (xy 95.969236 -240.483422)
			(xy 95.965276 -240.434368) (xy 95.646748 -240.434368) (xy 95.646236 -240.459814) (xy 95.638072 -240.510048)
			(xy 95.621956 -240.558322) (xy 95.598305 -240.603385) (xy 95.567732 -240.644071) (xy 95.531028 -240.679326)
			(xy 95.489144 -240.708236) (xy 95.443165 -240.730053) (xy 95.394281 -240.744213) (xy 95.34376 -240.750347)
			(xy 95.292908 -240.748298) (xy 95.243044 -240.738118) (xy 95.195458 -240.720071) (xy 95.151384 -240.694625)
			(xy 95.111962 -240.662438) (xy 95.078214 -240.624344) (xy 95.051013 -240.58133) (xy 95.031065 -240.53451)
			(xy 95.018886 -240.485096) (xy 95.014791 -240.434368) (xy 94.706694 -240.434368) (xy 94.706182 -240.459814)
			(xy 94.698018 -240.510048) (xy 94.681902 -240.558322) (xy 94.658251 -240.603385) (xy 94.627678 -240.644071)
			(xy 94.590974 -240.679326) (xy 94.54909 -240.708236) (xy 94.503111 -240.730053) (xy 94.454227 -240.744213)
			(xy 94.403706 -240.750347) (xy 94.352854 -240.748298) (xy 94.30299 -240.738118) (xy 94.255404 -240.720071)
			(xy 94.21133 -240.694625) (xy 94.171908 -240.662438) (xy 94.13816 -240.624344) (xy 94.110959 -240.58133)
			(xy 94.091011 -240.53451) (xy 94.078832 -240.485096) (xy 94.074737 -240.434368) (xy 93.756226 -240.434368)
			(xy 93.755731 -240.458975) (xy 93.747836 -240.507552) (xy 93.732252 -240.554233) (xy 93.709381 -240.59781)
			(xy 93.679816 -240.637154) (xy 93.644323 -240.671246) (xy 93.60382 -240.699202) (xy 93.559358 -240.7203)
			(xy 93.512087 -240.733992) (xy 93.463232 -240.739924) (xy 93.414057 -240.737943) (xy 93.365838 -240.728099)
			(xy 93.319822 -240.710647) (xy 93.277201 -240.68604) (xy 93.23908 -240.654915) (xy 93.206445 -240.618078)
			(xy 93.180142 -240.576482) (xy 93.160851 -240.531206) (xy 93.149074 -240.483422) (xy 93.145114 -240.434368)
			(xy 92.82684 -240.434368) (xy 92.826328 -240.459814) (xy 92.818164 -240.510048) (xy 92.802048 -240.558322)
			(xy 92.778397 -240.603385) (xy 92.747824 -240.644071) (xy 92.71112 -240.679326) (xy 92.669236 -240.708236)
			(xy 92.623257 -240.730053) (xy 92.574373 -240.744213) (xy 92.523852 -240.750347) (xy 92.473 -240.748298)
			(xy 92.423136 -240.738118) (xy 92.37555 -240.720071) (xy 92.331476 -240.694625) (xy 92.292054 -240.662438)
			(xy 92.258306 -240.624344) (xy 92.231105 -240.58133) (xy 92.211157 -240.53451) (xy 92.198978 -240.485096)
			(xy 92.194883 -240.434368) (xy 91.876372 -240.434368) (xy 91.875877 -240.458975) (xy 91.867982 -240.507552)
			(xy 91.852398 -240.554233) (xy 91.829527 -240.59781) (xy 91.799962 -240.637154) (xy 91.764469 -240.671246)
			(xy 91.723966 -240.699202) (xy 91.679504 -240.7203) (xy 91.632233 -240.733992) (xy 91.583378 -240.739924)
			(xy 91.534203 -240.737943) (xy 91.485984 -240.728099) (xy 91.439968 -240.710647) (xy 91.397347 -240.68604)
			(xy 91.359226 -240.654915) (xy 91.326591 -240.618078) (xy 91.300288 -240.576482) (xy 91.280997 -240.531206)
			(xy 91.26922 -240.483422) (xy 91.26526 -240.434368) (xy 90.946732 -240.434368) (xy 90.94622 -240.459814)
			(xy 90.938056 -240.510048) (xy 90.92194 -240.558322) (xy 90.898289 -240.603385) (xy 90.867716 -240.644071)
			(xy 90.831012 -240.679326) (xy 90.789128 -240.708236) (xy 90.743149 -240.730053) (xy 90.694265 -240.744213)
			(xy 90.643744 -240.750347) (xy 90.592892 -240.748298) (xy 90.543028 -240.738118) (xy 90.495442 -240.720071)
			(xy 90.451368 -240.694625) (xy 90.411946 -240.662438) (xy 90.378198 -240.624344) (xy 90.350997 -240.58133)
			(xy 90.331049 -240.53451) (xy 90.31887 -240.485096) (xy 90.314775 -240.434368) (xy 89.995924 -240.434368)
			(xy 89.995925 -240.458641) (xy 89.988263 -240.506522) (xy 89.973131 -240.552591) (xy 89.950909 -240.59569)
			(xy 89.922155 -240.634736) (xy 89.887592 -240.668747) (xy 89.848089 -240.696869) (xy 89.804639 -240.718395)
			(xy 89.758332 -240.732785) (xy 89.73439 -240.736628) (xy 89.715594 -240.739422) (xy 89.690956 -240.76787)
			(xy 89.690956 -240.939066) (xy 89.691225 -240.945952) (xy 89.694965 -240.959209) (xy 89.698322 -240.965228)
			(xy 89.699338 -240.967006) (xy 89.707628 -240.981581) (xy 89.722622 -241.011574) (xy 89.72931 -241.02695)
			(xy 89.736168 -241.04346) (xy 89.741248 -241.056668) (xy 89.762838 -241.073686) (xy 89.879424 -241.088672)
			(xy 89.905078 -241.077496) (xy 89.913206 -241.066066) (xy 89.927673 -241.04677) (xy 89.961663 -241.012559)
			(xy 90.000604 -240.984109) (xy 90.043528 -240.962127) (xy 90.089372 -240.947156) (xy 90.136997 -240.93957)
			(xy 90.16111 -240.939066) (xy 90.186367 -240.939588) (xy 90.236192 -240.947904) (xy 90.283968 -240.964307)
			(xy 90.328393 -240.98835) (xy 90.368255 -241.019377) (xy 90.402467 -241.056542) (xy 90.430095 -241.098831)
			(xy 90.450386 -241.14509) (xy 90.462786 -241.194059) (xy 90.466955 -241.244374) (xy 90.784675 -241.244374)
			(xy 90.78877 -241.193646) (xy 90.800949 -241.144232) (xy 90.820897 -241.097412) (xy 90.848098 -241.054398)
			(xy 90.881846 -241.016304) (xy 90.921268 -240.984117) (xy 90.965342 -240.958671) (xy 91.012928 -240.940624)
			(xy 91.062792 -240.930444) (xy 91.113644 -240.928395) (xy 91.164165 -240.934529) (xy 91.213049 -240.948689)
			(xy 91.259028 -240.970506) (xy 91.300912 -240.999416) (xy 91.337616 -241.034671) (xy 91.368189 -241.075357)
			(xy 91.39184 -241.12042) (xy 91.407956 -241.168694) (xy 91.41612 -241.218928) (xy 91.416632 -241.244374)
			(xy 91.724729 -241.244374) (xy 91.728824 -241.193646) (xy 91.741003 -241.144232) (xy 91.760951 -241.097412)
			(xy 91.788152 -241.054398) (xy 91.8219 -241.016304) (xy 91.861322 -240.984117) (xy 91.905396 -240.958671)
			(xy 91.952982 -240.940624) (xy 92.002846 -240.930444) (xy 92.053698 -240.928395) (xy 92.104219 -240.934529)
			(xy 92.153103 -240.948689) (xy 92.199082 -240.970506) (xy 92.240966 -240.999416) (xy 92.27767 -241.034671)
			(xy 92.308243 -241.075357) (xy 92.331894 -241.12042) (xy 92.34801 -241.168694) (xy 92.356174 -241.218928)
			(xy 92.356686 -241.244374) (xy 92.675214 -241.244374) (xy 92.679174 -241.19532) (xy 92.690951 -241.147536)
			(xy 92.710242 -241.10226) (xy 92.736545 -241.060664) (xy 92.76918 -241.023827) (xy 92.807301 -240.992702)
			(xy 92.849922 -240.968095) (xy 92.895938 -240.950643) (xy 92.944157 -240.940799) (xy 92.993332 -240.938818)
			(xy 93.042187 -240.94475) (xy 93.089458 -240.958442) (xy 93.13392 -240.97954) (xy 93.174423 -241.007496)
			(xy 93.209916 -241.041588) (xy 93.239481 -241.080932) (xy 93.262352 -241.124509) (xy 93.277936 -241.17119)
			(xy 93.285831 -241.219767) (xy 93.286326 -241.244374) (xy 93.604837 -241.244374) (xy 93.608932 -241.193646)
			(xy 93.621111 -241.144232) (xy 93.641059 -241.097412) (xy 93.66826 -241.054398) (xy 93.702008 -241.016304)
			(xy 93.74143 -240.984117) (xy 93.785504 -240.958671) (xy 93.83309 -240.940624) (xy 93.882954 -240.930444)
			(xy 93.933806 -240.928395) (xy 93.984327 -240.934529) (xy 94.033211 -240.948689) (xy 94.07919 -240.970506)
			(xy 94.121074 -240.999416) (xy 94.157778 -241.034671) (xy 94.188351 -241.075357) (xy 94.212002 -241.12042)
			(xy 94.228118 -241.168694) (xy 94.236282 -241.218928) (xy 94.236794 -241.244374) (xy 94.555322 -241.244374)
			(xy 94.559282 -241.19532) (xy 94.571059 -241.147536) (xy 94.59035 -241.10226) (xy 94.616653 -241.060664)
			(xy 94.649288 -241.023827) (xy 94.687409 -240.992702) (xy 94.73003 -240.968095) (xy 94.776046 -240.950643)
			(xy 94.824265 -240.940799) (xy 94.87344 -240.938818) (xy 94.922295 -240.94475) (xy 94.969566 -240.958442)
			(xy 95.014028 -240.97954) (xy 95.054531 -241.007496) (xy 95.090024 -241.041588) (xy 95.119589 -241.080932)
			(xy 95.14246 -241.124509) (xy 95.158044 -241.17119) (xy 95.165939 -241.219767) (xy 95.166434 -241.244374)
			(xy 95.484691 -241.244374) (xy 95.488786 -241.193646) (xy 95.500965 -241.144232) (xy 95.520913 -241.097412)
			(xy 95.548114 -241.054398) (xy 95.581862 -241.016304) (xy 95.621284 -240.984117) (xy 95.665358 -240.958671)
			(xy 95.712944 -240.940624) (xy 95.762808 -240.930444) (xy 95.81366 -240.928395) (xy 95.864181 -240.934529)
			(xy 95.913065 -240.948689) (xy 95.959044 -240.970506) (xy 96.000928 -240.999416) (xy 96.037632 -241.034671)
			(xy 96.068205 -241.075357) (xy 96.091856 -241.12042) (xy 96.107972 -241.168694) (xy 96.116136 -241.218928)
			(xy 96.116648 -241.244374) (xy 96.435176 -241.244374) (xy 96.439136 -241.19532) (xy 96.450913 -241.147536)
			(xy 96.470204 -241.10226) (xy 96.496507 -241.060664) (xy 96.529142 -241.023827) (xy 96.567263 -240.992702)
			(xy 96.609884 -240.968095) (xy 96.6559 -240.950643) (xy 96.704119 -240.940799) (xy 96.753294 -240.938818)
			(xy 96.802149 -240.94475) (xy 96.84942 -240.958442) (xy 96.893882 -240.97954) (xy 96.934385 -241.007496)
			(xy 96.969878 -241.041588) (xy 96.999443 -241.080932) (xy 97.022314 -241.124509) (xy 97.037898 -241.17119)
			(xy 97.045793 -241.219767) (xy 97.046288 -241.244374) (xy 97.364799 -241.244374) (xy 97.368894 -241.193646)
			(xy 97.381073 -241.144232) (xy 97.401021 -241.097412) (xy 97.428222 -241.054398) (xy 97.46197 -241.016304)
			(xy 97.501392 -240.984117) (xy 97.545466 -240.958671) (xy 97.593052 -240.940624) (xy 97.642916 -240.930444)
			(xy 97.693768 -240.928395) (xy 97.744289 -240.934529) (xy 97.793173 -240.948689) (xy 97.839152 -240.970506)
			(xy 97.881036 -240.999416) (xy 97.91774 -241.034671) (xy 97.948313 -241.075357) (xy 97.971964 -241.12042)
			(xy 97.98808 -241.168694) (xy 97.996244 -241.218928) (xy 97.996756 -241.244374) (xy 98.304853 -241.244374)
			(xy 98.308948 -241.193646) (xy 98.321127 -241.144232) (xy 98.341075 -241.097412) (xy 98.368276 -241.054398)
			(xy 98.402024 -241.016304) (xy 98.441446 -240.984117) (xy 98.48552 -240.958671) (xy 98.533106 -240.940624)
			(xy 98.58297 -240.930444) (xy 98.633822 -240.928395) (xy 98.684343 -240.934529) (xy 98.733227 -240.948689)
			(xy 98.779206 -240.970506) (xy 98.82109 -240.999416) (xy 98.857794 -241.034671) (xy 98.888367 -241.075357)
			(xy 98.912018 -241.12042) (xy 98.928134 -241.168694) (xy 98.936298 -241.218928) (xy 98.93681 -241.244374)
			(xy 99.255338 -241.244374) (xy 99.259298 -241.19532) (xy 99.271075 -241.147536) (xy 99.290366 -241.10226)
			(xy 99.316669 -241.060664) (xy 99.349304 -241.023827) (xy 99.387425 -240.992702) (xy 99.430046 -240.968095)
			(xy 99.476062 -240.950643) (xy 99.524281 -240.940799) (xy 99.573456 -240.938818) (xy 99.622311 -240.94475)
			(xy 99.669582 -240.958442) (xy 99.714044 -240.97954) (xy 99.754547 -241.007496) (xy 99.79004 -241.041588)
			(xy 99.819605 -241.080932) (xy 99.842476 -241.124509) (xy 99.85806 -241.17119) (xy 99.865955 -241.219767)
			(xy 99.86645 -241.244374) (xy 100.184707 -241.244374) (xy 100.188802 -241.193646) (xy 100.200981 -241.144232)
			(xy 100.220929 -241.097412) (xy 100.24813 -241.054398) (xy 100.281878 -241.016304) (xy 100.3213 -240.984117)
			(xy 100.365374 -240.958671) (xy 100.41296 -240.940624) (xy 100.462824 -240.930444) (xy 100.513676 -240.928395)
			(xy 100.564197 -240.934529) (xy 100.613081 -240.948689) (xy 100.65906 -240.970506) (xy 100.700944 -240.999416)
			(xy 100.737648 -241.034671) (xy 100.768221 -241.075357) (xy 100.791872 -241.12042) (xy 100.807988 -241.168694)
			(xy 100.816152 -241.218928) (xy 100.816664 -241.244374) (xy 101.124761 -241.244374) (xy 101.128856 -241.193646)
			(xy 101.141035 -241.144232) (xy 101.160983 -241.097412) (xy 101.188184 -241.054398) (xy 101.221932 -241.016304)
			(xy 101.261354 -240.984117) (xy 101.305428 -240.958671) (xy 101.353014 -240.940624) (xy 101.402878 -240.930444)
			(xy 101.45373 -240.928395) (xy 101.504251 -240.934529) (xy 101.553135 -240.948689) (xy 101.599114 -240.970506)
			(xy 101.640998 -240.999416) (xy 101.677702 -241.034671) (xy 101.708275 -241.075357) (xy 101.731926 -241.12042)
			(xy 101.748042 -241.168694) (xy 101.756206 -241.218928) (xy 101.756718 -241.244374) (xy 102.075246 -241.244374)
			(xy 102.079206 -241.19532) (xy 102.090983 -241.147536) (xy 102.110274 -241.10226) (xy 102.136577 -241.060664)
			(xy 102.169212 -241.023827) (xy 102.207333 -240.992702) (xy 102.249954 -240.968095) (xy 102.29597 -240.950643)
			(xy 102.344189 -240.940799) (xy 102.393364 -240.938818) (xy 102.442219 -240.94475) (xy 102.48949 -240.958442)
			(xy 102.533952 -240.97954) (xy 102.574455 -241.007496) (xy 102.609948 -241.041588) (xy 102.639513 -241.080932)
			(xy 102.662384 -241.124509) (xy 102.677968 -241.17119) (xy 102.685863 -241.219767) (xy 102.686358 -241.244374)
			(xy 103.004869 -241.244374) (xy 103.008964 -241.193646) (xy 103.021143 -241.144232) (xy 103.041091 -241.097412)
			(xy 103.068292 -241.054398) (xy 103.10204 -241.016304) (xy 103.141462 -240.984117) (xy 103.185536 -240.958671)
			(xy 103.233122 -240.940624) (xy 103.282986 -240.930444) (xy 103.333838 -240.928395) (xy 103.384359 -240.934529)
			(xy 103.433243 -240.948689) (xy 103.479222 -240.970506) (xy 103.521106 -240.999416) (xy 103.55781 -241.034671)
			(xy 103.588383 -241.075357) (xy 103.612034 -241.12042) (xy 103.62815 -241.168694) (xy 103.636314 -241.218928)
			(xy 103.636826 -241.244374) (xy 103.944923 -241.244374) (xy 103.949018 -241.193646) (xy 103.961197 -241.144232)
			(xy 103.981145 -241.097412) (xy 104.008346 -241.054398) (xy 104.042094 -241.016304) (xy 104.081516 -240.984117)
			(xy 104.12559 -240.958671) (xy 104.173176 -240.940624) (xy 104.22304 -240.930444) (xy 104.273892 -240.928395)
			(xy 104.324413 -240.934529) (xy 104.373297 -240.948689) (xy 104.419276 -240.970506) (xy 104.46116 -240.999416)
			(xy 104.497864 -241.034671) (xy 104.528437 -241.075357) (xy 104.552088 -241.12042) (xy 104.568204 -241.168694)
			(xy 104.576368 -241.218928) (xy 104.57688 -241.244374) (xy 104.895154 -241.244374) (xy 104.899114 -241.19532)
			(xy 104.910891 -241.147536) (xy 104.930182 -241.10226) (xy 104.956485 -241.060664) (xy 104.98912 -241.023827)
			(xy 105.027241 -240.992702) (xy 105.069862 -240.968095) (xy 105.115878 -240.950643) (xy 105.164097 -240.940799)
			(xy 105.213272 -240.938818) (xy 105.262127 -240.94475) (xy 105.309398 -240.958442) (xy 105.35386 -240.97954)
			(xy 105.394363 -241.007496) (xy 105.429856 -241.041588) (xy 105.459421 -241.080932) (xy 105.482292 -241.124509)
			(xy 105.497876 -241.17119) (xy 105.505771 -241.219767) (xy 105.506266 -241.244374) (xy 105.824777 -241.244374)
			(xy 105.828872 -241.193646) (xy 105.841051 -241.144232) (xy 105.860999 -241.097412) (xy 105.8882 -241.054398)
			(xy 105.921948 -241.016304) (xy 105.96137 -240.984117) (xy 106.005444 -240.958671) (xy 106.05303 -240.940624)
			(xy 106.102894 -240.930444) (xy 106.153746 -240.928395) (xy 106.204267 -240.934529) (xy 106.253151 -240.948689)
			(xy 106.29913 -240.970506) (xy 106.341014 -240.999416) (xy 106.377718 -241.034671) (xy 106.408291 -241.075357)
			(xy 106.431942 -241.12042) (xy 106.448058 -241.168694) (xy 106.456222 -241.218928) (xy 106.456734 -241.244374)
			(xy 106.764831 -241.244374) (xy 106.768926 -241.193646) (xy 106.781105 -241.144232) (xy 106.801053 -241.097412)
			(xy 106.828254 -241.054398) (xy 106.862002 -241.016304) (xy 106.901424 -240.984117) (xy 106.945498 -240.958671)
			(xy 106.993084 -240.940624) (xy 107.042948 -240.930444) (xy 107.0938 -240.928395) (xy 107.144321 -240.934529)
			(xy 107.193205 -240.948689) (xy 107.239184 -240.970506) (xy 107.281068 -240.999416) (xy 107.317772 -241.034671)
			(xy 107.348345 -241.075357) (xy 107.371996 -241.12042) (xy 107.388112 -241.168694) (xy 107.396276 -241.218928)
			(xy 107.396788 -241.244374) (xy 107.715316 -241.244374) (xy 107.719276 -241.19532) (xy 107.731053 -241.147536)
			(xy 107.750344 -241.10226) (xy 107.776647 -241.060664) (xy 107.809282 -241.023827) (xy 107.847403 -240.992702)
			(xy 107.890024 -240.968095) (xy 107.93604 -240.950643) (xy 107.984259 -240.940799) (xy 108.033434 -240.938818)
			(xy 108.082289 -240.94475) (xy 108.12956 -240.958442) (xy 108.174022 -240.97954) (xy 108.214525 -241.007496)
			(xy 108.250018 -241.041588) (xy 108.279583 -241.080932) (xy 108.302454 -241.124509) (xy 108.318038 -241.17119)
			(xy 108.325933 -241.219767) (xy 108.326428 -241.244374) (xy 108.65537 -241.244374) (xy 108.65933 -241.19532)
			(xy 108.671107 -241.147536) (xy 108.690398 -241.10226) (xy 108.716701 -241.060664) (xy 108.749336 -241.023827)
			(xy 108.787457 -240.992702) (xy 108.830078 -240.968095) (xy 108.876094 -240.950643) (xy 108.924313 -240.940799)
			(xy 108.973488 -240.938818) (xy 109.022343 -240.94475) (xy 109.069614 -240.958442) (xy 109.114076 -240.97954)
			(xy 109.154579 -241.007496) (xy 109.190072 -241.041588) (xy 109.219637 -241.080932) (xy 109.242508 -241.124509)
			(xy 109.258092 -241.17119) (xy 109.265987 -241.219767) (xy 109.266482 -241.244374) (xy 109.59517 -241.244374)
			(xy 109.59913 -241.19532) (xy 109.610907 -241.147536) (xy 109.630198 -241.10226) (xy 109.656501 -241.060664)
			(xy 109.689136 -241.023827) (xy 109.727257 -240.992702) (xy 109.769878 -240.968095) (xy 109.815894 -240.950643)
			(xy 109.864113 -240.940799) (xy 109.913288 -240.938818) (xy 109.962143 -240.94475) (xy 110.009414 -240.958442)
			(xy 110.053876 -240.97954) (xy 110.094379 -241.007496) (xy 110.129872 -241.041588) (xy 110.159437 -241.080932)
			(xy 110.182308 -241.124509) (xy 110.197892 -241.17119) (xy 110.205787 -241.219767) (xy 110.206282 -241.244374)
			(xy 110.205787 -241.268981) (xy 110.197892 -241.317558) (xy 110.182308 -241.364239) (xy 110.159437 -241.407816)
			(xy 110.129872 -241.44716) (xy 110.094379 -241.481252) (xy 110.053876 -241.509208) (xy 110.009414 -241.530306)
			(xy 109.962143 -241.543998) (xy 109.913288 -241.54993) (xy 109.864113 -241.547949) (xy 109.815894 -241.538105)
			(xy 109.769878 -241.520653) (xy 109.727257 -241.496046) (xy 109.689136 -241.464921) (xy 109.656501 -241.428084)
			(xy 109.630198 -241.386488) (xy 109.610907 -241.341212) (xy 109.59913 -241.293428) (xy 109.59517 -241.244374)
			(xy 109.266482 -241.244374) (xy 109.265987 -241.268981) (xy 109.258092 -241.317558) (xy 109.242508 -241.364239)
			(xy 109.219637 -241.407816) (xy 109.190072 -241.44716) (xy 109.154579 -241.481252) (xy 109.114076 -241.509208)
			(xy 109.069614 -241.530306) (xy 109.022343 -241.543998) (xy 108.973488 -241.54993) (xy 108.924313 -241.547949)
			(xy 108.876094 -241.538105) (xy 108.830078 -241.520653) (xy 108.787457 -241.496046) (xy 108.749336 -241.464921)
			(xy 108.716701 -241.428084) (xy 108.690398 -241.386488) (xy 108.671107 -241.341212) (xy 108.65933 -241.293428)
			(xy 108.65537 -241.244374) (xy 108.326428 -241.244374) (xy 108.325933 -241.268981) (xy 108.318038 -241.317558)
			(xy 108.302454 -241.364239) (xy 108.279583 -241.407816) (xy 108.250018 -241.44716) (xy 108.214525 -241.481252)
			(xy 108.174022 -241.509208) (xy 108.12956 -241.530306) (xy 108.082289 -241.543998) (xy 108.033434 -241.54993)
			(xy 107.984259 -241.547949) (xy 107.93604 -241.538105) (xy 107.890024 -241.520653) (xy 107.847403 -241.496046)
			(xy 107.809282 -241.464921) (xy 107.776647 -241.428084) (xy 107.750344 -241.386488) (xy 107.731053 -241.341212)
			(xy 107.719276 -241.293428) (xy 107.715316 -241.244374) (xy 107.396788 -241.244374) (xy 107.396276 -241.26982)
			(xy 107.388112 -241.320054) (xy 107.371996 -241.368328) (xy 107.348345 -241.413391) (xy 107.317772 -241.454077)
			(xy 107.281068 -241.489332) (xy 107.239184 -241.518242) (xy 107.193205 -241.540059) (xy 107.144321 -241.554219)
			(xy 107.0938 -241.560353) (xy 107.042948 -241.558304) (xy 106.993084 -241.548124) (xy 106.945498 -241.530077)
			(xy 106.901424 -241.504631) (xy 106.862002 -241.472444) (xy 106.828254 -241.43435) (xy 106.801053 -241.391336)
			(xy 106.781105 -241.344516) (xy 106.768926 -241.295102) (xy 106.764831 -241.244374) (xy 106.456734 -241.244374)
			(xy 106.456222 -241.26982) (xy 106.448058 -241.320054) (xy 106.431942 -241.368328) (xy 106.408291 -241.413391)
			(xy 106.377718 -241.454077) (xy 106.341014 -241.489332) (xy 106.29913 -241.518242) (xy 106.253151 -241.540059)
			(xy 106.204267 -241.554219) (xy 106.153746 -241.560353) (xy 106.102894 -241.558304) (xy 106.05303 -241.548124)
			(xy 106.005444 -241.530077) (xy 105.96137 -241.504631) (xy 105.921948 -241.472444) (xy 105.8882 -241.43435)
			(xy 105.860999 -241.391336) (xy 105.841051 -241.344516) (xy 105.828872 -241.295102) (xy 105.824777 -241.244374)
			(xy 105.506266 -241.244374) (xy 105.505771 -241.268981) (xy 105.497876 -241.317558) (xy 105.482292 -241.364239)
			(xy 105.459421 -241.407816) (xy 105.429856 -241.44716) (xy 105.394363 -241.481252) (xy 105.35386 -241.509208)
			(xy 105.309398 -241.530306) (xy 105.262127 -241.543998) (xy 105.213272 -241.54993) (xy 105.164097 -241.547949)
			(xy 105.115878 -241.538105) (xy 105.069862 -241.520653) (xy 105.027241 -241.496046) (xy 104.98912 -241.464921)
			(xy 104.956485 -241.428084) (xy 104.930182 -241.386488) (xy 104.910891 -241.341212) (xy 104.899114 -241.293428)
			(xy 104.895154 -241.244374) (xy 104.57688 -241.244374) (xy 104.576368 -241.26982) (xy 104.568204 -241.320054)
			(xy 104.552088 -241.368328) (xy 104.528437 -241.413391) (xy 104.497864 -241.454077) (xy 104.46116 -241.489332)
			(xy 104.419276 -241.518242) (xy 104.373297 -241.540059) (xy 104.324413 -241.554219) (xy 104.273892 -241.560353)
			(xy 104.22304 -241.558304) (xy 104.173176 -241.548124) (xy 104.12559 -241.530077) (xy 104.081516 -241.504631)
			(xy 104.042094 -241.472444) (xy 104.008346 -241.43435) (xy 103.981145 -241.391336) (xy 103.961197 -241.344516)
			(xy 103.949018 -241.295102) (xy 103.944923 -241.244374) (xy 103.636826 -241.244374) (xy 103.636314 -241.26982)
			(xy 103.62815 -241.320054) (xy 103.612034 -241.368328) (xy 103.588383 -241.413391) (xy 103.55781 -241.454077)
			(xy 103.521106 -241.489332) (xy 103.479222 -241.518242) (xy 103.433243 -241.540059) (xy 103.384359 -241.554219)
			(xy 103.333838 -241.560353) (xy 103.282986 -241.558304) (xy 103.233122 -241.548124) (xy 103.185536 -241.530077)
			(xy 103.141462 -241.504631) (xy 103.10204 -241.472444) (xy 103.068292 -241.43435) (xy 103.041091 -241.391336)
			(xy 103.021143 -241.344516) (xy 103.008964 -241.295102) (xy 103.004869 -241.244374) (xy 102.686358 -241.244374)
			(xy 102.685863 -241.268981) (xy 102.677968 -241.317558) (xy 102.662384 -241.364239) (xy 102.639513 -241.407816)
			(xy 102.609948 -241.44716) (xy 102.574455 -241.481252) (xy 102.533952 -241.509208) (xy 102.48949 -241.530306)
			(xy 102.442219 -241.543998) (xy 102.393364 -241.54993) (xy 102.344189 -241.547949) (xy 102.29597 -241.538105)
			(xy 102.249954 -241.520653) (xy 102.207333 -241.496046) (xy 102.169212 -241.464921) (xy 102.136577 -241.428084)
			(xy 102.110274 -241.386488) (xy 102.090983 -241.341212) (xy 102.079206 -241.293428) (xy 102.075246 -241.244374)
			(xy 101.756718 -241.244374) (xy 101.756206 -241.26982) (xy 101.748042 -241.320054) (xy 101.731926 -241.368328)
			(xy 101.708275 -241.413391) (xy 101.677702 -241.454077) (xy 101.640998 -241.489332) (xy 101.599114 -241.518242)
			(xy 101.553135 -241.540059) (xy 101.504251 -241.554219) (xy 101.45373 -241.560353) (xy 101.402878 -241.558304)
			(xy 101.353014 -241.548124) (xy 101.305428 -241.530077) (xy 101.261354 -241.504631) (xy 101.221932 -241.472444)
			(xy 101.188184 -241.43435) (xy 101.160983 -241.391336) (xy 101.141035 -241.344516) (xy 101.128856 -241.295102)
			(xy 101.124761 -241.244374) (xy 100.816664 -241.244374) (xy 100.816152 -241.26982) (xy 100.807988 -241.320054)
			(xy 100.791872 -241.368328) (xy 100.768221 -241.413391) (xy 100.737648 -241.454077) (xy 100.700944 -241.489332)
			(xy 100.65906 -241.518242) (xy 100.613081 -241.540059) (xy 100.564197 -241.554219) (xy 100.513676 -241.560353)
			(xy 100.462824 -241.558304) (xy 100.41296 -241.548124) (xy 100.365374 -241.530077) (xy 100.3213 -241.504631)
			(xy 100.281878 -241.472444) (xy 100.24813 -241.43435) (xy 100.220929 -241.391336) (xy 100.200981 -241.344516)
			(xy 100.188802 -241.295102) (xy 100.184707 -241.244374) (xy 99.86645 -241.244374) (xy 99.865955 -241.268981)
			(xy 99.85806 -241.317558) (xy 99.842476 -241.364239) (xy 99.819605 -241.407816) (xy 99.79004 -241.44716)
			(xy 99.754547 -241.481252) (xy 99.714044 -241.509208) (xy 99.669582 -241.530306) (xy 99.622311 -241.543998)
			(xy 99.573456 -241.54993) (xy 99.524281 -241.547949) (xy 99.476062 -241.538105) (xy 99.430046 -241.520653)
			(xy 99.387425 -241.496046) (xy 99.349304 -241.464921) (xy 99.316669 -241.428084) (xy 99.290366 -241.386488)
			(xy 99.271075 -241.341212) (xy 99.259298 -241.293428) (xy 99.255338 -241.244374) (xy 98.93681 -241.244374)
			(xy 98.936298 -241.26982) (xy 98.928134 -241.320054) (xy 98.912018 -241.368328) (xy 98.888367 -241.413391)
			(xy 98.857794 -241.454077) (xy 98.82109 -241.489332) (xy 98.779206 -241.518242) (xy 98.733227 -241.540059)
			(xy 98.684343 -241.554219) (xy 98.633822 -241.560353) (xy 98.58297 -241.558304) (xy 98.533106 -241.548124)
			(xy 98.48552 -241.530077) (xy 98.441446 -241.504631) (xy 98.402024 -241.472444) (xy 98.368276 -241.43435)
			(xy 98.341075 -241.391336) (xy 98.321127 -241.344516) (xy 98.308948 -241.295102) (xy 98.304853 -241.244374)
			(xy 97.996756 -241.244374) (xy 97.996244 -241.26982) (xy 97.98808 -241.320054) (xy 97.971964 -241.368328)
			(xy 97.948313 -241.413391) (xy 97.91774 -241.454077) (xy 97.881036 -241.489332) (xy 97.839152 -241.518242)
			(xy 97.793173 -241.540059) (xy 97.744289 -241.554219) (xy 97.693768 -241.560353) (xy 97.642916 -241.558304)
			(xy 97.593052 -241.548124) (xy 97.545466 -241.530077) (xy 97.501392 -241.504631) (xy 97.46197 -241.472444)
			(xy 97.428222 -241.43435) (xy 97.401021 -241.391336) (xy 97.381073 -241.344516) (xy 97.368894 -241.295102)
			(xy 97.364799 -241.244374) (xy 97.046288 -241.244374) (xy 97.045793 -241.268981) (xy 97.037898 -241.317558)
			(xy 97.022314 -241.364239) (xy 96.999443 -241.407816) (xy 96.969878 -241.44716) (xy 96.934385 -241.481252)
			(xy 96.893882 -241.509208) (xy 96.84942 -241.530306) (xy 96.802149 -241.543998) (xy 96.753294 -241.54993)
			(xy 96.704119 -241.547949) (xy 96.6559 -241.538105) (xy 96.609884 -241.520653) (xy 96.567263 -241.496046)
			(xy 96.529142 -241.464921) (xy 96.496507 -241.428084) (xy 96.470204 -241.386488) (xy 96.450913 -241.341212)
			(xy 96.439136 -241.293428) (xy 96.435176 -241.244374) (xy 96.116648 -241.244374) (xy 96.116136 -241.26982)
			(xy 96.107972 -241.320054) (xy 96.091856 -241.368328) (xy 96.068205 -241.413391) (xy 96.037632 -241.454077)
			(xy 96.000928 -241.489332) (xy 95.959044 -241.518242) (xy 95.913065 -241.540059) (xy 95.864181 -241.554219)
			(xy 95.81366 -241.560353) (xy 95.762808 -241.558304) (xy 95.712944 -241.548124) (xy 95.665358 -241.530077)
			(xy 95.621284 -241.504631) (xy 95.581862 -241.472444) (xy 95.548114 -241.43435) (xy 95.520913 -241.391336)
			(xy 95.500965 -241.344516) (xy 95.488786 -241.295102) (xy 95.484691 -241.244374) (xy 95.166434 -241.244374)
			(xy 95.165939 -241.268981) (xy 95.158044 -241.317558) (xy 95.14246 -241.364239) (xy 95.119589 -241.407816)
			(xy 95.090024 -241.44716) (xy 95.054531 -241.481252) (xy 95.014028 -241.509208) (xy 94.969566 -241.530306)
			(xy 94.922295 -241.543998) (xy 94.87344 -241.54993) (xy 94.824265 -241.547949) (xy 94.776046 -241.538105)
			(xy 94.73003 -241.520653) (xy 94.687409 -241.496046) (xy 94.649288 -241.464921) (xy 94.616653 -241.428084)
			(xy 94.59035 -241.386488) (xy 94.571059 -241.341212) (xy 94.559282 -241.293428) (xy 94.555322 -241.244374)
			(xy 94.236794 -241.244374) (xy 94.236282 -241.26982) (xy 94.228118 -241.320054) (xy 94.212002 -241.368328)
			(xy 94.188351 -241.413391) (xy 94.157778 -241.454077) (xy 94.121074 -241.489332) (xy 94.07919 -241.518242)
			(xy 94.033211 -241.540059) (xy 93.984327 -241.554219) (xy 93.933806 -241.560353) (xy 93.882954 -241.558304)
			(xy 93.83309 -241.548124) (xy 93.785504 -241.530077) (xy 93.74143 -241.504631) (xy 93.702008 -241.472444)
			(xy 93.66826 -241.43435) (xy 93.641059 -241.391336) (xy 93.621111 -241.344516) (xy 93.608932 -241.295102)
			(xy 93.604837 -241.244374) (xy 93.286326 -241.244374) (xy 93.285831 -241.268981) (xy 93.277936 -241.317558)
			(xy 93.262352 -241.364239) (xy 93.239481 -241.407816) (xy 93.209916 -241.44716) (xy 93.174423 -241.481252)
			(xy 93.13392 -241.509208) (xy 93.089458 -241.530306) (xy 93.042187 -241.543998) (xy 92.993332 -241.54993)
			(xy 92.944157 -241.547949) (xy 92.895938 -241.538105) (xy 92.849922 -241.520653) (xy 92.807301 -241.496046)
			(xy 92.76918 -241.464921) (xy 92.736545 -241.428084) (xy 92.710242 -241.386488) (xy 92.690951 -241.341212)
			(xy 92.679174 -241.293428) (xy 92.675214 -241.244374) (xy 92.356686 -241.244374) (xy 92.356174 -241.26982)
			(xy 92.34801 -241.320054) (xy 92.331894 -241.368328) (xy 92.308243 -241.413391) (xy 92.27767 -241.454077)
			(xy 92.240966 -241.489332) (xy 92.199082 -241.518242) (xy 92.153103 -241.540059) (xy 92.104219 -241.554219)
			(xy 92.053698 -241.560353) (xy 92.002846 -241.558304) (xy 91.952982 -241.548124) (xy 91.905396 -241.530077)
			(xy 91.861322 -241.504631) (xy 91.8219 -241.472444) (xy 91.788152 -241.43435) (xy 91.760951 -241.391336)
			(xy 91.741003 -241.344516) (xy 91.728824 -241.295102) (xy 91.724729 -241.244374) (xy 91.416632 -241.244374)
			(xy 91.41612 -241.26982) (xy 91.407956 -241.320054) (xy 91.39184 -241.368328) (xy 91.368189 -241.413391)
			(xy 91.337616 -241.454077) (xy 91.300912 -241.489332) (xy 91.259028 -241.518242) (xy 91.213049 -241.540059)
			(xy 91.164165 -241.554219) (xy 91.113644 -241.560353) (xy 91.062792 -241.558304) (xy 91.012928 -241.548124)
			(xy 90.965342 -241.530077) (xy 90.921268 -241.504631) (xy 90.881846 -241.472444) (xy 90.848098 -241.43435)
			(xy 90.820897 -241.391336) (xy 90.800949 -241.344516) (xy 90.78877 -241.295102) (xy 90.784675 -241.244374)
			(xy 90.466955 -241.244374) (xy 90.466957 -241.2444) (xy 90.462786 -241.294741) (xy 90.450386 -241.34371)
			(xy 90.430095 -241.389969) (xy 90.402467 -241.432258) (xy 90.368255 -241.469423) (xy 90.328393 -241.50045)
			(xy 90.283968 -241.524493) (xy 90.236192 -241.540896) (xy 90.186367 -241.549212) (xy 90.16111 -241.549682)
			(xy 90.148347 -241.549546) (xy 90.122912 -241.547387) (xy 90.11031 -241.545364) (xy 90.11031 -241.545618)
			(xy 90.086857 -241.541191) (xy 90.041603 -241.526028) (xy 89.999253 -241.504023) (xy 89.960832 -241.47571)
			(xy 89.927273 -241.441776) (xy 89.912952 -241.422682) (xy 89.904824 -241.411252) (xy 89.87917 -241.400076)
			(xy 89.762838 -241.415062) (xy 89.741248 -241.43208) (xy 89.736168 -241.445288) (xy 89.728022 -241.465612)
			(xy 89.708953 -241.50503) (xy 89.698068 -241.524028) (xy 89.694766 -241.529616) (xy 89.692734 -241.53622)
			(xy 89.690956 -241.549682) (xy 89.690956 -241.720878) (xy 89.715594 -241.749326) (xy 89.73439 -241.75212)
			(xy 89.758322 -241.756026) (xy 89.804627 -241.770414) (xy 89.848076 -241.791938) (xy 89.887579 -241.820058)
			(xy 89.922141 -241.854067) (xy 89.950894 -241.89311) (xy 89.973117 -241.936207) (xy 89.988249 -241.982274)
			(xy 89.995912 -242.030153) (xy 89.995912 -242.05438) (xy 90.314775 -242.05438) (xy 90.31887 -242.003652)
			(xy 90.331049 -241.954238) (xy 90.350997 -241.907418) (xy 90.378198 -241.864404) (xy 90.411946 -241.82631)
			(xy 90.451368 -241.794123) (xy 90.495442 -241.768677) (xy 90.543028 -241.75063) (xy 90.592892 -241.74045)
			(xy 90.643744 -241.738401) (xy 90.694265 -241.744535) (xy 90.743149 -241.758695) (xy 90.789128 -241.780512)
			(xy 90.831012 -241.809422) (xy 90.867716 -241.844677) (xy 90.898289 -241.885363) (xy 90.92194 -241.930426)
			(xy 90.938056 -241.9787) (xy 90.94622 -242.028934) (xy 90.946732 -242.05438) (xy 91.26526 -242.05438)
			(xy 91.26922 -242.005326) (xy 91.280997 -241.957542) (xy 91.300288 -241.912266) (xy 91.326591 -241.87067)
			(xy 91.359226 -241.833833) (xy 91.397347 -241.802708) (xy 91.439968 -241.778101) (xy 91.485984 -241.760649)
			(xy 91.534203 -241.750805) (xy 91.583378 -241.748824) (xy 91.632233 -241.754756) (xy 91.679504 -241.768448)
			(xy 91.723966 -241.789546) (xy 91.764469 -241.817502) (xy 91.799962 -241.851594) (xy 91.829527 -241.890938)
			(xy 91.852398 -241.934515) (xy 91.867982 -241.981196) (xy 91.875877 -242.029773) (xy 91.876372 -242.05438)
			(xy 92.194883 -242.05438) (xy 92.198978 -242.003652) (xy 92.211157 -241.954238) (xy 92.231105 -241.907418)
			(xy 92.258306 -241.864404) (xy 92.292054 -241.82631) (xy 92.331476 -241.794123) (xy 92.37555 -241.768677)
			(xy 92.423136 -241.75063) (xy 92.473 -241.74045) (xy 92.523852 -241.738401) (xy 92.574373 -241.744535)
			(xy 92.623257 -241.758695) (xy 92.669236 -241.780512) (xy 92.71112 -241.809422) (xy 92.747824 -241.844677)
			(xy 92.778397 -241.885363) (xy 92.802048 -241.930426) (xy 92.818164 -241.9787) (xy 92.826328 -242.028934)
			(xy 92.82684 -242.05438) (xy 93.145114 -242.05438) (xy 93.149074 -242.005326) (xy 93.160851 -241.957542)
			(xy 93.180142 -241.912266) (xy 93.206445 -241.87067) (xy 93.23908 -241.833833) (xy 93.277201 -241.802708)
			(xy 93.319822 -241.778101) (xy 93.365838 -241.760649) (xy 93.414057 -241.750805) (xy 93.463232 -241.748824)
			(xy 93.512087 -241.754756) (xy 93.559358 -241.768448) (xy 93.60382 -241.789546) (xy 93.644323 -241.817502)
			(xy 93.679816 -241.851594) (xy 93.709381 -241.890938) (xy 93.732252 -241.934515) (xy 93.747836 -241.981196)
			(xy 93.755731 -242.029773) (xy 93.756226 -242.05438) (xy 94.074737 -242.05438) (xy 94.078832 -242.003652)
			(xy 94.091011 -241.954238) (xy 94.110959 -241.907418) (xy 94.13816 -241.864404) (xy 94.171908 -241.82631)
			(xy 94.21133 -241.794123) (xy 94.255404 -241.768677) (xy 94.30299 -241.75063) (xy 94.352854 -241.74045)
			(xy 94.403706 -241.738401) (xy 94.454227 -241.744535) (xy 94.503111 -241.758695) (xy 94.54909 -241.780512)
			(xy 94.590974 -241.809422) (xy 94.627678 -241.844677) (xy 94.658251 -241.885363) (xy 94.681902 -241.930426)
			(xy 94.698018 -241.9787) (xy 94.706182 -242.028934) (xy 94.706694 -242.05438) (xy 95.014791 -242.05438)
			(xy 95.018886 -242.003652) (xy 95.031065 -241.954238) (xy 95.051013 -241.907418) (xy 95.078214 -241.864404)
			(xy 95.111962 -241.82631) (xy 95.151384 -241.794123) (xy 95.195458 -241.768677) (xy 95.243044 -241.75063)
			(xy 95.292908 -241.74045) (xy 95.34376 -241.738401) (xy 95.394281 -241.744535) (xy 95.443165 -241.758695)
			(xy 95.489144 -241.780512) (xy 95.531028 -241.809422) (xy 95.567732 -241.844677) (xy 95.598305 -241.885363)
			(xy 95.621956 -241.930426) (xy 95.638072 -241.9787) (xy 95.646236 -242.028934) (xy 95.646748 -242.05438)
			(xy 95.965276 -242.05438) (xy 95.969236 -242.005326) (xy 95.981013 -241.957542) (xy 96.000304 -241.912266)
			(xy 96.026607 -241.87067) (xy 96.059242 -241.833833) (xy 96.097363 -241.802708) (xy 96.139984 -241.778101)
			(xy 96.186 -241.760649) (xy 96.234219 -241.750805) (xy 96.283394 -241.748824) (xy 96.332249 -241.754756)
			(xy 96.37952 -241.768448) (xy 96.423982 -241.789546) (xy 96.464485 -241.817502) (xy 96.499978 -241.851594)
			(xy 96.529543 -241.890938) (xy 96.552414 -241.934515) (xy 96.567998 -241.981196) (xy 96.575893 -242.029773)
			(xy 96.576388 -242.05438) (xy 98.785184 -242.05438) (xy 98.789144 -242.005326) (xy 98.800921 -241.957542)
			(xy 98.820212 -241.912266) (xy 98.846515 -241.87067) (xy 98.87915 -241.833833) (xy 98.917271 -241.802708)
			(xy 98.959892 -241.778101) (xy 99.005908 -241.760649) (xy 99.054127 -241.750805) (xy 99.103302 -241.748824)
			(xy 99.152157 -241.754756) (xy 99.199428 -241.768448) (xy 99.24389 -241.789546) (xy 99.284393 -241.817502)
			(xy 99.319886 -241.851594) (xy 99.349451 -241.890938) (xy 99.372322 -241.934515) (xy 99.387906 -241.981196)
			(xy 99.395801 -242.029773) (xy 99.396296 -242.05438) (xy 101.605346 -242.05438) (xy 101.609306 -242.005326)
			(xy 101.621083 -241.957542) (xy 101.640374 -241.912266) (xy 101.666677 -241.87067) (xy 101.699312 -241.833833)
			(xy 101.737433 -241.802708) (xy 101.780054 -241.778101) (xy 101.82607 -241.760649) (xy 101.874289 -241.750805)
			(xy 101.923464 -241.748824) (xy 101.972319 -241.754756) (xy 102.01959 -241.768448) (xy 102.064052 -241.789546)
			(xy 102.104555 -241.817502) (xy 102.140048 -241.851594) (xy 102.169613 -241.890938) (xy 102.192484 -241.934515)
			(xy 102.208068 -241.981196) (xy 102.215963 -242.029773) (xy 102.216458 -242.05438) (xy 104.425254 -242.05438)
			(xy 104.429214 -242.005326) (xy 104.440991 -241.957542) (xy 104.460282 -241.912266) (xy 104.486585 -241.87067)
			(xy 104.51922 -241.833833) (xy 104.557341 -241.802708) (xy 104.599962 -241.778101) (xy 104.645978 -241.760649)
			(xy 104.694197 -241.750805) (xy 104.743372 -241.748824) (xy 104.792227 -241.754756) (xy 104.839498 -241.768448)
			(xy 104.88396 -241.789546) (xy 104.924463 -241.817502) (xy 104.959956 -241.851594) (xy 104.989521 -241.890938)
			(xy 105.012392 -241.934515) (xy 105.027976 -241.981196) (xy 105.035871 -242.029773) (xy 105.036366 -242.05438)
			(xy 107.245162 -242.05438) (xy 107.249122 -242.005326) (xy 107.260899 -241.957542) (xy 107.28019 -241.912266)
			(xy 107.306493 -241.87067) (xy 107.339128 -241.833833) (xy 107.377249 -241.802708) (xy 107.41987 -241.778101)
			(xy 107.465886 -241.760649) (xy 107.514105 -241.750805) (xy 107.56328 -241.748824) (xy 107.612135 -241.754756)
			(xy 107.659406 -241.768448) (xy 107.703868 -241.789546) (xy 107.744371 -241.817502) (xy 107.779864 -241.851594)
			(xy 107.809429 -241.890938) (xy 107.8323 -241.934515) (xy 107.847884 -241.981196) (xy 107.855779 -242.029773)
			(xy 107.856274 -242.05438) (xy 108.174785 -242.05438) (xy 108.17888 -242.003652) (xy 108.191059 -241.954238)
			(xy 108.211007 -241.907418) (xy 108.238208 -241.864404) (xy 108.271956 -241.82631) (xy 108.311378 -241.794123)
			(xy 108.355452 -241.768677) (xy 108.403038 -241.75063) (xy 108.452902 -241.74045) (xy 108.503754 -241.738401)
			(xy 108.554275 -241.744535) (xy 108.603159 -241.758695) (xy 108.649138 -241.780512) (xy 108.691022 -241.809422)
			(xy 108.727726 -241.844677) (xy 108.758299 -241.885363) (xy 108.78195 -241.930426) (xy 108.798066 -241.9787)
			(xy 108.80623 -242.028934) (xy 108.806742 -242.05438) (xy 109.114839 -242.05438) (xy 109.118934 -242.003652)
			(xy 109.131113 -241.954238) (xy 109.151061 -241.907418) (xy 109.178262 -241.864404) (xy 109.21201 -241.82631)
			(xy 109.251432 -241.794123) (xy 109.295506 -241.768677) (xy 109.343092 -241.75063) (xy 109.392956 -241.74045)
			(xy 109.443808 -241.738401) (xy 109.494329 -241.744535) (xy 109.543213 -241.758695) (xy 109.589192 -241.780512)
			(xy 109.631076 -241.809422) (xy 109.66778 -241.844677) (xy 109.698353 -241.885363) (xy 109.722004 -241.930426)
			(xy 109.73812 -241.9787) (xy 109.746284 -242.028934) (xy 109.746796 -242.05438) (xy 110.065324 -242.05438)
			(xy 110.069284 -242.005326) (xy 110.081061 -241.957542) (xy 110.100352 -241.912266) (xy 110.126655 -241.87067)
			(xy 110.15929 -241.833833) (xy 110.197411 -241.802708) (xy 110.240032 -241.778101) (xy 110.286048 -241.760649)
			(xy 110.334267 -241.750805) (xy 110.383442 -241.748824) (xy 110.432297 -241.754756) (xy 110.479568 -241.768448)
			(xy 110.52403 -241.789546) (xy 110.564533 -241.817502) (xy 110.600026 -241.851594) (xy 110.629591 -241.890938)
			(xy 110.652462 -241.934515) (xy 110.668046 -241.981196) (xy 110.675941 -242.029773) (xy 110.676436 -242.05438)
			(xy 110.675941 -242.078987) (xy 110.668046 -242.127564) (xy 110.652462 -242.174245) (xy 110.629591 -242.217822)
			(xy 110.600026 -242.257166) (xy 110.564533 -242.291258) (xy 110.52403 -242.319214) (xy 110.479568 -242.340312)
			(xy 110.432297 -242.354004) (xy 110.383442 -242.359936) (xy 110.334267 -242.357955) (xy 110.286048 -242.348111)
			(xy 110.240032 -242.330659) (xy 110.197411 -242.306052) (xy 110.15929 -242.274927) (xy 110.126655 -242.23809)
			(xy 110.100352 -242.196494) (xy 110.081061 -242.151218) (xy 110.069284 -242.103434) (xy 110.065324 -242.05438)
			(xy 109.746796 -242.05438) (xy 109.746284 -242.079826) (xy 109.73812 -242.13006) (xy 109.722004 -242.178334)
			(xy 109.698353 -242.223397) (xy 109.66778 -242.264083) (xy 109.631076 -242.299338) (xy 109.589192 -242.328248)
			(xy 109.543213 -242.350065) (xy 109.494329 -242.364225) (xy 109.443808 -242.370359) (xy 109.392956 -242.36831)
			(xy 109.343092 -242.35813) (xy 109.295506 -242.340083) (xy 109.251432 -242.314637) (xy 109.21201 -242.28245)
			(xy 109.178262 -242.244356) (xy 109.151061 -242.201342) (xy 109.131113 -242.154522) (xy 109.118934 -242.105108)
			(xy 109.114839 -242.05438) (xy 108.806742 -242.05438) (xy 108.80623 -242.079826) (xy 108.798066 -242.13006)
			(xy 108.78195 -242.178334) (xy 108.758299 -242.223397) (xy 108.727726 -242.264083) (xy 108.691022 -242.299338)
			(xy 108.649138 -242.328248) (xy 108.603159 -242.350065) (xy 108.554275 -242.364225) (xy 108.503754 -242.370359)
			(xy 108.452902 -242.36831) (xy 108.403038 -242.35813) (xy 108.355452 -242.340083) (xy 108.311378 -242.314637)
			(xy 108.271956 -242.28245) (xy 108.238208 -242.244356) (xy 108.211007 -242.201342) (xy 108.191059 -242.154522)
			(xy 108.17888 -242.105108) (xy 108.174785 -242.05438) (xy 107.856274 -242.05438) (xy 107.855779 -242.078987)
			(xy 107.847884 -242.127564) (xy 107.8323 -242.174245) (xy 107.809429 -242.217822) (xy 107.779864 -242.257166)
			(xy 107.744371 -242.291258) (xy 107.703868 -242.319214) (xy 107.659406 -242.340312) (xy 107.612135 -242.354004)
			(xy 107.56328 -242.359936) (xy 107.514105 -242.357955) (xy 107.465886 -242.348111) (xy 107.41987 -242.330659)
			(xy 107.377249 -242.306052) (xy 107.339128 -242.274927) (xy 107.306493 -242.23809) (xy 107.28019 -242.196494)
			(xy 107.260899 -242.151218) (xy 107.249122 -242.103434) (xy 107.245162 -242.05438) (xy 105.036366 -242.05438)
			(xy 105.035871 -242.078987) (xy 105.027976 -242.127564) (xy 105.012392 -242.174245) (xy 104.989521 -242.217822)
			(xy 104.959956 -242.257166) (xy 104.924463 -242.291258) (xy 104.88396 -242.319214) (xy 104.839498 -242.340312)
			(xy 104.792227 -242.354004) (xy 104.743372 -242.359936) (xy 104.694197 -242.357955) (xy 104.645978 -242.348111)
			(xy 104.599962 -242.330659) (xy 104.557341 -242.306052) (xy 104.51922 -242.274927) (xy 104.486585 -242.23809)
			(xy 104.460282 -242.196494) (xy 104.440991 -242.151218) (xy 104.429214 -242.103434) (xy 104.425254 -242.05438)
			(xy 102.216458 -242.05438) (xy 102.215963 -242.078987) (xy 102.208068 -242.127564) (xy 102.192484 -242.174245)
			(xy 102.169613 -242.217822) (xy 102.140048 -242.257166) (xy 102.104555 -242.291258) (xy 102.064052 -242.319214)
			(xy 102.01959 -242.340312) (xy 101.972319 -242.354004) (xy 101.923464 -242.359936) (xy 101.874289 -242.357955)
			(xy 101.82607 -242.348111) (xy 101.780054 -242.330659) (xy 101.737433 -242.306052) (xy 101.699312 -242.274927)
			(xy 101.666677 -242.23809) (xy 101.640374 -242.196494) (xy 101.621083 -242.151218) (xy 101.609306 -242.103434)
			(xy 101.605346 -242.05438) (xy 99.396296 -242.05438) (xy 99.395801 -242.078987) (xy 99.387906 -242.127564)
			(xy 99.372322 -242.174245) (xy 99.349451 -242.217822) (xy 99.319886 -242.257166) (xy 99.284393 -242.291258)
			(xy 99.24389 -242.319214) (xy 99.199428 -242.340312) (xy 99.152157 -242.354004) (xy 99.103302 -242.359936)
			(xy 99.054127 -242.357955) (xy 99.005908 -242.348111) (xy 98.959892 -242.330659) (xy 98.917271 -242.306052)
			(xy 98.87915 -242.274927) (xy 98.846515 -242.23809) (xy 98.820212 -242.196494) (xy 98.800921 -242.151218)
			(xy 98.789144 -242.103434) (xy 98.785184 -242.05438) (xy 96.576388 -242.05438) (xy 96.575893 -242.078987)
			(xy 96.567998 -242.127564) (xy 96.552414 -242.174245) (xy 96.529543 -242.217822) (xy 96.499978 -242.257166)
			(xy 96.464485 -242.291258) (xy 96.423982 -242.319214) (xy 96.37952 -242.340312) (xy 96.332249 -242.354004)
			(xy 96.283394 -242.359936) (xy 96.234219 -242.357955) (xy 96.186 -242.348111) (xy 96.139984 -242.330659)
			(xy 96.097363 -242.306052) (xy 96.059242 -242.274927) (xy 96.026607 -242.23809) (xy 96.000304 -242.196494)
			(xy 95.981013 -242.151218) (xy 95.969236 -242.103434) (xy 95.965276 -242.05438) (xy 95.646748 -242.05438)
			(xy 95.646236 -242.079826) (xy 95.638072 -242.13006) (xy 95.621956 -242.178334) (xy 95.598305 -242.223397)
			(xy 95.567732 -242.264083) (xy 95.531028 -242.299338) (xy 95.489144 -242.328248) (xy 95.443165 -242.350065)
			(xy 95.394281 -242.364225) (xy 95.34376 -242.370359) (xy 95.292908 -242.36831) (xy 95.243044 -242.35813)
			(xy 95.195458 -242.340083) (xy 95.151384 -242.314637) (xy 95.111962 -242.28245) (xy 95.078214 -242.244356)
			(xy 95.051013 -242.201342) (xy 95.031065 -242.154522) (xy 95.018886 -242.105108) (xy 95.014791 -242.05438)
			(xy 94.706694 -242.05438) (xy 94.706182 -242.079826) (xy 94.698018 -242.13006) (xy 94.681902 -242.178334)
			(xy 94.658251 -242.223397) (xy 94.627678 -242.264083) (xy 94.590974 -242.299338) (xy 94.54909 -242.328248)
			(xy 94.503111 -242.350065) (xy 94.454227 -242.364225) (xy 94.403706 -242.370359) (xy 94.352854 -242.36831)
			(xy 94.30299 -242.35813) (xy 94.255404 -242.340083) (xy 94.21133 -242.314637) (xy 94.171908 -242.28245)
			(xy 94.13816 -242.244356) (xy 94.110959 -242.201342) (xy 94.091011 -242.154522) (xy 94.078832 -242.105108)
			(xy 94.074737 -242.05438) (xy 93.756226 -242.05438) (xy 93.755731 -242.078987) (xy 93.747836 -242.127564)
			(xy 93.732252 -242.174245) (xy 93.709381 -242.217822) (xy 93.679816 -242.257166) (xy 93.644323 -242.291258)
			(xy 93.60382 -242.319214) (xy 93.559358 -242.340312) (xy 93.512087 -242.354004) (xy 93.463232 -242.359936)
			(xy 93.414057 -242.357955) (xy 93.365838 -242.348111) (xy 93.319822 -242.330659) (xy 93.277201 -242.306052)
			(xy 93.23908 -242.274927) (xy 93.206445 -242.23809) (xy 93.180142 -242.196494) (xy 93.160851 -242.151218)
			(xy 93.149074 -242.103434) (xy 93.145114 -242.05438) (xy 92.82684 -242.05438) (xy 92.826328 -242.079826)
			(xy 92.818164 -242.13006) (xy 92.802048 -242.178334) (xy 92.778397 -242.223397) (xy 92.747824 -242.264083)
			(xy 92.71112 -242.299338) (xy 92.669236 -242.328248) (xy 92.623257 -242.350065) (xy 92.574373 -242.364225)
			(xy 92.523852 -242.370359) (xy 92.473 -242.36831) (xy 92.423136 -242.35813) (xy 92.37555 -242.340083)
			(xy 92.331476 -242.314637) (xy 92.292054 -242.28245) (xy 92.258306 -242.244356) (xy 92.231105 -242.201342)
			(xy 92.211157 -242.154522) (xy 92.198978 -242.105108) (xy 92.194883 -242.05438) (xy 91.876372 -242.05438)
			(xy 91.875877 -242.078987) (xy 91.867982 -242.127564) (xy 91.852398 -242.174245) (xy 91.829527 -242.217822)
			(xy 91.799962 -242.257166) (xy 91.764469 -242.291258) (xy 91.723966 -242.319214) (xy 91.679504 -242.340312)
			(xy 91.632233 -242.354004) (xy 91.583378 -242.359936) (xy 91.534203 -242.357955) (xy 91.485984 -242.348111)
			(xy 91.439968 -242.330659) (xy 91.397347 -242.306052) (xy 91.359226 -242.274927) (xy 91.326591 -242.23809)
			(xy 91.300288 -242.196494) (xy 91.280997 -242.151218) (xy 91.26922 -242.103434) (xy 91.26526 -242.05438)
			(xy 90.946732 -242.05438) (xy 90.94622 -242.079826) (xy 90.938056 -242.13006) (xy 90.92194 -242.178334)
			(xy 90.898289 -242.223397) (xy 90.867716 -242.264083) (xy 90.831012 -242.299338) (xy 90.789128 -242.328248)
			(xy 90.743149 -242.350065) (xy 90.694265 -242.364225) (xy 90.643744 -242.370359) (xy 90.592892 -242.36831)
			(xy 90.543028 -242.35813) (xy 90.495442 -242.340083) (xy 90.451368 -242.314637) (xy 90.411946 -242.28245)
			(xy 90.378198 -242.244356) (xy 90.350997 -242.201342) (xy 90.331049 -242.154522) (xy 90.31887 -242.105108)
			(xy 90.314775 -242.05438) (xy 89.995912 -242.05438) (xy 89.995913 -242.078641) (xy 89.988251 -242.126521)
			(xy 89.973119 -242.172588) (xy 89.950897 -242.215685) (xy 89.922144 -242.254729) (xy 89.887583 -242.288738)
			(xy 89.848081 -242.316859) (xy 89.804632 -242.338384) (xy 89.758328 -242.352773) (xy 89.73439 -242.35664)
			(xy 89.715594 -242.359434) (xy 89.690956 -242.387882) (xy 89.690956 -242.552728) (xy 89.691122 -242.559461)
			(xy 89.694591 -242.572469) (xy 89.697814 -242.578382) (xy 89.702132 -242.585494) (xy 89.708343 -242.596377)
			(xy 89.719903 -242.61861) (xy 89.725246 -242.629944) (xy 89.738454 -242.660932) (xy 89.743534 -242.673886)
			(xy 89.765378 -242.690904) (xy 89.867486 -242.704112) (xy 89.874224 -242.704694) (xy 89.887606 -242.702772)
			(xy 89.893902 -242.700302) (xy 89.900506 -242.697508) (xy 89.91092 -242.68938) (xy 89.914984 -242.683792)
			(xy 89.929479 -242.664822) (xy 89.963369 -242.6312) (xy 90.002078 -242.60326) (xy 90.044662 -242.581683)
			(xy 90.090085 -242.566995) (xy 90.137241 -242.559554) (xy 90.16111 -242.559078) (xy 90.186366 -242.5596)
			(xy 90.236189 -242.567916) (xy 90.283963 -242.584318) (xy 90.328387 -242.60836) (xy 90.368247 -242.639386)
			(xy 90.402457 -242.676549) (xy 90.430084 -242.718837) (xy 90.450374 -242.765094) (xy 90.462774 -242.814061)
			(xy 90.466944 -242.864386) (xy 90.784675 -242.864386) (xy 90.78877 -242.813658) (xy 90.800949 -242.764244)
			(xy 90.820897 -242.717424) (xy 90.848098 -242.67441) (xy 90.881846 -242.636316) (xy 90.921268 -242.604129)
			(xy 90.965342 -242.578683) (xy 91.012928 -242.560636) (xy 91.062792 -242.550456) (xy 91.113644 -242.548407)
			(xy 91.164165 -242.554541) (xy 91.213049 -242.568701) (xy 91.259028 -242.590518) (xy 91.300912 -242.619428)
			(xy 91.337616 -242.654683) (xy 91.368189 -242.695369) (xy 91.39184 -242.740432) (xy 91.407956 -242.788706)
			(xy 91.41612 -242.83894) (xy 91.416632 -242.864386) (xy 91.724729 -242.864386) (xy 91.728824 -242.813658)
			(xy 91.741003 -242.764244) (xy 91.760951 -242.717424) (xy 91.788152 -242.67441) (xy 91.8219 -242.636316)
			(xy 91.861322 -242.604129) (xy 91.905396 -242.578683) (xy 91.952982 -242.560636) (xy 92.002846 -242.550456)
			(xy 92.053698 -242.548407) (xy 92.104219 -242.554541) (xy 92.153103 -242.568701) (xy 92.199082 -242.590518)
			(xy 92.240966 -242.619428) (xy 92.27767 -242.654683) (xy 92.308243 -242.695369) (xy 92.331894 -242.740432)
			(xy 92.34801 -242.788706) (xy 92.356174 -242.83894) (xy 92.356686 -242.864386) (xy 92.675214 -242.864386)
			(xy 92.679174 -242.815332) (xy 92.690951 -242.767548) (xy 92.710242 -242.722272) (xy 92.736545 -242.680676)
			(xy 92.76918 -242.643839) (xy 92.807301 -242.612714) (xy 92.849922 -242.588107) (xy 92.895938 -242.570655)
			(xy 92.944157 -242.560811) (xy 92.993332 -242.55883) (xy 93.042187 -242.564762) (xy 93.089458 -242.578454)
			(xy 93.13392 -242.599552) (xy 93.174423 -242.627508) (xy 93.209916 -242.6616) (xy 93.239481 -242.700944)
			(xy 93.262352 -242.744521) (xy 93.277936 -242.791202) (xy 93.285831 -242.839779) (xy 93.286326 -242.864386)
			(xy 93.604837 -242.864386) (xy 93.608932 -242.813658) (xy 93.621111 -242.764244) (xy 93.641059 -242.717424)
			(xy 93.66826 -242.67441) (xy 93.702008 -242.636316) (xy 93.74143 -242.604129) (xy 93.785504 -242.578683)
			(xy 93.83309 -242.560636) (xy 93.882954 -242.550456) (xy 93.933806 -242.548407) (xy 93.984327 -242.554541)
			(xy 94.033211 -242.568701) (xy 94.07919 -242.590518) (xy 94.121074 -242.619428) (xy 94.157778 -242.654683)
			(xy 94.188351 -242.695369) (xy 94.212002 -242.740432) (xy 94.228118 -242.788706) (xy 94.236282 -242.83894)
			(xy 94.236794 -242.864386) (xy 94.555322 -242.864386) (xy 94.559282 -242.815332) (xy 94.571059 -242.767548)
			(xy 94.59035 -242.722272) (xy 94.616653 -242.680676) (xy 94.649288 -242.643839) (xy 94.687409 -242.612714)
			(xy 94.73003 -242.588107) (xy 94.776046 -242.570655) (xy 94.824265 -242.560811) (xy 94.87344 -242.55883)
			(xy 94.922295 -242.564762) (xy 94.969566 -242.578454) (xy 95.014028 -242.599552) (xy 95.054531 -242.627508)
			(xy 95.090024 -242.6616) (xy 95.119589 -242.700944) (xy 95.14246 -242.744521) (xy 95.158044 -242.791202)
			(xy 95.165939 -242.839779) (xy 95.166434 -242.864386) (xy 95.484691 -242.864386) (xy 95.488786 -242.813658)
			(xy 95.500965 -242.764244) (xy 95.520913 -242.717424) (xy 95.548114 -242.67441) (xy 95.581862 -242.636316)
			(xy 95.621284 -242.604129) (xy 95.665358 -242.578683) (xy 95.712944 -242.560636) (xy 95.762808 -242.550456)
			(xy 95.81366 -242.548407) (xy 95.864181 -242.554541) (xy 95.913065 -242.568701) (xy 95.959044 -242.590518)
			(xy 96.000928 -242.619428) (xy 96.037632 -242.654683) (xy 96.068205 -242.695369) (xy 96.091856 -242.740432)
			(xy 96.107972 -242.788706) (xy 96.116136 -242.83894) (xy 96.116648 -242.864386) (xy 96.435176 -242.864386)
			(xy 96.439136 -242.815332) (xy 96.450913 -242.767548) (xy 96.470204 -242.722272) (xy 96.496507 -242.680676)
			(xy 96.529142 -242.643839) (xy 96.567263 -242.612714) (xy 96.609884 -242.588107) (xy 96.6559 -242.570655)
			(xy 96.704119 -242.560811) (xy 96.753294 -242.55883) (xy 96.802149 -242.564762) (xy 96.84942 -242.578454)
			(xy 96.893882 -242.599552) (xy 96.934385 -242.627508) (xy 96.969878 -242.6616) (xy 96.999443 -242.700944)
			(xy 97.022314 -242.744521) (xy 97.037898 -242.791202) (xy 97.045793 -242.839779) (xy 97.046288 -242.864386)
			(xy 97.364799 -242.864386) (xy 97.368894 -242.813658) (xy 97.381073 -242.764244) (xy 97.401021 -242.717424)
			(xy 97.428222 -242.67441) (xy 97.46197 -242.636316) (xy 97.501392 -242.604129) (xy 97.545466 -242.578683)
			(xy 97.593052 -242.560636) (xy 97.642916 -242.550456) (xy 97.693768 -242.548407) (xy 97.744289 -242.554541)
			(xy 97.793173 -242.568701) (xy 97.839152 -242.590518) (xy 97.881036 -242.619428) (xy 97.91774 -242.654683)
			(xy 97.948313 -242.695369) (xy 97.971964 -242.740432) (xy 97.98808 -242.788706) (xy 97.996244 -242.83894)
			(xy 97.996756 -242.864386) (xy 98.304853 -242.864386) (xy 98.308948 -242.813658) (xy 98.321127 -242.764244)
			(xy 98.341075 -242.717424) (xy 98.368276 -242.67441) (xy 98.402024 -242.636316) (xy 98.441446 -242.604129)
			(xy 98.48552 -242.578683) (xy 98.533106 -242.560636) (xy 98.58297 -242.550456) (xy 98.633822 -242.548407)
			(xy 98.684343 -242.554541) (xy 98.733227 -242.568701) (xy 98.779206 -242.590518) (xy 98.82109 -242.619428)
			(xy 98.857794 -242.654683) (xy 98.888367 -242.695369) (xy 98.912018 -242.740432) (xy 98.928134 -242.788706)
			(xy 98.936298 -242.83894) (xy 98.93681 -242.864386) (xy 99.255338 -242.864386) (xy 99.259298 -242.815332)
			(xy 99.271075 -242.767548) (xy 99.290366 -242.722272) (xy 99.316669 -242.680676) (xy 99.349304 -242.643839)
			(xy 99.387425 -242.612714) (xy 99.430046 -242.588107) (xy 99.476062 -242.570655) (xy 99.524281 -242.560811)
			(xy 99.573456 -242.55883) (xy 99.622311 -242.564762) (xy 99.669582 -242.578454) (xy 99.714044 -242.599552)
			(xy 99.754547 -242.627508) (xy 99.79004 -242.6616) (xy 99.819605 -242.700944) (xy 99.842476 -242.744521)
			(xy 99.85806 -242.791202) (xy 99.865955 -242.839779) (xy 99.86645 -242.864386) (xy 100.184707 -242.864386)
			(xy 100.188802 -242.813658) (xy 100.200981 -242.764244) (xy 100.220929 -242.717424) (xy 100.24813 -242.67441)
			(xy 100.281878 -242.636316) (xy 100.3213 -242.604129) (xy 100.365374 -242.578683) (xy 100.41296 -242.560636)
			(xy 100.462824 -242.550456) (xy 100.513676 -242.548407) (xy 100.564197 -242.554541) (xy 100.613081 -242.568701)
			(xy 100.65906 -242.590518) (xy 100.700944 -242.619428) (xy 100.737648 -242.654683) (xy 100.768221 -242.695369)
			(xy 100.791872 -242.740432) (xy 100.807988 -242.788706) (xy 100.816152 -242.83894) (xy 100.816664 -242.864386)
			(xy 101.124761 -242.864386) (xy 101.128856 -242.813658) (xy 101.141035 -242.764244) (xy 101.160983 -242.717424)
			(xy 101.188184 -242.67441) (xy 101.221932 -242.636316) (xy 101.261354 -242.604129) (xy 101.305428 -242.578683)
			(xy 101.353014 -242.560636) (xy 101.402878 -242.550456) (xy 101.45373 -242.548407) (xy 101.504251 -242.554541)
			(xy 101.553135 -242.568701) (xy 101.599114 -242.590518) (xy 101.640998 -242.619428) (xy 101.677702 -242.654683)
			(xy 101.708275 -242.695369) (xy 101.731926 -242.740432) (xy 101.748042 -242.788706) (xy 101.756206 -242.83894)
			(xy 101.756718 -242.864386) (xy 102.075246 -242.864386) (xy 102.079206 -242.815332) (xy 102.090983 -242.767548)
			(xy 102.110274 -242.722272) (xy 102.136577 -242.680676) (xy 102.169212 -242.643839) (xy 102.207333 -242.612714)
			(xy 102.249954 -242.588107) (xy 102.29597 -242.570655) (xy 102.344189 -242.560811) (xy 102.393364 -242.55883)
			(xy 102.442219 -242.564762) (xy 102.48949 -242.578454) (xy 102.533952 -242.599552) (xy 102.574455 -242.627508)
			(xy 102.609948 -242.6616) (xy 102.639513 -242.700944) (xy 102.662384 -242.744521) (xy 102.677968 -242.791202)
			(xy 102.685863 -242.839779) (xy 102.686358 -242.864386) (xy 103.004869 -242.864386) (xy 103.008964 -242.813658)
			(xy 103.021143 -242.764244) (xy 103.041091 -242.717424) (xy 103.068292 -242.67441) (xy 103.10204 -242.636316)
			(xy 103.141462 -242.604129) (xy 103.185536 -242.578683) (xy 103.233122 -242.560636) (xy 103.282986 -242.550456)
			(xy 103.333838 -242.548407) (xy 103.384359 -242.554541) (xy 103.433243 -242.568701) (xy 103.479222 -242.590518)
			(xy 103.521106 -242.619428) (xy 103.55781 -242.654683) (xy 103.588383 -242.695369) (xy 103.612034 -242.740432)
			(xy 103.62815 -242.788706) (xy 103.636314 -242.83894) (xy 103.636826 -242.864386) (xy 103.944923 -242.864386)
			(xy 103.949018 -242.813658) (xy 103.961197 -242.764244) (xy 103.981145 -242.717424) (xy 104.008346 -242.67441)
			(xy 104.042094 -242.636316) (xy 104.081516 -242.604129) (xy 104.12559 -242.578683) (xy 104.173176 -242.560636)
			(xy 104.22304 -242.550456) (xy 104.273892 -242.548407) (xy 104.324413 -242.554541) (xy 104.373297 -242.568701)
			(xy 104.419276 -242.590518) (xy 104.46116 -242.619428) (xy 104.497864 -242.654683) (xy 104.528437 -242.695369)
			(xy 104.552088 -242.740432) (xy 104.568204 -242.788706) (xy 104.576368 -242.83894) (xy 104.57688 -242.864386)
			(xy 104.895154 -242.864386) (xy 104.899114 -242.815332) (xy 104.910891 -242.767548) (xy 104.930182 -242.722272)
			(xy 104.956485 -242.680676) (xy 104.98912 -242.643839) (xy 105.027241 -242.612714) (xy 105.069862 -242.588107)
			(xy 105.115878 -242.570655) (xy 105.164097 -242.560811) (xy 105.213272 -242.55883) (xy 105.262127 -242.564762)
			(xy 105.309398 -242.578454) (xy 105.35386 -242.599552) (xy 105.394363 -242.627508) (xy 105.429856 -242.6616)
			(xy 105.459421 -242.700944) (xy 105.482292 -242.744521) (xy 105.497876 -242.791202) (xy 105.505771 -242.839779)
			(xy 105.506266 -242.864386) (xy 105.824777 -242.864386) (xy 105.828872 -242.813658) (xy 105.841051 -242.764244)
			(xy 105.860999 -242.717424) (xy 105.8882 -242.67441) (xy 105.921948 -242.636316) (xy 105.96137 -242.604129)
			(xy 106.005444 -242.578683) (xy 106.05303 -242.560636) (xy 106.102894 -242.550456) (xy 106.153746 -242.548407)
			(xy 106.204267 -242.554541) (xy 106.253151 -242.568701) (xy 106.29913 -242.590518) (xy 106.341014 -242.619428)
			(xy 106.377718 -242.654683) (xy 106.408291 -242.695369) (xy 106.431942 -242.740432) (xy 106.448058 -242.788706)
			(xy 106.456222 -242.83894) (xy 106.456734 -242.864386) (xy 106.764831 -242.864386) (xy 106.768926 -242.813658)
			(xy 106.781105 -242.764244) (xy 106.801053 -242.717424) (xy 106.828254 -242.67441) (xy 106.862002 -242.636316)
			(xy 106.901424 -242.604129) (xy 106.945498 -242.578683) (xy 106.993084 -242.560636) (xy 107.042948 -242.550456)
			(xy 107.0938 -242.548407) (xy 107.144321 -242.554541) (xy 107.193205 -242.568701) (xy 107.239184 -242.590518)
			(xy 107.281068 -242.619428) (xy 107.317772 -242.654683) (xy 107.348345 -242.695369) (xy 107.371996 -242.740432)
			(xy 107.388112 -242.788706) (xy 107.396276 -242.83894) (xy 107.396788 -242.864386) (xy 107.715316 -242.864386)
			(xy 107.719276 -242.815332) (xy 107.731053 -242.767548) (xy 107.750344 -242.722272) (xy 107.776647 -242.680676)
			(xy 107.809282 -242.643839) (xy 107.847403 -242.612714) (xy 107.890024 -242.588107) (xy 107.93604 -242.570655)
			(xy 107.984259 -242.560811) (xy 108.033434 -242.55883) (xy 108.082289 -242.564762) (xy 108.12956 -242.578454)
			(xy 108.174022 -242.599552) (xy 108.214525 -242.627508) (xy 108.250018 -242.6616) (xy 108.279583 -242.700944)
			(xy 108.302454 -242.744521) (xy 108.318038 -242.791202) (xy 108.325933 -242.839779) (xy 108.326428 -242.864386)
			(xy 108.325933 -242.888993) (xy 108.318038 -242.93757) (xy 108.302454 -242.984251) (xy 108.279583 -243.027828)
			(xy 108.250018 -243.067172) (xy 108.214525 -243.101264) (xy 108.174022 -243.12922) (xy 108.12956 -243.150318)
			(xy 108.082289 -243.16401) (xy 108.033434 -243.169942) (xy 107.984259 -243.167961) (xy 107.93604 -243.158117)
			(xy 107.890024 -243.140665) (xy 107.847403 -243.116058) (xy 107.809282 -243.084933) (xy 107.776647 -243.048096)
			(xy 107.750344 -243.0065) (xy 107.731053 -242.961224) (xy 107.719276 -242.91344) (xy 107.715316 -242.864386)
			(xy 107.396788 -242.864386) (xy 107.396276 -242.889832) (xy 107.388112 -242.940066) (xy 107.371996 -242.98834)
			(xy 107.348345 -243.033403) (xy 107.317772 -243.074089) (xy 107.281068 -243.109344) (xy 107.239184 -243.138254)
			(xy 107.193205 -243.160071) (xy 107.144321 -243.174231) (xy 107.0938 -243.180365) (xy 107.042948 -243.178316)
			(xy 106.993084 -243.168136) (xy 106.945498 -243.150089) (xy 106.901424 -243.124643) (xy 106.862002 -243.092456)
			(xy 106.828254 -243.054362) (xy 106.801053 -243.011348) (xy 106.781105 -242.964528) (xy 106.768926 -242.915114)
			(xy 106.764831 -242.864386) (xy 106.456734 -242.864386) (xy 106.456222 -242.889832) (xy 106.448058 -242.940066)
			(xy 106.431942 -242.98834) (xy 106.408291 -243.033403) (xy 106.377718 -243.074089) (xy 106.341014 -243.109344)
			(xy 106.29913 -243.138254) (xy 106.253151 -243.160071) (xy 106.204267 -243.174231) (xy 106.153746 -243.180365)
			(xy 106.102894 -243.178316) (xy 106.05303 -243.168136) (xy 106.005444 -243.150089) (xy 105.96137 -243.124643)
			(xy 105.921948 -243.092456) (xy 105.8882 -243.054362) (xy 105.860999 -243.011348) (xy 105.841051 -242.964528)
			(xy 105.828872 -242.915114) (xy 105.824777 -242.864386) (xy 105.506266 -242.864386) (xy 105.505771 -242.888993)
			(xy 105.497876 -242.93757) (xy 105.482292 -242.984251) (xy 105.459421 -243.027828) (xy 105.429856 -243.067172)
			(xy 105.394363 -243.101264) (xy 105.35386 -243.12922) (xy 105.309398 -243.150318) (xy 105.262127 -243.16401)
			(xy 105.213272 -243.169942) (xy 105.164097 -243.167961) (xy 105.115878 -243.158117) (xy 105.069862 -243.140665)
			(xy 105.027241 -243.116058) (xy 104.98912 -243.084933) (xy 104.956485 -243.048096) (xy 104.930182 -243.0065)
			(xy 104.910891 -242.961224) (xy 104.899114 -242.91344) (xy 104.895154 -242.864386) (xy 104.57688 -242.864386)
			(xy 104.576368 -242.889832) (xy 104.568204 -242.940066) (xy 104.552088 -242.98834) (xy 104.528437 -243.033403)
			(xy 104.497864 -243.074089) (xy 104.46116 -243.109344) (xy 104.419276 -243.138254) (xy 104.373297 -243.160071)
			(xy 104.324413 -243.174231) (xy 104.273892 -243.180365) (xy 104.22304 -243.178316) (xy 104.173176 -243.168136)
			(xy 104.12559 -243.150089) (xy 104.081516 -243.124643) (xy 104.042094 -243.092456) (xy 104.008346 -243.054362)
			(xy 103.981145 -243.011348) (xy 103.961197 -242.964528) (xy 103.949018 -242.915114) (xy 103.944923 -242.864386)
			(xy 103.636826 -242.864386) (xy 103.636314 -242.889832) (xy 103.62815 -242.940066) (xy 103.612034 -242.98834)
			(xy 103.588383 -243.033403) (xy 103.55781 -243.074089) (xy 103.521106 -243.109344) (xy 103.479222 -243.138254)
			(xy 103.433243 -243.160071) (xy 103.384359 -243.174231) (xy 103.333838 -243.180365) (xy 103.282986 -243.178316)
			(xy 103.233122 -243.168136) (xy 103.185536 -243.150089) (xy 103.141462 -243.124643) (xy 103.10204 -243.092456)
			(xy 103.068292 -243.054362) (xy 103.041091 -243.011348) (xy 103.021143 -242.964528) (xy 103.008964 -242.915114)
			(xy 103.004869 -242.864386) (xy 102.686358 -242.864386) (xy 102.685863 -242.888993) (xy 102.677968 -242.93757)
			(xy 102.662384 -242.984251) (xy 102.639513 -243.027828) (xy 102.609948 -243.067172) (xy 102.574455 -243.101264)
			(xy 102.533952 -243.12922) (xy 102.48949 -243.150318) (xy 102.442219 -243.16401) (xy 102.393364 -243.169942)
			(xy 102.344189 -243.167961) (xy 102.29597 -243.158117) (xy 102.249954 -243.140665) (xy 102.207333 -243.116058)
			(xy 102.169212 -243.084933) (xy 102.136577 -243.048096) (xy 102.110274 -243.0065) (xy 102.090983 -242.961224)
			(xy 102.079206 -242.91344) (xy 102.075246 -242.864386) (xy 101.756718 -242.864386) (xy 101.756206 -242.889832)
			(xy 101.748042 -242.940066) (xy 101.731926 -242.98834) (xy 101.708275 -243.033403) (xy 101.677702 -243.074089)
			(xy 101.640998 -243.109344) (xy 101.599114 -243.138254) (xy 101.553135 -243.160071) (xy 101.504251 -243.174231)
			(xy 101.45373 -243.180365) (xy 101.402878 -243.178316) (xy 101.353014 -243.168136) (xy 101.305428 -243.150089)
			(xy 101.261354 -243.124643) (xy 101.221932 -243.092456) (xy 101.188184 -243.054362) (xy 101.160983 -243.011348)
			(xy 101.141035 -242.964528) (xy 101.128856 -242.915114) (xy 101.124761 -242.864386) (xy 100.816664 -242.864386)
			(xy 100.816152 -242.889832) (xy 100.807988 -242.940066) (xy 100.791872 -242.98834) (xy 100.768221 -243.033403)
			(xy 100.737648 -243.074089) (xy 100.700944 -243.109344) (xy 100.65906 -243.138254) (xy 100.613081 -243.160071)
			(xy 100.564197 -243.174231) (xy 100.513676 -243.180365) (xy 100.462824 -243.178316) (xy 100.41296 -243.168136)
			(xy 100.365374 -243.150089) (xy 100.3213 -243.124643) (xy 100.281878 -243.092456) (xy 100.24813 -243.054362)
			(xy 100.220929 -243.011348) (xy 100.200981 -242.964528) (xy 100.188802 -242.915114) (xy 100.184707 -242.864386)
			(xy 99.86645 -242.864386) (xy 99.865955 -242.888993) (xy 99.85806 -242.93757) (xy 99.842476 -242.984251)
			(xy 99.819605 -243.027828) (xy 99.79004 -243.067172) (xy 99.754547 -243.101264) (xy 99.714044 -243.12922)
			(xy 99.669582 -243.150318) (xy 99.622311 -243.16401) (xy 99.573456 -243.169942) (xy 99.524281 -243.167961)
			(xy 99.476062 -243.158117) (xy 99.430046 -243.140665) (xy 99.387425 -243.116058) (xy 99.349304 -243.084933)
			(xy 99.316669 -243.048096) (xy 99.290366 -243.0065) (xy 99.271075 -242.961224) (xy 99.259298 -242.91344)
			(xy 99.255338 -242.864386) (xy 98.93681 -242.864386) (xy 98.936298 -242.889832) (xy 98.928134 -242.940066)
			(xy 98.912018 -242.98834) (xy 98.888367 -243.033403) (xy 98.857794 -243.074089) (xy 98.82109 -243.109344)
			(xy 98.779206 -243.138254) (xy 98.733227 -243.160071) (xy 98.684343 -243.174231) (xy 98.633822 -243.180365)
			(xy 98.58297 -243.178316) (xy 98.533106 -243.168136) (xy 98.48552 -243.150089) (xy 98.441446 -243.124643)
			(xy 98.402024 -243.092456) (xy 98.368276 -243.054362) (xy 98.341075 -243.011348) (xy 98.321127 -242.964528)
			(xy 98.308948 -242.915114) (xy 98.304853 -242.864386) (xy 97.996756 -242.864386) (xy 97.996244 -242.889832)
			(xy 97.98808 -242.940066) (xy 97.971964 -242.98834) (xy 97.948313 -243.033403) (xy 97.91774 -243.074089)
			(xy 97.881036 -243.109344) (xy 97.839152 -243.138254) (xy 97.793173 -243.160071) (xy 97.744289 -243.174231)
			(xy 97.693768 -243.180365) (xy 97.642916 -243.178316) (xy 97.593052 -243.168136) (xy 97.545466 -243.150089)
			(xy 97.501392 -243.124643) (xy 97.46197 -243.092456) (xy 97.428222 -243.054362) (xy 97.401021 -243.011348)
			(xy 97.381073 -242.964528) (xy 97.368894 -242.915114) (xy 97.364799 -242.864386) (xy 97.046288 -242.864386)
			(xy 97.045793 -242.888993) (xy 97.037898 -242.93757) (xy 97.022314 -242.984251) (xy 96.999443 -243.027828)
			(xy 96.969878 -243.067172) (xy 96.934385 -243.101264) (xy 96.893882 -243.12922) (xy 96.84942 -243.150318)
			(xy 96.802149 -243.16401) (xy 96.753294 -243.169942) (xy 96.704119 -243.167961) (xy 96.6559 -243.158117)
			(xy 96.609884 -243.140665) (xy 96.567263 -243.116058) (xy 96.529142 -243.084933) (xy 96.496507 -243.048096)
			(xy 96.470204 -243.0065) (xy 96.450913 -242.961224) (xy 96.439136 -242.91344) (xy 96.435176 -242.864386)
			(xy 96.116648 -242.864386) (xy 96.116136 -242.889832) (xy 96.107972 -242.940066) (xy 96.091856 -242.98834)
			(xy 96.068205 -243.033403) (xy 96.037632 -243.074089) (xy 96.000928 -243.109344) (xy 95.959044 -243.138254)
			(xy 95.913065 -243.160071) (xy 95.864181 -243.174231) (xy 95.81366 -243.180365) (xy 95.762808 -243.178316)
			(xy 95.712944 -243.168136) (xy 95.665358 -243.150089) (xy 95.621284 -243.124643) (xy 95.581862 -243.092456)
			(xy 95.548114 -243.054362) (xy 95.520913 -243.011348) (xy 95.500965 -242.964528) (xy 95.488786 -242.915114)
			(xy 95.484691 -242.864386) (xy 95.166434 -242.864386) (xy 95.165939 -242.888993) (xy 95.158044 -242.93757)
			(xy 95.14246 -242.984251) (xy 95.119589 -243.027828) (xy 95.090024 -243.067172) (xy 95.054531 -243.101264)
			(xy 95.014028 -243.12922) (xy 94.969566 -243.150318) (xy 94.922295 -243.16401) (xy 94.87344 -243.169942)
			(xy 94.824265 -243.167961) (xy 94.776046 -243.158117) (xy 94.73003 -243.140665) (xy 94.687409 -243.116058)
			(xy 94.649288 -243.084933) (xy 94.616653 -243.048096) (xy 94.59035 -243.0065) (xy 94.571059 -242.961224)
			(xy 94.559282 -242.91344) (xy 94.555322 -242.864386) (xy 94.236794 -242.864386) (xy 94.236282 -242.889832)
			(xy 94.228118 -242.940066) (xy 94.212002 -242.98834) (xy 94.188351 -243.033403) (xy 94.157778 -243.074089)
			(xy 94.121074 -243.109344) (xy 94.07919 -243.138254) (xy 94.033211 -243.160071) (xy 93.984327 -243.174231)
			(xy 93.933806 -243.180365) (xy 93.882954 -243.178316) (xy 93.83309 -243.168136) (xy 93.785504 -243.150089)
			(xy 93.74143 -243.124643) (xy 93.702008 -243.092456) (xy 93.66826 -243.054362) (xy 93.641059 -243.011348)
			(xy 93.621111 -242.964528) (xy 93.608932 -242.915114) (xy 93.604837 -242.864386) (xy 93.286326 -242.864386)
			(xy 93.285831 -242.888993) (xy 93.277936 -242.93757) (xy 93.262352 -242.984251) (xy 93.239481 -243.027828)
			(xy 93.209916 -243.067172) (xy 93.174423 -243.101264) (xy 93.13392 -243.12922) (xy 93.089458 -243.150318)
			(xy 93.042187 -243.16401) (xy 92.993332 -243.169942) (xy 92.944157 -243.167961) (xy 92.895938 -243.158117)
			(xy 92.849922 -243.140665) (xy 92.807301 -243.116058) (xy 92.76918 -243.084933) (xy 92.736545 -243.048096)
			(xy 92.710242 -243.0065) (xy 92.690951 -242.961224) (xy 92.679174 -242.91344) (xy 92.675214 -242.864386)
			(xy 92.356686 -242.864386) (xy 92.356174 -242.889832) (xy 92.34801 -242.940066) (xy 92.331894 -242.98834)
			(xy 92.308243 -243.033403) (xy 92.27767 -243.074089) (xy 92.240966 -243.109344) (xy 92.199082 -243.138254)
			(xy 92.153103 -243.160071) (xy 92.104219 -243.174231) (xy 92.053698 -243.180365) (xy 92.002846 -243.178316)
			(xy 91.952982 -243.168136) (xy 91.905396 -243.150089) (xy 91.861322 -243.124643) (xy 91.8219 -243.092456)
			(xy 91.788152 -243.054362) (xy 91.760951 -243.011348) (xy 91.741003 -242.964528) (xy 91.728824 -242.915114)
			(xy 91.724729 -242.864386) (xy 91.416632 -242.864386) (xy 91.41612 -242.889832) (xy 91.407956 -242.940066)
			(xy 91.39184 -242.98834) (xy 91.368189 -243.033403) (xy 91.337616 -243.074089) (xy 91.300912 -243.109344)
			(xy 91.259028 -243.138254) (xy 91.213049 -243.160071) (xy 91.164165 -243.174231) (xy 91.113644 -243.180365)
			(xy 91.062792 -243.178316) (xy 91.012928 -243.168136) (xy 90.965342 -243.150089) (xy 90.921268 -243.124643)
			(xy 90.881846 -243.092456) (xy 90.848098 -243.054362) (xy 90.820897 -243.011348) (xy 90.800949 -242.964528)
			(xy 90.78877 -242.915114) (xy 90.784675 -242.864386) (xy 90.466944 -242.864386) (xy 90.466945 -242.8644)
			(xy 90.462774 -242.914739) (xy 90.450374 -242.963706) (xy 90.430084 -243.009963) (xy 90.402457 -243.052251)
			(xy 90.368247 -243.089414) (xy 90.328387 -243.12044) (xy 90.283963 -243.144482) (xy 90.236189 -243.160884)
			(xy 90.186366 -243.1692) (xy 90.16111 -243.169694) (xy 90.137239 -243.169233) (xy 90.090079 -243.161801)
			(xy 90.044652 -243.147116) (xy 90.002066 -243.125536) (xy 89.963359 -243.097588) (xy 89.929476 -243.063954)
			(xy 89.914984 -243.04498) (xy 89.91092 -243.039392) (xy 89.900506 -243.031264) (xy 89.893902 -243.02847)
			(xy 89.887618 -243.025956) (xy 89.874226 -243.024037) (xy 89.867486 -243.02466) (xy 89.765378 -243.037868)
			(xy 89.743534 -243.054886) (xy 89.738454 -243.06784) (xy 89.72985 -243.089053) (xy 89.70963 -243.130125)
			(xy 89.698068 -243.149882) (xy 89.694512 -243.155724) (xy 89.690956 -243.168932) (xy 89.690956 -243.34089)
			(xy 89.715594 -243.369338) (xy 89.73439 -243.372132) (xy 89.758321 -243.376038) (xy 89.804624 -243.390425)
			(xy 89.848072 -243.411949) (xy 89.887572 -243.440068) (xy 89.922133 -243.474076) (xy 89.950885 -243.513118)
			(xy 89.973106 -243.556213) (xy 89.988238 -243.602278) (xy 89.9959 -243.650155) (xy 89.9959 -243.674392)
			(xy 90.314775 -243.674392) (xy 90.31887 -243.623664) (xy 90.331049 -243.57425) (xy 90.350997 -243.52743)
			(xy 90.378198 -243.484416) (xy 90.411946 -243.446322) (xy 90.451368 -243.414135) (xy 90.495442 -243.388689)
			(xy 90.543028 -243.370642) (xy 90.592892 -243.360462) (xy 90.643744 -243.358413) (xy 90.694265 -243.364547)
			(xy 90.743149 -243.378707) (xy 90.789128 -243.400524) (xy 90.831012 -243.429434) (xy 90.867716 -243.464689)
			(xy 90.898289 -243.505375) (xy 90.92194 -243.550438) (xy 90.938056 -243.598712) (xy 90.94622 -243.648946)
			(xy 90.946732 -243.674392) (xy 91.26526 -243.674392) (xy 91.26922 -243.625338) (xy 91.280997 -243.577554)
			(xy 91.300288 -243.532278) (xy 91.326591 -243.490682) (xy 91.359226 -243.453845) (xy 91.397347 -243.42272)
			(xy 91.439968 -243.398113) (xy 91.485984 -243.380661) (xy 91.534203 -243.370817) (xy 91.583378 -243.368836)
			(xy 91.632233 -243.374768) (xy 91.679504 -243.38846) (xy 91.723966 -243.409558) (xy 91.764469 -243.437514)
			(xy 91.799962 -243.471606) (xy 91.829527 -243.51095) (xy 91.852398 -243.554527) (xy 91.867982 -243.601208)
			(xy 91.875877 -243.649785) (xy 91.876372 -243.674392) (xy 92.194883 -243.674392) (xy 92.198978 -243.623664)
			(xy 92.211157 -243.57425) (xy 92.231105 -243.52743) (xy 92.258306 -243.484416) (xy 92.292054 -243.446322)
			(xy 92.331476 -243.414135) (xy 92.37555 -243.388689) (xy 92.423136 -243.370642) (xy 92.473 -243.360462)
			(xy 92.523852 -243.358413) (xy 92.574373 -243.364547) (xy 92.623257 -243.378707) (xy 92.669236 -243.400524)
			(xy 92.71112 -243.429434) (xy 92.747824 -243.464689) (xy 92.778397 -243.505375) (xy 92.802048 -243.550438)
			(xy 92.818164 -243.598712) (xy 92.826328 -243.648946) (xy 92.82684 -243.674392) (xy 93.145114 -243.674392)
			(xy 93.149074 -243.625338) (xy 93.160851 -243.577554) (xy 93.180142 -243.532278) (xy 93.206445 -243.490682)
			(xy 93.23908 -243.453845) (xy 93.277201 -243.42272) (xy 93.319822 -243.398113) (xy 93.365838 -243.380661)
			(xy 93.414057 -243.370817) (xy 93.463232 -243.368836) (xy 93.512087 -243.374768) (xy 93.559358 -243.38846)
			(xy 93.60382 -243.409558) (xy 93.644323 -243.437514) (xy 93.679816 -243.471606) (xy 93.709381 -243.51095)
			(xy 93.732252 -243.554527) (xy 93.747836 -243.601208) (xy 93.755731 -243.649785) (xy 93.756226 -243.674392)
			(xy 94.074737 -243.674392) (xy 94.078832 -243.623664) (xy 94.091011 -243.57425) (xy 94.110959 -243.52743)
			(xy 94.13816 -243.484416) (xy 94.171908 -243.446322) (xy 94.21133 -243.414135) (xy 94.255404 -243.388689)
			(xy 94.30299 -243.370642) (xy 94.352854 -243.360462) (xy 94.403706 -243.358413) (xy 94.454227 -243.364547)
			(xy 94.503111 -243.378707) (xy 94.54909 -243.400524) (xy 94.590974 -243.429434) (xy 94.627678 -243.464689)
			(xy 94.658251 -243.505375) (xy 94.681902 -243.550438) (xy 94.698018 -243.598712) (xy 94.706182 -243.648946)
			(xy 94.706694 -243.674392) (xy 95.014791 -243.674392) (xy 95.018886 -243.623664) (xy 95.031065 -243.57425)
			(xy 95.051013 -243.52743) (xy 95.078214 -243.484416) (xy 95.111962 -243.446322) (xy 95.151384 -243.414135)
			(xy 95.195458 -243.388689) (xy 95.243044 -243.370642) (xy 95.292908 -243.360462) (xy 95.34376 -243.358413)
			(xy 95.394281 -243.364547) (xy 95.443165 -243.378707) (xy 95.489144 -243.400524) (xy 95.531028 -243.429434)
			(xy 95.567732 -243.464689) (xy 95.598305 -243.505375) (xy 95.621956 -243.550438) (xy 95.638072 -243.598712)
			(xy 95.646236 -243.648946) (xy 95.646748 -243.674392) (xy 95.965276 -243.674392) (xy 95.969236 -243.625338)
			(xy 95.981013 -243.577554) (xy 96.000304 -243.532278) (xy 96.026607 -243.490682) (xy 96.059242 -243.453845)
			(xy 96.097363 -243.42272) (xy 96.139984 -243.398113) (xy 96.186 -243.380661) (xy 96.234219 -243.370817)
			(xy 96.283394 -243.368836) (xy 96.332249 -243.374768) (xy 96.37952 -243.38846) (xy 96.423982 -243.409558)
			(xy 96.464485 -243.437514) (xy 96.499978 -243.471606) (xy 96.529543 -243.51095) (xy 96.552414 -243.554527)
			(xy 96.567998 -243.601208) (xy 96.575893 -243.649785) (xy 96.576388 -243.674392) (xy 96.90533 -243.674392)
			(xy 96.90929 -243.625338) (xy 96.921067 -243.577554) (xy 96.940358 -243.532278) (xy 96.966661 -243.490682)
			(xy 96.999296 -243.453845) (xy 97.037417 -243.42272) (xy 97.080038 -243.398113) (xy 97.126054 -243.380661)
			(xy 97.174273 -243.370817) (xy 97.223448 -243.368836) (xy 97.272303 -243.374768) (xy 97.319574 -243.38846)
			(xy 97.364036 -243.409558) (xy 97.404539 -243.437514) (xy 97.440032 -243.471606) (xy 97.469597 -243.51095)
			(xy 97.492468 -243.554527) (xy 97.508052 -243.601208) (xy 97.515947 -243.649785) (xy 97.516442 -243.674392)
			(xy 97.84513 -243.674392) (xy 97.84909 -243.625338) (xy 97.860867 -243.577554) (xy 97.880158 -243.532278)
			(xy 97.906461 -243.490682) (xy 97.939096 -243.453845) (xy 97.977217 -243.42272) (xy 98.019838 -243.398113)
			(xy 98.065854 -243.380661) (xy 98.114073 -243.370817) (xy 98.163248 -243.368836) (xy 98.212103 -243.374768)
			(xy 98.259374 -243.38846) (xy 98.303836 -243.409558) (xy 98.344339 -243.437514) (xy 98.379832 -243.471606)
			(xy 98.409397 -243.51095) (xy 98.432268 -243.554527) (xy 98.447852 -243.601208) (xy 98.455747 -243.649785)
			(xy 98.456242 -243.674392) (xy 98.785184 -243.674392) (xy 98.789144 -243.625338) (xy 98.800921 -243.577554)
			(xy 98.820212 -243.532278) (xy 98.846515 -243.490682) (xy 98.87915 -243.453845) (xy 98.917271 -243.42272)
			(xy 98.959892 -243.398113) (xy 99.005908 -243.380661) (xy 99.054127 -243.370817) (xy 99.103302 -243.368836)
			(xy 99.152157 -243.374768) (xy 99.199428 -243.38846) (xy 99.24389 -243.409558) (xy 99.284393 -243.437514)
			(xy 99.319886 -243.471606) (xy 99.349451 -243.51095) (xy 99.372322 -243.554527) (xy 99.387906 -243.601208)
			(xy 99.395801 -243.649785) (xy 99.396296 -243.674392) (xy 99.725238 -243.674392) (xy 99.729198 -243.625338)
			(xy 99.740975 -243.577554) (xy 99.760266 -243.532278) (xy 99.786569 -243.490682) (xy 99.819204 -243.453845)
			(xy 99.857325 -243.42272) (xy 99.899946 -243.398113) (xy 99.945962 -243.380661) (xy 99.994181 -243.370817)
			(xy 100.043356 -243.368836) (xy 100.092211 -243.374768) (xy 100.139482 -243.38846) (xy 100.183944 -243.409558)
			(xy 100.224447 -243.437514) (xy 100.25994 -243.471606) (xy 100.289505 -243.51095) (xy 100.312376 -243.554527)
			(xy 100.32796 -243.601208) (xy 100.335855 -243.649785) (xy 100.33635 -243.674392) (xy 100.665292 -243.674392)
			(xy 100.669252 -243.625338) (xy 100.681029 -243.577554) (xy 100.70032 -243.532278) (xy 100.726623 -243.490682)
			(xy 100.759258 -243.453845) (xy 100.797379 -243.42272) (xy 100.84 -243.398113) (xy 100.886016 -243.380661)
			(xy 100.934235 -243.370817) (xy 100.98341 -243.368836) (xy 101.032265 -243.374768) (xy 101.079536 -243.38846)
			(xy 101.123998 -243.409558) (xy 101.164501 -243.437514) (xy 101.199994 -243.471606) (xy 101.229559 -243.51095)
			(xy 101.25243 -243.554527) (xy 101.268014 -243.601208) (xy 101.275909 -243.649785) (xy 101.276404 -243.674392)
			(xy 101.605346 -243.674392) (xy 101.609306 -243.625338) (xy 101.621083 -243.577554) (xy 101.640374 -243.532278)
			(xy 101.666677 -243.490682) (xy 101.699312 -243.453845) (xy 101.737433 -243.42272) (xy 101.780054 -243.398113)
			(xy 101.82607 -243.380661) (xy 101.874289 -243.370817) (xy 101.923464 -243.368836) (xy 101.972319 -243.374768)
			(xy 102.01959 -243.38846) (xy 102.064052 -243.409558) (xy 102.104555 -243.437514) (xy 102.140048 -243.471606)
			(xy 102.169613 -243.51095) (xy 102.192484 -243.554527) (xy 102.208068 -243.601208) (xy 102.215963 -243.649785)
			(xy 102.216458 -243.674392) (xy 102.545146 -243.674392) (xy 102.549106 -243.625338) (xy 102.560883 -243.577554)
			(xy 102.580174 -243.532278) (xy 102.606477 -243.490682) (xy 102.639112 -243.453845) (xy 102.677233 -243.42272)
			(xy 102.719854 -243.398113) (xy 102.76587 -243.380661) (xy 102.814089 -243.370817) (xy 102.863264 -243.368836)
			(xy 102.912119 -243.374768) (xy 102.95939 -243.38846) (xy 103.003852 -243.409558) (xy 103.044355 -243.437514)
			(xy 103.079848 -243.471606) (xy 103.109413 -243.51095) (xy 103.132284 -243.554527) (xy 103.147868 -243.601208)
			(xy 103.155763 -243.649785) (xy 103.156258 -243.674392) (xy 103.4852 -243.674392) (xy 103.48916 -243.625338)
			(xy 103.500937 -243.577554) (xy 103.520228 -243.532278) (xy 103.546531 -243.490682) (xy 103.579166 -243.453845)
			(xy 103.617287 -243.42272) (xy 103.659908 -243.398113) (xy 103.705924 -243.380661) (xy 103.754143 -243.370817)
			(xy 103.803318 -243.368836) (xy 103.852173 -243.374768) (xy 103.899444 -243.38846) (xy 103.943906 -243.409558)
			(xy 103.984409 -243.437514) (xy 104.019902 -243.471606) (xy 104.049467 -243.51095) (xy 104.072338 -243.554527)
			(xy 104.087922 -243.601208) (xy 104.095817 -243.649785) (xy 104.096312 -243.674392) (xy 104.425254 -243.674392)
			(xy 104.429214 -243.625338) (xy 104.440991 -243.577554) (xy 104.460282 -243.532278) (xy 104.486585 -243.490682)
			(xy 104.51922 -243.453845) (xy 104.557341 -243.42272) (xy 104.599962 -243.398113) (xy 104.645978 -243.380661)
			(xy 104.694197 -243.370817) (xy 104.743372 -243.368836) (xy 104.792227 -243.374768) (xy 104.839498 -243.38846)
			(xy 104.88396 -243.409558) (xy 104.924463 -243.437514) (xy 104.959956 -243.471606) (xy 104.989521 -243.51095)
			(xy 105.012392 -243.554527) (xy 105.027976 -243.601208) (xy 105.035871 -243.649785) (xy 105.036366 -243.674392)
			(xy 105.365308 -243.674392) (xy 105.369268 -243.625338) (xy 105.381045 -243.577554) (xy 105.400336 -243.532278)
			(xy 105.426639 -243.490682) (xy 105.459274 -243.453845) (xy 105.497395 -243.42272) (xy 105.540016 -243.398113)
			(xy 105.586032 -243.380661) (xy 105.634251 -243.370817) (xy 105.683426 -243.368836) (xy 105.732281 -243.374768)
			(xy 105.779552 -243.38846) (xy 105.824014 -243.409558) (xy 105.864517 -243.437514) (xy 105.90001 -243.471606)
			(xy 105.929575 -243.51095) (xy 105.952446 -243.554527) (xy 105.96803 -243.601208) (xy 105.975925 -243.649785)
			(xy 105.97642 -243.674392) (xy 106.305362 -243.674392) (xy 106.309322 -243.625338) (xy 106.321099 -243.577554)
			(xy 106.34039 -243.532278) (xy 106.366693 -243.490682) (xy 106.399328 -243.453845) (xy 106.437449 -243.42272)
			(xy 106.48007 -243.398113) (xy 106.526086 -243.380661) (xy 106.574305 -243.370817) (xy 106.62348 -243.368836)
			(xy 106.672335 -243.374768) (xy 106.719606 -243.38846) (xy 106.764068 -243.409558) (xy 106.804571 -243.437514)
			(xy 106.840064 -243.471606) (xy 106.869629 -243.51095) (xy 106.8925 -243.554527) (xy 106.908084 -243.601208)
			(xy 106.915979 -243.649785) (xy 106.916474 -243.674392) (xy 107.245162 -243.674392) (xy 107.249122 -243.625338)
			(xy 107.260899 -243.577554) (xy 107.28019 -243.532278) (xy 107.306493 -243.490682) (xy 107.339128 -243.453845)
			(xy 107.377249 -243.42272) (xy 107.41987 -243.398113) (xy 107.465886 -243.380661) (xy 107.514105 -243.370817)
			(xy 107.56328 -243.368836) (xy 107.612135 -243.374768) (xy 107.659406 -243.38846) (xy 107.703868 -243.409558)
			(xy 107.744371 -243.437514) (xy 107.779864 -243.471606) (xy 107.809429 -243.51095) (xy 107.8323 -243.554527)
			(xy 107.847884 -243.601208) (xy 107.855779 -243.649785) (xy 107.856274 -243.674392) (xy 108.174785 -243.674392)
			(xy 108.17888 -243.623664) (xy 108.191059 -243.57425) (xy 108.211007 -243.52743) (xy 108.238208 -243.484416)
			(xy 108.271956 -243.446322) (xy 108.311378 -243.414135) (xy 108.355452 -243.388689) (xy 108.403038 -243.370642)
			(xy 108.452902 -243.360462) (xy 108.503754 -243.358413) (xy 108.554275 -243.364547) (xy 108.603159 -243.378707)
			(xy 108.649138 -243.400524) (xy 108.691022 -243.429434) (xy 108.727726 -243.464689) (xy 108.758299 -243.505375)
			(xy 108.78195 -243.550438) (xy 108.798066 -243.598712) (xy 108.80623 -243.648946) (xy 108.806742 -243.674392)
			(xy 109.114839 -243.674392) (xy 109.118934 -243.623664) (xy 109.131113 -243.57425) (xy 109.151061 -243.52743)
			(xy 109.178262 -243.484416) (xy 109.21201 -243.446322) (xy 109.251432 -243.414135) (xy 109.295506 -243.388689)
			(xy 109.343092 -243.370642) (xy 109.392956 -243.360462) (xy 109.443808 -243.358413) (xy 109.494329 -243.364547)
			(xy 109.543213 -243.378707) (xy 109.589192 -243.400524) (xy 109.631076 -243.429434) (xy 109.66778 -243.464689)
			(xy 109.698353 -243.505375) (xy 109.722004 -243.550438) (xy 109.73812 -243.598712) (xy 109.746284 -243.648946)
			(xy 109.746796 -243.674392) (xy 110.065324 -243.674392) (xy 110.069284 -243.625338) (xy 110.081061 -243.577554)
			(xy 110.100352 -243.532278) (xy 110.126655 -243.490682) (xy 110.15929 -243.453845) (xy 110.197411 -243.42272)
			(xy 110.240032 -243.398113) (xy 110.286048 -243.380661) (xy 110.334267 -243.370817) (xy 110.383442 -243.368836)
			(xy 110.432297 -243.374768) (xy 110.479568 -243.38846) (xy 110.52403 -243.409558) (xy 110.564533 -243.437514)
			(xy 110.600026 -243.471606) (xy 110.629591 -243.51095) (xy 110.652462 -243.554527) (xy 110.668046 -243.601208)
			(xy 110.675941 -243.649785) (xy 110.676436 -243.674392) (xy 112.878882 -243.674392) (xy 112.882842 -243.625338)
			(xy 112.894619 -243.577554) (xy 112.91391 -243.532278) (xy 112.940213 -243.490682) (xy 112.972848 -243.453845)
			(xy 113.010969 -243.42272) (xy 113.05359 -243.398113) (xy 113.099606 -243.380661) (xy 113.147825 -243.370817)
			(xy 113.197 -243.368836) (xy 113.245855 -243.374768) (xy 113.293126 -243.38846) (xy 113.337588 -243.409558)
			(xy 113.378091 -243.437514) (xy 113.413584 -243.471606) (xy 113.443149 -243.51095) (xy 113.46602 -243.554527)
			(xy 113.481604 -243.601208) (xy 113.489499 -243.649785) (xy 113.489994 -243.674392) (xy 113.818936 -243.674392)
			(xy 113.822896 -243.625338) (xy 113.834673 -243.577554) (xy 113.853964 -243.532278) (xy 113.880267 -243.490682)
			(xy 113.912902 -243.453845) (xy 113.951023 -243.42272) (xy 113.993644 -243.398113) (xy 114.03966 -243.380661)
			(xy 114.087879 -243.370817) (xy 114.137054 -243.368836) (xy 114.185909 -243.374768) (xy 114.23318 -243.38846)
			(xy 114.277642 -243.409558) (xy 114.318145 -243.437514) (xy 114.353638 -243.471606) (xy 114.383203 -243.51095)
			(xy 114.406074 -243.554527) (xy 114.421658 -243.601208) (xy 114.429553 -243.649785) (xy 114.430048 -243.674392)
			(xy 114.75899 -243.674392) (xy 114.76295 -243.625338) (xy 114.774727 -243.577554) (xy 114.794018 -243.532278)
			(xy 114.820321 -243.490682) (xy 114.852956 -243.453845) (xy 114.891077 -243.42272) (xy 114.933698 -243.398113)
			(xy 114.979714 -243.380661) (xy 115.027933 -243.370817) (xy 115.077108 -243.368836) (xy 115.125963 -243.374768)
			(xy 115.173234 -243.38846) (xy 115.217696 -243.409558) (xy 115.258199 -243.437514) (xy 115.293692 -243.471606)
			(xy 115.323257 -243.51095) (xy 115.346128 -243.554527) (xy 115.361712 -243.601208) (xy 115.369607 -243.649785)
			(xy 115.370102 -243.674392) (xy 115.369607 -243.698999) (xy 115.361712 -243.747576) (xy 115.346128 -243.794257)
			(xy 115.323257 -243.837834) (xy 115.293692 -243.877178) (xy 115.258199 -243.91127) (xy 115.217696 -243.939226)
			(xy 115.173234 -243.960324) (xy 115.125963 -243.974016) (xy 115.077108 -243.979948) (xy 115.027933 -243.977967)
			(xy 114.979714 -243.968123) (xy 114.933698 -243.950671) (xy 114.891077 -243.926064) (xy 114.852956 -243.894939)
			(xy 114.820321 -243.858102) (xy 114.794018 -243.816506) (xy 114.774727 -243.77123) (xy 114.76295 -243.723446)
			(xy 114.75899 -243.674392) (xy 114.430048 -243.674392) (xy 114.429553 -243.698999) (xy 114.421658 -243.747576)
			(xy 114.406074 -243.794257) (xy 114.383203 -243.837834) (xy 114.353638 -243.877178) (xy 114.318145 -243.91127)
			(xy 114.277642 -243.939226) (xy 114.23318 -243.960324) (xy 114.185909 -243.974016) (xy 114.137054 -243.979948)
			(xy 114.087879 -243.977967) (xy 114.03966 -243.968123) (xy 113.993644 -243.950671) (xy 113.951023 -243.926064)
			(xy 113.912902 -243.894939) (xy 113.880267 -243.858102) (xy 113.853964 -243.816506) (xy 113.834673 -243.77123)
			(xy 113.822896 -243.723446) (xy 113.818936 -243.674392) (xy 113.489994 -243.674392) (xy 113.489499 -243.698999)
			(xy 113.481604 -243.747576) (xy 113.46602 -243.794257) (xy 113.443149 -243.837834) (xy 113.413584 -243.877178)
			(xy 113.378091 -243.91127) (xy 113.337588 -243.939226) (xy 113.293126 -243.960324) (xy 113.245855 -243.974016)
			(xy 113.197 -243.979948) (xy 113.147825 -243.977967) (xy 113.099606 -243.968123) (xy 113.05359 -243.950671)
			(xy 113.010969 -243.926064) (xy 112.972848 -243.894939) (xy 112.940213 -243.858102) (xy 112.91391 -243.816506)
			(xy 112.894619 -243.77123) (xy 112.882842 -243.723446) (xy 112.878882 -243.674392) (xy 110.676436 -243.674392)
			(xy 110.675941 -243.698999) (xy 110.668046 -243.747576) (xy 110.652462 -243.794257) (xy 110.629591 -243.837834)
			(xy 110.600026 -243.877178) (xy 110.564533 -243.91127) (xy 110.52403 -243.939226) (xy 110.479568 -243.960324)
			(xy 110.432297 -243.974016) (xy 110.383442 -243.979948) (xy 110.334267 -243.977967) (xy 110.286048 -243.968123)
			(xy 110.240032 -243.950671) (xy 110.197411 -243.926064) (xy 110.15929 -243.894939) (xy 110.126655 -243.858102)
			(xy 110.100352 -243.816506) (xy 110.081061 -243.77123) (xy 110.069284 -243.723446) (xy 110.065324 -243.674392)
			(xy 109.746796 -243.674392) (xy 109.746284 -243.699838) (xy 109.73812 -243.750072) (xy 109.722004 -243.798346)
			(xy 109.698353 -243.843409) (xy 109.66778 -243.884095) (xy 109.631076 -243.91935) (xy 109.589192 -243.94826)
			(xy 109.543213 -243.970077) (xy 109.494329 -243.984237) (xy 109.443808 -243.990371) (xy 109.392956 -243.988322)
			(xy 109.343092 -243.978142) (xy 109.295506 -243.960095) (xy 109.251432 -243.934649) (xy 109.21201 -243.902462)
			(xy 109.178262 -243.864368) (xy 109.151061 -243.821354) (xy 109.131113 -243.774534) (xy 109.118934 -243.72512)
			(xy 109.114839 -243.674392) (xy 108.806742 -243.674392) (xy 108.80623 -243.699838) (xy 108.798066 -243.750072)
			(xy 108.78195 -243.798346) (xy 108.758299 -243.843409) (xy 108.727726 -243.884095) (xy 108.691022 -243.91935)
			(xy 108.649138 -243.94826) (xy 108.603159 -243.970077) (xy 108.554275 -243.984237) (xy 108.503754 -243.990371)
			(xy 108.452902 -243.988322) (xy 108.403038 -243.978142) (xy 108.355452 -243.960095) (xy 108.311378 -243.934649)
			(xy 108.271956 -243.902462) (xy 108.238208 -243.864368) (xy 108.211007 -243.821354) (xy 108.191059 -243.774534)
			(xy 108.17888 -243.72512) (xy 108.174785 -243.674392) (xy 107.856274 -243.674392) (xy 107.855779 -243.698999)
			(xy 107.847884 -243.747576) (xy 107.8323 -243.794257) (xy 107.809429 -243.837834) (xy 107.779864 -243.877178)
			(xy 107.744371 -243.91127) (xy 107.703868 -243.939226) (xy 107.659406 -243.960324) (xy 107.612135 -243.974016)
			(xy 107.56328 -243.979948) (xy 107.514105 -243.977967) (xy 107.465886 -243.968123) (xy 107.41987 -243.950671)
			(xy 107.377249 -243.926064) (xy 107.339128 -243.894939) (xy 107.306493 -243.858102) (xy 107.28019 -243.816506)
			(xy 107.260899 -243.77123) (xy 107.249122 -243.723446) (xy 107.245162 -243.674392) (xy 106.916474 -243.674392)
			(xy 106.915979 -243.698999) (xy 106.908084 -243.747576) (xy 106.8925 -243.794257) (xy 106.869629 -243.837834)
			(xy 106.840064 -243.877178) (xy 106.804571 -243.91127) (xy 106.764068 -243.939226) (xy 106.719606 -243.960324)
			(xy 106.672335 -243.974016) (xy 106.62348 -243.979948) (xy 106.574305 -243.977967) (xy 106.526086 -243.968123)
			(xy 106.48007 -243.950671) (xy 106.437449 -243.926064) (xy 106.399328 -243.894939) (xy 106.366693 -243.858102)
			(xy 106.34039 -243.816506) (xy 106.321099 -243.77123) (xy 106.309322 -243.723446) (xy 106.305362 -243.674392)
			(xy 105.97642 -243.674392) (xy 105.975925 -243.698999) (xy 105.96803 -243.747576) (xy 105.952446 -243.794257)
			(xy 105.929575 -243.837834) (xy 105.90001 -243.877178) (xy 105.864517 -243.91127) (xy 105.824014 -243.939226)
			(xy 105.779552 -243.960324) (xy 105.732281 -243.974016) (xy 105.683426 -243.979948) (xy 105.634251 -243.977967)
			(xy 105.586032 -243.968123) (xy 105.540016 -243.950671) (xy 105.497395 -243.926064) (xy 105.459274 -243.894939)
			(xy 105.426639 -243.858102) (xy 105.400336 -243.816506) (xy 105.381045 -243.77123) (xy 105.369268 -243.723446)
			(xy 105.365308 -243.674392) (xy 105.036366 -243.674392) (xy 105.035871 -243.698999) (xy 105.027976 -243.747576)
			(xy 105.012392 -243.794257) (xy 104.989521 -243.837834) (xy 104.959956 -243.877178) (xy 104.924463 -243.91127)
			(xy 104.88396 -243.939226) (xy 104.839498 -243.960324) (xy 104.792227 -243.974016) (xy 104.743372 -243.979948)
			(xy 104.694197 -243.977967) (xy 104.645978 -243.968123) (xy 104.599962 -243.950671) (xy 104.557341 -243.926064)
			(xy 104.51922 -243.894939) (xy 104.486585 -243.858102) (xy 104.460282 -243.816506) (xy 104.440991 -243.77123)
			(xy 104.429214 -243.723446) (xy 104.425254 -243.674392) (xy 104.096312 -243.674392) (xy 104.095817 -243.698999)
			(xy 104.087922 -243.747576) (xy 104.072338 -243.794257) (xy 104.049467 -243.837834) (xy 104.019902 -243.877178)
			(xy 103.984409 -243.91127) (xy 103.943906 -243.939226) (xy 103.899444 -243.960324) (xy 103.852173 -243.974016)
			(xy 103.803318 -243.979948) (xy 103.754143 -243.977967) (xy 103.705924 -243.968123) (xy 103.659908 -243.950671)
			(xy 103.617287 -243.926064) (xy 103.579166 -243.894939) (xy 103.546531 -243.858102) (xy 103.520228 -243.816506)
			(xy 103.500937 -243.77123) (xy 103.48916 -243.723446) (xy 103.4852 -243.674392) (xy 103.156258 -243.674392)
			(xy 103.155763 -243.698999) (xy 103.147868 -243.747576) (xy 103.132284 -243.794257) (xy 103.109413 -243.837834)
			(xy 103.079848 -243.877178) (xy 103.044355 -243.91127) (xy 103.003852 -243.939226) (xy 102.95939 -243.960324)
			(xy 102.912119 -243.974016) (xy 102.863264 -243.979948) (xy 102.814089 -243.977967) (xy 102.76587 -243.968123)
			(xy 102.719854 -243.950671) (xy 102.677233 -243.926064) (xy 102.639112 -243.894939) (xy 102.606477 -243.858102)
			(xy 102.580174 -243.816506) (xy 102.560883 -243.77123) (xy 102.549106 -243.723446) (xy 102.545146 -243.674392)
			(xy 102.216458 -243.674392) (xy 102.215963 -243.698999) (xy 102.208068 -243.747576) (xy 102.192484 -243.794257)
			(xy 102.169613 -243.837834) (xy 102.140048 -243.877178) (xy 102.104555 -243.91127) (xy 102.064052 -243.939226)
			(xy 102.01959 -243.960324) (xy 101.972319 -243.974016) (xy 101.923464 -243.979948) (xy 101.874289 -243.977967)
			(xy 101.82607 -243.968123) (xy 101.780054 -243.950671) (xy 101.737433 -243.926064) (xy 101.699312 -243.894939)
			(xy 101.666677 -243.858102) (xy 101.640374 -243.816506) (xy 101.621083 -243.77123) (xy 101.609306 -243.723446)
			(xy 101.605346 -243.674392) (xy 101.276404 -243.674392) (xy 101.275909 -243.698999) (xy 101.268014 -243.747576)
			(xy 101.25243 -243.794257) (xy 101.229559 -243.837834) (xy 101.199994 -243.877178) (xy 101.164501 -243.91127)
			(xy 101.123998 -243.939226) (xy 101.079536 -243.960324) (xy 101.032265 -243.974016) (xy 100.98341 -243.979948)
			(xy 100.934235 -243.977967) (xy 100.886016 -243.968123) (xy 100.84 -243.950671) (xy 100.797379 -243.926064)
			(xy 100.759258 -243.894939) (xy 100.726623 -243.858102) (xy 100.70032 -243.816506) (xy 100.681029 -243.77123)
			(xy 100.669252 -243.723446) (xy 100.665292 -243.674392) (xy 100.33635 -243.674392) (xy 100.335855 -243.698999)
			(xy 100.32796 -243.747576) (xy 100.312376 -243.794257) (xy 100.289505 -243.837834) (xy 100.25994 -243.877178)
			(xy 100.224447 -243.91127) (xy 100.183944 -243.939226) (xy 100.139482 -243.960324) (xy 100.092211 -243.974016)
			(xy 100.043356 -243.979948) (xy 99.994181 -243.977967) (xy 99.945962 -243.968123) (xy 99.899946 -243.950671)
			(xy 99.857325 -243.926064) (xy 99.819204 -243.894939) (xy 99.786569 -243.858102) (xy 99.760266 -243.816506)
			(xy 99.740975 -243.77123) (xy 99.729198 -243.723446) (xy 99.725238 -243.674392) (xy 99.396296 -243.674392)
			(xy 99.395801 -243.698999) (xy 99.387906 -243.747576) (xy 99.372322 -243.794257) (xy 99.349451 -243.837834)
			(xy 99.319886 -243.877178) (xy 99.284393 -243.91127) (xy 99.24389 -243.939226) (xy 99.199428 -243.960324)
			(xy 99.152157 -243.974016) (xy 99.103302 -243.979948) (xy 99.054127 -243.977967) (xy 99.005908 -243.968123)
			(xy 98.959892 -243.950671) (xy 98.917271 -243.926064) (xy 98.87915 -243.894939) (xy 98.846515 -243.858102)
			(xy 98.820212 -243.816506) (xy 98.800921 -243.77123) (xy 98.789144 -243.723446) (xy 98.785184 -243.674392)
			(xy 98.456242 -243.674392) (xy 98.455747 -243.698999) (xy 98.447852 -243.747576) (xy 98.432268 -243.794257)
			(xy 98.409397 -243.837834) (xy 98.379832 -243.877178) (xy 98.344339 -243.91127) (xy 98.303836 -243.939226)
			(xy 98.259374 -243.960324) (xy 98.212103 -243.974016) (xy 98.163248 -243.979948) (xy 98.114073 -243.977967)
			(xy 98.065854 -243.968123) (xy 98.019838 -243.950671) (xy 97.977217 -243.926064) (xy 97.939096 -243.894939)
			(xy 97.906461 -243.858102) (xy 97.880158 -243.816506) (xy 97.860867 -243.77123) (xy 97.84909 -243.723446)
			(xy 97.84513 -243.674392) (xy 97.516442 -243.674392) (xy 97.515947 -243.698999) (xy 97.508052 -243.747576)
			(xy 97.492468 -243.794257) (xy 97.469597 -243.837834) (xy 97.440032 -243.877178) (xy 97.404539 -243.91127)
			(xy 97.364036 -243.939226) (xy 97.319574 -243.960324) (xy 97.272303 -243.974016) (xy 97.223448 -243.979948)
			(xy 97.174273 -243.977967) (xy 97.126054 -243.968123) (xy 97.080038 -243.950671) (xy 97.037417 -243.926064)
			(xy 96.999296 -243.894939) (xy 96.966661 -243.858102) (xy 96.940358 -243.816506) (xy 96.921067 -243.77123)
			(xy 96.90929 -243.723446) (xy 96.90533 -243.674392) (xy 96.576388 -243.674392) (xy 96.575893 -243.698999)
			(xy 96.567998 -243.747576) (xy 96.552414 -243.794257) (xy 96.529543 -243.837834) (xy 96.499978 -243.877178)
			(xy 96.464485 -243.91127) (xy 96.423982 -243.939226) (xy 96.37952 -243.960324) (xy 96.332249 -243.974016)
			(xy 96.283394 -243.979948) (xy 96.234219 -243.977967) (xy 96.186 -243.968123) (xy 96.139984 -243.950671)
			(xy 96.097363 -243.926064) (xy 96.059242 -243.894939) (xy 96.026607 -243.858102) (xy 96.000304 -243.816506)
			(xy 95.981013 -243.77123) (xy 95.969236 -243.723446) (xy 95.965276 -243.674392) (xy 95.646748 -243.674392)
			(xy 95.646236 -243.699838) (xy 95.638072 -243.750072) (xy 95.621956 -243.798346) (xy 95.598305 -243.843409)
			(xy 95.567732 -243.884095) (xy 95.531028 -243.91935) (xy 95.489144 -243.94826) (xy 95.443165 -243.970077)
			(xy 95.394281 -243.984237) (xy 95.34376 -243.990371) (xy 95.292908 -243.988322) (xy 95.243044 -243.978142)
			(xy 95.195458 -243.960095) (xy 95.151384 -243.934649) (xy 95.111962 -243.902462) (xy 95.078214 -243.864368)
			(xy 95.051013 -243.821354) (xy 95.031065 -243.774534) (xy 95.018886 -243.72512) (xy 95.014791 -243.674392)
			(xy 94.706694 -243.674392) (xy 94.706182 -243.699838) (xy 94.698018 -243.750072) (xy 94.681902 -243.798346)
			(xy 94.658251 -243.843409) (xy 94.627678 -243.884095) (xy 94.590974 -243.91935) (xy 94.54909 -243.94826)
			(xy 94.503111 -243.970077) (xy 94.454227 -243.984237) (xy 94.403706 -243.990371) (xy 94.352854 -243.988322)
			(xy 94.30299 -243.978142) (xy 94.255404 -243.960095) (xy 94.21133 -243.934649) (xy 94.171908 -243.902462)
			(xy 94.13816 -243.864368) (xy 94.110959 -243.821354) (xy 94.091011 -243.774534) (xy 94.078832 -243.72512)
			(xy 94.074737 -243.674392) (xy 93.756226 -243.674392) (xy 93.755731 -243.698999) (xy 93.747836 -243.747576)
			(xy 93.732252 -243.794257) (xy 93.709381 -243.837834) (xy 93.679816 -243.877178) (xy 93.644323 -243.91127)
			(xy 93.60382 -243.939226) (xy 93.559358 -243.960324) (xy 93.512087 -243.974016) (xy 93.463232 -243.979948)
			(xy 93.414057 -243.977967) (xy 93.365838 -243.968123) (xy 93.319822 -243.950671) (xy 93.277201 -243.926064)
			(xy 93.23908 -243.894939) (xy 93.206445 -243.858102) (xy 93.180142 -243.816506) (xy 93.160851 -243.77123)
			(xy 93.149074 -243.723446) (xy 93.145114 -243.674392) (xy 92.82684 -243.674392) (xy 92.826328 -243.699838)
			(xy 92.818164 -243.750072) (xy 92.802048 -243.798346) (xy 92.778397 -243.843409) (xy 92.747824 -243.884095)
			(xy 92.71112 -243.91935) (xy 92.669236 -243.94826) (xy 92.623257 -243.970077) (xy 92.574373 -243.984237)
			(xy 92.523852 -243.990371) (xy 92.473 -243.988322) (xy 92.423136 -243.978142) (xy 92.37555 -243.960095)
			(xy 92.331476 -243.934649) (xy 92.292054 -243.902462) (xy 92.258306 -243.864368) (xy 92.231105 -243.821354)
			(xy 92.211157 -243.774534) (xy 92.198978 -243.72512) (xy 92.194883 -243.674392) (xy 91.876372 -243.674392)
			(xy 91.875877 -243.698999) (xy 91.867982 -243.747576) (xy 91.852398 -243.794257) (xy 91.829527 -243.837834)
			(xy 91.799962 -243.877178) (xy 91.764469 -243.91127) (xy 91.723966 -243.939226) (xy 91.679504 -243.960324)
			(xy 91.632233 -243.974016) (xy 91.583378 -243.979948) (xy 91.534203 -243.977967) (xy 91.485984 -243.968123)
			(xy 91.439968 -243.950671) (xy 91.397347 -243.926064) (xy 91.359226 -243.894939) (xy 91.326591 -243.858102)
			(xy 91.300288 -243.816506) (xy 91.280997 -243.77123) (xy 91.26922 -243.723446) (xy 91.26526 -243.674392)
			(xy 90.946732 -243.674392) (xy 90.94622 -243.699838) (xy 90.938056 -243.750072) (xy 90.92194 -243.798346)
			(xy 90.898289 -243.843409) (xy 90.867716 -243.884095) (xy 90.831012 -243.91935) (xy 90.789128 -243.94826)
			(xy 90.743149 -243.970077) (xy 90.694265 -243.984237) (xy 90.643744 -243.990371) (xy 90.592892 -243.988322)
			(xy 90.543028 -243.978142) (xy 90.495442 -243.960095) (xy 90.451368 -243.934649) (xy 90.411946 -243.902462)
			(xy 90.378198 -243.864368) (xy 90.350997 -243.821354) (xy 90.331049 -243.774534) (xy 90.31887 -243.72512)
			(xy 90.314775 -243.674392) (xy 89.9959 -243.674392) (xy 89.995901 -243.698642) (xy 89.988239 -243.74652)
			(xy 89.973107 -243.792585) (xy 89.950886 -243.83568) (xy 89.922134 -243.874722) (xy 89.887574 -243.90873)
			(xy 89.848074 -243.93685) (xy 89.804626 -243.958374) (xy 89.758323 -243.972762) (xy 89.73439 -243.976652)
			(xy 89.715594 -243.979446) (xy 89.690956 -244.007894) (xy 89.690956 -244.153182) (xy 89.691426 -244.163055)
			(xy 89.698881 -244.181341) (xy 89.705434 -244.188742) (xy 89.705688 -244.188996) (xy 89.793318 -244.276626)
			(xy 89.800825 -244.283538) (xy 89.819694 -244.291264) (xy 89.829894 -244.291612) (xy 89.913206 -244.290596)
			(xy 89.932002 -244.282214) (xy 89.939114 -244.274848) (xy 89.956546 -244.257102) (xy 89.996108 -244.226951)
			(xy 90.040032 -244.203608) (xy 90.087157 -244.187689) (xy 90.136239 -244.179616) (xy 90.16111 -244.17909)
			(xy 90.185101 -244.179561) (xy 90.232491 -244.187069) (xy 90.278124 -244.201897) (xy 90.320876 -244.223681)
			(xy 90.359693 -244.251885) (xy 90.393621 -244.285813) (xy 90.421823 -244.324631) (xy 90.443606 -244.367383)
			(xy 90.458433 -244.413016) (xy 90.465939 -244.460407) (xy 90.466418 -244.484398) (xy 90.784675 -244.484398)
			(xy 90.78877 -244.43367) (xy 90.800949 -244.384256) (xy 90.820897 -244.337436) (xy 90.848098 -244.294422)
			(xy 90.881846 -244.256328) (xy 90.921268 -244.224141) (xy 90.965342 -244.198695) (xy 91.012928 -244.180648)
			(xy 91.062792 -244.170468) (xy 91.113644 -244.168419) (xy 91.164165 -244.174553) (xy 91.213049 -244.188713)
			(xy 91.259028 -244.21053) (xy 91.300912 -244.23944) (xy 91.337616 -244.274695) (xy 91.368189 -244.315381)
			(xy 91.39184 -244.360444) (xy 91.407956 -244.408718) (xy 91.41612 -244.458952) (xy 91.416632 -244.484398)
			(xy 91.724729 -244.484398) (xy 91.728824 -244.43367) (xy 91.741003 -244.384256) (xy 91.760951 -244.337436)
			(xy 91.788152 -244.294422) (xy 91.8219 -244.256328) (xy 91.861322 -244.224141) (xy 91.905396 -244.198695)
			(xy 91.952982 -244.180648) (xy 92.002846 -244.170468) (xy 92.053698 -244.168419) (xy 92.104219 -244.174553)
			(xy 92.153103 -244.188713) (xy 92.199082 -244.21053) (xy 92.240966 -244.23944) (xy 92.27767 -244.274695)
			(xy 92.308243 -244.315381) (xy 92.331894 -244.360444) (xy 92.34801 -244.408718) (xy 92.356174 -244.458952)
			(xy 92.356686 -244.484398) (xy 92.675214 -244.484398) (xy 92.679174 -244.435344) (xy 92.690951 -244.38756)
			(xy 92.710242 -244.342284) (xy 92.736545 -244.300688) (xy 92.76918 -244.263851) (xy 92.807301 -244.232726)
			(xy 92.849922 -244.208119) (xy 92.895938 -244.190667) (xy 92.944157 -244.180823) (xy 92.993332 -244.178842)
			(xy 93.042187 -244.184774) (xy 93.089458 -244.198466) (xy 93.13392 -244.219564) (xy 93.174423 -244.24752)
			(xy 93.209916 -244.281612) (xy 93.239481 -244.320956) (xy 93.262352 -244.364533) (xy 93.277936 -244.411214)
			(xy 93.285831 -244.459791) (xy 93.286326 -244.484398) (xy 93.604837 -244.484398) (xy 93.608932 -244.43367)
			(xy 93.621111 -244.384256) (xy 93.641059 -244.337436) (xy 93.66826 -244.294422) (xy 93.702008 -244.256328)
			(xy 93.74143 -244.224141) (xy 93.785504 -244.198695) (xy 93.83309 -244.180648) (xy 93.882954 -244.170468)
			(xy 93.933806 -244.168419) (xy 93.984327 -244.174553) (xy 94.033211 -244.188713) (xy 94.07919 -244.21053)
			(xy 94.121074 -244.23944) (xy 94.157778 -244.274695) (xy 94.188351 -244.315381) (xy 94.212002 -244.360444)
			(xy 94.228118 -244.408718) (xy 94.236282 -244.458952) (xy 94.236794 -244.484398) (xy 94.555322 -244.484398)
			(xy 94.559282 -244.435344) (xy 94.571059 -244.38756) (xy 94.59035 -244.342284) (xy 94.616653 -244.300688)
			(xy 94.649288 -244.263851) (xy 94.687409 -244.232726) (xy 94.73003 -244.208119) (xy 94.776046 -244.190667)
			(xy 94.824265 -244.180823) (xy 94.87344 -244.178842) (xy 94.922295 -244.184774) (xy 94.969566 -244.198466)
			(xy 95.014028 -244.219564) (xy 95.054531 -244.24752) (xy 95.090024 -244.281612) (xy 95.119589 -244.320956)
			(xy 95.14246 -244.364533) (xy 95.158044 -244.411214) (xy 95.165939 -244.459791) (xy 95.166434 -244.484398)
			(xy 95.484691 -244.484398) (xy 95.488786 -244.43367) (xy 95.500965 -244.384256) (xy 95.520913 -244.337436)
			(xy 95.548114 -244.294422) (xy 95.581862 -244.256328) (xy 95.621284 -244.224141) (xy 95.665358 -244.198695)
			(xy 95.712944 -244.180648) (xy 95.762808 -244.170468) (xy 95.81366 -244.168419) (xy 95.864181 -244.174553)
			(xy 95.913065 -244.188713) (xy 95.959044 -244.21053) (xy 96.000928 -244.23944) (xy 96.037632 -244.274695)
			(xy 96.068205 -244.315381) (xy 96.091856 -244.360444) (xy 96.107972 -244.408718) (xy 96.116136 -244.458952)
			(xy 96.116648 -244.484398) (xy 96.435176 -244.484398) (xy 96.439136 -244.435344) (xy 96.450913 -244.38756)
			(xy 96.470204 -244.342284) (xy 96.496507 -244.300688) (xy 96.529142 -244.263851) (xy 96.567263 -244.232726)
			(xy 96.609884 -244.208119) (xy 96.6559 -244.190667) (xy 96.704119 -244.180823) (xy 96.753294 -244.178842)
			(xy 96.802149 -244.184774) (xy 96.84942 -244.198466) (xy 96.893882 -244.219564) (xy 96.934385 -244.24752)
			(xy 96.969878 -244.281612) (xy 96.999443 -244.320956) (xy 97.022314 -244.364533) (xy 97.037898 -244.411214)
			(xy 97.045793 -244.459791) (xy 97.046288 -244.484398) (xy 97.364799 -244.484398) (xy 97.368894 -244.43367)
			(xy 97.381073 -244.384256) (xy 97.401021 -244.337436) (xy 97.428222 -244.294422) (xy 97.46197 -244.256328)
			(xy 97.501392 -244.224141) (xy 97.545466 -244.198695) (xy 97.593052 -244.180648) (xy 97.642916 -244.170468)
			(xy 97.693768 -244.168419) (xy 97.744289 -244.174553) (xy 97.793173 -244.188713) (xy 97.839152 -244.21053)
			(xy 97.881036 -244.23944) (xy 97.91774 -244.274695) (xy 97.948313 -244.315381) (xy 97.971964 -244.360444)
			(xy 97.98808 -244.408718) (xy 97.996244 -244.458952) (xy 97.996756 -244.484398) (xy 98.304853 -244.484398)
			(xy 98.308948 -244.43367) (xy 98.321127 -244.384256) (xy 98.341075 -244.337436) (xy 98.368276 -244.294422)
			(xy 98.402024 -244.256328) (xy 98.441446 -244.224141) (xy 98.48552 -244.198695) (xy 98.533106 -244.180648)
			(xy 98.58297 -244.170468) (xy 98.633822 -244.168419) (xy 98.684343 -244.174553) (xy 98.733227 -244.188713)
			(xy 98.779206 -244.21053) (xy 98.82109 -244.23944) (xy 98.857794 -244.274695) (xy 98.888367 -244.315381)
			(xy 98.912018 -244.360444) (xy 98.928134 -244.408718) (xy 98.936298 -244.458952) (xy 98.93681 -244.484398)
			(xy 99.255338 -244.484398) (xy 99.259298 -244.435344) (xy 99.271075 -244.38756) (xy 99.290366 -244.342284)
			(xy 99.316669 -244.300688) (xy 99.349304 -244.263851) (xy 99.387425 -244.232726) (xy 99.430046 -244.208119)
			(xy 99.476062 -244.190667) (xy 99.524281 -244.180823) (xy 99.573456 -244.178842) (xy 99.622311 -244.184774)
			(xy 99.669582 -244.198466) (xy 99.714044 -244.219564) (xy 99.754547 -244.24752) (xy 99.79004 -244.281612)
			(xy 99.819605 -244.320956) (xy 99.842476 -244.364533) (xy 99.85806 -244.411214) (xy 99.865955 -244.459791)
			(xy 99.86645 -244.484398) (xy 100.184707 -244.484398) (xy 100.188802 -244.43367) (xy 100.200981 -244.384256)
			(xy 100.220929 -244.337436) (xy 100.24813 -244.294422) (xy 100.281878 -244.256328) (xy 100.3213 -244.224141)
			(xy 100.365374 -244.198695) (xy 100.41296 -244.180648) (xy 100.462824 -244.170468) (xy 100.513676 -244.168419)
			(xy 100.564197 -244.174553) (xy 100.613081 -244.188713) (xy 100.65906 -244.21053) (xy 100.700944 -244.23944)
			(xy 100.737648 -244.274695) (xy 100.768221 -244.315381) (xy 100.791872 -244.360444) (xy 100.807988 -244.408718)
			(xy 100.816152 -244.458952) (xy 100.816664 -244.484398) (xy 101.124761 -244.484398) (xy 101.128856 -244.43367)
			(xy 101.141035 -244.384256) (xy 101.160983 -244.337436) (xy 101.188184 -244.294422) (xy 101.221932 -244.256328)
			(xy 101.261354 -244.224141) (xy 101.305428 -244.198695) (xy 101.353014 -244.180648) (xy 101.402878 -244.170468)
			(xy 101.45373 -244.168419) (xy 101.504251 -244.174553) (xy 101.553135 -244.188713) (xy 101.599114 -244.21053)
			(xy 101.640998 -244.23944) (xy 101.677702 -244.274695) (xy 101.708275 -244.315381) (xy 101.731926 -244.360444)
			(xy 101.748042 -244.408718) (xy 101.756206 -244.458952) (xy 101.756718 -244.484398) (xy 102.075246 -244.484398)
			(xy 102.079206 -244.435344) (xy 102.090983 -244.38756) (xy 102.110274 -244.342284) (xy 102.136577 -244.300688)
			(xy 102.169212 -244.263851) (xy 102.207333 -244.232726) (xy 102.249954 -244.208119) (xy 102.29597 -244.190667)
			(xy 102.344189 -244.180823) (xy 102.393364 -244.178842) (xy 102.442219 -244.184774) (xy 102.48949 -244.198466)
			(xy 102.533952 -244.219564) (xy 102.574455 -244.24752) (xy 102.609948 -244.281612) (xy 102.639513 -244.320956)
			(xy 102.662384 -244.364533) (xy 102.677968 -244.411214) (xy 102.685863 -244.459791) (xy 102.686358 -244.484398)
			(xy 103.004869 -244.484398) (xy 103.008964 -244.43367) (xy 103.021143 -244.384256) (xy 103.041091 -244.337436)
			(xy 103.068292 -244.294422) (xy 103.10204 -244.256328) (xy 103.141462 -244.224141) (xy 103.185536 -244.198695)
			(xy 103.233122 -244.180648) (xy 103.282986 -244.170468) (xy 103.333838 -244.168419) (xy 103.384359 -244.174553)
			(xy 103.433243 -244.188713) (xy 103.479222 -244.21053) (xy 103.521106 -244.23944) (xy 103.55781 -244.274695)
			(xy 103.588383 -244.315381) (xy 103.612034 -244.360444) (xy 103.62815 -244.408718) (xy 103.636314 -244.458952)
			(xy 103.636826 -244.484398) (xy 103.944923 -244.484398) (xy 103.949018 -244.43367) (xy 103.961197 -244.384256)
			(xy 103.981145 -244.337436) (xy 104.008346 -244.294422) (xy 104.042094 -244.256328) (xy 104.081516 -244.224141)
			(xy 104.12559 -244.198695) (xy 104.173176 -244.180648) (xy 104.22304 -244.170468) (xy 104.273892 -244.168419)
			(xy 104.324413 -244.174553) (xy 104.373297 -244.188713) (xy 104.419276 -244.21053) (xy 104.46116 -244.23944)
			(xy 104.497864 -244.274695) (xy 104.528437 -244.315381) (xy 104.552088 -244.360444) (xy 104.568204 -244.408718)
			(xy 104.576368 -244.458952) (xy 104.57688 -244.484398) (xy 104.895154 -244.484398) (xy 104.899114 -244.435344)
			(xy 104.910891 -244.38756) (xy 104.930182 -244.342284) (xy 104.956485 -244.300688) (xy 104.98912 -244.263851)
			(xy 105.027241 -244.232726) (xy 105.069862 -244.208119) (xy 105.115878 -244.190667) (xy 105.164097 -244.180823)
			(xy 105.213272 -244.178842) (xy 105.262127 -244.184774) (xy 105.309398 -244.198466) (xy 105.35386 -244.219564)
			(xy 105.394363 -244.24752) (xy 105.429856 -244.281612) (xy 105.459421 -244.320956) (xy 105.482292 -244.364533)
			(xy 105.497876 -244.411214) (xy 105.505771 -244.459791) (xy 105.506266 -244.484398) (xy 105.824777 -244.484398)
			(xy 105.828872 -244.43367) (xy 105.841051 -244.384256) (xy 105.860999 -244.337436) (xy 105.8882 -244.294422)
			(xy 105.921948 -244.256328) (xy 105.96137 -244.224141) (xy 106.005444 -244.198695) (xy 106.05303 -244.180648)
			(xy 106.102894 -244.170468) (xy 106.153746 -244.168419) (xy 106.204267 -244.174553) (xy 106.253151 -244.188713)
			(xy 106.29913 -244.21053) (xy 106.341014 -244.23944) (xy 106.377718 -244.274695) (xy 106.408291 -244.315381)
			(xy 106.431942 -244.360444) (xy 106.448058 -244.408718) (xy 106.456222 -244.458952) (xy 106.456734 -244.484398)
			(xy 106.764831 -244.484398) (xy 106.768926 -244.43367) (xy 106.781105 -244.384256) (xy 106.801053 -244.337436)
			(xy 106.828254 -244.294422) (xy 106.862002 -244.256328) (xy 106.901424 -244.224141) (xy 106.945498 -244.198695)
			(xy 106.993084 -244.180648) (xy 107.042948 -244.170468) (xy 107.0938 -244.168419) (xy 107.144321 -244.174553)
			(xy 107.193205 -244.188713) (xy 107.239184 -244.21053) (xy 107.281068 -244.23944) (xy 107.317772 -244.274695)
			(xy 107.348345 -244.315381) (xy 107.371996 -244.360444) (xy 107.388112 -244.408718) (xy 107.396276 -244.458952)
			(xy 107.396788 -244.484398) (xy 107.715316 -244.484398) (xy 107.719276 -244.435344) (xy 107.731053 -244.38756)
			(xy 107.750344 -244.342284) (xy 107.776647 -244.300688) (xy 107.809282 -244.263851) (xy 107.847403 -244.232726)
			(xy 107.890024 -244.208119) (xy 107.93604 -244.190667) (xy 107.984259 -244.180823) (xy 108.033434 -244.178842)
			(xy 108.082289 -244.184774) (xy 108.12956 -244.198466) (xy 108.174022 -244.219564) (xy 108.214525 -244.24752)
			(xy 108.250018 -244.281612) (xy 108.279583 -244.320956) (xy 108.302454 -244.364533) (xy 108.318038 -244.411214)
			(xy 108.325933 -244.459791) (xy 108.326428 -244.484398) (xy 108.65537 -244.484398) (xy 108.65933 -244.435344)
			(xy 108.671107 -244.38756) (xy 108.690398 -244.342284) (xy 108.716701 -244.300688) (xy 108.749336 -244.263851)
			(xy 108.787457 -244.232726) (xy 108.830078 -244.208119) (xy 108.876094 -244.190667) (xy 108.924313 -244.180823)
			(xy 108.973488 -244.178842) (xy 109.022343 -244.184774) (xy 109.069614 -244.198466) (xy 109.114076 -244.219564)
			(xy 109.154579 -244.24752) (xy 109.190072 -244.281612) (xy 109.219637 -244.320956) (xy 109.242508 -244.364533)
			(xy 109.258092 -244.411214) (xy 109.265987 -244.459791) (xy 109.266482 -244.484398) (xy 109.59517 -244.484398)
			(xy 109.59913 -244.435344) (xy 109.610907 -244.38756) (xy 109.630198 -244.342284) (xy 109.656501 -244.300688)
			(xy 109.689136 -244.263851) (xy 109.727257 -244.232726) (xy 109.769878 -244.208119) (xy 109.815894 -244.190667)
			(xy 109.864113 -244.180823) (xy 109.913288 -244.178842) (xy 109.962143 -244.184774) (xy 110.009414 -244.198466)
			(xy 110.053876 -244.219564) (xy 110.094379 -244.24752) (xy 110.129872 -244.281612) (xy 110.159437 -244.320956)
			(xy 110.182308 -244.364533) (xy 110.197892 -244.411214) (xy 110.205787 -244.459791) (xy 110.206282 -244.484398)
			(xy 113.349036 -244.484398) (xy 113.352996 -244.435344) (xy 113.364773 -244.38756) (xy 113.384064 -244.342284)
			(xy 113.410367 -244.300688) (xy 113.443002 -244.263851) (xy 113.481123 -244.232726) (xy 113.523744 -244.208119)
			(xy 113.56976 -244.190667) (xy 113.617979 -244.180823) (xy 113.667154 -244.178842) (xy 113.716009 -244.184774)
			(xy 113.76328 -244.198466) (xy 113.807742 -244.219564) (xy 113.848245 -244.24752) (xy 113.883738 -244.281612)
			(xy 113.913303 -244.320956) (xy 113.936174 -244.364533) (xy 113.951758 -244.411214) (xy 113.959653 -244.459791)
			(xy 113.960148 -244.484398) (xy 114.288836 -244.484398) (xy 114.292796 -244.435344) (xy 114.304573 -244.38756)
			(xy 114.323864 -244.342284) (xy 114.350167 -244.300688) (xy 114.382802 -244.263851) (xy 114.420923 -244.232726)
			(xy 114.463544 -244.208119) (xy 114.50956 -244.190667) (xy 114.557779 -244.180823) (xy 114.606954 -244.178842)
			(xy 114.655809 -244.184774) (xy 114.70308 -244.198466) (xy 114.747542 -244.219564) (xy 114.788045 -244.24752)
			(xy 114.823538 -244.281612) (xy 114.853103 -244.320956) (xy 114.875974 -244.364533) (xy 114.891558 -244.411214)
			(xy 114.899453 -244.459791) (xy 114.899948 -244.484398) (xy 115.22889 -244.484398) (xy 115.23285 -244.435344)
			(xy 115.244627 -244.38756) (xy 115.263918 -244.342284) (xy 115.290221 -244.300688) (xy 115.322856 -244.263851)
			(xy 115.360977 -244.232726) (xy 115.403598 -244.208119) (xy 115.449614 -244.190667) (xy 115.497833 -244.180823)
			(xy 115.547008 -244.178842) (xy 115.595863 -244.184774) (xy 115.643134 -244.198466) (xy 115.687596 -244.219564)
			(xy 115.728099 -244.24752) (xy 115.763592 -244.281612) (xy 115.793157 -244.320956) (xy 115.816028 -244.364533)
			(xy 115.831612 -244.411214) (xy 115.839507 -244.459791) (xy 115.840002 -244.484398) (xy 116.168944 -244.484398)
			(xy 116.172904 -244.435344) (xy 116.184681 -244.38756) (xy 116.203972 -244.342284) (xy 116.230275 -244.300688)
			(xy 116.26291 -244.263851) (xy 116.301031 -244.232726) (xy 116.343652 -244.208119) (xy 116.389668 -244.190667)
			(xy 116.437887 -244.180823) (xy 116.487062 -244.178842) (xy 116.535917 -244.184774) (xy 116.583188 -244.198466)
			(xy 116.62765 -244.219564) (xy 116.668153 -244.24752) (xy 116.703646 -244.281612) (xy 116.733211 -244.320956)
			(xy 116.756082 -244.364533) (xy 116.771666 -244.411214) (xy 116.779561 -244.459791) (xy 116.780056 -244.484398)
			(xy 117.108998 -244.484398) (xy 117.112958 -244.435344) (xy 117.124735 -244.38756) (xy 117.144026 -244.342284)
			(xy 117.170329 -244.300688) (xy 117.202964 -244.263851) (xy 117.241085 -244.232726) (xy 117.283706 -244.208119)
			(xy 117.329722 -244.190667) (xy 117.377941 -244.180823) (xy 117.427116 -244.178842) (xy 117.475971 -244.184774)
			(xy 117.523242 -244.198466) (xy 117.567704 -244.219564) (xy 117.608207 -244.24752) (xy 117.6437 -244.281612)
			(xy 117.673265 -244.320956) (xy 117.696136 -244.364533) (xy 117.71172 -244.411214) (xy 117.719615 -244.459791)
			(xy 117.72011 -244.484398) (xy 118.049052 -244.484398) (xy 118.053012 -244.435344) (xy 118.064789 -244.38756)
			(xy 118.08408 -244.342284) (xy 118.110383 -244.300688) (xy 118.143018 -244.263851) (xy 118.181139 -244.232726)
			(xy 118.22376 -244.208119) (xy 118.269776 -244.190667) (xy 118.317995 -244.180823) (xy 118.36717 -244.178842)
			(xy 118.416025 -244.184774) (xy 118.463296 -244.198466) (xy 118.507758 -244.219564) (xy 118.548261 -244.24752)
			(xy 118.583754 -244.281612) (xy 118.613319 -244.320956) (xy 118.63619 -244.364533) (xy 118.651774 -244.411214)
			(xy 118.659669 -244.459791) (xy 118.660164 -244.484398) (xy 118.988852 -244.484398) (xy 118.992812 -244.435344)
			(xy 119.004589 -244.38756) (xy 119.02388 -244.342284) (xy 119.050183 -244.300688) (xy 119.082818 -244.263851)
			(xy 119.120939 -244.232726) (xy 119.16356 -244.208119) (xy 119.209576 -244.190667) (xy 119.257795 -244.180823)
			(xy 119.30697 -244.178842) (xy 119.355825 -244.184774) (xy 119.403096 -244.198466) (xy 119.447558 -244.219564)
			(xy 119.488061 -244.24752) (xy 119.523554 -244.281612) (xy 119.553119 -244.320956) (xy 119.57599 -244.364533)
			(xy 119.591574 -244.411214) (xy 119.599469 -244.459791) (xy 119.599964 -244.484398) (xy 119.928906 -244.484398)
			(xy 119.932866 -244.435344) (xy 119.944643 -244.38756) (xy 119.963934 -244.342284) (xy 119.990237 -244.300688)
			(xy 120.022872 -244.263851) (xy 120.060993 -244.232726) (xy 120.103614 -244.208119) (xy 120.14963 -244.190667)
			(xy 120.197849 -244.180823) (xy 120.247024 -244.178842) (xy 120.295879 -244.184774) (xy 120.34315 -244.198466)
			(xy 120.387612 -244.219564) (xy 120.428115 -244.24752) (xy 120.463608 -244.281612) (xy 120.493173 -244.320956)
			(xy 120.516044 -244.364533) (xy 120.531628 -244.411214) (xy 120.539523 -244.459791) (xy 120.540018 -244.484398)
			(xy 120.86896 -244.484398) (xy 120.87292 -244.435344) (xy 120.884697 -244.38756) (xy 120.903988 -244.342284)
			(xy 120.930291 -244.300688) (xy 120.962926 -244.263851) (xy 121.001047 -244.232726) (xy 121.043668 -244.208119)
			(xy 121.089684 -244.190667) (xy 121.137903 -244.180823) (xy 121.187078 -244.178842) (xy 121.235933 -244.184774)
			(xy 121.283204 -244.198466) (xy 121.327666 -244.219564) (xy 121.368169 -244.24752) (xy 121.403662 -244.281612)
			(xy 121.433227 -244.320956) (xy 121.456098 -244.364533) (xy 121.471682 -244.411214) (xy 121.479577 -244.459791)
			(xy 121.480072 -244.484398) (xy 121.809014 -244.484398) (xy 121.812974 -244.435344) (xy 121.824751 -244.38756)
			(xy 121.844042 -244.342284) (xy 121.870345 -244.300688) (xy 121.90298 -244.263851) (xy 121.941101 -244.232726)
			(xy 121.983722 -244.208119) (xy 122.029738 -244.190667) (xy 122.077957 -244.180823) (xy 122.127132 -244.178842)
			(xy 122.175987 -244.184774) (xy 122.223258 -244.198466) (xy 122.26772 -244.219564) (xy 122.308223 -244.24752)
			(xy 122.343716 -244.281612) (xy 122.373281 -244.320956) (xy 122.396152 -244.364533) (xy 122.411736 -244.411214)
			(xy 122.419631 -244.459791) (xy 122.420126 -244.484398) (xy 122.748814 -244.484398) (xy 122.752774 -244.435344)
			(xy 122.764551 -244.38756) (xy 122.783842 -244.342284) (xy 122.810145 -244.300688) (xy 122.84278 -244.263851)
			(xy 122.880901 -244.232726) (xy 122.923522 -244.208119) (xy 122.969538 -244.190667) (xy 123.017757 -244.180823)
			(xy 123.066932 -244.178842) (xy 123.115787 -244.184774) (xy 123.163058 -244.198466) (xy 123.20752 -244.219564)
			(xy 123.248023 -244.24752) (xy 123.283516 -244.281612) (xy 123.313081 -244.320956) (xy 123.335952 -244.364533)
			(xy 123.351536 -244.411214) (xy 123.359431 -244.459791) (xy 123.359926 -244.484398) (xy 123.688868 -244.484398)
			(xy 123.692828 -244.435344) (xy 123.704605 -244.38756) (xy 123.723896 -244.342284) (xy 123.750199 -244.300688)
			(xy 123.782834 -244.263851) (xy 123.820955 -244.232726) (xy 123.863576 -244.208119) (xy 123.909592 -244.190667)
			(xy 123.957811 -244.180823) (xy 124.006986 -244.178842) (xy 124.055841 -244.184774) (xy 124.103112 -244.198466)
			(xy 124.147574 -244.219564) (xy 124.188077 -244.24752) (xy 124.22357 -244.281612) (xy 124.253135 -244.320956)
			(xy 124.276006 -244.364533) (xy 124.29159 -244.411214) (xy 124.299485 -244.459791) (xy 124.29998 -244.484398)
			(xy 124.628922 -244.484398) (xy 124.632882 -244.435344) (xy 124.644659 -244.38756) (xy 124.66395 -244.342284)
			(xy 124.690253 -244.300688) (xy 124.722888 -244.263851) (xy 124.761009 -244.232726) (xy 124.80363 -244.208119)
			(xy 124.849646 -244.190667) (xy 124.897865 -244.180823) (xy 124.94704 -244.178842) (xy 124.995895 -244.184774)
			(xy 125.043166 -244.198466) (xy 125.087628 -244.219564) (xy 125.128131 -244.24752) (xy 125.163624 -244.281612)
			(xy 125.193189 -244.320956) (xy 125.21606 -244.364533) (xy 125.231644 -244.411214) (xy 125.239539 -244.459791)
			(xy 125.240034 -244.484398) (xy 125.568976 -244.484398) (xy 125.572936 -244.435344) (xy 125.584713 -244.38756)
			(xy 125.604004 -244.342284) (xy 125.630307 -244.300688) (xy 125.662942 -244.263851) (xy 125.701063 -244.232726)
			(xy 125.743684 -244.208119) (xy 125.7897 -244.190667) (xy 125.837919 -244.180823) (xy 125.887094 -244.178842)
			(xy 125.935949 -244.184774) (xy 125.98322 -244.198466) (xy 126.027682 -244.219564) (xy 126.068185 -244.24752)
			(xy 126.103678 -244.281612) (xy 126.133243 -244.320956) (xy 126.156114 -244.364533) (xy 126.171698 -244.411214)
			(xy 126.179593 -244.459791) (xy 126.180088 -244.484398) (xy 126.179593 -244.509005) (xy 126.171698 -244.557582)
			(xy 126.156114 -244.604263) (xy 126.133243 -244.64784) (xy 126.103678 -244.687184) (xy 126.068185 -244.721276)
			(xy 126.027682 -244.749232) (xy 125.98322 -244.77033) (xy 125.935949 -244.784022) (xy 125.887094 -244.789954)
			(xy 125.837919 -244.787973) (xy 125.7897 -244.778129) (xy 125.743684 -244.760677) (xy 125.701063 -244.73607)
			(xy 125.662942 -244.704945) (xy 125.630307 -244.668108) (xy 125.604004 -244.626512) (xy 125.584713 -244.581236)
			(xy 125.572936 -244.533452) (xy 125.568976 -244.484398) (xy 125.240034 -244.484398) (xy 125.239539 -244.509005)
			(xy 125.231644 -244.557582) (xy 125.21606 -244.604263) (xy 125.193189 -244.64784) (xy 125.163624 -244.687184)
			(xy 125.128131 -244.721276) (xy 125.087628 -244.749232) (xy 125.043166 -244.77033) (xy 124.995895 -244.784022)
			(xy 124.94704 -244.789954) (xy 124.897865 -244.787973) (xy 124.849646 -244.778129) (xy 124.80363 -244.760677)
			(xy 124.761009 -244.73607) (xy 124.722888 -244.704945) (xy 124.690253 -244.668108) (xy 124.66395 -244.626512)
			(xy 124.644659 -244.581236) (xy 124.632882 -244.533452) (xy 124.628922 -244.484398) (xy 124.29998 -244.484398)
			(xy 124.299485 -244.509005) (xy 124.29159 -244.557582) (xy 124.276006 -244.604263) (xy 124.253135 -244.64784)
			(xy 124.22357 -244.687184) (xy 124.188077 -244.721276) (xy 124.147574 -244.749232) (xy 124.103112 -244.77033)
			(xy 124.055841 -244.784022) (xy 124.006986 -244.789954) (xy 123.957811 -244.787973) (xy 123.909592 -244.778129)
			(xy 123.863576 -244.760677) (xy 123.820955 -244.73607) (xy 123.782834 -244.704945) (xy 123.750199 -244.668108)
			(xy 123.723896 -244.626512) (xy 123.704605 -244.581236) (xy 123.692828 -244.533452) (xy 123.688868 -244.484398)
			(xy 123.359926 -244.484398) (xy 123.359431 -244.509005) (xy 123.351536 -244.557582) (xy 123.335952 -244.604263)
			(xy 123.313081 -244.64784) (xy 123.283516 -244.687184) (xy 123.248023 -244.721276) (xy 123.20752 -244.749232)
			(xy 123.163058 -244.77033) (xy 123.115787 -244.784022) (xy 123.066932 -244.789954) (xy 123.017757 -244.787973)
			(xy 122.969538 -244.778129) (xy 122.923522 -244.760677) (xy 122.880901 -244.73607) (xy 122.84278 -244.704945)
			(xy 122.810145 -244.668108) (xy 122.783842 -244.626512) (xy 122.764551 -244.581236) (xy 122.752774 -244.533452)
			(xy 122.748814 -244.484398) (xy 122.420126 -244.484398) (xy 122.419631 -244.509005) (xy 122.411736 -244.557582)
			(xy 122.396152 -244.604263) (xy 122.373281 -244.64784) (xy 122.343716 -244.687184) (xy 122.308223 -244.721276)
			(xy 122.26772 -244.749232) (xy 122.223258 -244.77033) (xy 122.175987 -244.784022) (xy 122.127132 -244.789954)
			(xy 122.077957 -244.787973) (xy 122.029738 -244.778129) (xy 121.983722 -244.760677) (xy 121.941101 -244.73607)
			(xy 121.90298 -244.704945) (xy 121.870345 -244.668108) (xy 121.844042 -244.626512) (xy 121.824751 -244.581236)
			(xy 121.812974 -244.533452) (xy 121.809014 -244.484398) (xy 121.480072 -244.484398) (xy 121.479577 -244.509005)
			(xy 121.471682 -244.557582) (xy 121.456098 -244.604263) (xy 121.433227 -244.64784) (xy 121.403662 -244.687184)
			(xy 121.368169 -244.721276) (xy 121.327666 -244.749232) (xy 121.283204 -244.77033) (xy 121.235933 -244.784022)
			(xy 121.187078 -244.789954) (xy 121.137903 -244.787973) (xy 121.089684 -244.778129) (xy 121.043668 -244.760677)
			(xy 121.001047 -244.73607) (xy 120.962926 -244.704945) (xy 120.930291 -244.668108) (xy 120.903988 -244.626512)
			(xy 120.884697 -244.581236) (xy 120.87292 -244.533452) (xy 120.86896 -244.484398) (xy 120.540018 -244.484398)
			(xy 120.539523 -244.509005) (xy 120.531628 -244.557582) (xy 120.516044 -244.604263) (xy 120.493173 -244.64784)
			(xy 120.463608 -244.687184) (xy 120.428115 -244.721276) (xy 120.387612 -244.749232) (xy 120.34315 -244.77033)
			(xy 120.295879 -244.784022) (xy 120.247024 -244.789954) (xy 120.197849 -244.787973) (xy 120.14963 -244.778129)
			(xy 120.103614 -244.760677) (xy 120.060993 -244.73607) (xy 120.022872 -244.704945) (xy 119.990237 -244.668108)
			(xy 119.963934 -244.626512) (xy 119.944643 -244.581236) (xy 119.932866 -244.533452) (xy 119.928906 -244.484398)
			(xy 119.599964 -244.484398) (xy 119.599469 -244.509005) (xy 119.591574 -244.557582) (xy 119.57599 -244.604263)
			(xy 119.553119 -244.64784) (xy 119.523554 -244.687184) (xy 119.488061 -244.721276) (xy 119.447558 -244.749232)
			(xy 119.403096 -244.77033) (xy 119.355825 -244.784022) (xy 119.30697 -244.789954) (xy 119.257795 -244.787973)
			(xy 119.209576 -244.778129) (xy 119.16356 -244.760677) (xy 119.120939 -244.73607) (xy 119.082818 -244.704945)
			(xy 119.050183 -244.668108) (xy 119.02388 -244.626512) (xy 119.004589 -244.581236) (xy 118.992812 -244.533452)
			(xy 118.988852 -244.484398) (xy 118.660164 -244.484398) (xy 118.659669 -244.509005) (xy 118.651774 -244.557582)
			(xy 118.63619 -244.604263) (xy 118.613319 -244.64784) (xy 118.583754 -244.687184) (xy 118.548261 -244.721276)
			(xy 118.507758 -244.749232) (xy 118.463296 -244.77033) (xy 118.416025 -244.784022) (xy 118.36717 -244.789954)
			(xy 118.317995 -244.787973) (xy 118.269776 -244.778129) (xy 118.22376 -244.760677) (xy 118.181139 -244.73607)
			(xy 118.143018 -244.704945) (xy 118.110383 -244.668108) (xy 118.08408 -244.626512) (xy 118.064789 -244.581236)
			(xy 118.053012 -244.533452) (xy 118.049052 -244.484398) (xy 117.72011 -244.484398) (xy 117.719615 -244.509005)
			(xy 117.71172 -244.557582) (xy 117.696136 -244.604263) (xy 117.673265 -244.64784) (xy 117.6437 -244.687184)
			(xy 117.608207 -244.721276) (xy 117.567704 -244.749232) (xy 117.523242 -244.77033) (xy 117.475971 -244.784022)
			(xy 117.427116 -244.789954) (xy 117.377941 -244.787973) (xy 117.329722 -244.778129) (xy 117.283706 -244.760677)
			(xy 117.241085 -244.73607) (xy 117.202964 -244.704945) (xy 117.170329 -244.668108) (xy 117.144026 -244.626512)
			(xy 117.124735 -244.581236) (xy 117.112958 -244.533452) (xy 117.108998 -244.484398) (xy 116.780056 -244.484398)
			(xy 116.779561 -244.509005) (xy 116.771666 -244.557582) (xy 116.756082 -244.604263) (xy 116.733211 -244.64784)
			(xy 116.703646 -244.687184) (xy 116.668153 -244.721276) (xy 116.62765 -244.749232) (xy 116.583188 -244.77033)
			(xy 116.535917 -244.784022) (xy 116.487062 -244.789954) (xy 116.437887 -244.787973) (xy 116.389668 -244.778129)
			(xy 116.343652 -244.760677) (xy 116.301031 -244.73607) (xy 116.26291 -244.704945) (xy 116.230275 -244.668108)
			(xy 116.203972 -244.626512) (xy 116.184681 -244.581236) (xy 116.172904 -244.533452) (xy 116.168944 -244.484398)
			(xy 115.840002 -244.484398) (xy 115.839507 -244.509005) (xy 115.831612 -244.557582) (xy 115.816028 -244.604263)
			(xy 115.793157 -244.64784) (xy 115.763592 -244.687184) (xy 115.728099 -244.721276) (xy 115.687596 -244.749232)
			(xy 115.643134 -244.77033) (xy 115.595863 -244.784022) (xy 115.547008 -244.789954) (xy 115.497833 -244.787973)
			(xy 115.449614 -244.778129) (xy 115.403598 -244.760677) (xy 115.360977 -244.73607) (xy 115.322856 -244.704945)
			(xy 115.290221 -244.668108) (xy 115.263918 -244.626512) (xy 115.244627 -244.581236) (xy 115.23285 -244.533452)
			(xy 115.22889 -244.484398) (xy 114.899948 -244.484398) (xy 114.899453 -244.509005) (xy 114.891558 -244.557582)
			(xy 114.875974 -244.604263) (xy 114.853103 -244.64784) (xy 114.823538 -244.687184) (xy 114.788045 -244.721276)
			(xy 114.747542 -244.749232) (xy 114.70308 -244.77033) (xy 114.655809 -244.784022) (xy 114.606954 -244.789954)
			(xy 114.557779 -244.787973) (xy 114.50956 -244.778129) (xy 114.463544 -244.760677) (xy 114.420923 -244.73607)
			(xy 114.382802 -244.704945) (xy 114.350167 -244.668108) (xy 114.323864 -244.626512) (xy 114.304573 -244.581236)
			(xy 114.292796 -244.533452) (xy 114.288836 -244.484398) (xy 113.960148 -244.484398) (xy 113.959653 -244.509005)
			(xy 113.951758 -244.557582) (xy 113.936174 -244.604263) (xy 113.913303 -244.64784) (xy 113.883738 -244.687184)
			(xy 113.848245 -244.721276) (xy 113.807742 -244.749232) (xy 113.76328 -244.77033) (xy 113.716009 -244.784022)
			(xy 113.667154 -244.789954) (xy 113.617979 -244.787973) (xy 113.56976 -244.778129) (xy 113.523744 -244.760677)
			(xy 113.481123 -244.73607) (xy 113.443002 -244.704945) (xy 113.410367 -244.668108) (xy 113.384064 -244.626512)
			(xy 113.364773 -244.581236) (xy 113.352996 -244.533452) (xy 113.349036 -244.484398) (xy 110.206282 -244.484398)
			(xy 110.205787 -244.509005) (xy 110.197892 -244.557582) (xy 110.182308 -244.604263) (xy 110.159437 -244.64784)
			(xy 110.129872 -244.687184) (xy 110.094379 -244.721276) (xy 110.053876 -244.749232) (xy 110.009414 -244.77033)
			(xy 109.962143 -244.784022) (xy 109.913288 -244.789954) (xy 109.864113 -244.787973) (xy 109.815894 -244.778129)
			(xy 109.769878 -244.760677) (xy 109.727257 -244.73607) (xy 109.689136 -244.704945) (xy 109.656501 -244.668108)
			(xy 109.630198 -244.626512) (xy 109.610907 -244.581236) (xy 109.59913 -244.533452) (xy 109.59517 -244.484398)
			(xy 109.266482 -244.484398) (xy 109.265987 -244.509005) (xy 109.258092 -244.557582) (xy 109.242508 -244.604263)
			(xy 109.219637 -244.64784) (xy 109.190072 -244.687184) (xy 109.154579 -244.721276) (xy 109.114076 -244.749232)
			(xy 109.069614 -244.77033) (xy 109.022343 -244.784022) (xy 108.973488 -244.789954) (xy 108.924313 -244.787973)
			(xy 108.876094 -244.778129) (xy 108.830078 -244.760677) (xy 108.787457 -244.73607) (xy 108.749336 -244.704945)
			(xy 108.716701 -244.668108) (xy 108.690398 -244.626512) (xy 108.671107 -244.581236) (xy 108.65933 -244.533452)
			(xy 108.65537 -244.484398) (xy 108.326428 -244.484398) (xy 108.325933 -244.509005) (xy 108.318038 -244.557582)
			(xy 108.302454 -244.604263) (xy 108.279583 -244.64784) (xy 108.250018 -244.687184) (xy 108.214525 -244.721276)
			(xy 108.174022 -244.749232) (xy 108.12956 -244.77033) (xy 108.082289 -244.784022) (xy 108.033434 -244.789954)
			(xy 107.984259 -244.787973) (xy 107.93604 -244.778129) (xy 107.890024 -244.760677) (xy 107.847403 -244.73607)
			(xy 107.809282 -244.704945) (xy 107.776647 -244.668108) (xy 107.750344 -244.626512) (xy 107.731053 -244.581236)
			(xy 107.719276 -244.533452) (xy 107.715316 -244.484398) (xy 107.396788 -244.484398) (xy 107.396276 -244.509844)
			(xy 107.388112 -244.560078) (xy 107.371996 -244.608352) (xy 107.348345 -244.653415) (xy 107.317772 -244.694101)
			(xy 107.281068 -244.729356) (xy 107.239184 -244.758266) (xy 107.193205 -244.780083) (xy 107.144321 -244.794243)
			(xy 107.0938 -244.800377) (xy 107.042948 -244.798328) (xy 106.993084 -244.788148) (xy 106.945498 -244.770101)
			(xy 106.901424 -244.744655) (xy 106.862002 -244.712468) (xy 106.828254 -244.674374) (xy 106.801053 -244.63136)
			(xy 106.781105 -244.58454) (xy 106.768926 -244.535126) (xy 106.764831 -244.484398) (xy 106.456734 -244.484398)
			(xy 106.456222 -244.509844) (xy 106.448058 -244.560078) (xy 106.431942 -244.608352) (xy 106.408291 -244.653415)
			(xy 106.377718 -244.694101) (xy 106.341014 -244.729356) (xy 106.29913 -244.758266) (xy 106.253151 -244.780083)
			(xy 106.204267 -244.794243) (xy 106.153746 -244.800377) (xy 106.102894 -244.798328) (xy 106.05303 -244.788148)
			(xy 106.005444 -244.770101) (xy 105.96137 -244.744655) (xy 105.921948 -244.712468) (xy 105.8882 -244.674374)
			(xy 105.860999 -244.63136) (xy 105.841051 -244.58454) (xy 105.828872 -244.535126) (xy 105.824777 -244.484398)
			(xy 105.506266 -244.484398) (xy 105.505771 -244.509005) (xy 105.497876 -244.557582) (xy 105.482292 -244.604263)
			(xy 105.459421 -244.64784) (xy 105.429856 -244.687184) (xy 105.394363 -244.721276) (xy 105.35386 -244.749232)
			(xy 105.309398 -244.77033) (xy 105.262127 -244.784022) (xy 105.213272 -244.789954) (xy 105.164097 -244.787973)
			(xy 105.115878 -244.778129) (xy 105.069862 -244.760677) (xy 105.027241 -244.73607) (xy 104.98912 -244.704945)
			(xy 104.956485 -244.668108) (xy 104.930182 -244.626512) (xy 104.910891 -244.581236) (xy 104.899114 -244.533452)
			(xy 104.895154 -244.484398) (xy 104.57688 -244.484398) (xy 104.576368 -244.509844) (xy 104.568204 -244.560078)
			(xy 104.552088 -244.608352) (xy 104.528437 -244.653415) (xy 104.497864 -244.694101) (xy 104.46116 -244.729356)
			(xy 104.419276 -244.758266) (xy 104.373297 -244.780083) (xy 104.324413 -244.794243) (xy 104.273892 -244.800377)
			(xy 104.22304 -244.798328) (xy 104.173176 -244.788148) (xy 104.12559 -244.770101) (xy 104.081516 -244.744655)
			(xy 104.042094 -244.712468) (xy 104.008346 -244.674374) (xy 103.981145 -244.63136) (xy 103.961197 -244.58454)
			(xy 103.949018 -244.535126) (xy 103.944923 -244.484398) (xy 103.636826 -244.484398) (xy 103.636314 -244.509844)
			(xy 103.62815 -244.560078) (xy 103.612034 -244.608352) (xy 103.588383 -244.653415) (xy 103.55781 -244.694101)
			(xy 103.521106 -244.729356) (xy 103.479222 -244.758266) (xy 103.433243 -244.780083) (xy 103.384359 -244.794243)
			(xy 103.333838 -244.800377) (xy 103.282986 -244.798328) (xy 103.233122 -244.788148) (xy 103.185536 -244.770101)
			(xy 103.141462 -244.744655) (xy 103.10204 -244.712468) (xy 103.068292 -244.674374) (xy 103.041091 -244.63136)
			(xy 103.021143 -244.58454) (xy 103.008964 -244.535126) (xy 103.004869 -244.484398) (xy 102.686358 -244.484398)
			(xy 102.685863 -244.509005) (xy 102.677968 -244.557582) (xy 102.662384 -244.604263) (xy 102.639513 -244.64784)
			(xy 102.609948 -244.687184) (xy 102.574455 -244.721276) (xy 102.533952 -244.749232) (xy 102.48949 -244.77033)
			(xy 102.442219 -244.784022) (xy 102.393364 -244.789954) (xy 102.344189 -244.787973) (xy 102.29597 -244.778129)
			(xy 102.249954 -244.760677) (xy 102.207333 -244.73607) (xy 102.169212 -244.704945) (xy 102.136577 -244.668108)
			(xy 102.110274 -244.626512) (xy 102.090983 -244.581236) (xy 102.079206 -244.533452) (xy 102.075246 -244.484398)
			(xy 101.756718 -244.484398) (xy 101.756206 -244.509844) (xy 101.748042 -244.560078) (xy 101.731926 -244.608352)
			(xy 101.708275 -244.653415) (xy 101.677702 -244.694101) (xy 101.640998 -244.729356) (xy 101.599114 -244.758266)
			(xy 101.553135 -244.780083) (xy 101.504251 -244.794243) (xy 101.45373 -244.800377) (xy 101.402878 -244.798328)
			(xy 101.353014 -244.788148) (xy 101.305428 -244.770101) (xy 101.261354 -244.744655) (xy 101.221932 -244.712468)
			(xy 101.188184 -244.674374) (xy 101.160983 -244.63136) (xy 101.141035 -244.58454) (xy 101.128856 -244.535126)
			(xy 101.124761 -244.484398) (xy 100.816664 -244.484398) (xy 100.816152 -244.509844) (xy 100.807988 -244.560078)
			(xy 100.791872 -244.608352) (xy 100.768221 -244.653415) (xy 100.737648 -244.694101) (xy 100.700944 -244.729356)
			(xy 100.65906 -244.758266) (xy 100.613081 -244.780083) (xy 100.564197 -244.794243) (xy 100.513676 -244.800377)
			(xy 100.462824 -244.798328) (xy 100.41296 -244.788148) (xy 100.365374 -244.770101) (xy 100.3213 -244.744655)
			(xy 100.281878 -244.712468) (xy 100.24813 -244.674374) (xy 100.220929 -244.63136) (xy 100.200981 -244.58454)
			(xy 100.188802 -244.535126) (xy 100.184707 -244.484398) (xy 99.86645 -244.484398) (xy 99.865955 -244.509005)
			(xy 99.85806 -244.557582) (xy 99.842476 -244.604263) (xy 99.819605 -244.64784) (xy 99.79004 -244.687184)
			(xy 99.754547 -244.721276) (xy 99.714044 -244.749232) (xy 99.669582 -244.77033) (xy 99.622311 -244.784022)
			(xy 99.573456 -244.789954) (xy 99.524281 -244.787973) (xy 99.476062 -244.778129) (xy 99.430046 -244.760677)
			(xy 99.387425 -244.73607) (xy 99.349304 -244.704945) (xy 99.316669 -244.668108) (xy 99.290366 -244.626512)
			(xy 99.271075 -244.581236) (xy 99.259298 -244.533452) (xy 99.255338 -244.484398) (xy 98.93681 -244.484398)
			(xy 98.936298 -244.509844) (xy 98.928134 -244.560078) (xy 98.912018 -244.608352) (xy 98.888367 -244.653415)
			(xy 98.857794 -244.694101) (xy 98.82109 -244.729356) (xy 98.779206 -244.758266) (xy 98.733227 -244.780083)
			(xy 98.684343 -244.794243) (xy 98.633822 -244.800377) (xy 98.58297 -244.798328) (xy 98.533106 -244.788148)
			(xy 98.48552 -244.770101) (xy 98.441446 -244.744655) (xy 98.402024 -244.712468) (xy 98.368276 -244.674374)
			(xy 98.341075 -244.63136) (xy 98.321127 -244.58454) (xy 98.308948 -244.535126) (xy 98.304853 -244.484398)
			(xy 97.996756 -244.484398) (xy 97.996244 -244.509844) (xy 97.98808 -244.560078) (xy 97.971964 -244.608352)
			(xy 97.948313 -244.653415) (xy 97.91774 -244.694101) (xy 97.881036 -244.729356) (xy 97.839152 -244.758266)
			(xy 97.793173 -244.780083) (xy 97.744289 -244.794243) (xy 97.693768 -244.800377) (xy 97.642916 -244.798328)
			(xy 97.593052 -244.788148) (xy 97.545466 -244.770101) (xy 97.501392 -244.744655) (xy 97.46197 -244.712468)
			(xy 97.428222 -244.674374) (xy 97.401021 -244.63136) (xy 97.381073 -244.58454) (xy 97.368894 -244.535126)
			(xy 97.364799 -244.484398) (xy 97.046288 -244.484398) (xy 97.045793 -244.509005) (xy 97.037898 -244.557582)
			(xy 97.022314 -244.604263) (xy 96.999443 -244.64784) (xy 96.969878 -244.687184) (xy 96.934385 -244.721276)
			(xy 96.893882 -244.749232) (xy 96.84942 -244.77033) (xy 96.802149 -244.784022) (xy 96.753294 -244.789954)
			(xy 96.704119 -244.787973) (xy 96.6559 -244.778129) (xy 96.609884 -244.760677) (xy 96.567263 -244.73607)
			(xy 96.529142 -244.704945) (xy 96.496507 -244.668108) (xy 96.470204 -244.626512) (xy 96.450913 -244.581236)
			(xy 96.439136 -244.533452) (xy 96.435176 -244.484398) (xy 96.116648 -244.484398) (xy 96.116136 -244.509844)
			(xy 96.107972 -244.560078) (xy 96.091856 -244.608352) (xy 96.068205 -244.653415) (xy 96.037632 -244.694101)
			(xy 96.000928 -244.729356) (xy 95.959044 -244.758266) (xy 95.913065 -244.780083) (xy 95.864181 -244.794243)
			(xy 95.81366 -244.800377) (xy 95.762808 -244.798328) (xy 95.712944 -244.788148) (xy 95.665358 -244.770101)
			(xy 95.621284 -244.744655) (xy 95.581862 -244.712468) (xy 95.548114 -244.674374) (xy 95.520913 -244.63136)
			(xy 95.500965 -244.58454) (xy 95.488786 -244.535126) (xy 95.484691 -244.484398) (xy 95.166434 -244.484398)
			(xy 95.165939 -244.509005) (xy 95.158044 -244.557582) (xy 95.14246 -244.604263) (xy 95.119589 -244.64784)
			(xy 95.090024 -244.687184) (xy 95.054531 -244.721276) (xy 95.014028 -244.749232) (xy 94.969566 -244.77033)
			(xy 94.922295 -244.784022) (xy 94.87344 -244.789954) (xy 94.824265 -244.787973) (xy 94.776046 -244.778129)
			(xy 94.73003 -244.760677) (xy 94.687409 -244.73607) (xy 94.649288 -244.704945) (xy 94.616653 -244.668108)
			(xy 94.59035 -244.626512) (xy 94.571059 -244.581236) (xy 94.559282 -244.533452) (xy 94.555322 -244.484398)
			(xy 94.236794 -244.484398) (xy 94.236282 -244.509844) (xy 94.228118 -244.560078) (xy 94.212002 -244.608352)
			(xy 94.188351 -244.653415) (xy 94.157778 -244.694101) (xy 94.121074 -244.729356) (xy 94.07919 -244.758266)
			(xy 94.033211 -244.780083) (xy 93.984327 -244.794243) (xy 93.933806 -244.800377) (xy 93.882954 -244.798328)
			(xy 93.83309 -244.788148) (xy 93.785504 -244.770101) (xy 93.74143 -244.744655) (xy 93.702008 -244.712468)
			(xy 93.66826 -244.674374) (xy 93.641059 -244.63136) (xy 93.621111 -244.58454) (xy 93.608932 -244.535126)
			(xy 93.604837 -244.484398) (xy 93.286326 -244.484398) (xy 93.285831 -244.509005) (xy 93.277936 -244.557582)
			(xy 93.262352 -244.604263) (xy 93.239481 -244.64784) (xy 93.209916 -244.687184) (xy 93.174423 -244.721276)
			(xy 93.13392 -244.749232) (xy 93.089458 -244.77033) (xy 93.042187 -244.784022) (xy 92.993332 -244.789954)
			(xy 92.944157 -244.787973) (xy 92.895938 -244.778129) (xy 92.849922 -244.760677) (xy 92.807301 -244.73607)
			(xy 92.76918 -244.704945) (xy 92.736545 -244.668108) (xy 92.710242 -244.626512) (xy 92.690951 -244.581236)
			(xy 92.679174 -244.533452) (xy 92.675214 -244.484398) (xy 92.356686 -244.484398) (xy 92.356174 -244.509844)
			(xy 92.34801 -244.560078) (xy 92.331894 -244.608352) (xy 92.308243 -244.653415) (xy 92.27767 -244.694101)
			(xy 92.240966 -244.729356) (xy 92.199082 -244.758266) (xy 92.153103 -244.780083) (xy 92.104219 -244.794243)
			(xy 92.053698 -244.800377) (xy 92.002846 -244.798328) (xy 91.952982 -244.788148) (xy 91.905396 -244.770101)
			(xy 91.861322 -244.744655) (xy 91.8219 -244.712468) (xy 91.788152 -244.674374) (xy 91.760951 -244.63136)
			(xy 91.741003 -244.58454) (xy 91.728824 -244.535126) (xy 91.724729 -244.484398) (xy 91.416632 -244.484398)
			(xy 91.41612 -244.509844) (xy 91.407956 -244.560078) (xy 91.39184 -244.608352) (xy 91.368189 -244.653415)
			(xy 91.337616 -244.694101) (xy 91.300912 -244.729356) (xy 91.259028 -244.758266) (xy 91.213049 -244.780083)
			(xy 91.164165 -244.794243) (xy 91.113644 -244.800377) (xy 91.062792 -244.798328) (xy 91.012928 -244.788148)
			(xy 90.965342 -244.770101) (xy 90.921268 -244.744655) (xy 90.881846 -244.712468) (xy 90.848098 -244.674374)
			(xy 90.820897 -244.63136) (xy 90.800949 -244.58454) (xy 90.78877 -244.535126) (xy 90.784675 -244.484398)
			(xy 90.466418 -244.484398) (xy 90.465927 -244.509271) (xy 90.457858 -244.558357) (xy 90.441933 -244.605484)
			(xy 90.418574 -244.649404) (xy 90.3884 -244.688953) (xy 90.37066 -244.706394) (xy 90.363294 -244.713506)
			(xy 90.354912 -244.732302) (xy 90.353896 -244.815614) (xy 90.354247 -244.825813) (xy 90.361969 -244.844684)
			(xy 90.368882 -244.85219) (xy 90.499946 -244.983254) (xy 90.504802 -244.987862) (xy 90.516389 -244.994556)
			(xy 90.522806 -244.996462) (xy 90.525346 -244.99697) (xy 90.550936 -244.988508) (xy 90.604062 -244.979449)
			(xy 90.63101 -244.978936) (xy 90.655808 -244.979422) (xy 90.704793 -244.987178) (xy 90.751963 -245.002496)
			(xy 90.796158 -245.025) (xy 90.836292 -245.054137) (xy 90.871377 -245.08919) (xy 90.90055 -245.129297)
			(xy 90.923095 -245.173473) (xy 90.938455 -245.220629) (xy 90.946255 -245.269607) (xy 90.946732 -245.294404)
			(xy 91.26526 -245.294404) (xy 91.26922 -245.24535) (xy 91.280997 -245.197566) (xy 91.300288 -245.15229)
			(xy 91.326591 -245.110694) (xy 91.359226 -245.073857) (xy 91.397347 -245.042732) (xy 91.439968 -245.018125)
			(xy 91.485984 -245.000673) (xy 91.534203 -244.990829) (xy 91.583378 -244.988848) (xy 91.632233 -244.99478)
			(xy 91.679504 -245.008472) (xy 91.723966 -245.02957) (xy 91.764469 -245.057526) (xy 91.799962 -245.091618)
			(xy 91.829527 -245.130962) (xy 91.852398 -245.174539) (xy 91.867982 -245.22122) (xy 91.875877 -245.269797)
			(xy 91.876372 -245.294404) (xy 92.194883 -245.294404) (xy 92.198978 -245.243676) (xy 92.211157 -245.194262)
			(xy 92.231105 -245.147442) (xy 92.258306 -245.104428) (xy 92.292054 -245.066334) (xy 92.331476 -245.034147)
			(xy 92.37555 -245.008701) (xy 92.423136 -244.990654) (xy 92.473 -244.980474) (xy 92.523852 -244.978425)
			(xy 92.574373 -244.984559) (xy 92.623257 -244.998719) (xy 92.669236 -245.020536) (xy 92.71112 -245.049446)
			(xy 92.747824 -245.084701) (xy 92.778397 -245.125387) (xy 92.802048 -245.17045) (xy 92.818164 -245.218724)
			(xy 92.826328 -245.268958) (xy 92.82684 -245.294404) (xy 93.145114 -245.294404) (xy 93.149074 -245.24535)
			(xy 93.160851 -245.197566) (xy 93.180142 -245.15229) (xy 93.206445 -245.110694) (xy 93.23908 -245.073857)
			(xy 93.277201 -245.042732) (xy 93.319822 -245.018125) (xy 93.365838 -245.000673) (xy 93.414057 -244.990829)
			(xy 93.463232 -244.988848) (xy 93.512087 -244.99478) (xy 93.559358 -245.008472) (xy 93.60382 -245.02957)
			(xy 93.644323 -245.057526) (xy 93.679816 -245.091618) (xy 93.709381 -245.130962) (xy 93.732252 -245.174539)
			(xy 93.747836 -245.22122) (xy 93.755731 -245.269797) (xy 93.756226 -245.294404) (xy 94.074737 -245.294404)
			(xy 94.078832 -245.243676) (xy 94.091011 -245.194262) (xy 94.110959 -245.147442) (xy 94.13816 -245.104428)
			(xy 94.171908 -245.066334) (xy 94.21133 -245.034147) (xy 94.255404 -245.008701) (xy 94.30299 -244.990654)
			(xy 94.352854 -244.980474) (xy 94.403706 -244.978425) (xy 94.454227 -244.984559) (xy 94.503111 -244.998719)
			(xy 94.54909 -245.020536) (xy 94.590974 -245.049446) (xy 94.627678 -245.084701) (xy 94.658251 -245.125387)
			(xy 94.681902 -245.17045) (xy 94.698018 -245.218724) (xy 94.706182 -245.268958) (xy 94.706694 -245.294404)
			(xy 95.014791 -245.294404) (xy 95.018886 -245.243676) (xy 95.031065 -245.194262) (xy 95.051013 -245.147442)
			(xy 95.078214 -245.104428) (xy 95.111962 -245.066334) (xy 95.151384 -245.034147) (xy 95.195458 -245.008701)
			(xy 95.243044 -244.990654) (xy 95.292908 -244.980474) (xy 95.34376 -244.978425) (xy 95.394281 -244.984559)
			(xy 95.443165 -244.998719) (xy 95.489144 -245.020536) (xy 95.531028 -245.049446) (xy 95.567732 -245.084701)
			(xy 95.598305 -245.125387) (xy 95.621956 -245.17045) (xy 95.638072 -245.218724) (xy 95.646236 -245.268958)
			(xy 95.646748 -245.294404) (xy 95.965276 -245.294404) (xy 95.969236 -245.24535) (xy 95.981013 -245.197566)
			(xy 96.000304 -245.15229) (xy 96.026607 -245.110694) (xy 96.059242 -245.073857) (xy 96.097363 -245.042732)
			(xy 96.139984 -245.018125) (xy 96.186 -245.000673) (xy 96.234219 -244.990829) (xy 96.283394 -244.988848)
			(xy 96.332249 -244.99478) (xy 96.37952 -245.008472) (xy 96.423982 -245.02957) (xy 96.464485 -245.057526)
			(xy 96.499978 -245.091618) (xy 96.529543 -245.130962) (xy 96.552414 -245.174539) (xy 96.567998 -245.22122)
			(xy 96.575893 -245.269797) (xy 96.576388 -245.294404) (xy 98.785184 -245.294404) (xy 98.789144 -245.24535)
			(xy 98.800921 -245.197566) (xy 98.820212 -245.15229) (xy 98.846515 -245.110694) (xy 98.87915 -245.073857)
			(xy 98.917271 -245.042732) (xy 98.959892 -245.018125) (xy 99.005908 -245.000673) (xy 99.054127 -244.990829)
			(xy 99.103302 -244.988848) (xy 99.152157 -244.99478) (xy 99.199428 -245.008472) (xy 99.24389 -245.02957)
			(xy 99.284393 -245.057526) (xy 99.319886 -245.091618) (xy 99.349451 -245.130962) (xy 99.372322 -245.174539)
			(xy 99.387906 -245.22122) (xy 99.395801 -245.269797) (xy 99.396296 -245.294404) (xy 101.605346 -245.294404)
			(xy 101.609306 -245.24535) (xy 101.621083 -245.197566) (xy 101.640374 -245.15229) (xy 101.666677 -245.110694)
			(xy 101.699312 -245.073857) (xy 101.737433 -245.042732) (xy 101.780054 -245.018125) (xy 101.82607 -245.000673)
			(xy 101.874289 -244.990829) (xy 101.923464 -244.988848) (xy 101.972319 -244.99478) (xy 102.01959 -245.008472)
			(xy 102.064052 -245.02957) (xy 102.104555 -245.057526) (xy 102.140048 -245.091618) (xy 102.169613 -245.130962)
			(xy 102.192484 -245.174539) (xy 102.208068 -245.22122) (xy 102.215963 -245.269797) (xy 102.216458 -245.294404)
			(xy 104.425254 -245.294404) (xy 104.429214 -245.24535) (xy 104.440991 -245.197566) (xy 104.460282 -245.15229)
			(xy 104.486585 -245.110694) (xy 104.51922 -245.073857) (xy 104.557341 -245.042732) (xy 104.599962 -245.018125)
			(xy 104.645978 -245.000673) (xy 104.694197 -244.990829) (xy 104.743372 -244.988848) (xy 104.792227 -244.99478)
			(xy 104.839498 -245.008472) (xy 104.88396 -245.02957) (xy 104.924463 -245.057526) (xy 104.959956 -245.091618)
			(xy 104.989521 -245.130962) (xy 105.012392 -245.174539) (xy 105.027976 -245.22122) (xy 105.035871 -245.269797)
			(xy 105.036366 -245.294404) (xy 107.245162 -245.294404) (xy 107.249122 -245.24535) (xy 107.260899 -245.197566)
			(xy 107.28019 -245.15229) (xy 107.306493 -245.110694) (xy 107.339128 -245.073857) (xy 107.377249 -245.042732)
			(xy 107.41987 -245.018125) (xy 107.465886 -245.000673) (xy 107.514105 -244.990829) (xy 107.56328 -244.988848)
			(xy 107.612135 -244.99478) (xy 107.659406 -245.008472) (xy 107.703868 -245.02957) (xy 107.744371 -245.057526)
			(xy 107.779864 -245.091618) (xy 107.809429 -245.130962) (xy 107.8323 -245.174539) (xy 107.847884 -245.22122)
			(xy 107.855779 -245.269797) (xy 107.856274 -245.294404) (xy 108.174785 -245.294404) (xy 108.17888 -245.243676)
			(xy 108.191059 -245.194262) (xy 108.211007 -245.147442) (xy 108.238208 -245.104428) (xy 108.271956 -245.066334)
			(xy 108.311378 -245.034147) (xy 108.355452 -245.008701) (xy 108.403038 -244.990654) (xy 108.452902 -244.980474)
			(xy 108.503754 -244.978425) (xy 108.554275 -244.984559) (xy 108.603159 -244.998719) (xy 108.649138 -245.020536)
			(xy 108.691022 -245.049446) (xy 108.727726 -245.084701) (xy 108.758299 -245.125387) (xy 108.78195 -245.17045)
			(xy 108.798066 -245.218724) (xy 108.80623 -245.268958) (xy 108.806742 -245.294404) (xy 109.114839 -245.294404)
			(xy 109.118934 -245.243676) (xy 109.131113 -245.194262) (xy 109.151061 -245.147442) (xy 109.178262 -245.104428)
			(xy 109.21201 -245.066334) (xy 109.251432 -245.034147) (xy 109.295506 -245.008701) (xy 109.343092 -244.990654)
			(xy 109.392956 -244.980474) (xy 109.443808 -244.978425) (xy 109.494329 -244.984559) (xy 109.543213 -244.998719)
			(xy 109.589192 -245.020536) (xy 109.631076 -245.049446) (xy 109.66778 -245.084701) (xy 109.698353 -245.125387)
			(xy 109.722004 -245.17045) (xy 109.73812 -245.218724) (xy 109.746284 -245.268958) (xy 109.746796 -245.294404)
			(xy 110.065324 -245.294404) (xy 110.069284 -245.24535) (xy 110.081061 -245.197566) (xy 110.100352 -245.15229)
			(xy 110.126655 -245.110694) (xy 110.15929 -245.073857) (xy 110.197411 -245.042732) (xy 110.240032 -245.018125)
			(xy 110.286048 -245.000673) (xy 110.334267 -244.990829) (xy 110.383442 -244.988848) (xy 110.432297 -244.99478)
			(xy 110.479568 -245.008472) (xy 110.52403 -245.02957) (xy 110.564533 -245.057526) (xy 110.600026 -245.091618)
			(xy 110.629591 -245.130962) (xy 110.652462 -245.174539) (xy 110.668046 -245.22122) (xy 110.675941 -245.269797)
			(xy 110.676436 -245.294404) (xy 110.675941 -245.319011) (xy 110.668046 -245.367588) (xy 110.652462 -245.414269)
			(xy 110.629591 -245.457846) (xy 110.600026 -245.49719) (xy 110.564533 -245.531282) (xy 110.534206 -245.552214)
			(xy 111.456473 -245.552214) (xy 111.460503 -245.499716) (xy 111.4725 -245.448448) (xy 111.492183 -245.399613)
			(xy 111.519089 -245.354354) (xy 111.552589 -245.313733) (xy 111.591897 -245.278702) (xy 111.636092 -245.250082)
			(xy 111.684137 -245.228543) (xy 111.734908 -245.214591) (xy 111.787213 -245.208553) (xy 111.839827 -245.21057)
			(xy 111.891517 -245.220594) (xy 111.94107 -245.238392) (xy 111.987326 -245.263545) (xy 112.027809 -245.294404)
			(xy 112.878882 -245.294404) (xy 112.882842 -245.24535) (xy 112.894619 -245.197566) (xy 112.91391 -245.15229)
			(xy 112.940213 -245.110694) (xy 112.972848 -245.073857) (xy 113.010969 -245.042732) (xy 113.05359 -245.018125)
			(xy 113.099606 -245.000673) (xy 113.147825 -244.990829) (xy 113.197 -244.988848) (xy 113.245855 -244.99478)
			(xy 113.293126 -245.008472) (xy 113.337588 -245.02957) (xy 113.378091 -245.057526) (xy 113.413584 -245.091618)
			(xy 113.443149 -245.130962) (xy 113.46602 -245.174539) (xy 113.481604 -245.22122) (xy 113.489499 -245.269797)
			(xy 113.489994 -245.294404) (xy 113.818936 -245.294404) (xy 113.822896 -245.24535) (xy 113.834673 -245.197566)
			(xy 113.853964 -245.15229) (xy 113.880267 -245.110694) (xy 113.912902 -245.073857) (xy 113.951023 -245.042732)
			(xy 113.993644 -245.018125) (xy 114.03966 -245.000673) (xy 114.087879 -244.990829) (xy 114.137054 -244.988848)
			(xy 114.185909 -244.99478) (xy 114.23318 -245.008472) (xy 114.277642 -245.02957) (xy 114.318145 -245.057526)
			(xy 114.353638 -245.091618) (xy 114.383203 -245.130962) (xy 114.406074 -245.174539) (xy 114.421658 -245.22122)
			(xy 114.429553 -245.269797) (xy 114.430048 -245.294404) (xy 114.75899 -245.294404) (xy 114.76295 -245.24535)
			(xy 114.774727 -245.197566) (xy 114.794018 -245.15229) (xy 114.820321 -245.110694) (xy 114.852956 -245.073857)
			(xy 114.891077 -245.042732) (xy 114.933698 -245.018125) (xy 114.979714 -245.000673) (xy 115.027933 -244.990829)
			(xy 115.077108 -244.988848) (xy 115.125963 -244.99478) (xy 115.173234 -245.008472) (xy 115.217696 -245.02957)
			(xy 115.258199 -245.057526) (xy 115.293692 -245.091618) (xy 115.323257 -245.130962) (xy 115.346128 -245.174539)
			(xy 115.361712 -245.22122) (xy 115.369607 -245.269797) (xy 115.370102 -245.294404) (xy 115.699044 -245.294404)
			(xy 115.703004 -245.24535) (xy 115.714781 -245.197566) (xy 115.734072 -245.15229) (xy 115.760375 -245.110694)
			(xy 115.79301 -245.073857) (xy 115.831131 -245.042732) (xy 115.873752 -245.018125) (xy 115.919768 -245.000673)
			(xy 115.967987 -244.990829) (xy 116.017162 -244.988848) (xy 116.066017 -244.99478) (xy 116.113288 -245.008472)
			(xy 116.15775 -245.02957) (xy 116.198253 -245.057526) (xy 116.233746 -245.091618) (xy 116.263311 -245.130962)
			(xy 116.286182 -245.174539) (xy 116.301766 -245.22122) (xy 116.309661 -245.269797) (xy 116.310156 -245.294404)
			(xy 118.518952 -245.294404) (xy 118.522912 -245.24535) (xy 118.534689 -245.197566) (xy 118.55398 -245.15229)
			(xy 118.580283 -245.110694) (xy 118.612918 -245.073857) (xy 118.651039 -245.042732) (xy 118.69366 -245.018125)
			(xy 118.739676 -245.000673) (xy 118.787895 -244.990829) (xy 118.83707 -244.988848) (xy 118.885925 -244.99478)
			(xy 118.933196 -245.008472) (xy 118.977658 -245.02957) (xy 119.018161 -245.057526) (xy 119.053654 -245.091618)
			(xy 119.083219 -245.130962) (xy 119.10609 -245.174539) (xy 119.121674 -245.22122) (xy 119.129569 -245.269797)
			(xy 119.130064 -245.294404) (xy 121.33886 -245.294404) (xy 121.34282 -245.24535) (xy 121.354597 -245.197566)
			(xy 121.373888 -245.15229) (xy 121.400191 -245.110694) (xy 121.432826 -245.073857) (xy 121.470947 -245.042732)
			(xy 121.513568 -245.018125) (xy 121.559584 -245.000673) (xy 121.607803 -244.990829) (xy 121.656978 -244.988848)
			(xy 121.705833 -244.99478) (xy 121.753104 -245.008472) (xy 121.797566 -245.02957) (xy 121.838069 -245.057526)
			(xy 121.873562 -245.091618) (xy 121.903127 -245.130962) (xy 121.925998 -245.174539) (xy 121.941582 -245.22122)
			(xy 121.949477 -245.269797) (xy 121.949972 -245.294404) (xy 124.159022 -245.294404) (xy 124.162982 -245.24535)
			(xy 124.174759 -245.197566) (xy 124.19405 -245.15229) (xy 124.220353 -245.110694) (xy 124.252988 -245.073857)
			(xy 124.291109 -245.042732) (xy 124.33373 -245.018125) (xy 124.379746 -245.000673) (xy 124.427965 -244.990829)
			(xy 124.47714 -244.988848) (xy 124.525995 -244.99478) (xy 124.573266 -245.008472) (xy 124.617728 -245.02957)
			(xy 124.658231 -245.057526) (xy 124.693724 -245.091618) (xy 124.723289 -245.130962) (xy 124.74616 -245.174539)
			(xy 124.761744 -245.22122) (xy 124.769639 -245.269797) (xy 124.770134 -245.294404) (xy 124.769639 -245.319011)
			(xy 124.761744 -245.367588) (xy 124.74616 -245.414269) (xy 124.723289 -245.457846) (xy 124.693724 -245.49719)
			(xy 124.658231 -245.531282) (xy 124.617728 -245.559238) (xy 124.573266 -245.580336) (xy 124.525995 -245.594028)
			(xy 124.47714 -245.59996) (xy 124.427965 -245.597979) (xy 124.379746 -245.588135) (xy 124.33373 -245.570683)
			(xy 124.291109 -245.546076) (xy 124.252988 -245.514951) (xy 124.220353 -245.478114) (xy 124.19405 -245.436518)
			(xy 124.174759 -245.391242) (xy 124.162982 -245.343458) (xy 124.159022 -245.294404) (xy 121.949972 -245.294404)
			(xy 121.949477 -245.319011) (xy 121.941582 -245.367588) (xy 121.925998 -245.414269) (xy 121.903127 -245.457846)
			(xy 121.873562 -245.49719) (xy 121.838069 -245.531282) (xy 121.797566 -245.559238) (xy 121.753104 -245.580336)
			(xy 121.705833 -245.594028) (xy 121.656978 -245.59996) (xy 121.607803 -245.597979) (xy 121.559584 -245.588135)
			(xy 121.513568 -245.570683) (xy 121.470947 -245.546076) (xy 121.432826 -245.514951) (xy 121.400191 -245.478114)
			(xy 121.373888 -245.436518) (xy 121.354597 -245.391242) (xy 121.34282 -245.343458) (xy 121.33886 -245.294404)
			(xy 119.130064 -245.294404) (xy 119.129569 -245.319011) (xy 119.121674 -245.367588) (xy 119.10609 -245.414269)
			(xy 119.083219 -245.457846) (xy 119.053654 -245.49719) (xy 119.018161 -245.531282) (xy 118.977658 -245.559238)
			(xy 118.933196 -245.580336) (xy 118.885925 -245.594028) (xy 118.83707 -245.59996) (xy 118.787895 -245.597979)
			(xy 118.739676 -245.588135) (xy 118.69366 -245.570683) (xy 118.651039 -245.546076) (xy 118.612918 -245.514951)
			(xy 118.580283 -245.478114) (xy 118.55398 -245.436518) (xy 118.534689 -245.391242) (xy 118.522912 -245.343458)
			(xy 118.518952 -245.294404) (xy 116.310156 -245.294404) (xy 116.309661 -245.319011) (xy 116.301766 -245.367588)
			(xy 116.286182 -245.414269) (xy 116.263311 -245.457846) (xy 116.233746 -245.49719) (xy 116.198253 -245.531282)
			(xy 116.15775 -245.559238) (xy 116.113288 -245.580336) (xy 116.066017 -245.594028) (xy 116.017162 -245.59996)
			(xy 115.967987 -245.597979) (xy 115.919768 -245.588135) (xy 115.873752 -245.570683) (xy 115.831131 -245.546076)
			(xy 115.79301 -245.514951) (xy 115.760375 -245.478114) (xy 115.734072 -245.436518) (xy 115.714781 -245.391242)
			(xy 115.703004 -245.343458) (xy 115.699044 -245.294404) (xy 115.370102 -245.294404) (xy 115.369607 -245.319011)
			(xy 115.361712 -245.367588) (xy 115.346128 -245.414269) (xy 115.323257 -245.457846) (xy 115.293692 -245.49719)
			(xy 115.258199 -245.531282) (xy 115.217696 -245.559238) (xy 115.173234 -245.580336) (xy 115.125963 -245.594028)
			(xy 115.077108 -245.59996) (xy 115.027933 -245.597979) (xy 114.979714 -245.588135) (xy 114.933698 -245.570683)
			(xy 114.891077 -245.546076) (xy 114.852956 -245.514951) (xy 114.820321 -245.478114) (xy 114.794018 -245.436518)
			(xy 114.774727 -245.391242) (xy 114.76295 -245.343458) (xy 114.75899 -245.294404) (xy 114.430048 -245.294404)
			(xy 114.429553 -245.319011) (xy 114.421658 -245.367588) (xy 114.406074 -245.414269) (xy 114.383203 -245.457846)
			(xy 114.353638 -245.49719) (xy 114.318145 -245.531282) (xy 114.277642 -245.559238) (xy 114.23318 -245.580336)
			(xy 114.185909 -245.594028) (xy 114.137054 -245.59996) (xy 114.087879 -245.597979) (xy 114.03966 -245.588135)
			(xy 113.993644 -245.570683) (xy 113.951023 -245.546076) (xy 113.912902 -245.514951) (xy 113.880267 -245.478114)
			(xy 113.853964 -245.436518) (xy 113.834673 -245.391242) (xy 113.822896 -245.343458) (xy 113.818936 -245.294404)
			(xy 113.489994 -245.294404) (xy 113.489499 -245.319011) (xy 113.481604 -245.367588) (xy 113.46602 -245.414269)
			(xy 113.443149 -245.457846) (xy 113.413584 -245.49719) (xy 113.378091 -245.531282) (xy 113.337588 -245.559238)
			(xy 113.293126 -245.580336) (xy 113.245855 -245.594028) (xy 113.197 -245.59996) (xy 113.147825 -245.597979)
			(xy 113.099606 -245.588135) (xy 113.05359 -245.570683) (xy 113.010969 -245.546076) (xy 112.972848 -245.514951)
			(xy 112.940213 -245.478114) (xy 112.91391 -245.436518) (xy 112.894619 -245.391242) (xy 112.882842 -245.343458)
			(xy 112.878882 -245.294404) (xy 112.027809 -245.294404) (xy 112.0292 -245.295464) (xy 112.065712 -245.333402)
			(xy 112.096004 -245.376468) (xy 112.119367 -245.423653) (xy 112.135253 -245.473852) (xy 112.14329 -245.525888)
			(xy 112.143794 -245.552214) (xy 112.14329 -245.57854) (xy 112.135253 -245.630576) (xy 112.119367 -245.680775)
			(xy 112.096004 -245.72796) (xy 112.065712 -245.771026) (xy 112.0292 -245.808964) (xy 111.987326 -245.840883)
			(xy 111.94107 -245.866036) (xy 111.891517 -245.883834) (xy 111.839827 -245.893858) (xy 111.787213 -245.895875)
			(xy 111.734908 -245.889837) (xy 111.684137 -245.875885) (xy 111.636092 -245.854346) (xy 111.591897 -245.825726)
			(xy 111.552589 -245.790695) (xy 111.519089 -245.750074) (xy 111.492183 -245.704815) (xy 111.4725 -245.65598)
			(xy 111.460503 -245.604712) (xy 111.456473 -245.552214) (xy 110.534206 -245.552214) (xy 110.52403 -245.559238)
			(xy 110.479568 -245.580336) (xy 110.432297 -245.594028) (xy 110.383442 -245.59996) (xy 110.334267 -245.597979)
			(xy 110.286048 -245.588135) (xy 110.240032 -245.570683) (xy 110.197411 -245.546076) (xy 110.15929 -245.514951)
			(xy 110.126655 -245.478114) (xy 110.100352 -245.436518) (xy 110.081061 -245.391242) (xy 110.069284 -245.343458)
			(xy 110.065324 -245.294404) (xy 109.746796 -245.294404) (xy 109.746284 -245.31985) (xy 109.73812 -245.370084)
			(xy 109.722004 -245.418358) (xy 109.698353 -245.463421) (xy 109.66778 -245.504107) (xy 109.631076 -245.539362)
			(xy 109.589192 -245.568272) (xy 109.543213 -245.590089) (xy 109.494329 -245.604249) (xy 109.443808 -245.610383)
			(xy 109.392956 -245.608334) (xy 109.343092 -245.598154) (xy 109.295506 -245.580107) (xy 109.251432 -245.554661)
			(xy 109.21201 -245.522474) (xy 109.178262 -245.48438) (xy 109.151061 -245.441366) (xy 109.131113 -245.394546)
			(xy 109.118934 -245.345132) (xy 109.114839 -245.294404) (xy 108.806742 -245.294404) (xy 108.80623 -245.31985)
			(xy 108.798066 -245.370084) (xy 108.78195 -245.418358) (xy 108.758299 -245.463421) (xy 108.727726 -245.504107)
			(xy 108.691022 -245.539362) (xy 108.649138 -245.568272) (xy 108.603159 -245.590089) (xy 108.554275 -245.604249)
			(xy 108.503754 -245.610383) (xy 108.452902 -245.608334) (xy 108.403038 -245.598154) (xy 108.355452 -245.580107)
			(xy 108.311378 -245.554661) (xy 108.271956 -245.522474) (xy 108.238208 -245.48438) (xy 108.211007 -245.441366)
			(xy 108.191059 -245.394546) (xy 108.17888 -245.345132) (xy 108.174785 -245.294404) (xy 107.856274 -245.294404)
			(xy 107.855779 -245.319011) (xy 107.847884 -245.367588) (xy 107.8323 -245.414269) (xy 107.809429 -245.457846)
			(xy 107.779864 -245.49719) (xy 107.744371 -245.531282) (xy 107.703868 -245.559238) (xy 107.659406 -245.580336)
			(xy 107.612135 -245.594028) (xy 107.56328 -245.59996) (xy 107.514105 -245.597979) (xy 107.465886 -245.588135)
			(xy 107.41987 -245.570683) (xy 107.377249 -245.546076) (xy 107.339128 -245.514951) (xy 107.306493 -245.478114)
			(xy 107.28019 -245.436518) (xy 107.260899 -245.391242) (xy 107.249122 -245.343458) (xy 107.245162 -245.294404)
			(xy 105.036366 -245.294404) (xy 105.035871 -245.319011) (xy 105.027976 -245.367588) (xy 105.012392 -245.414269)
			(xy 104.989521 -245.457846) (xy 104.959956 -245.49719) (xy 104.924463 -245.531282) (xy 104.88396 -245.559238)
			(xy 104.839498 -245.580336) (xy 104.792227 -245.594028) (xy 104.743372 -245.59996) (xy 104.694197 -245.597979)
			(xy 104.645978 -245.588135) (xy 104.599962 -245.570683) (xy 104.557341 -245.546076) (xy 104.51922 -245.514951)
			(xy 104.486585 -245.478114) (xy 104.460282 -245.436518) (xy 104.440991 -245.391242) (xy 104.429214 -245.343458)
			(xy 104.425254 -245.294404) (xy 102.216458 -245.294404) (xy 102.215963 -245.319011) (xy 102.208068 -245.367588)
			(xy 102.192484 -245.414269) (xy 102.169613 -245.457846) (xy 102.140048 -245.49719) (xy 102.104555 -245.531282)
			(xy 102.064052 -245.559238) (xy 102.01959 -245.580336) (xy 101.972319 -245.594028) (xy 101.923464 -245.59996)
			(xy 101.874289 -245.597979) (xy 101.82607 -245.588135) (xy 101.780054 -245.570683) (xy 101.737433 -245.546076)
			(xy 101.699312 -245.514951) (xy 101.666677 -245.478114) (xy 101.640374 -245.436518) (xy 101.621083 -245.391242)
			(xy 101.609306 -245.343458) (xy 101.605346 -245.294404) (xy 99.396296 -245.294404) (xy 99.395801 -245.319011)
			(xy 99.387906 -245.367588) (xy 99.372322 -245.414269) (xy 99.349451 -245.457846) (xy 99.319886 -245.49719)
			(xy 99.284393 -245.531282) (xy 99.24389 -245.559238) (xy 99.199428 -245.580336) (xy 99.152157 -245.594028)
			(xy 99.103302 -245.59996) (xy 99.054127 -245.597979) (xy 99.005908 -245.588135) (xy 98.959892 -245.570683)
			(xy 98.917271 -245.546076) (xy 98.87915 -245.514951) (xy 98.846515 -245.478114) (xy 98.820212 -245.436518)
			(xy 98.800921 -245.391242) (xy 98.789144 -245.343458) (xy 98.785184 -245.294404) (xy 96.576388 -245.294404)
			(xy 96.575893 -245.319011) (xy 96.567998 -245.367588) (xy 96.552414 -245.414269) (xy 96.529543 -245.457846)
			(xy 96.499978 -245.49719) (xy 96.464485 -245.531282) (xy 96.423982 -245.559238) (xy 96.37952 -245.580336)
			(xy 96.332249 -245.594028) (xy 96.283394 -245.59996) (xy 96.234219 -245.597979) (xy 96.186 -245.588135)
			(xy 96.139984 -245.570683) (xy 96.097363 -245.546076) (xy 96.059242 -245.514951) (xy 96.026607 -245.478114)
			(xy 96.000304 -245.436518) (xy 95.981013 -245.391242) (xy 95.969236 -245.343458) (xy 95.965276 -245.294404)
			(xy 95.646748 -245.294404) (xy 95.646236 -245.31985) (xy 95.638072 -245.370084) (xy 95.621956 -245.418358)
			(xy 95.598305 -245.463421) (xy 95.567732 -245.504107) (xy 95.531028 -245.539362) (xy 95.489144 -245.568272)
			(xy 95.443165 -245.590089) (xy 95.394281 -245.604249) (xy 95.34376 -245.610383) (xy 95.292908 -245.608334)
			(xy 95.243044 -245.598154) (xy 95.195458 -245.580107) (xy 95.151384 -245.554661) (xy 95.111962 -245.522474)
			(xy 95.078214 -245.48438) (xy 95.051013 -245.441366) (xy 95.031065 -245.394546) (xy 95.018886 -245.345132)
			(xy 95.014791 -245.294404) (xy 94.706694 -245.294404) (xy 94.706182 -245.31985) (xy 94.698018 -245.370084)
			(xy 94.681902 -245.418358) (xy 94.658251 -245.463421) (xy 94.627678 -245.504107) (xy 94.590974 -245.539362)
			(xy 94.54909 -245.568272) (xy 94.503111 -245.590089) (xy 94.454227 -245.604249) (xy 94.403706 -245.610383)
			(xy 94.352854 -245.608334) (xy 94.30299 -245.598154) (xy 94.255404 -245.580107) (xy 94.21133 -245.554661)
			(xy 94.171908 -245.522474) (xy 94.13816 -245.48438) (xy 94.110959 -245.441366) (xy 94.091011 -245.394546)
			(xy 94.078832 -245.345132) (xy 94.074737 -245.294404) (xy 93.756226 -245.294404) (xy 93.755731 -245.319011)
			(xy 93.747836 -245.367588) (xy 93.732252 -245.414269) (xy 93.709381 -245.457846) (xy 93.679816 -245.49719)
			(xy 93.644323 -245.531282) (xy 93.60382 -245.559238) (xy 93.559358 -245.580336) (xy 93.512087 -245.594028)
			(xy 93.463232 -245.59996) (xy 93.414057 -245.597979) (xy 93.365838 -245.588135) (xy 93.319822 -245.570683)
			(xy 93.277201 -245.546076) (xy 93.23908 -245.514951) (xy 93.206445 -245.478114) (xy 93.180142 -245.436518)
			(xy 93.160851 -245.391242) (xy 93.149074 -245.343458) (xy 93.145114 -245.294404) (xy 92.82684 -245.294404)
			(xy 92.826328 -245.31985) (xy 92.818164 -245.370084) (xy 92.802048 -245.418358) (xy 92.778397 -245.463421)
			(xy 92.747824 -245.504107) (xy 92.71112 -245.539362) (xy 92.669236 -245.568272) (xy 92.623257 -245.590089)
			(xy 92.574373 -245.604249) (xy 92.523852 -245.610383) (xy 92.473 -245.608334) (xy 92.423136 -245.598154)
			(xy 92.37555 -245.580107) (xy 92.331476 -245.554661) (xy 92.292054 -245.522474) (xy 92.258306 -245.48438)
			(xy 92.231105 -245.441366) (xy 92.211157 -245.394546) (xy 92.198978 -245.345132) (xy 92.194883 -245.294404)
			(xy 91.876372 -245.294404) (xy 91.875877 -245.319011) (xy 91.867982 -245.367588) (xy 91.852398 -245.414269)
			(xy 91.829527 -245.457846) (xy 91.799962 -245.49719) (xy 91.764469 -245.531282) (xy 91.723966 -245.559238)
			(xy 91.679504 -245.580336) (xy 91.632233 -245.594028) (xy 91.583378 -245.59996) (xy 91.534203 -245.597979)
			(xy 91.485984 -245.588135) (xy 91.439968 -245.570683) (xy 91.397347 -245.546076) (xy 91.359226 -245.514951)
			(xy 91.326591 -245.478114) (xy 91.300288 -245.436518) (xy 91.280997 -245.391242) (xy 91.26922 -245.343458)
			(xy 91.26526 -245.294404) (xy 90.946732 -245.294404) (xy 90.946339 -245.316351) (xy 90.940225 -245.359817)
			(xy 90.93454 -245.381018) (xy 90.93073 -245.394226) (xy 90.937588 -245.420896) (xy 91.575382 -246.05869)
			(xy 91.579954 -246.062754) (xy 91.589505 -246.069553) (xy 91.612403 -246.074461) (xy 91.623896 -246.072152)
			(xy 91.714574 -246.049038) (xy 91.733878 -246.030242) (xy 91.737688 -246.017288) (xy 91.745178 -245.992922)
			(xy 91.766914 -245.946816) (xy 91.795778 -245.904803) (xy 91.83102 -245.867976) (xy 91.871725 -245.837293)
			(xy 91.916832 -245.813553) (xy 91.965168 -245.797373) (xy 92.015478 -245.789173) (xy 92.040964 -245.788688)
			(xy 92.065771 -245.789147) (xy 92.114775 -245.796907) (xy 92.161961 -245.812241) (xy 92.206165 -245.834771)
			(xy 92.246299 -245.863941) (xy 92.281372 -245.899034) (xy 92.31052 -245.939183) (xy 92.333026 -245.9834)
			(xy 92.348334 -246.030594) (xy 92.356066 -246.079602) (xy 92.356432 -246.10441) (xy 92.675214 -246.10441)
			(xy 92.679174 -246.055356) (xy 92.690951 -246.007572) (xy 92.710242 -245.962296) (xy 92.736545 -245.9207)
			(xy 92.76918 -245.883863) (xy 92.807301 -245.852738) (xy 92.849922 -245.828131) (xy 92.895938 -245.810679)
			(xy 92.944157 -245.800835) (xy 92.993332 -245.798854) (xy 93.042187 -245.804786) (xy 93.089458 -245.818478)
			(xy 93.13392 -245.839576) (xy 93.174423 -245.867532) (xy 93.209916 -245.901624) (xy 93.239481 -245.940968)
			(xy 93.262352 -245.984545) (xy 93.277936 -246.031226) (xy 93.285831 -246.079803) (xy 93.286326 -246.10441)
			(xy 93.604837 -246.10441) (xy 93.608932 -246.053682) (xy 93.621111 -246.004268) (xy 93.641059 -245.957448)
			(xy 93.66826 -245.914434) (xy 93.702008 -245.87634) (xy 93.74143 -245.844153) (xy 93.785504 -245.818707)
			(xy 93.83309 -245.80066) (xy 93.882954 -245.79048) (xy 93.933806 -245.788431) (xy 93.984327 -245.794565)
			(xy 94.033211 -245.808725) (xy 94.07919 -245.830542) (xy 94.121074 -245.859452) (xy 94.157778 -245.894707)
			(xy 94.188351 -245.935393) (xy 94.212002 -245.980456) (xy 94.228118 -246.02873) (xy 94.236282 -246.078964)
			(xy 94.236794 -246.10441) (xy 94.555322 -246.10441) (xy 94.559282 -246.055356) (xy 94.571059 -246.007572)
			(xy 94.59035 -245.962296) (xy 94.616653 -245.9207) (xy 94.649288 -245.883863) (xy 94.687409 -245.852738)
			(xy 94.73003 -245.828131) (xy 94.776046 -245.810679) (xy 94.824265 -245.800835) (xy 94.87344 -245.798854)
			(xy 94.922295 -245.804786) (xy 94.969566 -245.818478) (xy 95.014028 -245.839576) (xy 95.054531 -245.867532)
			(xy 95.090024 -245.901624) (xy 95.119589 -245.940968) (xy 95.14246 -245.984545) (xy 95.158044 -246.031226)
			(xy 95.165939 -246.079803) (xy 95.166434 -246.10441) (xy 95.484691 -246.10441) (xy 95.488786 -246.053682)
			(xy 95.500965 -246.004268) (xy 95.520913 -245.957448) (xy 95.548114 -245.914434) (xy 95.581862 -245.87634)
			(xy 95.621284 -245.844153) (xy 95.665358 -245.818707) (xy 95.712944 -245.80066) (xy 95.762808 -245.79048)
			(xy 95.81366 -245.788431) (xy 95.864181 -245.794565) (xy 95.913065 -245.808725) (xy 95.959044 -245.830542)
			(xy 96.000928 -245.859452) (xy 96.037632 -245.894707) (xy 96.068205 -245.935393) (xy 96.091856 -245.980456)
			(xy 96.107972 -246.02873) (xy 96.116136 -246.078964) (xy 96.116648 -246.10441) (xy 96.435176 -246.10441)
			(xy 96.439136 -246.055356) (xy 96.450913 -246.007572) (xy 96.470204 -245.962296) (xy 96.496507 -245.9207)
			(xy 96.529142 -245.883863) (xy 96.567263 -245.852738) (xy 96.609884 -245.828131) (xy 96.6559 -245.810679)
			(xy 96.704119 -245.800835) (xy 96.753294 -245.798854) (xy 96.802149 -245.804786) (xy 96.84942 -245.818478)
			(xy 96.893882 -245.839576) (xy 96.934385 -245.867532) (xy 96.969878 -245.901624) (xy 96.999443 -245.940968)
			(xy 97.022314 -245.984545) (xy 97.037898 -246.031226) (xy 97.045793 -246.079803) (xy 97.046288 -246.10441)
			(xy 97.364799 -246.10441) (xy 97.368894 -246.053682) (xy 97.381073 -246.004268) (xy 97.401021 -245.957448)
			(xy 97.428222 -245.914434) (xy 97.46197 -245.87634) (xy 97.501392 -245.844153) (xy 97.545466 -245.818707)
			(xy 97.593052 -245.80066) (xy 97.642916 -245.79048) (xy 97.693768 -245.788431) (xy 97.744289 -245.794565)
			(xy 97.793173 -245.808725) (xy 97.839152 -245.830542) (xy 97.881036 -245.859452) (xy 97.91774 -245.894707)
			(xy 97.948313 -245.935393) (xy 97.971964 -245.980456) (xy 97.98808 -246.02873) (xy 97.996244 -246.078964)
			(xy 97.996756 -246.10441) (xy 98.304853 -246.10441) (xy 98.308948 -246.053682) (xy 98.321127 -246.004268)
			(xy 98.341075 -245.957448) (xy 98.368276 -245.914434) (xy 98.402024 -245.87634) (xy 98.441446 -245.844153)
			(xy 98.48552 -245.818707) (xy 98.533106 -245.80066) (xy 98.58297 -245.79048) (xy 98.633822 -245.788431)
			(xy 98.684343 -245.794565) (xy 98.733227 -245.808725) (xy 98.779206 -245.830542) (xy 98.82109 -245.859452)
			(xy 98.857794 -245.894707) (xy 98.888367 -245.935393) (xy 98.912018 -245.980456) (xy 98.928134 -246.02873)
			(xy 98.936298 -246.078964) (xy 98.93681 -246.10441) (xy 99.255338 -246.10441) (xy 99.259298 -246.055356)
			(xy 99.271075 -246.007572) (xy 99.290366 -245.962296) (xy 99.316669 -245.9207) (xy 99.349304 -245.883863)
			(xy 99.387425 -245.852738) (xy 99.430046 -245.828131) (xy 99.476062 -245.810679) (xy 99.524281 -245.800835)
			(xy 99.573456 -245.798854) (xy 99.622311 -245.804786) (xy 99.669582 -245.818478) (xy 99.714044 -245.839576)
			(xy 99.754547 -245.867532) (xy 99.79004 -245.901624) (xy 99.819605 -245.940968) (xy 99.842476 -245.984545)
			(xy 99.85806 -246.031226) (xy 99.865955 -246.079803) (xy 99.86645 -246.10441) (xy 100.184707 -246.10441)
			(xy 100.188802 -246.053682) (xy 100.200981 -246.004268) (xy 100.220929 -245.957448) (xy 100.24813 -245.914434)
			(xy 100.281878 -245.87634) (xy 100.3213 -245.844153) (xy 100.365374 -245.818707) (xy 100.41296 -245.80066)
			(xy 100.462824 -245.79048) (xy 100.513676 -245.788431) (xy 100.564197 -245.794565) (xy 100.613081 -245.808725)
			(xy 100.65906 -245.830542) (xy 100.700944 -245.859452) (xy 100.737648 -245.894707) (xy 100.768221 -245.935393)
			(xy 100.791872 -245.980456) (xy 100.807988 -246.02873) (xy 100.816152 -246.078964) (xy 100.816664 -246.10441)
			(xy 101.124761 -246.10441) (xy 101.128856 -246.053682) (xy 101.141035 -246.004268) (xy 101.160983 -245.957448)
			(xy 101.188184 -245.914434) (xy 101.221932 -245.87634) (xy 101.261354 -245.844153) (xy 101.305428 -245.818707)
			(xy 101.353014 -245.80066) (xy 101.402878 -245.79048) (xy 101.45373 -245.788431) (xy 101.504251 -245.794565)
			(xy 101.553135 -245.808725) (xy 101.599114 -245.830542) (xy 101.640998 -245.859452) (xy 101.677702 -245.894707)
			(xy 101.708275 -245.935393) (xy 101.731926 -245.980456) (xy 101.748042 -246.02873) (xy 101.756206 -246.078964)
			(xy 101.756718 -246.10441) (xy 102.075246 -246.10441) (xy 102.079206 -246.055356) (xy 102.090983 -246.007572)
			(xy 102.110274 -245.962296) (xy 102.136577 -245.9207) (xy 102.169212 -245.883863) (xy 102.207333 -245.852738)
			(xy 102.249954 -245.828131) (xy 102.29597 -245.810679) (xy 102.344189 -245.800835) (xy 102.393364 -245.798854)
			(xy 102.442219 -245.804786) (xy 102.48949 -245.818478) (xy 102.533952 -245.839576) (xy 102.574455 -245.867532)
			(xy 102.609948 -245.901624) (xy 102.639513 -245.940968) (xy 102.662384 -245.984545) (xy 102.677968 -246.031226)
			(xy 102.685863 -246.079803) (xy 102.686358 -246.10441) (xy 103.004869 -246.10441) (xy 103.008964 -246.053682)
			(xy 103.021143 -246.004268) (xy 103.041091 -245.957448) (xy 103.068292 -245.914434) (xy 103.10204 -245.87634)
			(xy 103.141462 -245.844153) (xy 103.185536 -245.818707) (xy 103.233122 -245.80066) (xy 103.282986 -245.79048)
			(xy 103.333838 -245.788431) (xy 103.384359 -245.794565) (xy 103.433243 -245.808725) (xy 103.479222 -245.830542)
			(xy 103.521106 -245.859452) (xy 103.55781 -245.894707) (xy 103.588383 -245.935393) (xy 103.612034 -245.980456)
			(xy 103.62815 -246.02873) (xy 103.636314 -246.078964) (xy 103.636826 -246.10441) (xy 103.944923 -246.10441)
			(xy 103.949018 -246.053682) (xy 103.961197 -246.004268) (xy 103.981145 -245.957448) (xy 104.008346 -245.914434)
			(xy 104.042094 -245.87634) (xy 104.081516 -245.844153) (xy 104.12559 -245.818707) (xy 104.173176 -245.80066)
			(xy 104.22304 -245.79048) (xy 104.273892 -245.788431) (xy 104.324413 -245.794565) (xy 104.373297 -245.808725)
			(xy 104.419276 -245.830542) (xy 104.46116 -245.859452) (xy 104.497864 -245.894707) (xy 104.528437 -245.935393)
			(xy 104.552088 -245.980456) (xy 104.568204 -246.02873) (xy 104.576368 -246.078964) (xy 104.57688 -246.10441)
			(xy 104.895154 -246.10441) (xy 104.899114 -246.055356) (xy 104.910891 -246.007572) (xy 104.930182 -245.962296)
			(xy 104.956485 -245.9207) (xy 104.98912 -245.883863) (xy 105.027241 -245.852738) (xy 105.069862 -245.828131)
			(xy 105.115878 -245.810679) (xy 105.164097 -245.800835) (xy 105.213272 -245.798854) (xy 105.262127 -245.804786)
			(xy 105.309398 -245.818478) (xy 105.35386 -245.839576) (xy 105.394363 -245.867532) (xy 105.429856 -245.901624)
			(xy 105.459421 -245.940968) (xy 105.482292 -245.984545) (xy 105.497876 -246.031226) (xy 105.505771 -246.079803)
			(xy 105.506266 -246.10441) (xy 105.824777 -246.10441) (xy 105.828872 -246.053682) (xy 105.841051 -246.004268)
			(xy 105.860999 -245.957448) (xy 105.8882 -245.914434) (xy 105.921948 -245.87634) (xy 105.96137 -245.844153)
			(xy 106.005444 -245.818707) (xy 106.05303 -245.80066) (xy 106.102894 -245.79048) (xy 106.153746 -245.788431)
			(xy 106.204267 -245.794565) (xy 106.253151 -245.808725) (xy 106.29913 -245.830542) (xy 106.341014 -245.859452)
			(xy 106.377718 -245.894707) (xy 106.408291 -245.935393) (xy 106.431942 -245.980456) (xy 106.448058 -246.02873)
			(xy 106.456222 -246.078964) (xy 106.456734 -246.10441) (xy 106.764831 -246.10441) (xy 106.768926 -246.053682)
			(xy 106.781105 -246.004268) (xy 106.801053 -245.957448) (xy 106.828254 -245.914434) (xy 106.862002 -245.87634)
			(xy 106.901424 -245.844153) (xy 106.945498 -245.818707) (xy 106.993084 -245.80066) (xy 107.042948 -245.79048)
			(xy 107.0938 -245.788431) (xy 107.144321 -245.794565) (xy 107.193205 -245.808725) (xy 107.239184 -245.830542)
			(xy 107.281068 -245.859452) (xy 107.317772 -245.894707) (xy 107.348345 -245.935393) (xy 107.371996 -245.980456)
			(xy 107.388112 -246.02873) (xy 107.396276 -246.078964) (xy 107.396788 -246.10441) (xy 107.715316 -246.10441)
			(xy 107.719276 -246.055356) (xy 107.731053 -246.007572) (xy 107.750344 -245.962296) (xy 107.776647 -245.9207)
			(xy 107.809282 -245.883863) (xy 107.847403 -245.852738) (xy 107.890024 -245.828131) (xy 107.93604 -245.810679)
			(xy 107.984259 -245.800835) (xy 108.033434 -245.798854) (xy 108.082289 -245.804786) (xy 108.12956 -245.818478)
			(xy 108.174022 -245.839576) (xy 108.214525 -245.867532) (xy 108.250018 -245.901624) (xy 108.279583 -245.940968)
			(xy 108.302454 -245.984545) (xy 108.318038 -246.031226) (xy 108.325933 -246.079803) (xy 108.326428 -246.10441)
			(xy 115.22889 -246.10441) (xy 115.23285 -246.055356) (xy 115.244627 -246.007572) (xy 115.263918 -245.962296)
			(xy 115.290221 -245.9207) (xy 115.322856 -245.883863) (xy 115.360977 -245.852738) (xy 115.403598 -245.828131)
			(xy 115.449614 -245.810679) (xy 115.497833 -245.800835) (xy 115.547008 -245.798854) (xy 115.595863 -245.804786)
			(xy 115.643134 -245.818478) (xy 115.687596 -245.839576) (xy 115.728099 -245.867532) (xy 115.763592 -245.901624)
			(xy 115.793157 -245.940968) (xy 115.816028 -245.984545) (xy 115.831612 -246.031226) (xy 115.839507 -246.079803)
			(xy 115.840002 -246.10441) (xy 116.168944 -246.10441) (xy 116.172904 -246.055356) (xy 116.184681 -246.007572)
			(xy 116.203972 -245.962296) (xy 116.230275 -245.9207) (xy 116.26291 -245.883863) (xy 116.301031 -245.852738)
			(xy 116.343652 -245.828131) (xy 116.389668 -245.810679) (xy 116.437887 -245.800835) (xy 116.487062 -245.798854)
			(xy 116.535917 -245.804786) (xy 116.583188 -245.818478) (xy 116.62765 -245.839576) (xy 116.668153 -245.867532)
			(xy 116.703646 -245.901624) (xy 116.733211 -245.940968) (xy 116.756082 -245.984545) (xy 116.771666 -246.031226)
			(xy 116.779561 -246.079803) (xy 116.780056 -246.10441) (xy 117.108998 -246.10441) (xy 117.112958 -246.055356)
			(xy 117.124735 -246.007572) (xy 117.144026 -245.962296) (xy 117.170329 -245.9207) (xy 117.202964 -245.883863)
			(xy 117.241085 -245.852738) (xy 117.283706 -245.828131) (xy 117.329722 -245.810679) (xy 117.377941 -245.800835)
			(xy 117.427116 -245.798854) (xy 117.475971 -245.804786) (xy 117.523242 -245.818478) (xy 117.567704 -245.839576)
			(xy 117.608207 -245.867532) (xy 117.6437 -245.901624) (xy 117.673265 -245.940968) (xy 117.696136 -245.984545)
			(xy 117.71172 -246.031226) (xy 117.719615 -246.079803) (xy 117.72011 -246.10441) (xy 118.049052 -246.10441)
			(xy 118.053012 -246.055356) (xy 118.064789 -246.007572) (xy 118.08408 -245.962296) (xy 118.110383 -245.9207)
			(xy 118.143018 -245.883863) (xy 118.181139 -245.852738) (xy 118.22376 -245.828131) (xy 118.269776 -245.810679)
			(xy 118.317995 -245.800835) (xy 118.36717 -245.798854) (xy 118.416025 -245.804786) (xy 118.463296 -245.818478)
			(xy 118.507758 -245.839576) (xy 118.548261 -245.867532) (xy 118.583754 -245.901624) (xy 118.613319 -245.940968)
			(xy 118.63619 -245.984545) (xy 118.651774 -246.031226) (xy 118.659669 -246.079803) (xy 118.660164 -246.10441)
			(xy 118.988852 -246.10441) (xy 118.992812 -246.055356) (xy 119.004589 -246.007572) (xy 119.02388 -245.962296)
			(xy 119.050183 -245.9207) (xy 119.082818 -245.883863) (xy 119.120939 -245.852738) (xy 119.16356 -245.828131)
			(xy 119.209576 -245.810679) (xy 119.257795 -245.800835) (xy 119.30697 -245.798854) (xy 119.355825 -245.804786)
			(xy 119.403096 -245.818478) (xy 119.447558 -245.839576) (xy 119.488061 -245.867532) (xy 119.523554 -245.901624)
			(xy 119.553119 -245.940968) (xy 119.57599 -245.984545) (xy 119.591574 -246.031226) (xy 119.599469 -246.079803)
			(xy 119.599964 -246.10441) (xy 119.928906 -246.10441) (xy 119.932866 -246.055356) (xy 119.944643 -246.007572)
			(xy 119.963934 -245.962296) (xy 119.990237 -245.9207) (xy 120.022872 -245.883863) (xy 120.060993 -245.852738)
			(xy 120.103614 -245.828131) (xy 120.14963 -245.810679) (xy 120.197849 -245.800835) (xy 120.247024 -245.798854)
			(xy 120.295879 -245.804786) (xy 120.34315 -245.818478) (xy 120.387612 -245.839576) (xy 120.428115 -245.867532)
			(xy 120.463608 -245.901624) (xy 120.493173 -245.940968) (xy 120.516044 -245.984545) (xy 120.531628 -246.031226)
			(xy 120.539523 -246.079803) (xy 120.540018 -246.10441) (xy 120.86896 -246.10441) (xy 120.87292 -246.055356)
			(xy 120.884697 -246.007572) (xy 120.903988 -245.962296) (xy 120.930291 -245.9207) (xy 120.962926 -245.883863)
			(xy 121.001047 -245.852738) (xy 121.043668 -245.828131) (xy 121.089684 -245.810679) (xy 121.137903 -245.800835)
			(xy 121.187078 -245.798854) (xy 121.235933 -245.804786) (xy 121.283204 -245.818478) (xy 121.327666 -245.839576)
			(xy 121.368169 -245.867532) (xy 121.403662 -245.901624) (xy 121.433227 -245.940968) (xy 121.456098 -245.984545)
			(xy 121.471682 -246.031226) (xy 121.479577 -246.079803) (xy 121.480072 -246.10441) (xy 121.809014 -246.10441)
			(xy 121.812974 -246.055356) (xy 121.824751 -246.007572) (xy 121.844042 -245.962296) (xy 121.870345 -245.9207)
			(xy 121.90298 -245.883863) (xy 121.941101 -245.852738) (xy 121.983722 -245.828131) (xy 122.029738 -245.810679)
			(xy 122.077957 -245.800835) (xy 122.127132 -245.798854) (xy 122.175987 -245.804786) (xy 122.223258 -245.818478)
			(xy 122.26772 -245.839576) (xy 122.308223 -245.867532) (xy 122.343716 -245.901624) (xy 122.373281 -245.940968)
			(xy 122.396152 -245.984545) (xy 122.411736 -246.031226) (xy 122.419631 -246.079803) (xy 122.420126 -246.10441)
			(xy 122.748814 -246.10441) (xy 122.752774 -246.055356) (xy 122.764551 -246.007572) (xy 122.783842 -245.962296)
			(xy 122.810145 -245.9207) (xy 122.84278 -245.883863) (xy 122.880901 -245.852738) (xy 122.923522 -245.828131)
			(xy 122.969538 -245.810679) (xy 123.017757 -245.800835) (xy 123.066932 -245.798854) (xy 123.115787 -245.804786)
			(xy 123.163058 -245.818478) (xy 123.20752 -245.839576) (xy 123.248023 -245.867532) (xy 123.283516 -245.901624)
			(xy 123.313081 -245.940968) (xy 123.335952 -245.984545) (xy 123.351536 -246.031226) (xy 123.359431 -246.079803)
			(xy 123.359926 -246.10441) (xy 123.688868 -246.10441) (xy 123.692828 -246.055356) (xy 123.704605 -246.007572)
			(xy 123.723896 -245.962296) (xy 123.750199 -245.9207) (xy 123.782834 -245.883863) (xy 123.820955 -245.852738)
			(xy 123.863576 -245.828131) (xy 123.909592 -245.810679) (xy 123.957811 -245.800835) (xy 124.006986 -245.798854)
			(xy 124.055841 -245.804786) (xy 124.103112 -245.818478) (xy 124.147574 -245.839576) (xy 124.188077 -245.867532)
			(xy 124.22357 -245.901624) (xy 124.253135 -245.940968) (xy 124.276006 -245.984545) (xy 124.29159 -246.031226)
			(xy 124.299485 -246.079803) (xy 124.29998 -246.10441) (xy 124.628922 -246.10441) (xy 124.632882 -246.055356)
			(xy 124.644659 -246.007572) (xy 124.66395 -245.962296) (xy 124.690253 -245.9207) (xy 124.722888 -245.883863)
			(xy 124.761009 -245.852738) (xy 124.80363 -245.828131) (xy 124.849646 -245.810679) (xy 124.897865 -245.800835)
			(xy 124.94704 -245.798854) (xy 124.995895 -245.804786) (xy 125.043166 -245.818478) (xy 125.087628 -245.839576)
			(xy 125.128131 -245.867532) (xy 125.163624 -245.901624) (xy 125.193189 -245.940968) (xy 125.21606 -245.984545)
			(xy 125.231644 -246.031226) (xy 125.239539 -246.079803) (xy 125.240034 -246.10441) (xy 125.568976 -246.10441)
			(xy 125.572936 -246.055356) (xy 125.584713 -246.007572) (xy 125.604004 -245.962296) (xy 125.630307 -245.9207)
			(xy 125.662942 -245.883863) (xy 125.701063 -245.852738) (xy 125.743684 -245.828131) (xy 125.7897 -245.810679)
			(xy 125.837919 -245.800835) (xy 125.887094 -245.798854) (xy 125.935949 -245.804786) (xy 125.98322 -245.818478)
			(xy 126.027682 -245.839576) (xy 126.068185 -245.867532) (xy 126.103678 -245.901624) (xy 126.133243 -245.940968)
			(xy 126.156114 -245.984545) (xy 126.171698 -246.031226) (xy 126.179593 -246.079803) (xy 126.180088 -246.10441)
			(xy 126.179593 -246.129017) (xy 126.171698 -246.177594) (xy 126.156114 -246.224275) (xy 126.133243 -246.267852)
			(xy 126.103678 -246.307196) (xy 126.068185 -246.341288) (xy 126.027682 -246.369244) (xy 125.98322 -246.390342)
			(xy 125.935949 -246.404034) (xy 125.887094 -246.409966) (xy 125.837919 -246.407985) (xy 125.7897 -246.398141)
			(xy 125.743684 -246.380689) (xy 125.701063 -246.356082) (xy 125.662942 -246.324957) (xy 125.630307 -246.28812)
			(xy 125.604004 -246.246524) (xy 125.584713 -246.201248) (xy 125.572936 -246.153464) (xy 125.568976 -246.10441)
			(xy 125.240034 -246.10441) (xy 125.239539 -246.129017) (xy 125.231644 -246.177594) (xy 125.21606 -246.224275)
			(xy 125.193189 -246.267852) (xy 125.163624 -246.307196) (xy 125.128131 -246.341288) (xy 125.087628 -246.369244)
			(xy 125.043166 -246.390342) (xy 124.995895 -246.404034) (xy 124.94704 -246.409966) (xy 124.897865 -246.407985)
			(xy 124.849646 -246.398141) (xy 124.80363 -246.380689) (xy 124.761009 -246.356082) (xy 124.722888 -246.324957)
			(xy 124.690253 -246.28812) (xy 124.66395 -246.246524) (xy 124.644659 -246.201248) (xy 124.632882 -246.153464)
			(xy 124.628922 -246.10441) (xy 124.29998 -246.10441) (xy 124.299485 -246.129017) (xy 124.29159 -246.177594)
			(xy 124.276006 -246.224275) (xy 124.253135 -246.267852) (xy 124.22357 -246.307196) (xy 124.188077 -246.341288)
			(xy 124.147574 -246.369244) (xy 124.103112 -246.390342) (xy 124.055841 -246.404034) (xy 124.006986 -246.409966)
			(xy 123.957811 -246.407985) (xy 123.909592 -246.398141) (xy 123.863576 -246.380689) (xy 123.820955 -246.356082)
			(xy 123.782834 -246.324957) (xy 123.750199 -246.28812) (xy 123.723896 -246.246524) (xy 123.704605 -246.201248)
			(xy 123.692828 -246.153464) (xy 123.688868 -246.10441) (xy 123.359926 -246.10441) (xy 123.359431 -246.129017)
			(xy 123.351536 -246.177594) (xy 123.335952 -246.224275) (xy 123.313081 -246.267852) (xy 123.283516 -246.307196)
			(xy 123.248023 -246.341288) (xy 123.20752 -246.369244) (xy 123.163058 -246.390342) (xy 123.115787 -246.404034)
			(xy 123.066932 -246.409966) (xy 123.017757 -246.407985) (xy 122.969538 -246.398141) (xy 122.923522 -246.380689)
			(xy 122.880901 -246.356082) (xy 122.84278 -246.324957) (xy 122.810145 -246.28812) (xy 122.783842 -246.246524)
			(xy 122.764551 -246.201248) (xy 122.752774 -246.153464) (xy 122.748814 -246.10441) (xy 122.420126 -246.10441)
			(xy 122.419631 -246.129017) (xy 122.411736 -246.177594) (xy 122.396152 -246.224275) (xy 122.373281 -246.267852)
			(xy 122.343716 -246.307196) (xy 122.308223 -246.341288) (xy 122.26772 -246.369244) (xy 122.223258 -246.390342)
			(xy 122.175987 -246.404034) (xy 122.127132 -246.409966) (xy 122.077957 -246.407985) (xy 122.029738 -246.398141)
			(xy 121.983722 -246.380689) (xy 121.941101 -246.356082) (xy 121.90298 -246.324957) (xy 121.870345 -246.28812)
			(xy 121.844042 -246.246524) (xy 121.824751 -246.201248) (xy 121.812974 -246.153464) (xy 121.809014 -246.10441)
			(xy 121.480072 -246.10441) (xy 121.479577 -246.129017) (xy 121.471682 -246.177594) (xy 121.456098 -246.224275)
			(xy 121.433227 -246.267852) (xy 121.403662 -246.307196) (xy 121.368169 -246.341288) (xy 121.327666 -246.369244)
			(xy 121.283204 -246.390342) (xy 121.235933 -246.404034) (xy 121.187078 -246.409966) (xy 121.137903 -246.407985)
			(xy 121.089684 -246.398141) (xy 121.043668 -246.380689) (xy 121.001047 -246.356082) (xy 120.962926 -246.324957)
			(xy 120.930291 -246.28812) (xy 120.903988 -246.246524) (xy 120.884697 -246.201248) (xy 120.87292 -246.153464)
			(xy 120.86896 -246.10441) (xy 120.540018 -246.10441) (xy 120.539523 -246.129017) (xy 120.531628 -246.177594)
			(xy 120.516044 -246.224275) (xy 120.493173 -246.267852) (xy 120.463608 -246.307196) (xy 120.428115 -246.341288)
			(xy 120.387612 -246.369244) (xy 120.34315 -246.390342) (xy 120.295879 -246.404034) (xy 120.247024 -246.409966)
			(xy 120.197849 -246.407985) (xy 120.14963 -246.398141) (xy 120.103614 -246.380689) (xy 120.060993 -246.356082)
			(xy 120.022872 -246.324957) (xy 119.990237 -246.28812) (xy 119.963934 -246.246524) (xy 119.944643 -246.201248)
			(xy 119.932866 -246.153464) (xy 119.928906 -246.10441) (xy 119.599964 -246.10441) (xy 119.599469 -246.129017)
			(xy 119.591574 -246.177594) (xy 119.57599 -246.224275) (xy 119.553119 -246.267852) (xy 119.523554 -246.307196)
			(xy 119.488061 -246.341288) (xy 119.447558 -246.369244) (xy 119.403096 -246.390342) (xy 119.355825 -246.404034)
			(xy 119.30697 -246.409966) (xy 119.257795 -246.407985) (xy 119.209576 -246.398141) (xy 119.16356 -246.380689)
			(xy 119.120939 -246.356082) (xy 119.082818 -246.324957) (xy 119.050183 -246.28812) (xy 119.02388 -246.246524)
			(xy 119.004589 -246.201248) (xy 118.992812 -246.153464) (xy 118.988852 -246.10441) (xy 118.660164 -246.10441)
			(xy 118.659669 -246.129017) (xy 118.651774 -246.177594) (xy 118.63619 -246.224275) (xy 118.613319 -246.267852)
			(xy 118.583754 -246.307196) (xy 118.548261 -246.341288) (xy 118.507758 -246.369244) (xy 118.463296 -246.390342)
			(xy 118.416025 -246.404034) (xy 118.36717 -246.409966) (xy 118.317995 -246.407985) (xy 118.269776 -246.398141)
			(xy 118.22376 -246.380689) (xy 118.181139 -246.356082) (xy 118.143018 -246.324957) (xy 118.110383 -246.28812)
			(xy 118.08408 -246.246524) (xy 118.064789 -246.201248) (xy 118.053012 -246.153464) (xy 118.049052 -246.10441)
			(xy 117.72011 -246.10441) (xy 117.719615 -246.129017) (xy 117.71172 -246.177594) (xy 117.696136 -246.224275)
			(xy 117.673265 -246.267852) (xy 117.6437 -246.307196) (xy 117.608207 -246.341288) (xy 117.567704 -246.369244)
			(xy 117.523242 -246.390342) (xy 117.475971 -246.404034) (xy 117.427116 -246.409966) (xy 117.377941 -246.407985)
			(xy 117.329722 -246.398141) (xy 117.283706 -246.380689) (xy 117.241085 -246.356082) (xy 117.202964 -246.324957)
			(xy 117.170329 -246.28812) (xy 117.144026 -246.246524) (xy 117.124735 -246.201248) (xy 117.112958 -246.153464)
			(xy 117.108998 -246.10441) (xy 116.780056 -246.10441) (xy 116.779561 -246.129017) (xy 116.771666 -246.177594)
			(xy 116.756082 -246.224275) (xy 116.733211 -246.267852) (xy 116.703646 -246.307196) (xy 116.668153 -246.341288)
			(xy 116.62765 -246.369244) (xy 116.583188 -246.390342) (xy 116.535917 -246.404034) (xy 116.487062 -246.409966)
			(xy 116.437887 -246.407985) (xy 116.389668 -246.398141) (xy 116.343652 -246.380689) (xy 116.301031 -246.356082)
			(xy 116.26291 -246.324957) (xy 116.230275 -246.28812) (xy 116.203972 -246.246524) (xy 116.184681 -246.201248)
			(xy 116.172904 -246.153464) (xy 116.168944 -246.10441) (xy 115.840002 -246.10441) (xy 115.839507 -246.129017)
			(xy 115.831612 -246.177594) (xy 115.816028 -246.224275) (xy 115.793157 -246.267852) (xy 115.763592 -246.307196)
			(xy 115.728099 -246.341288) (xy 115.687596 -246.369244) (xy 115.643134 -246.390342) (xy 115.595863 -246.404034)
			(xy 115.547008 -246.409966) (xy 115.497833 -246.407985) (xy 115.449614 -246.398141) (xy 115.403598 -246.380689)
			(xy 115.360977 -246.356082) (xy 115.322856 -246.324957) (xy 115.290221 -246.28812) (xy 115.263918 -246.246524)
			(xy 115.244627 -246.201248) (xy 115.23285 -246.153464) (xy 115.22889 -246.10441) (xy 108.326428 -246.10441)
			(xy 108.325933 -246.129017) (xy 108.318038 -246.177594) (xy 108.302454 -246.224275) (xy 108.279583 -246.267852)
			(xy 108.250018 -246.307196) (xy 108.214525 -246.341288) (xy 108.174022 -246.369244) (xy 108.12956 -246.390342)
			(xy 108.082289 -246.404034) (xy 108.033434 -246.409966) (xy 107.984259 -246.407985) (xy 107.93604 -246.398141)
			(xy 107.890024 -246.380689) (xy 107.847403 -246.356082) (xy 107.809282 -246.324957) (xy 107.776647 -246.28812)
			(xy 107.750344 -246.246524) (xy 107.731053 -246.201248) (xy 107.719276 -246.153464) (xy 107.715316 -246.10441)
			(xy 107.396788 -246.10441) (xy 107.396276 -246.129856) (xy 107.388112 -246.18009) (xy 107.371996 -246.228364)
			(xy 107.348345 -246.273427) (xy 107.317772 -246.314113) (xy 107.281068 -246.349368) (xy 107.239184 -246.378278)
			(xy 107.193205 -246.400095) (xy 107.144321 -246.414255) (xy 107.0938 -246.420389) (xy 107.042948 -246.41834)
			(xy 106.993084 -246.40816) (xy 106.945498 -246.390113) (xy 106.901424 -246.364667) (xy 106.862002 -246.33248)
			(xy 106.828254 -246.294386) (xy 106.801053 -246.251372) (xy 106.781105 -246.204552) (xy 106.768926 -246.155138)
			(xy 106.764831 -246.10441) (xy 106.456734 -246.10441) (xy 106.456222 -246.129856) (xy 106.448058 -246.18009)
			(xy 106.431942 -246.228364) (xy 106.408291 -246.273427) (xy 106.377718 -246.314113) (xy 106.341014 -246.349368)
			(xy 106.29913 -246.378278) (xy 106.253151 -246.400095) (xy 106.204267 -246.414255) (xy 106.153746 -246.420389)
			(xy 106.102894 -246.41834) (xy 106.05303 -246.40816) (xy 106.005444 -246.390113) (xy 105.96137 -246.364667)
			(xy 105.921948 -246.33248) (xy 105.8882 -246.294386) (xy 105.860999 -246.251372) (xy 105.841051 -246.204552)
			(xy 105.828872 -246.155138) (xy 105.824777 -246.10441) (xy 105.506266 -246.10441) (xy 105.505771 -246.129017)
			(xy 105.497876 -246.177594) (xy 105.482292 -246.224275) (xy 105.459421 -246.267852) (xy 105.429856 -246.307196)
			(xy 105.394363 -246.341288) (xy 105.35386 -246.369244) (xy 105.309398 -246.390342) (xy 105.262127 -246.404034)
			(xy 105.213272 -246.409966) (xy 105.164097 -246.407985) (xy 105.115878 -246.398141) (xy 105.069862 -246.380689)
			(xy 105.027241 -246.356082) (xy 104.98912 -246.324957) (xy 104.956485 -246.28812) (xy 104.930182 -246.246524)
			(xy 104.910891 -246.201248) (xy 104.899114 -246.153464) (xy 104.895154 -246.10441) (xy 104.57688 -246.10441)
			(xy 104.576368 -246.129856) (xy 104.568204 -246.18009) (xy 104.552088 -246.228364) (xy 104.528437 -246.273427)
			(xy 104.497864 -246.314113) (xy 104.46116 -246.349368) (xy 104.419276 -246.378278) (xy 104.373297 -246.400095)
			(xy 104.324413 -246.414255) (xy 104.273892 -246.420389) (xy 104.22304 -246.41834) (xy 104.173176 -246.40816)
			(xy 104.12559 -246.390113) (xy 104.081516 -246.364667) (xy 104.042094 -246.33248) (xy 104.008346 -246.294386)
			(xy 103.981145 -246.251372) (xy 103.961197 -246.204552) (xy 103.949018 -246.155138) (xy 103.944923 -246.10441)
			(xy 103.636826 -246.10441) (xy 103.636314 -246.129856) (xy 103.62815 -246.18009) (xy 103.612034 -246.228364)
			(xy 103.588383 -246.273427) (xy 103.55781 -246.314113) (xy 103.521106 -246.349368) (xy 103.479222 -246.378278)
			(xy 103.433243 -246.400095) (xy 103.384359 -246.414255) (xy 103.333838 -246.420389) (xy 103.282986 -246.41834)
			(xy 103.233122 -246.40816) (xy 103.185536 -246.390113) (xy 103.141462 -246.364667) (xy 103.10204 -246.33248)
			(xy 103.068292 -246.294386) (xy 103.041091 -246.251372) (xy 103.021143 -246.204552) (xy 103.008964 -246.155138)
			(xy 103.004869 -246.10441) (xy 102.686358 -246.10441) (xy 102.685863 -246.129017) (xy 102.677968 -246.177594)
			(xy 102.662384 -246.224275) (xy 102.639513 -246.267852) (xy 102.609948 -246.307196) (xy 102.574455 -246.341288)
			(xy 102.533952 -246.369244) (xy 102.48949 -246.390342) (xy 102.442219 -246.404034) (xy 102.393364 -246.409966)
			(xy 102.344189 -246.407985) (xy 102.29597 -246.398141) (xy 102.249954 -246.380689) (xy 102.207333 -246.356082)
			(xy 102.169212 -246.324957) (xy 102.136577 -246.28812) (xy 102.110274 -246.246524) (xy 102.090983 -246.201248)
			(xy 102.079206 -246.153464) (xy 102.075246 -246.10441) (xy 101.756718 -246.10441) (xy 101.756206 -246.129856)
			(xy 101.748042 -246.18009) (xy 101.731926 -246.228364) (xy 101.708275 -246.273427) (xy 101.677702 -246.314113)
			(xy 101.640998 -246.349368) (xy 101.599114 -246.378278) (xy 101.553135 -246.400095) (xy 101.504251 -246.414255)
			(xy 101.45373 -246.420389) (xy 101.402878 -246.41834) (xy 101.353014 -246.40816) (xy 101.305428 -246.390113)
			(xy 101.261354 -246.364667) (xy 101.221932 -246.33248) (xy 101.188184 -246.294386) (xy 101.160983 -246.251372)
			(xy 101.141035 -246.204552) (xy 101.128856 -246.155138) (xy 101.124761 -246.10441) (xy 100.816664 -246.10441)
			(xy 100.816152 -246.129856) (xy 100.807988 -246.18009) (xy 100.791872 -246.228364) (xy 100.768221 -246.273427)
			(xy 100.737648 -246.314113) (xy 100.700944 -246.349368) (xy 100.65906 -246.378278) (xy 100.613081 -246.400095)
			(xy 100.564197 -246.414255) (xy 100.513676 -246.420389) (xy 100.462824 -246.41834) (xy 100.41296 -246.40816)
			(xy 100.365374 -246.390113) (xy 100.3213 -246.364667) (xy 100.281878 -246.33248) (xy 100.24813 -246.294386)
			(xy 100.220929 -246.251372) (xy 100.200981 -246.204552) (xy 100.188802 -246.155138) (xy 100.184707 -246.10441)
			(xy 99.86645 -246.10441) (xy 99.865955 -246.129017) (xy 99.85806 -246.177594) (xy 99.842476 -246.224275)
			(xy 99.819605 -246.267852) (xy 99.79004 -246.307196) (xy 99.754547 -246.341288) (xy 99.714044 -246.369244)
			(xy 99.669582 -246.390342) (xy 99.622311 -246.404034) (xy 99.573456 -246.409966) (xy 99.524281 -246.407985)
			(xy 99.476062 -246.398141) (xy 99.430046 -246.380689) (xy 99.387425 -246.356082) (xy 99.349304 -246.324957)
			(xy 99.316669 -246.28812) (xy 99.290366 -246.246524) (xy 99.271075 -246.201248) (xy 99.259298 -246.153464)
			(xy 99.255338 -246.10441) (xy 98.93681 -246.10441) (xy 98.936298 -246.129856) (xy 98.928134 -246.18009)
			(xy 98.912018 -246.228364) (xy 98.888367 -246.273427) (xy 98.857794 -246.314113) (xy 98.82109 -246.349368)
			(xy 98.779206 -246.378278) (xy 98.733227 -246.400095) (xy 98.684343 -246.414255) (xy 98.633822 -246.420389)
			(xy 98.58297 -246.41834) (xy 98.533106 -246.40816) (xy 98.48552 -246.390113) (xy 98.441446 -246.364667)
			(xy 98.402024 -246.33248) (xy 98.368276 -246.294386) (xy 98.341075 -246.251372) (xy 98.321127 -246.204552)
			(xy 98.308948 -246.155138) (xy 98.304853 -246.10441) (xy 97.996756 -246.10441) (xy 97.996244 -246.129856)
			(xy 97.98808 -246.18009) (xy 97.971964 -246.228364) (xy 97.948313 -246.273427) (xy 97.91774 -246.314113)
			(xy 97.881036 -246.349368) (xy 97.839152 -246.378278) (xy 97.793173 -246.400095) (xy 97.744289 -246.414255)
			(xy 97.693768 -246.420389) (xy 97.642916 -246.41834) (xy 97.593052 -246.40816) (xy 97.545466 -246.390113)
			(xy 97.501392 -246.364667) (xy 97.46197 -246.33248) (xy 97.428222 -246.294386) (xy 97.401021 -246.251372)
			(xy 97.381073 -246.204552) (xy 97.368894 -246.155138) (xy 97.364799 -246.10441) (xy 97.046288 -246.10441)
			(xy 97.045793 -246.129017) (xy 97.037898 -246.177594) (xy 97.022314 -246.224275) (xy 96.999443 -246.267852)
			(xy 96.969878 -246.307196) (xy 96.934385 -246.341288) (xy 96.893882 -246.369244) (xy 96.84942 -246.390342)
			(xy 96.802149 -246.404034) (xy 96.753294 -246.409966) (xy 96.704119 -246.407985) (xy 96.6559 -246.398141)
			(xy 96.609884 -246.380689) (xy 96.567263 -246.356082) (xy 96.529142 -246.324957) (xy 96.496507 -246.28812)
			(xy 96.470204 -246.246524) (xy 96.450913 -246.201248) (xy 96.439136 -246.153464) (xy 96.435176 -246.10441)
			(xy 96.116648 -246.10441) (xy 96.116136 -246.129856) (xy 96.107972 -246.18009) (xy 96.091856 -246.228364)
			(xy 96.068205 -246.273427) (xy 96.037632 -246.314113) (xy 96.000928 -246.349368) (xy 95.959044 -246.378278)
			(xy 95.913065 -246.400095) (xy 95.864181 -246.414255) (xy 95.81366 -246.420389) (xy 95.762808 -246.41834)
			(xy 95.712944 -246.40816) (xy 95.665358 -246.390113) (xy 95.621284 -246.364667) (xy 95.581862 -246.33248)
			(xy 95.548114 -246.294386) (xy 95.520913 -246.251372) (xy 95.500965 -246.204552) (xy 95.488786 -246.155138)
			(xy 95.484691 -246.10441) (xy 95.166434 -246.10441) (xy 95.165939 -246.129017) (xy 95.158044 -246.177594)
			(xy 95.14246 -246.224275) (xy 95.119589 -246.267852) (xy 95.090024 -246.307196) (xy 95.054531 -246.341288)
			(xy 95.014028 -246.369244) (xy 94.969566 -246.390342) (xy 94.922295 -246.404034) (xy 94.87344 -246.409966)
			(xy 94.824265 -246.407985) (xy 94.776046 -246.398141) (xy 94.73003 -246.380689) (xy 94.687409 -246.356082)
			(xy 94.649288 -246.324957) (xy 94.616653 -246.28812) (xy 94.59035 -246.246524) (xy 94.571059 -246.201248)
			(xy 94.559282 -246.153464) (xy 94.555322 -246.10441) (xy 94.236794 -246.10441) (xy 94.236282 -246.129856)
			(xy 94.228118 -246.18009) (xy 94.212002 -246.228364) (xy 94.188351 -246.273427) (xy 94.157778 -246.314113)
			(xy 94.121074 -246.349368) (xy 94.07919 -246.378278) (xy 94.033211 -246.400095) (xy 93.984327 -246.414255)
			(xy 93.933806 -246.420389) (xy 93.882954 -246.41834) (xy 93.83309 -246.40816) (xy 93.785504 -246.390113)
			(xy 93.74143 -246.364667) (xy 93.702008 -246.33248) (xy 93.66826 -246.294386) (xy 93.641059 -246.251372)
			(xy 93.621111 -246.204552) (xy 93.608932 -246.155138) (xy 93.604837 -246.10441) (xy 93.286326 -246.10441)
			(xy 93.285831 -246.129017) (xy 93.277936 -246.177594) (xy 93.262352 -246.224275) (xy 93.239481 -246.267852)
			(xy 93.209916 -246.307196) (xy 93.174423 -246.341288) (xy 93.13392 -246.369244) (xy 93.089458 -246.390342)
			(xy 93.042187 -246.404034) (xy 92.993332 -246.409966) (xy 92.944157 -246.407985) (xy 92.895938 -246.398141)
			(xy 92.849922 -246.380689) (xy 92.807301 -246.356082) (xy 92.76918 -246.324957) (xy 92.736545 -246.28812)
			(xy 92.710242 -246.246524) (xy 92.690951 -246.201248) (xy 92.679174 -246.153464) (xy 92.675214 -246.10441)
			(xy 92.356432 -246.10441) (xy 92.355937 -246.12988) (xy 92.347739 -246.180156) (xy 92.331573 -246.228462)
			(xy 92.30786 -246.273546) (xy 92.277215 -246.314237) (xy 92.240433 -246.349478) (xy 92.198469 -246.378355)
			(xy 92.152412 -246.400118) (xy 92.128086 -246.407686) (xy 92.115132 -246.411496) (xy 92.096336 -246.4308)
			(xy 92.073222 -246.521478) (xy 92.070928 -246.532972) (xy 92.075831 -246.555865) (xy 92.08262 -246.56542)
			(xy 92.084398 -246.567706) (xy 92.201492 -246.6848) (xy 92.20454 -246.687594) (xy 92.204794 -246.687848)
			(xy 92.211956 -246.693403) (xy 92.229008 -246.699508) (xy 92.238068 -246.699786) (xy 92.269056 -246.699532)
			(xy 92.286582 -246.69242) (xy 92.293694 -246.685562) (xy 92.311403 -246.669372) (xy 92.350805 -246.641994)
			(xy 92.3939 -246.6209) (xy 92.439693 -246.606578) (xy 92.487127 -246.599358) (xy 92.511118 -246.598948)
			(xy 92.535915 -246.599435) (xy 92.584898 -246.607191) (xy 92.632067 -246.62251) (xy 92.67626 -246.645015)
			(xy 92.716392 -246.674153) (xy 92.751474 -246.709206) (xy 92.780646 -246.749313) (xy 92.803188 -246.793487)
			(xy 92.818546 -246.840643) (xy 92.826344 -246.88962) (xy 92.82684 -246.914416) (xy 93.145114 -246.914416)
			(xy 93.149074 -246.865362) (xy 93.160851 -246.817578) (xy 93.180142 -246.772302) (xy 93.206445 -246.730706)
			(xy 93.23908 -246.693869) (xy 93.277201 -246.662744) (xy 93.319822 -246.638137) (xy 93.365838 -246.620685)
			(xy 93.414057 -246.610841) (xy 93.463232 -246.60886) (xy 93.512087 -246.614792) (xy 93.559358 -246.628484)
			(xy 93.60382 -246.649582) (xy 93.644323 -246.677538) (xy 93.679816 -246.71163) (xy 93.709381 -246.750974)
			(xy 93.732252 -246.794551) (xy 93.747836 -246.841232) (xy 93.755731 -246.889809) (xy 93.756226 -246.914416)
			(xy 94.074737 -246.914416) (xy 94.078832 -246.863688) (xy 94.091011 -246.814274) (xy 94.110959 -246.767454)
			(xy 94.13816 -246.72444) (xy 94.171908 -246.686346) (xy 94.21133 -246.654159) (xy 94.255404 -246.628713)
			(xy 94.30299 -246.610666) (xy 94.352854 -246.600486) (xy 94.403706 -246.598437) (xy 94.454227 -246.604571)
			(xy 94.503111 -246.618731) (xy 94.54909 -246.640548) (xy 94.590974 -246.669458) (xy 94.627678 -246.704713)
			(xy 94.658251 -246.745399) (xy 94.681902 -246.790462) (xy 94.698018 -246.838736) (xy 94.706182 -246.88897)
			(xy 94.706694 -246.914416) (xy 95.014791 -246.914416) (xy 95.018886 -246.863688) (xy 95.031065 -246.814274)
			(xy 95.051013 -246.767454) (xy 95.078214 -246.72444) (xy 95.111962 -246.686346) (xy 95.151384 -246.654159)
			(xy 95.195458 -246.628713) (xy 95.243044 -246.610666) (xy 95.292908 -246.600486) (xy 95.34376 -246.598437)
			(xy 95.394281 -246.604571) (xy 95.443165 -246.618731) (xy 95.489144 -246.640548) (xy 95.531028 -246.669458)
			(xy 95.567732 -246.704713) (xy 95.598305 -246.745399) (xy 95.621956 -246.790462) (xy 95.638072 -246.838736)
			(xy 95.646236 -246.88897) (xy 95.646748 -246.914416) (xy 95.965276 -246.914416) (xy 95.969236 -246.865362)
			(xy 95.981013 -246.817578) (xy 96.000304 -246.772302) (xy 96.026607 -246.730706) (xy 96.059242 -246.693869)
			(xy 96.097363 -246.662744) (xy 96.139984 -246.638137) (xy 96.186 -246.620685) (xy 96.234219 -246.610841)
			(xy 96.283394 -246.60886) (xy 96.332249 -246.614792) (xy 96.37952 -246.628484) (xy 96.423982 -246.649582)
			(xy 96.464485 -246.677538) (xy 96.499978 -246.71163) (xy 96.529543 -246.750974) (xy 96.552414 -246.794551)
			(xy 96.567998 -246.841232) (xy 96.575893 -246.889809) (xy 96.576388 -246.914416) (xy 96.90533 -246.914416)
			(xy 96.90929 -246.865362) (xy 96.921067 -246.817578) (xy 96.940358 -246.772302) (xy 96.966661 -246.730706)
			(xy 96.999296 -246.693869) (xy 97.037417 -246.662744) (xy 97.080038 -246.638137) (xy 97.126054 -246.620685)
			(xy 97.174273 -246.610841) (xy 97.223448 -246.60886) (xy 97.272303 -246.614792) (xy 97.319574 -246.628484)
			(xy 97.364036 -246.649582) (xy 97.404539 -246.677538) (xy 97.440032 -246.71163) (xy 97.469597 -246.750974)
			(xy 97.492468 -246.794551) (xy 97.508052 -246.841232) (xy 97.515947 -246.889809) (xy 97.516442 -246.914416)
			(xy 97.84513 -246.914416) (xy 97.84909 -246.865362) (xy 97.860867 -246.817578) (xy 97.880158 -246.772302)
			(xy 97.906461 -246.730706) (xy 97.939096 -246.693869) (xy 97.977217 -246.662744) (xy 98.019838 -246.638137)
			(xy 98.065854 -246.620685) (xy 98.114073 -246.610841) (xy 98.163248 -246.60886) (xy 98.212103 -246.614792)
			(xy 98.259374 -246.628484) (xy 98.303836 -246.649582) (xy 98.344339 -246.677538) (xy 98.379832 -246.71163)
			(xy 98.409397 -246.750974) (xy 98.432268 -246.794551) (xy 98.447852 -246.841232) (xy 98.455747 -246.889809)
			(xy 98.456242 -246.914416) (xy 98.785184 -246.914416) (xy 98.789144 -246.865362) (xy 98.800921 -246.817578)
			(xy 98.820212 -246.772302) (xy 98.846515 -246.730706) (xy 98.87915 -246.693869) (xy 98.917271 -246.662744)
			(xy 98.959892 -246.638137) (xy 99.005908 -246.620685) (xy 99.054127 -246.610841) (xy 99.103302 -246.60886)
			(xy 99.152157 -246.614792) (xy 99.199428 -246.628484) (xy 99.24389 -246.649582) (xy 99.284393 -246.677538)
			(xy 99.319886 -246.71163) (xy 99.349451 -246.750974) (xy 99.372322 -246.794551) (xy 99.387906 -246.841232)
			(xy 99.395801 -246.889809) (xy 99.396296 -246.914416) (xy 99.725238 -246.914416) (xy 99.729198 -246.865362)
			(xy 99.740975 -246.817578) (xy 99.760266 -246.772302) (xy 99.786569 -246.730706) (xy 99.819204 -246.693869)
			(xy 99.857325 -246.662744) (xy 99.899946 -246.638137) (xy 99.945962 -246.620685) (xy 99.994181 -246.610841)
			(xy 100.043356 -246.60886) (xy 100.092211 -246.614792) (xy 100.139482 -246.628484) (xy 100.183944 -246.649582)
			(xy 100.224447 -246.677538) (xy 100.25994 -246.71163) (xy 100.289505 -246.750974) (xy 100.312376 -246.794551)
			(xy 100.32796 -246.841232) (xy 100.335855 -246.889809) (xy 100.33635 -246.914416) (xy 100.665292 -246.914416)
			(xy 100.669252 -246.865362) (xy 100.681029 -246.817578) (xy 100.70032 -246.772302) (xy 100.726623 -246.730706)
			(xy 100.759258 -246.693869) (xy 100.797379 -246.662744) (xy 100.84 -246.638137) (xy 100.886016 -246.620685)
			(xy 100.934235 -246.610841) (xy 100.98341 -246.60886) (xy 101.032265 -246.614792) (xy 101.079536 -246.628484)
			(xy 101.123998 -246.649582) (xy 101.164501 -246.677538) (xy 101.199994 -246.71163) (xy 101.229559 -246.750974)
			(xy 101.25243 -246.794551) (xy 101.268014 -246.841232) (xy 101.275909 -246.889809) (xy 101.276404 -246.914416)
			(xy 101.605346 -246.914416) (xy 101.609306 -246.865362) (xy 101.621083 -246.817578) (xy 101.640374 -246.772302)
			(xy 101.666677 -246.730706) (xy 101.699312 -246.693869) (xy 101.737433 -246.662744) (xy 101.780054 -246.638137)
			(xy 101.82607 -246.620685) (xy 101.874289 -246.610841) (xy 101.923464 -246.60886) (xy 101.972319 -246.614792)
			(xy 102.01959 -246.628484) (xy 102.064052 -246.649582) (xy 102.104555 -246.677538) (xy 102.140048 -246.71163)
			(xy 102.169613 -246.750974) (xy 102.192484 -246.794551) (xy 102.208068 -246.841232) (xy 102.215963 -246.889809)
			(xy 102.216458 -246.914416) (xy 102.545146 -246.914416) (xy 102.549106 -246.865362) (xy 102.560883 -246.817578)
			(xy 102.580174 -246.772302) (xy 102.606477 -246.730706) (xy 102.639112 -246.693869) (xy 102.677233 -246.662744)
			(xy 102.719854 -246.638137) (xy 102.76587 -246.620685) (xy 102.814089 -246.610841) (xy 102.863264 -246.60886)
			(xy 102.912119 -246.614792) (xy 102.95939 -246.628484) (xy 103.003852 -246.649582) (xy 103.044355 -246.677538)
			(xy 103.079848 -246.71163) (xy 103.109413 -246.750974) (xy 103.132284 -246.794551) (xy 103.147868 -246.841232)
			(xy 103.155763 -246.889809) (xy 103.156258 -246.914416) (xy 103.4852 -246.914416) (xy 103.48916 -246.865362)
			(xy 103.500937 -246.817578) (xy 103.520228 -246.772302) (xy 103.546531 -246.730706) (xy 103.579166 -246.693869)
			(xy 103.617287 -246.662744) (xy 103.659908 -246.638137) (xy 103.705924 -246.620685) (xy 103.754143 -246.610841)
			(xy 103.803318 -246.60886) (xy 103.852173 -246.614792) (xy 103.899444 -246.628484) (xy 103.943906 -246.649582)
			(xy 103.984409 -246.677538) (xy 104.019902 -246.71163) (xy 104.049467 -246.750974) (xy 104.072338 -246.794551)
			(xy 104.087922 -246.841232) (xy 104.095817 -246.889809) (xy 104.096312 -246.914416) (xy 104.425254 -246.914416)
			(xy 104.429214 -246.865362) (xy 104.440991 -246.817578) (xy 104.460282 -246.772302) (xy 104.486585 -246.730706)
			(xy 104.51922 -246.693869) (xy 104.557341 -246.662744) (xy 104.599962 -246.638137) (xy 104.645978 -246.620685)
			(xy 104.694197 -246.610841) (xy 104.743372 -246.60886) (xy 104.792227 -246.614792) (xy 104.839498 -246.628484)
			(xy 104.88396 -246.649582) (xy 104.924463 -246.677538) (xy 104.959956 -246.71163) (xy 104.989521 -246.750974)
			(xy 105.012392 -246.794551) (xy 105.027976 -246.841232) (xy 105.035871 -246.889809) (xy 105.036366 -246.914416)
			(xy 105.365308 -246.914416) (xy 105.369268 -246.865362) (xy 105.381045 -246.817578) (xy 105.400336 -246.772302)
			(xy 105.426639 -246.730706) (xy 105.459274 -246.693869) (xy 105.497395 -246.662744) (xy 105.540016 -246.638137)
			(xy 105.586032 -246.620685) (xy 105.634251 -246.610841) (xy 105.683426 -246.60886) (xy 105.732281 -246.614792)
			(xy 105.779552 -246.628484) (xy 105.824014 -246.649582) (xy 105.864517 -246.677538) (xy 105.90001 -246.71163)
			(xy 105.929575 -246.750974) (xy 105.952446 -246.794551) (xy 105.96803 -246.841232) (xy 105.975925 -246.889809)
			(xy 105.97642 -246.914416) (xy 106.305362 -246.914416) (xy 106.309322 -246.865362) (xy 106.321099 -246.817578)
			(xy 106.34039 -246.772302) (xy 106.366693 -246.730706) (xy 106.399328 -246.693869) (xy 106.437449 -246.662744)
			(xy 106.48007 -246.638137) (xy 106.526086 -246.620685) (xy 106.574305 -246.610841) (xy 106.62348 -246.60886)
			(xy 106.672335 -246.614792) (xy 106.719606 -246.628484) (xy 106.764068 -246.649582) (xy 106.804571 -246.677538)
			(xy 106.840064 -246.71163) (xy 106.869629 -246.750974) (xy 106.8925 -246.794551) (xy 106.908084 -246.841232)
			(xy 106.915979 -246.889809) (xy 106.916474 -246.914416) (xy 107.245162 -246.914416) (xy 107.249122 -246.865362)
			(xy 107.260899 -246.817578) (xy 107.28019 -246.772302) (xy 107.306493 -246.730706) (xy 107.339128 -246.693869)
			(xy 107.377249 -246.662744) (xy 107.41987 -246.638137) (xy 107.465886 -246.620685) (xy 107.514105 -246.610841)
			(xy 107.56328 -246.60886) (xy 107.612135 -246.614792) (xy 107.659406 -246.628484) (xy 107.703868 -246.649582)
			(xy 107.744371 -246.677538) (xy 107.779864 -246.71163) (xy 107.809429 -246.750974) (xy 107.8323 -246.794551)
			(xy 107.847884 -246.841232) (xy 107.855779 -246.889809) (xy 107.856274 -246.914416) (xy 108.174785 -246.914416)
			(xy 108.17888 -246.863688) (xy 108.191059 -246.814274) (xy 108.211007 -246.767454) (xy 108.238208 -246.72444)
			(xy 108.271956 -246.686346) (xy 108.311378 -246.654159) (xy 108.355452 -246.628713) (xy 108.403038 -246.610666)
			(xy 108.452902 -246.600486) (xy 108.503754 -246.598437) (xy 108.554275 -246.604571) (xy 108.603159 -246.618731)
			(xy 108.649138 -246.640548) (xy 108.691022 -246.669458) (xy 108.727726 -246.704713) (xy 108.758299 -246.745399)
			(xy 108.78195 -246.790462) (xy 108.798066 -246.838736) (xy 108.80623 -246.88897) (xy 108.806742 -246.914416)
			(xy 109.114839 -246.914416) (xy 109.118934 -246.863688) (xy 109.131113 -246.814274) (xy 109.151061 -246.767454)
			(xy 109.178262 -246.72444) (xy 109.21201 -246.686346) (xy 109.251432 -246.654159) (xy 109.295506 -246.628713)
			(xy 109.343092 -246.610666) (xy 109.392956 -246.600486) (xy 109.443808 -246.598437) (xy 109.494329 -246.604571)
			(xy 109.543213 -246.618731) (xy 109.589192 -246.640548) (xy 109.631076 -246.669458) (xy 109.66778 -246.704713)
			(xy 109.698353 -246.745399) (xy 109.722004 -246.790462) (xy 109.73812 -246.838736) (xy 109.746284 -246.88897)
			(xy 109.746796 -246.914416) (xy 110.065324 -246.914416) (xy 110.069284 -246.865362) (xy 110.081061 -246.817578)
			(xy 110.100352 -246.772302) (xy 110.126655 -246.730706) (xy 110.15929 -246.693869) (xy 110.197411 -246.662744)
			(xy 110.240032 -246.638137) (xy 110.286048 -246.620685) (xy 110.334267 -246.610841) (xy 110.383442 -246.60886)
			(xy 110.432297 -246.614792) (xy 110.479568 -246.628484) (xy 110.52403 -246.649582) (xy 110.564533 -246.677538)
			(xy 110.600026 -246.71163) (xy 110.629591 -246.750974) (xy 110.652462 -246.794551) (xy 110.668046 -246.841232)
			(xy 110.675941 -246.889809) (xy 110.676436 -246.914416) (xy 112.878882 -246.914416) (xy 112.882842 -246.865362)
			(xy 112.894619 -246.817578) (xy 112.91391 -246.772302) (xy 112.940213 -246.730706) (xy 112.972848 -246.693869)
			(xy 113.010969 -246.662744) (xy 113.05359 -246.638137) (xy 113.099606 -246.620685) (xy 113.147825 -246.610841)
			(xy 113.197 -246.60886) (xy 113.245855 -246.614792) (xy 113.293126 -246.628484) (xy 113.337588 -246.649582)
			(xy 113.378091 -246.677538) (xy 113.413584 -246.71163) (xy 113.443149 -246.750974) (xy 113.46602 -246.794551)
			(xy 113.481604 -246.841232) (xy 113.489499 -246.889809) (xy 113.489994 -246.914416) (xy 113.818936 -246.914416)
			(xy 113.822896 -246.865362) (xy 113.834673 -246.817578) (xy 113.853964 -246.772302) (xy 113.880267 -246.730706)
			(xy 113.912902 -246.693869) (xy 113.951023 -246.662744) (xy 113.993644 -246.638137) (xy 114.03966 -246.620685)
			(xy 114.087879 -246.610841) (xy 114.137054 -246.60886) (xy 114.185909 -246.614792) (xy 114.23318 -246.628484)
			(xy 114.277642 -246.649582) (xy 114.318145 -246.677538) (xy 114.353638 -246.71163) (xy 114.383203 -246.750974)
			(xy 114.406074 -246.794551) (xy 114.421658 -246.841232) (xy 114.429553 -246.889809) (xy 114.430048 -246.914416)
			(xy 114.75899 -246.914416) (xy 114.76295 -246.865362) (xy 114.774727 -246.817578) (xy 114.794018 -246.772302)
			(xy 114.820321 -246.730706) (xy 114.852956 -246.693869) (xy 114.891077 -246.662744) (xy 114.933698 -246.638137)
			(xy 114.979714 -246.620685) (xy 115.027933 -246.610841) (xy 115.077108 -246.60886) (xy 115.125963 -246.614792)
			(xy 115.173234 -246.628484) (xy 115.217696 -246.649582) (xy 115.258199 -246.677538) (xy 115.293692 -246.71163)
			(xy 115.323257 -246.750974) (xy 115.346128 -246.794551) (xy 115.361712 -246.841232) (xy 115.369607 -246.889809)
			(xy 115.370102 -246.914416) (xy 115.699044 -246.914416) (xy 115.703004 -246.865362) (xy 115.714781 -246.817578)
			(xy 115.734072 -246.772302) (xy 115.760375 -246.730706) (xy 115.79301 -246.693869) (xy 115.831131 -246.662744)
			(xy 115.873752 -246.638137) (xy 115.919768 -246.620685) (xy 115.967987 -246.610841) (xy 116.017162 -246.60886)
			(xy 116.066017 -246.614792) (xy 116.113288 -246.628484) (xy 116.15775 -246.649582) (xy 116.198253 -246.677538)
			(xy 116.233746 -246.71163) (xy 116.263311 -246.750974) (xy 116.286182 -246.794551) (xy 116.301766 -246.841232)
			(xy 116.309661 -246.889809) (xy 116.310156 -246.914416) (xy 116.638844 -246.914416) (xy 116.642804 -246.865362)
			(xy 116.654581 -246.817578) (xy 116.673872 -246.772302) (xy 116.700175 -246.730706) (xy 116.73281 -246.693869)
			(xy 116.770931 -246.662744) (xy 116.813552 -246.638137) (xy 116.859568 -246.620685) (xy 116.907787 -246.610841)
			(xy 116.956962 -246.60886) (xy 117.005817 -246.614792) (xy 117.053088 -246.628484) (xy 117.09755 -246.649582)
			(xy 117.138053 -246.677538) (xy 117.173546 -246.71163) (xy 117.203111 -246.750974) (xy 117.225982 -246.794551)
			(xy 117.241566 -246.841232) (xy 117.249461 -246.889809) (xy 117.249956 -246.914416) (xy 117.578898 -246.914416)
			(xy 117.582858 -246.865362) (xy 117.594635 -246.817578) (xy 117.613926 -246.772302) (xy 117.640229 -246.730706)
			(xy 117.672864 -246.693869) (xy 117.710985 -246.662744) (xy 117.753606 -246.638137) (xy 117.799622 -246.620685)
			(xy 117.847841 -246.610841) (xy 117.897016 -246.60886) (xy 117.945871 -246.614792) (xy 117.993142 -246.628484)
			(xy 118.037604 -246.649582) (xy 118.078107 -246.677538) (xy 118.1136 -246.71163) (xy 118.143165 -246.750974)
			(xy 118.166036 -246.794551) (xy 118.18162 -246.841232) (xy 118.189515 -246.889809) (xy 118.19001 -246.914416)
			(xy 118.518952 -246.914416) (xy 118.522912 -246.865362) (xy 118.534689 -246.817578) (xy 118.55398 -246.772302)
			(xy 118.580283 -246.730706) (xy 118.612918 -246.693869) (xy 118.651039 -246.662744) (xy 118.69366 -246.638137)
			(xy 118.739676 -246.620685) (xy 118.787895 -246.610841) (xy 118.83707 -246.60886) (xy 118.885925 -246.614792)
			(xy 118.933196 -246.628484) (xy 118.977658 -246.649582) (xy 119.018161 -246.677538) (xy 119.053654 -246.71163)
			(xy 119.083219 -246.750974) (xy 119.10609 -246.794551) (xy 119.121674 -246.841232) (xy 119.129569 -246.889809)
			(xy 119.130064 -246.914416) (xy 119.459006 -246.914416) (xy 119.462966 -246.865362) (xy 119.474743 -246.817578)
			(xy 119.494034 -246.772302) (xy 119.520337 -246.730706) (xy 119.552972 -246.693869) (xy 119.591093 -246.662744)
			(xy 119.633714 -246.638137) (xy 119.67973 -246.620685) (xy 119.727949 -246.610841) (xy 119.777124 -246.60886)
			(xy 119.825979 -246.614792) (xy 119.87325 -246.628484) (xy 119.917712 -246.649582) (xy 119.958215 -246.677538)
			(xy 119.993708 -246.71163) (xy 120.023273 -246.750974) (xy 120.046144 -246.794551) (xy 120.061728 -246.841232)
			(xy 120.069623 -246.889809) (xy 120.070118 -246.914416) (xy 120.398806 -246.914416) (xy 120.402766 -246.865362)
			(xy 120.414543 -246.817578) (xy 120.433834 -246.772302) (xy 120.460137 -246.730706) (xy 120.492772 -246.693869)
			(xy 120.530893 -246.662744) (xy 120.573514 -246.638137) (xy 120.61953 -246.620685) (xy 120.667749 -246.610841)
			(xy 120.716924 -246.60886) (xy 120.765779 -246.614792) (xy 120.81305 -246.628484) (xy 120.857512 -246.649582)
			(xy 120.898015 -246.677538) (xy 120.933508 -246.71163) (xy 120.963073 -246.750974) (xy 120.985944 -246.794551)
			(xy 121.001528 -246.841232) (xy 121.009423 -246.889809) (xy 121.009918 -246.914416) (xy 121.33886 -246.914416)
			(xy 121.34282 -246.865362) (xy 121.354597 -246.817578) (xy 121.373888 -246.772302) (xy 121.400191 -246.730706)
			(xy 121.432826 -246.693869) (xy 121.470947 -246.662744) (xy 121.513568 -246.638137) (xy 121.559584 -246.620685)
			(xy 121.607803 -246.610841) (xy 121.656978 -246.60886) (xy 121.705833 -246.614792) (xy 121.753104 -246.628484)
			(xy 121.797566 -246.649582) (xy 121.838069 -246.677538) (xy 121.873562 -246.71163) (xy 121.903127 -246.750974)
			(xy 121.925998 -246.794551) (xy 121.941582 -246.841232) (xy 121.949477 -246.889809) (xy 121.949972 -246.914416)
			(xy 122.278914 -246.914416) (xy 122.282874 -246.865362) (xy 122.294651 -246.817578) (xy 122.313942 -246.772302)
			(xy 122.340245 -246.730706) (xy 122.37288 -246.693869) (xy 122.411001 -246.662744) (xy 122.453622 -246.638137)
			(xy 122.499638 -246.620685) (xy 122.547857 -246.610841) (xy 122.597032 -246.60886) (xy 122.645887 -246.614792)
			(xy 122.693158 -246.628484) (xy 122.73762 -246.649582) (xy 122.778123 -246.677538) (xy 122.813616 -246.71163)
			(xy 122.843181 -246.750974) (xy 122.866052 -246.794551) (xy 122.881636 -246.841232) (xy 122.889531 -246.889809)
			(xy 122.890026 -246.914416) (xy 123.218968 -246.914416) (xy 123.222928 -246.865362) (xy 123.234705 -246.817578)
			(xy 123.253996 -246.772302) (xy 123.280299 -246.730706) (xy 123.312934 -246.693869) (xy 123.351055 -246.662744)
			(xy 123.393676 -246.638137) (xy 123.439692 -246.620685) (xy 123.487911 -246.610841) (xy 123.537086 -246.60886)
			(xy 123.585941 -246.614792) (xy 123.633212 -246.628484) (xy 123.677674 -246.649582) (xy 123.718177 -246.677538)
			(xy 123.75367 -246.71163) (xy 123.783235 -246.750974) (xy 123.806106 -246.794551) (xy 123.82169 -246.841232)
			(xy 123.829585 -246.889809) (xy 123.83008 -246.914416) (xy 124.159022 -246.914416) (xy 124.162982 -246.865362)
			(xy 124.174759 -246.817578) (xy 124.19405 -246.772302) (xy 124.220353 -246.730706) (xy 124.252988 -246.693869)
			(xy 124.291109 -246.662744) (xy 124.33373 -246.638137) (xy 124.379746 -246.620685) (xy 124.427965 -246.610841)
			(xy 124.47714 -246.60886) (xy 124.525995 -246.614792) (xy 124.573266 -246.628484) (xy 124.617728 -246.649582)
			(xy 124.658231 -246.677538) (xy 124.693724 -246.71163) (xy 124.723289 -246.750974) (xy 124.74616 -246.794551)
			(xy 124.761744 -246.841232) (xy 124.769639 -246.889809) (xy 124.770134 -246.914416) (xy 125.098822 -246.914416)
			(xy 125.102782 -246.865362) (xy 125.114559 -246.817578) (xy 125.13385 -246.772302) (xy 125.160153 -246.730706)
			(xy 125.192788 -246.693869) (xy 125.230909 -246.662744) (xy 125.27353 -246.638137) (xy 125.319546 -246.620685)
			(xy 125.367765 -246.610841) (xy 125.41694 -246.60886) (xy 125.465795 -246.614792) (xy 125.513066 -246.628484)
			(xy 125.557528 -246.649582) (xy 125.598031 -246.677538) (xy 125.633524 -246.71163) (xy 125.663089 -246.750974)
			(xy 125.68596 -246.794551) (xy 125.701544 -246.841232) (xy 125.709439 -246.889809) (xy 125.709934 -246.914416)
			(xy 125.709439 -246.939023) (xy 125.701544 -246.9876) (xy 125.68596 -247.034281) (xy 125.663089 -247.077858)
			(xy 125.633524 -247.117202) (xy 125.598031 -247.151294) (xy 125.557528 -247.17925) (xy 125.513066 -247.200348)
			(xy 125.465795 -247.21404) (xy 125.41694 -247.219972) (xy 125.367765 -247.217991) (xy 125.319546 -247.208147)
			(xy 125.27353 -247.190695) (xy 125.230909 -247.166088) (xy 125.192788 -247.134963) (xy 125.160153 -247.098126)
			(xy 125.13385 -247.05653) (xy 125.114559 -247.011254) (xy 125.102782 -246.96347) (xy 125.098822 -246.914416)
			(xy 124.770134 -246.914416) (xy 124.769639 -246.939023) (xy 124.761744 -246.9876) (xy 124.74616 -247.034281)
			(xy 124.723289 -247.077858) (xy 124.693724 -247.117202) (xy 124.658231 -247.151294) (xy 124.617728 -247.17925)
			(xy 124.573266 -247.200348) (xy 124.525995 -247.21404) (xy 124.47714 -247.219972) (xy 124.427965 -247.217991)
			(xy 124.379746 -247.208147) (xy 124.33373 -247.190695) (xy 124.291109 -247.166088) (xy 124.252988 -247.134963)
			(xy 124.220353 -247.098126) (xy 124.19405 -247.05653) (xy 124.174759 -247.011254) (xy 124.162982 -246.96347)
			(xy 124.159022 -246.914416) (xy 123.83008 -246.914416) (xy 123.829585 -246.939023) (xy 123.82169 -246.9876)
			(xy 123.806106 -247.034281) (xy 123.783235 -247.077858) (xy 123.75367 -247.117202) (xy 123.718177 -247.151294)
			(xy 123.677674 -247.17925) (xy 123.633212 -247.200348) (xy 123.585941 -247.21404) (xy 123.537086 -247.219972)
			(xy 123.487911 -247.217991) (xy 123.439692 -247.208147) (xy 123.393676 -247.190695) (xy 123.351055 -247.166088)
			(xy 123.312934 -247.134963) (xy 123.280299 -247.098126) (xy 123.253996 -247.05653) (xy 123.234705 -247.011254)
			(xy 123.222928 -246.96347) (xy 123.218968 -246.914416) (xy 122.890026 -246.914416) (xy 122.889531 -246.939023)
			(xy 122.881636 -246.9876) (xy 122.866052 -247.034281) (xy 122.843181 -247.077858) (xy 122.813616 -247.117202)
			(xy 122.778123 -247.151294) (xy 122.73762 -247.17925) (xy 122.693158 -247.200348) (xy 122.645887 -247.21404)
			(xy 122.597032 -247.219972) (xy 122.547857 -247.217991) (xy 122.499638 -247.208147) (xy 122.453622 -247.190695)
			(xy 122.411001 -247.166088) (xy 122.37288 -247.134963) (xy 122.340245 -247.098126) (xy 122.313942 -247.05653)
			(xy 122.294651 -247.011254) (xy 122.282874 -246.96347) (xy 122.278914 -246.914416) (xy 121.949972 -246.914416)
			(xy 121.949477 -246.939023) (xy 121.941582 -246.9876) (xy 121.925998 -247.034281) (xy 121.903127 -247.077858)
			(xy 121.873562 -247.117202) (xy 121.838069 -247.151294) (xy 121.797566 -247.17925) (xy 121.753104 -247.200348)
			(xy 121.705833 -247.21404) (xy 121.656978 -247.219972) (xy 121.607803 -247.217991) (xy 121.559584 -247.208147)
			(xy 121.513568 -247.190695) (xy 121.470947 -247.166088) (xy 121.432826 -247.134963) (xy 121.400191 -247.098126)
			(xy 121.373888 -247.05653) (xy 121.354597 -247.011254) (xy 121.34282 -246.96347) (xy 121.33886 -246.914416)
			(xy 121.009918 -246.914416) (xy 121.009423 -246.939023) (xy 121.001528 -246.9876) (xy 120.985944 -247.034281)
			(xy 120.963073 -247.077858) (xy 120.933508 -247.117202) (xy 120.898015 -247.151294) (xy 120.857512 -247.17925)
			(xy 120.81305 -247.200348) (xy 120.765779 -247.21404) (xy 120.716924 -247.219972) (xy 120.667749 -247.217991)
			(xy 120.61953 -247.208147) (xy 120.573514 -247.190695) (xy 120.530893 -247.166088) (xy 120.492772 -247.134963)
			(xy 120.460137 -247.098126) (xy 120.433834 -247.05653) (xy 120.414543 -247.011254) (xy 120.402766 -246.96347)
			(xy 120.398806 -246.914416) (xy 120.070118 -246.914416) (xy 120.069623 -246.939023) (xy 120.061728 -246.9876)
			(xy 120.046144 -247.034281) (xy 120.023273 -247.077858) (xy 119.993708 -247.117202) (xy 119.958215 -247.151294)
			(xy 119.917712 -247.17925) (xy 119.87325 -247.200348) (xy 119.825979 -247.21404) (xy 119.777124 -247.219972)
			(xy 119.727949 -247.217991) (xy 119.67973 -247.208147) (xy 119.633714 -247.190695) (xy 119.591093 -247.166088)
			(xy 119.552972 -247.134963) (xy 119.520337 -247.098126) (xy 119.494034 -247.05653) (xy 119.474743 -247.011254)
			(xy 119.462966 -246.96347) (xy 119.459006 -246.914416) (xy 119.130064 -246.914416) (xy 119.129569 -246.939023)
			(xy 119.121674 -246.9876) (xy 119.10609 -247.034281) (xy 119.083219 -247.077858) (xy 119.053654 -247.117202)
			(xy 119.018161 -247.151294) (xy 118.977658 -247.17925) (xy 118.933196 -247.200348) (xy 118.885925 -247.21404)
			(xy 118.83707 -247.219972) (xy 118.787895 -247.217991) (xy 118.739676 -247.208147) (xy 118.69366 -247.190695)
			(xy 118.651039 -247.166088) (xy 118.612918 -247.134963) (xy 118.580283 -247.098126) (xy 118.55398 -247.05653)
			(xy 118.534689 -247.011254) (xy 118.522912 -246.96347) (xy 118.518952 -246.914416) (xy 118.19001 -246.914416)
			(xy 118.189515 -246.939023) (xy 118.18162 -246.9876) (xy 118.166036 -247.034281) (xy 118.143165 -247.077858)
			(xy 118.1136 -247.117202) (xy 118.078107 -247.151294) (xy 118.037604 -247.17925) (xy 117.993142 -247.200348)
			(xy 117.945871 -247.21404) (xy 117.897016 -247.219972) (xy 117.847841 -247.217991) (xy 117.799622 -247.208147)
			(xy 117.753606 -247.190695) (xy 117.710985 -247.166088) (xy 117.672864 -247.134963) (xy 117.640229 -247.098126)
			(xy 117.613926 -247.05653) (xy 117.594635 -247.011254) (xy 117.582858 -246.96347) (xy 117.578898 -246.914416)
			(xy 117.249956 -246.914416) (xy 117.249461 -246.939023) (xy 117.241566 -246.9876) (xy 117.225982 -247.034281)
			(xy 117.203111 -247.077858) (xy 117.173546 -247.117202) (xy 117.138053 -247.151294) (xy 117.09755 -247.17925)
			(xy 117.053088 -247.200348) (xy 117.005817 -247.21404) (xy 116.956962 -247.219972) (xy 116.907787 -247.217991)
			(xy 116.859568 -247.208147) (xy 116.813552 -247.190695) (xy 116.770931 -247.166088) (xy 116.73281 -247.134963)
			(xy 116.700175 -247.098126) (xy 116.673872 -247.05653) (xy 116.654581 -247.011254) (xy 116.642804 -246.96347)
			(xy 116.638844 -246.914416) (xy 116.310156 -246.914416) (xy 116.309661 -246.939023) (xy 116.301766 -246.9876)
			(xy 116.286182 -247.034281) (xy 116.263311 -247.077858) (xy 116.233746 -247.117202) (xy 116.198253 -247.151294)
			(xy 116.15775 -247.17925) (xy 116.113288 -247.200348) (xy 116.066017 -247.21404) (xy 116.017162 -247.219972)
			(xy 115.967987 -247.217991) (xy 115.919768 -247.208147) (xy 115.873752 -247.190695) (xy 115.831131 -247.166088)
			(xy 115.79301 -247.134963) (xy 115.760375 -247.098126) (xy 115.734072 -247.05653) (xy 115.714781 -247.011254)
			(xy 115.703004 -246.96347) (xy 115.699044 -246.914416) (xy 115.370102 -246.914416) (xy 115.369607 -246.939023)
			(xy 115.361712 -246.9876) (xy 115.346128 -247.034281) (xy 115.323257 -247.077858) (xy 115.293692 -247.117202)
			(xy 115.258199 -247.151294) (xy 115.217696 -247.17925) (xy 115.173234 -247.200348) (xy 115.125963 -247.21404)
			(xy 115.077108 -247.219972) (xy 115.027933 -247.217991) (xy 114.979714 -247.208147) (xy 114.933698 -247.190695)
			(xy 114.891077 -247.166088) (xy 114.852956 -247.134963) (xy 114.820321 -247.098126) (xy 114.794018 -247.05653)
			(xy 114.774727 -247.011254) (xy 114.76295 -246.96347) (xy 114.75899 -246.914416) (xy 114.430048 -246.914416)
			(xy 114.429553 -246.939023) (xy 114.421658 -246.9876) (xy 114.406074 -247.034281) (xy 114.383203 -247.077858)
			(xy 114.353638 -247.117202) (xy 114.318145 -247.151294) (xy 114.277642 -247.17925) (xy 114.23318 -247.200348)
			(xy 114.185909 -247.21404) (xy 114.137054 -247.219972) (xy 114.087879 -247.217991) (xy 114.03966 -247.208147)
			(xy 113.993644 -247.190695) (xy 113.951023 -247.166088) (xy 113.912902 -247.134963) (xy 113.880267 -247.098126)
			(xy 113.853964 -247.05653) (xy 113.834673 -247.011254) (xy 113.822896 -246.96347) (xy 113.818936 -246.914416)
			(xy 113.489994 -246.914416) (xy 113.489499 -246.939023) (xy 113.481604 -246.9876) (xy 113.46602 -247.034281)
			(xy 113.443149 -247.077858) (xy 113.413584 -247.117202) (xy 113.378091 -247.151294) (xy 113.337588 -247.17925)
			(xy 113.293126 -247.200348) (xy 113.245855 -247.21404) (xy 113.197 -247.219972) (xy 113.147825 -247.217991)
			(xy 113.099606 -247.208147) (xy 113.05359 -247.190695) (xy 113.010969 -247.166088) (xy 112.972848 -247.134963)
			(xy 112.940213 -247.098126) (xy 112.91391 -247.05653) (xy 112.894619 -247.011254) (xy 112.882842 -246.96347)
			(xy 112.878882 -246.914416) (xy 110.676436 -246.914416) (xy 110.675941 -246.939023) (xy 110.668046 -246.9876)
			(xy 110.652462 -247.034281) (xy 110.629591 -247.077858) (xy 110.600026 -247.117202) (xy 110.564533 -247.151294)
			(xy 110.52403 -247.17925) (xy 110.479568 -247.200348) (xy 110.432297 -247.21404) (xy 110.383442 -247.219972)
			(xy 110.334267 -247.217991) (xy 110.286048 -247.208147) (xy 110.240032 -247.190695) (xy 110.197411 -247.166088)
			(xy 110.15929 -247.134963) (xy 110.126655 -247.098126) (xy 110.100352 -247.05653) (xy 110.081061 -247.011254)
			(xy 110.069284 -246.96347) (xy 110.065324 -246.914416) (xy 109.746796 -246.914416) (xy 109.746284 -246.939862)
			(xy 109.73812 -246.990096) (xy 109.722004 -247.03837) (xy 109.698353 -247.083433) (xy 109.66778 -247.124119)
			(xy 109.631076 -247.159374) (xy 109.589192 -247.188284) (xy 109.543213 -247.210101) (xy 109.494329 -247.224261)
			(xy 109.443808 -247.230395) (xy 109.392956 -247.228346) (xy 109.343092 -247.218166) (xy 109.295506 -247.200119)
			(xy 109.251432 -247.174673) (xy 109.21201 -247.142486) (xy 109.178262 -247.104392) (xy 109.151061 -247.061378)
			(xy 109.131113 -247.014558) (xy 109.118934 -246.965144) (xy 109.114839 -246.914416) (xy 108.806742 -246.914416)
			(xy 108.80623 -246.939862) (xy 108.798066 -246.990096) (xy 108.78195 -247.03837) (xy 108.758299 -247.083433)
			(xy 108.727726 -247.124119) (xy 108.691022 -247.159374) (xy 108.649138 -247.188284) (xy 108.603159 -247.210101)
			(xy 108.554275 -247.224261) (xy 108.503754 -247.230395) (xy 108.452902 -247.228346) (xy 108.403038 -247.218166)
			(xy 108.355452 -247.200119) (xy 108.311378 -247.174673) (xy 108.271956 -247.142486) (xy 108.238208 -247.104392)
			(xy 108.211007 -247.061378) (xy 108.191059 -247.014558) (xy 108.17888 -246.965144) (xy 108.174785 -246.914416)
			(xy 107.856274 -246.914416) (xy 107.855779 -246.939023) (xy 107.847884 -246.9876) (xy 107.8323 -247.034281)
			(xy 107.809429 -247.077858) (xy 107.779864 -247.117202) (xy 107.744371 -247.151294) (xy 107.703868 -247.17925)
			(xy 107.659406 -247.200348) (xy 107.612135 -247.21404) (xy 107.56328 -247.219972) (xy 107.514105 -247.217991)
			(xy 107.465886 -247.208147) (xy 107.41987 -247.190695) (xy 107.377249 -247.166088) (xy 107.339128 -247.134963)
			(xy 107.306493 -247.098126) (xy 107.28019 -247.05653) (xy 107.260899 -247.011254) (xy 107.249122 -246.96347)
			(xy 107.245162 -246.914416) (xy 106.916474 -246.914416) (xy 106.915979 -246.939023) (xy 106.908084 -246.9876)
			(xy 106.8925 -247.034281) (xy 106.869629 -247.077858) (xy 106.840064 -247.117202) (xy 106.804571 -247.151294)
			(xy 106.764068 -247.17925) (xy 106.719606 -247.200348) (xy 106.672335 -247.21404) (xy 106.62348 -247.219972)
			(xy 106.574305 -247.217991) (xy 106.526086 -247.208147) (xy 106.48007 -247.190695) (xy 106.437449 -247.166088)
			(xy 106.399328 -247.134963) (xy 106.366693 -247.098126) (xy 106.34039 -247.05653) (xy 106.321099 -247.011254)
			(xy 106.309322 -246.96347) (xy 106.305362 -246.914416) (xy 105.97642 -246.914416) (xy 105.975925 -246.939023)
			(xy 105.96803 -246.9876) (xy 105.952446 -247.034281) (xy 105.929575 -247.077858) (xy 105.90001 -247.117202)
			(xy 105.864517 -247.151294) (xy 105.824014 -247.17925) (xy 105.779552 -247.200348) (xy 105.732281 -247.21404)
			(xy 105.683426 -247.219972) (xy 105.634251 -247.217991) (xy 105.586032 -247.208147) (xy 105.540016 -247.190695)
			(xy 105.497395 -247.166088) (xy 105.459274 -247.134963) (xy 105.426639 -247.098126) (xy 105.400336 -247.05653)
			(xy 105.381045 -247.011254) (xy 105.369268 -246.96347) (xy 105.365308 -246.914416) (xy 105.036366 -246.914416)
			(xy 105.035871 -246.939023) (xy 105.027976 -246.9876) (xy 105.012392 -247.034281) (xy 104.989521 -247.077858)
			(xy 104.959956 -247.117202) (xy 104.924463 -247.151294) (xy 104.88396 -247.17925) (xy 104.839498 -247.200348)
			(xy 104.792227 -247.21404) (xy 104.743372 -247.219972) (xy 104.694197 -247.217991) (xy 104.645978 -247.208147)
			(xy 104.599962 -247.190695) (xy 104.557341 -247.166088) (xy 104.51922 -247.134963) (xy 104.486585 -247.098126)
			(xy 104.460282 -247.05653) (xy 104.440991 -247.011254) (xy 104.429214 -246.96347) (xy 104.425254 -246.914416)
			(xy 104.096312 -246.914416) (xy 104.095817 -246.939023) (xy 104.087922 -246.9876) (xy 104.072338 -247.034281)
			(xy 104.049467 -247.077858) (xy 104.019902 -247.117202) (xy 103.984409 -247.151294) (xy 103.943906 -247.17925)
			(xy 103.899444 -247.200348) (xy 103.852173 -247.21404) (xy 103.803318 -247.219972) (xy 103.754143 -247.217991)
			(xy 103.705924 -247.208147) (xy 103.659908 -247.190695) (xy 103.617287 -247.166088) (xy 103.579166 -247.134963)
			(xy 103.546531 -247.098126) (xy 103.520228 -247.05653) (xy 103.500937 -247.011254) (xy 103.48916 -246.96347)
			(xy 103.4852 -246.914416) (xy 103.156258 -246.914416) (xy 103.155763 -246.939023) (xy 103.147868 -246.9876)
			(xy 103.132284 -247.034281) (xy 103.109413 -247.077858) (xy 103.079848 -247.117202) (xy 103.044355 -247.151294)
			(xy 103.003852 -247.17925) (xy 102.95939 -247.200348) (xy 102.912119 -247.21404) (xy 102.863264 -247.219972)
			(xy 102.814089 -247.217991) (xy 102.76587 -247.208147) (xy 102.719854 -247.190695) (xy 102.677233 -247.166088)
			(xy 102.639112 -247.134963) (xy 102.606477 -247.098126) (xy 102.580174 -247.05653) (xy 102.560883 -247.011254)
			(xy 102.549106 -246.96347) (xy 102.545146 -246.914416) (xy 102.216458 -246.914416) (xy 102.215963 -246.939023)
			(xy 102.208068 -246.9876) (xy 102.192484 -247.034281) (xy 102.169613 -247.077858) (xy 102.140048 -247.117202)
			(xy 102.104555 -247.151294) (xy 102.064052 -247.17925) (xy 102.01959 -247.200348) (xy 101.972319 -247.21404)
			(xy 101.923464 -247.219972) (xy 101.874289 -247.217991) (xy 101.82607 -247.208147) (xy 101.780054 -247.190695)
			(xy 101.737433 -247.166088) (xy 101.699312 -247.134963) (xy 101.666677 -247.098126) (xy 101.640374 -247.05653)
			(xy 101.621083 -247.011254) (xy 101.609306 -246.96347) (xy 101.605346 -246.914416) (xy 101.276404 -246.914416)
			(xy 101.275909 -246.939023) (xy 101.268014 -246.9876) (xy 101.25243 -247.034281) (xy 101.229559 -247.077858)
			(xy 101.199994 -247.117202) (xy 101.164501 -247.151294) (xy 101.123998 -247.17925) (xy 101.079536 -247.200348)
			(xy 101.032265 -247.21404) (xy 100.98341 -247.219972) (xy 100.934235 -247.217991) (xy 100.886016 -247.208147)
			(xy 100.84 -247.190695) (xy 100.797379 -247.166088) (xy 100.759258 -247.134963) (xy 100.726623 -247.098126)
			(xy 100.70032 -247.05653) (xy 100.681029 -247.011254) (xy 100.669252 -246.96347) (xy 100.665292 -246.914416)
			(xy 100.33635 -246.914416) (xy 100.335855 -246.939023) (xy 100.32796 -246.9876) (xy 100.312376 -247.034281)
			(xy 100.289505 -247.077858) (xy 100.25994 -247.117202) (xy 100.224447 -247.151294) (xy 100.183944 -247.17925)
			(xy 100.139482 -247.200348) (xy 100.092211 -247.21404) (xy 100.043356 -247.219972) (xy 99.994181 -247.217991)
			(xy 99.945962 -247.208147) (xy 99.899946 -247.190695) (xy 99.857325 -247.166088) (xy 99.819204 -247.134963)
			(xy 99.786569 -247.098126) (xy 99.760266 -247.05653) (xy 99.740975 -247.011254) (xy 99.729198 -246.96347)
			(xy 99.725238 -246.914416) (xy 99.396296 -246.914416) (xy 99.395801 -246.939023) (xy 99.387906 -246.9876)
			(xy 99.372322 -247.034281) (xy 99.349451 -247.077858) (xy 99.319886 -247.117202) (xy 99.284393 -247.151294)
			(xy 99.24389 -247.17925) (xy 99.199428 -247.200348) (xy 99.152157 -247.21404) (xy 99.103302 -247.219972)
			(xy 99.054127 -247.217991) (xy 99.005908 -247.208147) (xy 98.959892 -247.190695) (xy 98.917271 -247.166088)
			(xy 98.87915 -247.134963) (xy 98.846515 -247.098126) (xy 98.820212 -247.05653) (xy 98.800921 -247.011254)
			(xy 98.789144 -246.96347) (xy 98.785184 -246.914416) (xy 98.456242 -246.914416) (xy 98.455747 -246.939023)
			(xy 98.447852 -246.9876) (xy 98.432268 -247.034281) (xy 98.409397 -247.077858) (xy 98.379832 -247.117202)
			(xy 98.344339 -247.151294) (xy 98.303836 -247.17925) (xy 98.259374 -247.200348) (xy 98.212103 -247.21404)
			(xy 98.163248 -247.219972) (xy 98.114073 -247.217991) (xy 98.065854 -247.208147) (xy 98.019838 -247.190695)
			(xy 97.977217 -247.166088) (xy 97.939096 -247.134963) (xy 97.906461 -247.098126) (xy 97.880158 -247.05653)
			(xy 97.860867 -247.011254) (xy 97.84909 -246.96347) (xy 97.84513 -246.914416) (xy 97.516442 -246.914416)
			(xy 97.515947 -246.939023) (xy 97.508052 -246.9876) (xy 97.492468 -247.034281) (xy 97.469597 -247.077858)
			(xy 97.440032 -247.117202) (xy 97.404539 -247.151294) (xy 97.364036 -247.17925) (xy 97.319574 -247.200348)
			(xy 97.272303 -247.21404) (xy 97.223448 -247.219972) (xy 97.174273 -247.217991) (xy 97.126054 -247.208147)
			(xy 97.080038 -247.190695) (xy 97.037417 -247.166088) (xy 96.999296 -247.134963) (xy 96.966661 -247.098126)
			(xy 96.940358 -247.05653) (xy 96.921067 -247.011254) (xy 96.90929 -246.96347) (xy 96.90533 -246.914416)
			(xy 96.576388 -246.914416) (xy 96.575893 -246.939023) (xy 96.567998 -246.9876) (xy 96.552414 -247.034281)
			(xy 96.529543 -247.077858) (xy 96.499978 -247.117202) (xy 96.464485 -247.151294) (xy 96.423982 -247.17925)
			(xy 96.37952 -247.200348) (xy 96.332249 -247.21404) (xy 96.283394 -247.219972) (xy 96.234219 -247.217991)
			(xy 96.186 -247.208147) (xy 96.139984 -247.190695) (xy 96.097363 -247.166088) (xy 96.059242 -247.134963)
			(xy 96.026607 -247.098126) (xy 96.000304 -247.05653) (xy 95.981013 -247.011254) (xy 95.969236 -246.96347)
			(xy 95.965276 -246.914416) (xy 95.646748 -246.914416) (xy 95.646236 -246.939862) (xy 95.638072 -246.990096)
			(xy 95.621956 -247.03837) (xy 95.598305 -247.083433) (xy 95.567732 -247.124119) (xy 95.531028 -247.159374)
			(xy 95.489144 -247.188284) (xy 95.443165 -247.210101) (xy 95.394281 -247.224261) (xy 95.34376 -247.230395)
			(xy 95.292908 -247.228346) (xy 95.243044 -247.218166) (xy 95.195458 -247.200119) (xy 95.151384 -247.174673)
			(xy 95.111962 -247.142486) (xy 95.078214 -247.104392) (xy 95.051013 -247.061378) (xy 95.031065 -247.014558)
			(xy 95.018886 -246.965144) (xy 95.014791 -246.914416) (xy 94.706694 -246.914416) (xy 94.706182 -246.939862)
			(xy 94.698018 -246.990096) (xy 94.681902 -247.03837) (xy 94.658251 -247.083433) (xy 94.627678 -247.124119)
			(xy 94.590974 -247.159374) (xy 94.54909 -247.188284) (xy 94.503111 -247.210101) (xy 94.454227 -247.224261)
			(xy 94.403706 -247.230395) (xy 94.352854 -247.228346) (xy 94.30299 -247.218166) (xy 94.255404 -247.200119)
			(xy 94.21133 -247.174673) (xy 94.171908 -247.142486) (xy 94.13816 -247.104392) (xy 94.110959 -247.061378)
			(xy 94.091011 -247.014558) (xy 94.078832 -246.965144) (xy 94.074737 -246.914416) (xy 93.756226 -246.914416)
			(xy 93.755731 -246.939023) (xy 93.747836 -246.9876) (xy 93.732252 -247.034281) (xy 93.709381 -247.077858)
			(xy 93.679816 -247.117202) (xy 93.644323 -247.151294) (xy 93.60382 -247.17925) (xy 93.559358 -247.200348)
			(xy 93.512087 -247.21404) (xy 93.463232 -247.219972) (xy 93.414057 -247.217991) (xy 93.365838 -247.208147)
			(xy 93.319822 -247.190695) (xy 93.277201 -247.166088) (xy 93.23908 -247.134963) (xy 93.206445 -247.098126)
			(xy 93.180142 -247.05653) (xy 93.160851 -247.011254) (xy 93.149074 -246.96347) (xy 93.145114 -246.914416)
			(xy 92.82684 -246.914416) (xy 92.826338 -246.939709) (xy 92.818262 -246.989646) (xy 92.80232 -247.037655)
			(xy 92.778921 -247.082504) (xy 92.748664 -247.123044) (xy 92.730828 -247.140984) (xy 92.73032 -247.141238)
			(xy 92.730066 -247.141746) (xy 92.723371 -247.149156) (xy 92.715754 -247.167596) (xy 92.715742 -247.187547)
			(xy 92.723339 -247.205996) (xy 92.730066 -247.213374) (xy 92.921582 -247.40489) (xy 92.925568 -247.408642)
			(xy 92.934791 -247.414534) (xy 92.93987 -247.416574) (xy 92.949776 -247.420384) (xy 92.957142 -247.42013)
			(xy 92.981018 -247.419114) (xy 93.00501 -247.419562) (xy 93.052402 -247.427071) (xy 93.098035 -247.441901)
			(xy 93.140787 -247.463688) (xy 93.179605 -247.491894) (xy 93.213532 -247.525826) (xy 93.241733 -247.564647)
			(xy 93.263514 -247.607402) (xy 93.278339 -247.653037) (xy 93.285842 -247.70043) (xy 93.286326 -247.724422)
			(xy 93.604837 -247.724422) (xy 93.608932 -247.673694) (xy 93.621111 -247.62428) (xy 93.641059 -247.57746)
			(xy 93.66826 -247.534446) (xy 93.702008 -247.496352) (xy 93.74143 -247.464165) (xy 93.785504 -247.438719)
			(xy 93.83309 -247.420672) (xy 93.882954 -247.410492) (xy 93.933806 -247.408443) (xy 93.984327 -247.414577)
			(xy 94.033211 -247.428737) (xy 94.07919 -247.450554) (xy 94.121074 -247.479464) (xy 94.157778 -247.514719)
			(xy 94.188351 -247.555405) (xy 94.212002 -247.600468) (xy 94.228118 -247.648742) (xy 94.236282 -247.698976)
			(xy 94.236794 -247.724422) (xy 94.555322 -247.724422) (xy 94.559282 -247.675368) (xy 94.571059 -247.627584)
			(xy 94.59035 -247.582308) (xy 94.616653 -247.540712) (xy 94.649288 -247.503875) (xy 94.687409 -247.47275)
			(xy 94.73003 -247.448143) (xy 94.776046 -247.430691) (xy 94.824265 -247.420847) (xy 94.87344 -247.418866)
			(xy 94.922295 -247.424798) (xy 94.969566 -247.43849) (xy 95.014028 -247.459588) (xy 95.054531 -247.487544)
			(xy 95.090024 -247.521636) (xy 95.119589 -247.56098) (xy 95.14246 -247.604557) (xy 95.158044 -247.651238)
			(xy 95.165939 -247.699815) (xy 95.166434 -247.724422) (xy 95.484691 -247.724422) (xy 95.488786 -247.673694)
			(xy 95.500965 -247.62428) (xy 95.520913 -247.57746) (xy 95.548114 -247.534446) (xy 95.581862 -247.496352)
			(xy 95.621284 -247.464165) (xy 95.665358 -247.438719) (xy 95.712944 -247.420672) (xy 95.762808 -247.410492)
			(xy 95.81366 -247.408443) (xy 95.864181 -247.414577) (xy 95.913065 -247.428737) (xy 95.959044 -247.450554)
			(xy 96.000928 -247.479464) (xy 96.037632 -247.514719) (xy 96.068205 -247.555405) (xy 96.091856 -247.600468)
			(xy 96.107972 -247.648742) (xy 96.116136 -247.698976) (xy 96.116648 -247.724422) (xy 96.435176 -247.724422)
			(xy 96.439136 -247.675368) (xy 96.450913 -247.627584) (xy 96.470204 -247.582308) (xy 96.496507 -247.540712)
			(xy 96.529142 -247.503875) (xy 96.567263 -247.47275) (xy 96.609884 -247.448143) (xy 96.6559 -247.430691)
			(xy 96.704119 -247.420847) (xy 96.753294 -247.418866) (xy 96.802149 -247.424798) (xy 96.84942 -247.43849)
			(xy 96.893882 -247.459588) (xy 96.934385 -247.487544) (xy 96.969878 -247.521636) (xy 96.999443 -247.56098)
			(xy 97.022314 -247.604557) (xy 97.037898 -247.651238) (xy 97.045793 -247.699815) (xy 97.046288 -247.724422)
			(xy 97.364799 -247.724422) (xy 97.368894 -247.673694) (xy 97.381073 -247.62428) (xy 97.401021 -247.57746)
			(xy 97.428222 -247.534446) (xy 97.46197 -247.496352) (xy 97.501392 -247.464165) (xy 97.545466 -247.438719)
			(xy 97.593052 -247.420672) (xy 97.642916 -247.410492) (xy 97.693768 -247.408443) (xy 97.744289 -247.414577)
			(xy 97.793173 -247.428737) (xy 97.839152 -247.450554) (xy 97.881036 -247.479464) (xy 97.91774 -247.514719)
			(xy 97.948313 -247.555405) (xy 97.971964 -247.600468) (xy 97.98808 -247.648742) (xy 97.996244 -247.698976)
			(xy 97.996756 -247.724422) (xy 98.304853 -247.724422) (xy 98.308948 -247.673694) (xy 98.321127 -247.62428)
			(xy 98.341075 -247.57746) (xy 98.368276 -247.534446) (xy 98.402024 -247.496352) (xy 98.441446 -247.464165)
			(xy 98.48552 -247.438719) (xy 98.533106 -247.420672) (xy 98.58297 -247.410492) (xy 98.633822 -247.408443)
			(xy 98.684343 -247.414577) (xy 98.733227 -247.428737) (xy 98.779206 -247.450554) (xy 98.82109 -247.479464)
			(xy 98.857794 -247.514719) (xy 98.888367 -247.555405) (xy 98.912018 -247.600468) (xy 98.928134 -247.648742)
			(xy 98.936298 -247.698976) (xy 98.93681 -247.724422) (xy 99.255338 -247.724422) (xy 99.259298 -247.675368)
			(xy 99.271075 -247.627584) (xy 99.290366 -247.582308) (xy 99.316669 -247.540712) (xy 99.349304 -247.503875)
			(xy 99.387425 -247.47275) (xy 99.430046 -247.448143) (xy 99.476062 -247.430691) (xy 99.524281 -247.420847)
			(xy 99.573456 -247.418866) (xy 99.622311 -247.424798) (xy 99.669582 -247.43849) (xy 99.714044 -247.459588)
			(xy 99.754547 -247.487544) (xy 99.79004 -247.521636) (xy 99.819605 -247.56098) (xy 99.842476 -247.604557)
			(xy 99.85806 -247.651238) (xy 99.865955 -247.699815) (xy 99.86645 -247.724422) (xy 100.184707 -247.724422)
			(xy 100.188802 -247.673694) (xy 100.200981 -247.62428) (xy 100.220929 -247.57746) (xy 100.24813 -247.534446)
			(xy 100.281878 -247.496352) (xy 100.3213 -247.464165) (xy 100.365374 -247.438719) (xy 100.41296 -247.420672)
			(xy 100.462824 -247.410492) (xy 100.513676 -247.408443) (xy 100.564197 -247.414577) (xy 100.613081 -247.428737)
			(xy 100.65906 -247.450554) (xy 100.700944 -247.479464) (xy 100.737648 -247.514719) (xy 100.768221 -247.555405)
			(xy 100.791872 -247.600468) (xy 100.807988 -247.648742) (xy 100.816152 -247.698976) (xy 100.816664 -247.724422)
			(xy 101.124761 -247.724422) (xy 101.128856 -247.673694) (xy 101.141035 -247.62428) (xy 101.160983 -247.57746)
			(xy 101.188184 -247.534446) (xy 101.221932 -247.496352) (xy 101.261354 -247.464165) (xy 101.305428 -247.438719)
			(xy 101.353014 -247.420672) (xy 101.402878 -247.410492) (xy 101.45373 -247.408443) (xy 101.504251 -247.414577)
			(xy 101.553135 -247.428737) (xy 101.599114 -247.450554) (xy 101.640998 -247.479464) (xy 101.677702 -247.514719)
			(xy 101.708275 -247.555405) (xy 101.731926 -247.600468) (xy 101.748042 -247.648742) (xy 101.756206 -247.698976)
			(xy 101.756718 -247.724422) (xy 102.075246 -247.724422) (xy 102.079206 -247.675368) (xy 102.090983 -247.627584)
			(xy 102.110274 -247.582308) (xy 102.136577 -247.540712) (xy 102.169212 -247.503875) (xy 102.207333 -247.47275)
			(xy 102.249954 -247.448143) (xy 102.29597 -247.430691) (xy 102.344189 -247.420847) (xy 102.393364 -247.418866)
			(xy 102.442219 -247.424798) (xy 102.48949 -247.43849) (xy 102.533952 -247.459588) (xy 102.574455 -247.487544)
			(xy 102.609948 -247.521636) (xy 102.639513 -247.56098) (xy 102.662384 -247.604557) (xy 102.677968 -247.651238)
			(xy 102.685863 -247.699815) (xy 102.686358 -247.724422) (xy 103.004869 -247.724422) (xy 103.008964 -247.673694)
			(xy 103.021143 -247.62428) (xy 103.041091 -247.57746) (xy 103.068292 -247.534446) (xy 103.10204 -247.496352)
			(xy 103.141462 -247.464165) (xy 103.185536 -247.438719) (xy 103.233122 -247.420672) (xy 103.282986 -247.410492)
			(xy 103.333838 -247.408443) (xy 103.384359 -247.414577) (xy 103.433243 -247.428737) (xy 103.479222 -247.450554)
			(xy 103.521106 -247.479464) (xy 103.55781 -247.514719) (xy 103.588383 -247.555405) (xy 103.612034 -247.600468)
			(xy 103.62815 -247.648742) (xy 103.636314 -247.698976) (xy 103.636826 -247.724422) (xy 103.944923 -247.724422)
			(xy 103.949018 -247.673694) (xy 103.961197 -247.62428) (xy 103.981145 -247.57746) (xy 104.008346 -247.534446)
			(xy 104.042094 -247.496352) (xy 104.081516 -247.464165) (xy 104.12559 -247.438719) (xy 104.173176 -247.420672)
			(xy 104.22304 -247.410492) (xy 104.273892 -247.408443) (xy 104.324413 -247.414577) (xy 104.373297 -247.428737)
			(xy 104.419276 -247.450554) (xy 104.46116 -247.479464) (xy 104.497864 -247.514719) (xy 104.528437 -247.555405)
			(xy 104.552088 -247.600468) (xy 104.568204 -247.648742) (xy 104.576368 -247.698976) (xy 104.57688 -247.724422)
			(xy 104.895154 -247.724422) (xy 104.899114 -247.675368) (xy 104.910891 -247.627584) (xy 104.930182 -247.582308)
			(xy 104.956485 -247.540712) (xy 104.98912 -247.503875) (xy 105.027241 -247.47275) (xy 105.069862 -247.448143)
			(xy 105.115878 -247.430691) (xy 105.164097 -247.420847) (xy 105.213272 -247.418866) (xy 105.262127 -247.424798)
			(xy 105.309398 -247.43849) (xy 105.35386 -247.459588) (xy 105.394363 -247.487544) (xy 105.429856 -247.521636)
			(xy 105.459421 -247.56098) (xy 105.482292 -247.604557) (xy 105.497876 -247.651238) (xy 105.505771 -247.699815)
			(xy 105.506266 -247.724422) (xy 105.824777 -247.724422) (xy 105.828872 -247.673694) (xy 105.841051 -247.62428)
			(xy 105.860999 -247.57746) (xy 105.8882 -247.534446) (xy 105.921948 -247.496352) (xy 105.96137 -247.464165)
			(xy 106.005444 -247.438719) (xy 106.05303 -247.420672) (xy 106.102894 -247.410492) (xy 106.153746 -247.408443)
			(xy 106.204267 -247.414577) (xy 106.253151 -247.428737) (xy 106.29913 -247.450554) (xy 106.341014 -247.479464)
			(xy 106.377718 -247.514719) (xy 106.408291 -247.555405) (xy 106.431942 -247.600468) (xy 106.448058 -247.648742)
			(xy 106.456222 -247.698976) (xy 106.456734 -247.724422) (xy 106.764831 -247.724422) (xy 106.768926 -247.673694)
			(xy 106.781105 -247.62428) (xy 106.801053 -247.57746) (xy 106.828254 -247.534446) (xy 106.862002 -247.496352)
			(xy 106.901424 -247.464165) (xy 106.945498 -247.438719) (xy 106.993084 -247.420672) (xy 107.042948 -247.410492)
			(xy 107.0938 -247.408443) (xy 107.144321 -247.414577) (xy 107.193205 -247.428737) (xy 107.239184 -247.450554)
			(xy 107.281068 -247.479464) (xy 107.317772 -247.514719) (xy 107.348345 -247.555405) (xy 107.371996 -247.600468)
			(xy 107.388112 -247.648742) (xy 107.396276 -247.698976) (xy 107.396788 -247.724422) (xy 107.715316 -247.724422)
			(xy 107.719276 -247.675368) (xy 107.731053 -247.627584) (xy 107.750344 -247.582308) (xy 107.776647 -247.540712)
			(xy 107.809282 -247.503875) (xy 107.847403 -247.47275) (xy 107.890024 -247.448143) (xy 107.93604 -247.430691)
			(xy 107.984259 -247.420847) (xy 108.033434 -247.418866) (xy 108.082289 -247.424798) (xy 108.12956 -247.43849)
			(xy 108.174022 -247.459588) (xy 108.214525 -247.487544) (xy 108.250018 -247.521636) (xy 108.279583 -247.56098)
			(xy 108.302454 -247.604557) (xy 108.318038 -247.651238) (xy 108.325933 -247.699815) (xy 108.326428 -247.724422)
			(xy 108.65537 -247.724422) (xy 108.65933 -247.675368) (xy 108.671107 -247.627584) (xy 108.690398 -247.582308)
			(xy 108.716701 -247.540712) (xy 108.749336 -247.503875) (xy 108.787457 -247.47275) (xy 108.830078 -247.448143)
			(xy 108.876094 -247.430691) (xy 108.924313 -247.420847) (xy 108.973488 -247.418866) (xy 109.022343 -247.424798)
			(xy 109.069614 -247.43849) (xy 109.114076 -247.459588) (xy 109.154579 -247.487544) (xy 109.190072 -247.521636)
			(xy 109.219637 -247.56098) (xy 109.242508 -247.604557) (xy 109.258092 -247.651238) (xy 109.265987 -247.699815)
			(xy 109.266482 -247.724422) (xy 109.59517 -247.724422) (xy 109.59913 -247.675368) (xy 109.610907 -247.627584)
			(xy 109.630198 -247.582308) (xy 109.656501 -247.540712) (xy 109.689136 -247.503875) (xy 109.727257 -247.47275)
			(xy 109.769878 -247.448143) (xy 109.815894 -247.430691) (xy 109.864113 -247.420847) (xy 109.913288 -247.418866)
			(xy 109.962143 -247.424798) (xy 110.009414 -247.43849) (xy 110.048873 -247.457214) (xy 111.456473 -247.457214)
			(xy 111.460503 -247.404716) (xy 111.4725 -247.353448) (xy 111.492183 -247.304613) (xy 111.519089 -247.259354)
			(xy 111.552589 -247.218733) (xy 111.591897 -247.183702) (xy 111.636092 -247.155082) (xy 111.684137 -247.133543)
			(xy 111.734908 -247.119591) (xy 111.787213 -247.113553) (xy 111.839827 -247.11557) (xy 111.891517 -247.125594)
			(xy 111.94107 -247.143392) (xy 111.987326 -247.168545) (xy 112.0292 -247.200464) (xy 112.065712 -247.238402)
			(xy 112.096004 -247.281468) (xy 112.119367 -247.328653) (xy 112.135253 -247.378852) (xy 112.14329 -247.430888)
			(xy 112.143794 -247.457214) (xy 112.14329 -247.48354) (xy 112.135253 -247.535576) (xy 112.119367 -247.585775)
			(xy 112.096004 -247.63296) (xy 112.065712 -247.676026) (xy 112.0292 -247.713964) (xy 112.01548 -247.724422)
			(xy 113.349036 -247.724422) (xy 113.352996 -247.675368) (xy 113.364773 -247.627584) (xy 113.384064 -247.582308)
			(xy 113.410367 -247.540712) (xy 113.443002 -247.503875) (xy 113.481123 -247.47275) (xy 113.523744 -247.448143)
			(xy 113.56976 -247.430691) (xy 113.617979 -247.420847) (xy 113.667154 -247.418866) (xy 113.716009 -247.424798)
			(xy 113.76328 -247.43849) (xy 113.807742 -247.459588) (xy 113.848245 -247.487544) (xy 113.883738 -247.521636)
			(xy 113.913303 -247.56098) (xy 113.936174 -247.604557) (xy 113.951758 -247.651238) (xy 113.959653 -247.699815)
			(xy 113.960148 -247.724422) (xy 114.288836 -247.724422) (xy 114.292796 -247.675368) (xy 114.304573 -247.627584)
			(xy 114.323864 -247.582308) (xy 114.350167 -247.540712) (xy 114.382802 -247.503875) (xy 114.420923 -247.47275)
			(xy 114.463544 -247.448143) (xy 114.50956 -247.430691) (xy 114.557779 -247.420847) (xy 114.606954 -247.418866)
			(xy 114.655809 -247.424798) (xy 114.70308 -247.43849) (xy 114.747542 -247.459588) (xy 114.788045 -247.487544)
			(xy 114.823538 -247.521636) (xy 114.853103 -247.56098) (xy 114.875974 -247.604557) (xy 114.891558 -247.651238)
			(xy 114.899453 -247.699815) (xy 114.899948 -247.724422) (xy 115.22889 -247.724422) (xy 115.23285 -247.675368)
			(xy 115.244627 -247.627584) (xy 115.263918 -247.582308) (xy 115.290221 -247.540712) (xy 115.322856 -247.503875)
			(xy 115.360977 -247.47275) (xy 115.403598 -247.448143) (xy 115.449614 -247.430691) (xy 115.497833 -247.420847)
			(xy 115.547008 -247.418866) (xy 115.595863 -247.424798) (xy 115.643134 -247.43849) (xy 115.687596 -247.459588)
			(xy 115.728099 -247.487544) (xy 115.763592 -247.521636) (xy 115.793157 -247.56098) (xy 115.816028 -247.604557)
			(xy 115.831612 -247.651238) (xy 115.839507 -247.699815) (xy 115.840002 -247.724422) (xy 116.168944 -247.724422)
			(xy 116.172904 -247.675368) (xy 116.184681 -247.627584) (xy 116.203972 -247.582308) (xy 116.230275 -247.540712)
			(xy 116.26291 -247.503875) (xy 116.301031 -247.47275) (xy 116.343652 -247.448143) (xy 116.389668 -247.430691)
			(xy 116.437887 -247.420847) (xy 116.487062 -247.418866) (xy 116.535917 -247.424798) (xy 116.583188 -247.43849)
			(xy 116.62765 -247.459588) (xy 116.668153 -247.487544) (xy 116.703646 -247.521636) (xy 116.733211 -247.56098)
			(xy 116.756082 -247.604557) (xy 116.771666 -247.651238) (xy 116.779561 -247.699815) (xy 116.780056 -247.724422)
			(xy 117.108998 -247.724422) (xy 117.112958 -247.675368) (xy 117.124735 -247.627584) (xy 117.144026 -247.582308)
			(xy 117.170329 -247.540712) (xy 117.202964 -247.503875) (xy 117.241085 -247.47275) (xy 117.283706 -247.448143)
			(xy 117.329722 -247.430691) (xy 117.377941 -247.420847) (xy 117.427116 -247.418866) (xy 117.475971 -247.424798)
			(xy 117.523242 -247.43849) (xy 117.567704 -247.459588) (xy 117.608207 -247.487544) (xy 117.6437 -247.521636)
			(xy 117.673265 -247.56098) (xy 117.696136 -247.604557) (xy 117.71172 -247.651238) (xy 117.719615 -247.699815)
			(xy 117.72011 -247.724422) (xy 118.049052 -247.724422) (xy 118.053012 -247.675368) (xy 118.064789 -247.627584)
			(xy 118.08408 -247.582308) (xy 118.110383 -247.540712) (xy 118.143018 -247.503875) (xy 118.181139 -247.47275)
			(xy 118.22376 -247.448143) (xy 118.269776 -247.430691) (xy 118.317995 -247.420847) (xy 118.36717 -247.418866)
			(xy 118.416025 -247.424798) (xy 118.463296 -247.43849) (xy 118.507758 -247.459588) (xy 118.548261 -247.487544)
			(xy 118.583754 -247.521636) (xy 118.613319 -247.56098) (xy 118.63619 -247.604557) (xy 118.651774 -247.651238)
			(xy 118.659669 -247.699815) (xy 118.660164 -247.724422) (xy 118.988852 -247.724422) (xy 118.992812 -247.675368)
			(xy 119.004589 -247.627584) (xy 119.02388 -247.582308) (xy 119.050183 -247.540712) (xy 119.082818 -247.503875)
			(xy 119.120939 -247.47275) (xy 119.16356 -247.448143) (xy 119.209576 -247.430691) (xy 119.257795 -247.420847)
			(xy 119.30697 -247.418866) (xy 119.355825 -247.424798) (xy 119.403096 -247.43849) (xy 119.447558 -247.459588)
			(xy 119.488061 -247.487544) (xy 119.523554 -247.521636) (xy 119.553119 -247.56098) (xy 119.57599 -247.604557)
			(xy 119.591574 -247.651238) (xy 119.599469 -247.699815) (xy 119.599964 -247.724422) (xy 119.928906 -247.724422)
			(xy 119.932866 -247.675368) (xy 119.944643 -247.627584) (xy 119.963934 -247.582308) (xy 119.990237 -247.540712)
			(xy 120.022872 -247.503875) (xy 120.060993 -247.47275) (xy 120.103614 -247.448143) (xy 120.14963 -247.430691)
			(xy 120.197849 -247.420847) (xy 120.247024 -247.418866) (xy 120.295879 -247.424798) (xy 120.34315 -247.43849)
			(xy 120.387612 -247.459588) (xy 120.428115 -247.487544) (xy 120.463608 -247.521636) (xy 120.493173 -247.56098)
			(xy 120.516044 -247.604557) (xy 120.531628 -247.651238) (xy 120.539523 -247.699815) (xy 120.540018 -247.724422)
			(xy 120.86896 -247.724422) (xy 120.87292 -247.675368) (xy 120.884697 -247.627584) (xy 120.903988 -247.582308)
			(xy 120.930291 -247.540712) (xy 120.962926 -247.503875) (xy 121.001047 -247.47275) (xy 121.043668 -247.448143)
			(xy 121.089684 -247.430691) (xy 121.137903 -247.420847) (xy 121.187078 -247.418866) (xy 121.235933 -247.424798)
			(xy 121.283204 -247.43849) (xy 121.327666 -247.459588) (xy 121.368169 -247.487544) (xy 121.403662 -247.521636)
			(xy 121.433227 -247.56098) (xy 121.456098 -247.604557) (xy 121.471682 -247.651238) (xy 121.479577 -247.699815)
			(xy 121.480072 -247.724422) (xy 121.809014 -247.724422) (xy 121.812974 -247.675368) (xy 121.824751 -247.627584)
			(xy 121.844042 -247.582308) (xy 121.870345 -247.540712) (xy 121.90298 -247.503875) (xy 121.941101 -247.47275)
			(xy 121.983722 -247.448143) (xy 122.029738 -247.430691) (xy 122.077957 -247.420847) (xy 122.127132 -247.418866)
			(xy 122.175987 -247.424798) (xy 122.223258 -247.43849) (xy 122.26772 -247.459588) (xy 122.308223 -247.487544)
			(xy 122.343716 -247.521636) (xy 122.373281 -247.56098) (xy 122.396152 -247.604557) (xy 122.411736 -247.651238)
			(xy 122.419631 -247.699815) (xy 122.420126 -247.724422) (xy 122.748814 -247.724422) (xy 122.752774 -247.675368)
			(xy 122.764551 -247.627584) (xy 122.783842 -247.582308) (xy 122.810145 -247.540712) (xy 122.84278 -247.503875)
			(xy 122.880901 -247.47275) (xy 122.923522 -247.448143) (xy 122.969538 -247.430691) (xy 123.017757 -247.420847)
			(xy 123.066932 -247.418866) (xy 123.115787 -247.424798) (xy 123.163058 -247.43849) (xy 123.20752 -247.459588)
			(xy 123.248023 -247.487544) (xy 123.283516 -247.521636) (xy 123.313081 -247.56098) (xy 123.335952 -247.604557)
			(xy 123.351536 -247.651238) (xy 123.359431 -247.699815) (xy 123.359926 -247.724422) (xy 123.688868 -247.724422)
			(xy 123.692828 -247.675368) (xy 123.704605 -247.627584) (xy 123.723896 -247.582308) (xy 123.750199 -247.540712)
			(xy 123.782834 -247.503875) (xy 123.820955 -247.47275) (xy 123.863576 -247.448143) (xy 123.909592 -247.430691)
			(xy 123.957811 -247.420847) (xy 124.006986 -247.418866) (xy 124.055841 -247.424798) (xy 124.103112 -247.43849)
			(xy 124.147574 -247.459588) (xy 124.188077 -247.487544) (xy 124.22357 -247.521636) (xy 124.253135 -247.56098)
			(xy 124.276006 -247.604557) (xy 124.29159 -247.651238) (xy 124.299485 -247.699815) (xy 124.29998 -247.724422)
			(xy 124.628922 -247.724422) (xy 124.632882 -247.675368) (xy 124.644659 -247.627584) (xy 124.66395 -247.582308)
			(xy 124.690253 -247.540712) (xy 124.722888 -247.503875) (xy 124.761009 -247.47275) (xy 124.80363 -247.448143)
			(xy 124.849646 -247.430691) (xy 124.897865 -247.420847) (xy 124.94704 -247.418866) (xy 124.995895 -247.424798)
			(xy 125.043166 -247.43849) (xy 125.087628 -247.459588) (xy 125.128131 -247.487544) (xy 125.163624 -247.521636)
			(xy 125.193189 -247.56098) (xy 125.21606 -247.604557) (xy 125.231644 -247.651238) (xy 125.239539 -247.699815)
			(xy 125.240034 -247.724422) (xy 125.568976 -247.724422) (xy 125.572936 -247.675368) (xy 125.584713 -247.627584)
			(xy 125.604004 -247.582308) (xy 125.630307 -247.540712) (xy 125.662942 -247.503875) (xy 125.701063 -247.47275)
			(xy 125.743684 -247.448143) (xy 125.7897 -247.430691) (xy 125.837919 -247.420847) (xy 125.887094 -247.418866)
			(xy 125.935949 -247.424798) (xy 125.98322 -247.43849) (xy 126.027682 -247.459588) (xy 126.068185 -247.487544)
			(xy 126.103678 -247.521636) (xy 126.133243 -247.56098) (xy 126.156114 -247.604557) (xy 126.171698 -247.651238)
			(xy 126.179593 -247.699815) (xy 126.180088 -247.724422) (xy 126.179593 -247.749029) (xy 126.171698 -247.797606)
			(xy 126.156114 -247.844287) (xy 126.133243 -247.887864) (xy 126.103678 -247.927208) (xy 126.068185 -247.9613)
			(xy 126.027682 -247.989256) (xy 125.98322 -248.010354) (xy 125.935949 -248.024046) (xy 125.887094 -248.029978)
			(xy 125.837919 -248.027997) (xy 125.7897 -248.018153) (xy 125.743684 -248.000701) (xy 125.701063 -247.976094)
			(xy 125.662942 -247.944969) (xy 125.630307 -247.908132) (xy 125.604004 -247.866536) (xy 125.584713 -247.82126)
			(xy 125.572936 -247.773476) (xy 125.568976 -247.724422) (xy 125.240034 -247.724422) (xy 125.239539 -247.749029)
			(xy 125.231644 -247.797606) (xy 125.21606 -247.844287) (xy 125.193189 -247.887864) (xy 125.163624 -247.927208)
			(xy 125.128131 -247.9613) (xy 125.087628 -247.989256) (xy 125.043166 -248.010354) (xy 124.995895 -248.024046)
			(xy 124.94704 -248.029978) (xy 124.897865 -248.027997) (xy 124.849646 -248.018153) (xy 124.80363 -248.000701)
			(xy 124.761009 -247.976094) (xy 124.722888 -247.944969) (xy 124.690253 -247.908132) (xy 124.66395 -247.866536)
			(xy 124.644659 -247.82126) (xy 124.632882 -247.773476) (xy 124.628922 -247.724422) (xy 124.29998 -247.724422)
			(xy 124.299485 -247.749029) (xy 124.29159 -247.797606) (xy 124.276006 -247.844287) (xy 124.253135 -247.887864)
			(xy 124.22357 -247.927208) (xy 124.188077 -247.9613) (xy 124.147574 -247.989256) (xy 124.103112 -248.010354)
			(xy 124.055841 -248.024046) (xy 124.006986 -248.029978) (xy 123.957811 -248.027997) (xy 123.909592 -248.018153)
			(xy 123.863576 -248.000701) (xy 123.820955 -247.976094) (xy 123.782834 -247.944969) (xy 123.750199 -247.908132)
			(xy 123.723896 -247.866536) (xy 123.704605 -247.82126) (xy 123.692828 -247.773476) (xy 123.688868 -247.724422)
			(xy 123.359926 -247.724422) (xy 123.359431 -247.749029) (xy 123.351536 -247.797606) (xy 123.335952 -247.844287)
			(xy 123.313081 -247.887864) (xy 123.283516 -247.927208) (xy 123.248023 -247.9613) (xy 123.20752 -247.989256)
			(xy 123.163058 -248.010354) (xy 123.115787 -248.024046) (xy 123.066932 -248.029978) (xy 123.017757 -248.027997)
			(xy 122.969538 -248.018153) (xy 122.923522 -248.000701) (xy 122.880901 -247.976094) (xy 122.84278 -247.944969)
			(xy 122.810145 -247.908132) (xy 122.783842 -247.866536) (xy 122.764551 -247.82126) (xy 122.752774 -247.773476)
			(xy 122.748814 -247.724422) (xy 122.420126 -247.724422) (xy 122.419631 -247.749029) (xy 122.411736 -247.797606)
			(xy 122.396152 -247.844287) (xy 122.373281 -247.887864) (xy 122.343716 -247.927208) (xy 122.308223 -247.9613)
			(xy 122.26772 -247.989256) (xy 122.223258 -248.010354) (xy 122.175987 -248.024046) (xy 122.127132 -248.029978)
			(xy 122.077957 -248.027997) (xy 122.029738 -248.018153) (xy 121.983722 -248.000701) (xy 121.941101 -247.976094)
			(xy 121.90298 -247.944969) (xy 121.870345 -247.908132) (xy 121.844042 -247.866536) (xy 121.824751 -247.82126)
			(xy 121.812974 -247.773476) (xy 121.809014 -247.724422) (xy 121.480072 -247.724422) (xy 121.479577 -247.749029)
			(xy 121.471682 -247.797606) (xy 121.456098 -247.844287) (xy 121.433227 -247.887864) (xy 121.403662 -247.927208)
			(xy 121.368169 -247.9613) (xy 121.327666 -247.989256) (xy 121.283204 -248.010354) (xy 121.235933 -248.024046)
			(xy 121.187078 -248.029978) (xy 121.137903 -248.027997) (xy 121.089684 -248.018153) (xy 121.043668 -248.000701)
			(xy 121.001047 -247.976094) (xy 120.962926 -247.944969) (xy 120.930291 -247.908132) (xy 120.903988 -247.866536)
			(xy 120.884697 -247.82126) (xy 120.87292 -247.773476) (xy 120.86896 -247.724422) (xy 120.540018 -247.724422)
			(xy 120.539523 -247.749029) (xy 120.531628 -247.797606) (xy 120.516044 -247.844287) (xy 120.493173 -247.887864)
			(xy 120.463608 -247.927208) (xy 120.428115 -247.9613) (xy 120.387612 -247.989256) (xy 120.34315 -248.010354)
			(xy 120.295879 -248.024046) (xy 120.247024 -248.029978) (xy 120.197849 -248.027997) (xy 120.14963 -248.018153)
			(xy 120.103614 -248.000701) (xy 120.060993 -247.976094) (xy 120.022872 -247.944969) (xy 119.990237 -247.908132)
			(xy 119.963934 -247.866536) (xy 119.944643 -247.82126) (xy 119.932866 -247.773476) (xy 119.928906 -247.724422)
			(xy 119.599964 -247.724422) (xy 119.599469 -247.749029) (xy 119.591574 -247.797606) (xy 119.57599 -247.844287)
			(xy 119.553119 -247.887864) (xy 119.523554 -247.927208) (xy 119.488061 -247.9613) (xy 119.447558 -247.989256)
			(xy 119.403096 -248.010354) (xy 119.355825 -248.024046) (xy 119.30697 -248.029978) (xy 119.257795 -248.027997)
			(xy 119.209576 -248.018153) (xy 119.16356 -248.000701) (xy 119.120939 -247.976094) (xy 119.082818 -247.944969)
			(xy 119.050183 -247.908132) (xy 119.02388 -247.866536) (xy 119.004589 -247.82126) (xy 118.992812 -247.773476)
			(xy 118.988852 -247.724422) (xy 118.660164 -247.724422) (xy 118.659669 -247.749029) (xy 118.651774 -247.797606)
			(xy 118.63619 -247.844287) (xy 118.613319 -247.887864) (xy 118.583754 -247.927208) (xy 118.548261 -247.9613)
			(xy 118.507758 -247.989256) (xy 118.463296 -248.010354) (xy 118.416025 -248.024046) (xy 118.36717 -248.029978)
			(xy 118.317995 -248.027997) (xy 118.269776 -248.018153) (xy 118.22376 -248.000701) (xy 118.181139 -247.976094)
			(xy 118.143018 -247.944969) (xy 118.110383 -247.908132) (xy 118.08408 -247.866536) (xy 118.064789 -247.82126)
			(xy 118.053012 -247.773476) (xy 118.049052 -247.724422) (xy 117.72011 -247.724422) (xy 117.719615 -247.749029)
			(xy 117.71172 -247.797606) (xy 117.696136 -247.844287) (xy 117.673265 -247.887864) (xy 117.6437 -247.927208)
			(xy 117.608207 -247.9613) (xy 117.567704 -247.989256) (xy 117.523242 -248.010354) (xy 117.475971 -248.024046)
			(xy 117.427116 -248.029978) (xy 117.377941 -248.027997) (xy 117.329722 -248.018153) (xy 117.283706 -248.000701)
			(xy 117.241085 -247.976094) (xy 117.202964 -247.944969) (xy 117.170329 -247.908132) (xy 117.144026 -247.866536)
			(xy 117.124735 -247.82126) (xy 117.112958 -247.773476) (xy 117.108998 -247.724422) (xy 116.780056 -247.724422)
			(xy 116.779561 -247.749029) (xy 116.771666 -247.797606) (xy 116.756082 -247.844287) (xy 116.733211 -247.887864)
			(xy 116.703646 -247.927208) (xy 116.668153 -247.9613) (xy 116.62765 -247.989256) (xy 116.583188 -248.010354)
			(xy 116.535917 -248.024046) (xy 116.487062 -248.029978) (xy 116.437887 -248.027997) (xy 116.389668 -248.018153)
			(xy 116.343652 -248.000701) (xy 116.301031 -247.976094) (xy 116.26291 -247.944969) (xy 116.230275 -247.908132)
			(xy 116.203972 -247.866536) (xy 116.184681 -247.82126) (xy 116.172904 -247.773476) (xy 116.168944 -247.724422)
			(xy 115.840002 -247.724422) (xy 115.839507 -247.749029) (xy 115.831612 -247.797606) (xy 115.816028 -247.844287)
			(xy 115.793157 -247.887864) (xy 115.763592 -247.927208) (xy 115.728099 -247.9613) (xy 115.687596 -247.989256)
			(xy 115.643134 -248.010354) (xy 115.595863 -248.024046) (xy 115.547008 -248.029978) (xy 115.497833 -248.027997)
			(xy 115.449614 -248.018153) (xy 115.403598 -248.000701) (xy 115.360977 -247.976094) (xy 115.322856 -247.944969)
			(xy 115.290221 -247.908132) (xy 115.263918 -247.866536) (xy 115.244627 -247.82126) (xy 115.23285 -247.773476)
			(xy 115.22889 -247.724422) (xy 114.899948 -247.724422) (xy 114.899453 -247.749029) (xy 114.891558 -247.797606)
			(xy 114.875974 -247.844287) (xy 114.853103 -247.887864) (xy 114.823538 -247.927208) (xy 114.788045 -247.9613)
			(xy 114.747542 -247.989256) (xy 114.70308 -248.010354) (xy 114.655809 -248.024046) (xy 114.606954 -248.029978)
			(xy 114.557779 -248.027997) (xy 114.50956 -248.018153) (xy 114.463544 -248.000701) (xy 114.420923 -247.976094)
			(xy 114.382802 -247.944969) (xy 114.350167 -247.908132) (xy 114.323864 -247.866536) (xy 114.304573 -247.82126)
			(xy 114.292796 -247.773476) (xy 114.288836 -247.724422) (xy 113.960148 -247.724422) (xy 113.959653 -247.749029)
			(xy 113.951758 -247.797606) (xy 113.936174 -247.844287) (xy 113.913303 -247.887864) (xy 113.883738 -247.927208)
			(xy 113.848245 -247.9613) (xy 113.807742 -247.989256) (xy 113.76328 -248.010354) (xy 113.716009 -248.024046)
			(xy 113.667154 -248.029978) (xy 113.617979 -248.027997) (xy 113.56976 -248.018153) (xy 113.523744 -248.000701)
			(xy 113.481123 -247.976094) (xy 113.443002 -247.944969) (xy 113.410367 -247.908132) (xy 113.384064 -247.866536)
			(xy 113.364773 -247.82126) (xy 113.352996 -247.773476) (xy 113.349036 -247.724422) (xy 112.01548 -247.724422)
			(xy 111.987326 -247.745883) (xy 111.94107 -247.771036) (xy 111.891517 -247.788834) (xy 111.839827 -247.798858)
			(xy 111.787213 -247.800875) (xy 111.734908 -247.794837) (xy 111.684137 -247.780885) (xy 111.636092 -247.759346)
			(xy 111.591897 -247.730726) (xy 111.552589 -247.695695) (xy 111.519089 -247.655074) (xy 111.492183 -247.609815)
			(xy 111.4725 -247.56098) (xy 111.460503 -247.509712) (xy 111.456473 -247.457214) (xy 110.048873 -247.457214)
			(xy 110.053876 -247.459588) (xy 110.094379 -247.487544) (xy 110.129872 -247.521636) (xy 110.159437 -247.56098)
			(xy 110.182308 -247.604557) (xy 110.197892 -247.651238) (xy 110.205787 -247.699815) (xy 110.206282 -247.724422)
			(xy 110.205787 -247.749029) (xy 110.197892 -247.797606) (xy 110.182308 -247.844287) (xy 110.159437 -247.887864)
			(xy 110.129872 -247.927208) (xy 110.094379 -247.9613) (xy 110.053876 -247.989256) (xy 110.009414 -248.010354)
			(xy 109.962143 -248.024046) (xy 109.913288 -248.029978) (xy 109.864113 -248.027997) (xy 109.815894 -248.018153)
			(xy 109.769878 -248.000701) (xy 109.727257 -247.976094) (xy 109.689136 -247.944969) (xy 109.656501 -247.908132)
			(xy 109.630198 -247.866536) (xy 109.610907 -247.82126) (xy 109.59913 -247.773476) (xy 109.59517 -247.724422)
			(xy 109.266482 -247.724422) (xy 109.265987 -247.749029) (xy 109.258092 -247.797606) (xy 109.242508 -247.844287)
			(xy 109.219637 -247.887864) (xy 109.190072 -247.927208) (xy 109.154579 -247.9613) (xy 109.114076 -247.989256)
			(xy 109.069614 -248.010354) (xy 109.022343 -248.024046) (xy 108.973488 -248.029978) (xy 108.924313 -248.027997)
			(xy 108.876094 -248.018153) (xy 108.830078 -248.000701) (xy 108.787457 -247.976094) (xy 108.749336 -247.944969)
			(xy 108.716701 -247.908132) (xy 108.690398 -247.866536) (xy 108.671107 -247.82126) (xy 108.65933 -247.773476)
			(xy 108.65537 -247.724422) (xy 108.326428 -247.724422) (xy 108.325933 -247.749029) (xy 108.318038 -247.797606)
			(xy 108.302454 -247.844287) (xy 108.279583 -247.887864) (xy 108.250018 -247.927208) (xy 108.214525 -247.9613)
			(xy 108.174022 -247.989256) (xy 108.12956 -248.010354) (xy 108.082289 -248.024046) (xy 108.033434 -248.029978)
			(xy 107.984259 -248.027997) (xy 107.93604 -248.018153) (xy 107.890024 -248.000701) (xy 107.847403 -247.976094)
			(xy 107.809282 -247.944969) (xy 107.776647 -247.908132) (xy 107.750344 -247.866536) (xy 107.731053 -247.82126)
			(xy 107.719276 -247.773476) (xy 107.715316 -247.724422) (xy 107.396788 -247.724422) (xy 107.396276 -247.749868)
			(xy 107.388112 -247.800102) (xy 107.371996 -247.848376) (xy 107.348345 -247.893439) (xy 107.317772 -247.934125)
			(xy 107.281068 -247.96938) (xy 107.239184 -247.99829) (xy 107.193205 -248.020107) (xy 107.144321 -248.034267)
			(xy 107.0938 -248.040401) (xy 107.042948 -248.038352) (xy 106.993084 -248.028172) (xy 106.945498 -248.010125)
			(xy 106.901424 -247.984679) (xy 106.862002 -247.952492) (xy 106.828254 -247.914398) (xy 106.801053 -247.871384)
			(xy 106.781105 -247.824564) (xy 106.768926 -247.77515) (xy 106.764831 -247.724422) (xy 106.456734 -247.724422)
			(xy 106.456222 -247.749868) (xy 106.448058 -247.800102) (xy 106.431942 -247.848376) (xy 106.408291 -247.893439)
			(xy 106.377718 -247.934125) (xy 106.341014 -247.96938) (xy 106.29913 -247.99829) (xy 106.253151 -248.020107)
			(xy 106.204267 -248.034267) (xy 106.153746 -248.040401) (xy 106.102894 -248.038352) (xy 106.05303 -248.028172)
			(xy 106.005444 -248.010125) (xy 105.96137 -247.984679) (xy 105.921948 -247.952492) (xy 105.8882 -247.914398)
			(xy 105.860999 -247.871384) (xy 105.841051 -247.824564) (xy 105.828872 -247.77515) (xy 105.824777 -247.724422)
			(xy 105.506266 -247.724422) (xy 105.505771 -247.749029) (xy 105.497876 -247.797606) (xy 105.482292 -247.844287)
			(xy 105.459421 -247.887864) (xy 105.429856 -247.927208) (xy 105.394363 -247.9613) (xy 105.35386 -247.989256)
			(xy 105.309398 -248.010354) (xy 105.262127 -248.024046) (xy 105.213272 -248.029978) (xy 105.164097 -248.027997)
			(xy 105.115878 -248.018153) (xy 105.069862 -248.000701) (xy 105.027241 -247.976094) (xy 104.98912 -247.944969)
			(xy 104.956485 -247.908132) (xy 104.930182 -247.866536) (xy 104.910891 -247.82126) (xy 104.899114 -247.773476)
			(xy 104.895154 -247.724422) (xy 104.57688 -247.724422) (xy 104.576368 -247.749868) (xy 104.568204 -247.800102)
			(xy 104.552088 -247.848376) (xy 104.528437 -247.893439) (xy 104.497864 -247.934125) (xy 104.46116 -247.96938)
			(xy 104.419276 -247.99829) (xy 104.373297 -248.020107) (xy 104.324413 -248.034267) (xy 104.273892 -248.040401)
			(xy 104.22304 -248.038352) (xy 104.173176 -248.028172) (xy 104.12559 -248.010125) (xy 104.081516 -247.984679)
			(xy 104.042094 -247.952492) (xy 104.008346 -247.914398) (xy 103.981145 -247.871384) (xy 103.961197 -247.824564)
			(xy 103.949018 -247.77515) (xy 103.944923 -247.724422) (xy 103.636826 -247.724422) (xy 103.636314 -247.749868)
			(xy 103.62815 -247.800102) (xy 103.612034 -247.848376) (xy 103.588383 -247.893439) (xy 103.55781 -247.934125)
			(xy 103.521106 -247.96938) (xy 103.479222 -247.99829) (xy 103.433243 -248.020107) (xy 103.384359 -248.034267)
			(xy 103.333838 -248.040401) (xy 103.282986 -248.038352) (xy 103.233122 -248.028172) (xy 103.185536 -248.010125)
			(xy 103.141462 -247.984679) (xy 103.10204 -247.952492) (xy 103.068292 -247.914398) (xy 103.041091 -247.871384)
			(xy 103.021143 -247.824564) (xy 103.008964 -247.77515) (xy 103.004869 -247.724422) (xy 102.686358 -247.724422)
			(xy 102.685863 -247.749029) (xy 102.677968 -247.797606) (xy 102.662384 -247.844287) (xy 102.639513 -247.887864)
			(xy 102.609948 -247.927208) (xy 102.574455 -247.9613) (xy 102.533952 -247.989256) (xy 102.48949 -248.010354)
			(xy 102.442219 -248.024046) (xy 102.393364 -248.029978) (xy 102.344189 -248.027997) (xy 102.29597 -248.018153)
			(xy 102.249954 -248.000701) (xy 102.207333 -247.976094) (xy 102.169212 -247.944969) (xy 102.136577 -247.908132)
			(xy 102.110274 -247.866536) (xy 102.090983 -247.82126) (xy 102.079206 -247.773476) (xy 102.075246 -247.724422)
			(xy 101.756718 -247.724422) (xy 101.756206 -247.749868) (xy 101.748042 -247.800102) (xy 101.731926 -247.848376)
			(xy 101.708275 -247.893439) (xy 101.677702 -247.934125) (xy 101.640998 -247.96938) (xy 101.599114 -247.99829)
			(xy 101.553135 -248.020107) (xy 101.504251 -248.034267) (xy 101.45373 -248.040401) (xy 101.402878 -248.038352)
			(xy 101.353014 -248.028172) (xy 101.305428 -248.010125) (xy 101.261354 -247.984679) (xy 101.221932 -247.952492)
			(xy 101.188184 -247.914398) (xy 101.160983 -247.871384) (xy 101.141035 -247.824564) (xy 101.128856 -247.77515)
			(xy 101.124761 -247.724422) (xy 100.816664 -247.724422) (xy 100.816152 -247.749868) (xy 100.807988 -247.800102)
			(xy 100.791872 -247.848376) (xy 100.768221 -247.893439) (xy 100.737648 -247.934125) (xy 100.700944 -247.96938)
			(xy 100.65906 -247.99829) (xy 100.613081 -248.020107) (xy 100.564197 -248.034267) (xy 100.513676 -248.040401)
			(xy 100.462824 -248.038352) (xy 100.41296 -248.028172) (xy 100.365374 -248.010125) (xy 100.3213 -247.984679)
			(xy 100.281878 -247.952492) (xy 100.24813 -247.914398) (xy 100.220929 -247.871384) (xy 100.200981 -247.824564)
			(xy 100.188802 -247.77515) (xy 100.184707 -247.724422) (xy 99.86645 -247.724422) (xy 99.865955 -247.749029)
			(xy 99.85806 -247.797606) (xy 99.842476 -247.844287) (xy 99.819605 -247.887864) (xy 99.79004 -247.927208)
			(xy 99.754547 -247.9613) (xy 99.714044 -247.989256) (xy 99.669582 -248.010354) (xy 99.622311 -248.024046)
			(xy 99.573456 -248.029978) (xy 99.524281 -248.027997) (xy 99.476062 -248.018153) (xy 99.430046 -248.000701)
			(xy 99.387425 -247.976094) (xy 99.349304 -247.944969) (xy 99.316669 -247.908132) (xy 99.290366 -247.866536)
			(xy 99.271075 -247.82126) (xy 99.259298 -247.773476) (xy 99.255338 -247.724422) (xy 98.93681 -247.724422)
			(xy 98.936298 -247.749868) (xy 98.928134 -247.800102) (xy 98.912018 -247.848376) (xy 98.888367 -247.893439)
			(xy 98.857794 -247.934125) (xy 98.82109 -247.96938) (xy 98.779206 -247.99829) (xy 98.733227 -248.020107)
			(xy 98.684343 -248.034267) (xy 98.633822 -248.040401) (xy 98.58297 -248.038352) (xy 98.533106 -248.028172)
			(xy 98.48552 -248.010125) (xy 98.441446 -247.984679) (xy 98.402024 -247.952492) (xy 98.368276 -247.914398)
			(xy 98.341075 -247.871384) (xy 98.321127 -247.824564) (xy 98.308948 -247.77515) (xy 98.304853 -247.724422)
			(xy 97.996756 -247.724422) (xy 97.996244 -247.749868) (xy 97.98808 -247.800102) (xy 97.971964 -247.848376)
			(xy 97.948313 -247.893439) (xy 97.91774 -247.934125) (xy 97.881036 -247.96938) (xy 97.839152 -247.99829)
			(xy 97.793173 -248.020107) (xy 97.744289 -248.034267) (xy 97.693768 -248.040401) (xy 97.642916 -248.038352)
			(xy 97.593052 -248.028172) (xy 97.545466 -248.010125) (xy 97.501392 -247.984679) (xy 97.46197 -247.952492)
			(xy 97.428222 -247.914398) (xy 97.401021 -247.871384) (xy 97.381073 -247.824564) (xy 97.368894 -247.77515)
			(xy 97.364799 -247.724422) (xy 97.046288 -247.724422) (xy 97.045793 -247.749029) (xy 97.037898 -247.797606)
			(xy 97.022314 -247.844287) (xy 96.999443 -247.887864) (xy 96.969878 -247.927208) (xy 96.934385 -247.9613)
			(xy 96.893882 -247.989256) (xy 96.84942 -248.010354) (xy 96.802149 -248.024046) (xy 96.753294 -248.029978)
			(xy 96.704119 -248.027997) (xy 96.6559 -248.018153) (xy 96.609884 -248.000701) (xy 96.567263 -247.976094)
			(xy 96.529142 -247.944969) (xy 96.496507 -247.908132) (xy 96.470204 -247.866536) (xy 96.450913 -247.82126)
			(xy 96.439136 -247.773476) (xy 96.435176 -247.724422) (xy 96.116648 -247.724422) (xy 96.116136 -247.749868)
			(xy 96.107972 -247.800102) (xy 96.091856 -247.848376) (xy 96.068205 -247.893439) (xy 96.037632 -247.934125)
			(xy 96.000928 -247.96938) (xy 95.959044 -247.99829) (xy 95.913065 -248.020107) (xy 95.864181 -248.034267)
			(xy 95.81366 -248.040401) (xy 95.762808 -248.038352) (xy 95.712944 -248.028172) (xy 95.665358 -248.010125)
			(xy 95.621284 -247.984679) (xy 95.581862 -247.952492) (xy 95.548114 -247.914398) (xy 95.520913 -247.871384)
			(xy 95.500965 -247.824564) (xy 95.488786 -247.77515) (xy 95.484691 -247.724422) (xy 95.166434 -247.724422)
			(xy 95.165939 -247.749029) (xy 95.158044 -247.797606) (xy 95.14246 -247.844287) (xy 95.119589 -247.887864)
			(xy 95.090024 -247.927208) (xy 95.054531 -247.9613) (xy 95.014028 -247.989256) (xy 94.969566 -248.010354)
			(xy 94.922295 -248.024046) (xy 94.87344 -248.029978) (xy 94.824265 -248.027997) (xy 94.776046 -248.018153)
			(xy 94.73003 -248.000701) (xy 94.687409 -247.976094) (xy 94.649288 -247.944969) (xy 94.616653 -247.908132)
			(xy 94.59035 -247.866536) (xy 94.571059 -247.82126) (xy 94.559282 -247.773476) (xy 94.555322 -247.724422)
			(xy 94.236794 -247.724422) (xy 94.236282 -247.749868) (xy 94.228118 -247.800102) (xy 94.212002 -247.848376)
			(xy 94.188351 -247.893439) (xy 94.157778 -247.934125) (xy 94.121074 -247.96938) (xy 94.07919 -247.99829)
			(xy 94.033211 -248.020107) (xy 93.984327 -248.034267) (xy 93.933806 -248.040401) (xy 93.882954 -248.038352)
			(xy 93.83309 -248.028172) (xy 93.785504 -248.010125) (xy 93.74143 -247.984679) (xy 93.702008 -247.952492)
			(xy 93.66826 -247.914398) (xy 93.641059 -247.871384) (xy 93.621111 -247.824564) (xy 93.608932 -247.77515)
			(xy 93.604837 -247.724422) (xy 93.286326 -247.724422) (xy 93.285564 -247.744488) (xy 93.285056 -247.75541)
			(xy 93.288866 -247.76557) (xy 93.290876 -247.770665) (xy 93.296771 -247.779893) (xy 93.30055 -247.783858)
			(xy 93.947488 -248.430796) (xy 93.956632 -248.438987) (xy 93.979992 -248.446408) (xy 93.992192 -248.44502)
			(xy 94.07906 -248.430034) (xy 94.098618 -248.414794) (xy 94.103952 -248.403364) (xy 94.115115 -248.380141)
			(xy 94.143846 -248.337371) (xy 94.179148 -248.299842) (xy 94.220082 -248.268551) (xy 94.265558 -248.244332)
			(xy 94.314367 -248.227828) (xy 94.36521 -248.219479) (xy 94.390972 -248.21896) (xy 94.415764 -248.219419)
			(xy 94.464739 -248.227172) (xy 94.511897 -248.242492) (xy 94.556078 -248.265001) (xy 94.596193 -248.294146)
			(xy 94.631254 -248.329207) (xy 94.660399 -248.369322) (xy 94.682908 -248.413503) (xy 94.698228 -248.460661)
			(xy 94.705981 -248.509636) (xy 94.70644 -248.534428) (xy 95.014791 -248.534428) (xy 95.018886 -248.4837)
			(xy 95.031065 -248.434286) (xy 95.051013 -248.387466) (xy 95.078214 -248.344452) (xy 95.111962 -248.306358)
			(xy 95.151384 -248.274171) (xy 95.195458 -248.248725) (xy 95.243044 -248.230678) (xy 95.292908 -248.220498)
			(xy 95.34376 -248.218449) (xy 95.394281 -248.224583) (xy 95.443165 -248.238743) (xy 95.489144 -248.26056)
			(xy 95.531028 -248.28947) (xy 95.567732 -248.324725) (xy 95.598305 -248.365411) (xy 95.621956 -248.410474)
			(xy 95.638072 -248.458748) (xy 95.646236 -248.508982) (xy 95.646748 -248.534428) (xy 95.965276 -248.534428)
			(xy 95.969236 -248.485374) (xy 95.981013 -248.43759) (xy 96.000304 -248.392314) (xy 96.026607 -248.350718)
			(xy 96.059242 -248.313881) (xy 96.097363 -248.282756) (xy 96.139984 -248.258149) (xy 96.186 -248.240697)
			(xy 96.234219 -248.230853) (xy 96.283394 -248.228872) (xy 96.332249 -248.234804) (xy 96.37952 -248.248496)
			(xy 96.423982 -248.269594) (xy 96.464485 -248.29755) (xy 96.499978 -248.331642) (xy 96.529543 -248.370986)
			(xy 96.552414 -248.414563) (xy 96.567998 -248.461244) (xy 96.575893 -248.509821) (xy 96.576388 -248.534428)
			(xy 98.785184 -248.534428) (xy 98.789144 -248.485374) (xy 98.800921 -248.43759) (xy 98.820212 -248.392314)
			(xy 98.846515 -248.350718) (xy 98.87915 -248.313881) (xy 98.917271 -248.282756) (xy 98.959892 -248.258149)
			(xy 99.005908 -248.240697) (xy 99.054127 -248.230853) (xy 99.103302 -248.228872) (xy 99.152157 -248.234804)
			(xy 99.199428 -248.248496) (xy 99.24389 -248.269594) (xy 99.284393 -248.29755) (xy 99.319886 -248.331642)
			(xy 99.349451 -248.370986) (xy 99.372322 -248.414563) (xy 99.387906 -248.461244) (xy 99.395801 -248.509821)
			(xy 99.396296 -248.534428) (xy 101.605346 -248.534428) (xy 101.609306 -248.485374) (xy 101.621083 -248.43759)
			(xy 101.640374 -248.392314) (xy 101.666677 -248.350718) (xy 101.699312 -248.313881) (xy 101.737433 -248.282756)
			(xy 101.780054 -248.258149) (xy 101.82607 -248.240697) (xy 101.874289 -248.230853) (xy 101.923464 -248.228872)
			(xy 101.972319 -248.234804) (xy 102.01959 -248.248496) (xy 102.064052 -248.269594) (xy 102.104555 -248.29755)
			(xy 102.140048 -248.331642) (xy 102.169613 -248.370986) (xy 102.192484 -248.414563) (xy 102.208068 -248.461244)
			(xy 102.215963 -248.509821) (xy 102.216458 -248.534428) (xy 104.425254 -248.534428) (xy 104.429214 -248.485374)
			(xy 104.440991 -248.43759) (xy 104.460282 -248.392314) (xy 104.486585 -248.350718) (xy 104.51922 -248.313881)
			(xy 104.557341 -248.282756) (xy 104.599962 -248.258149) (xy 104.645978 -248.240697) (xy 104.694197 -248.230853)
			(xy 104.743372 -248.228872) (xy 104.792227 -248.234804) (xy 104.839498 -248.248496) (xy 104.88396 -248.269594)
			(xy 104.924463 -248.29755) (xy 104.959956 -248.331642) (xy 104.989521 -248.370986) (xy 105.012392 -248.414563)
			(xy 105.027976 -248.461244) (xy 105.035871 -248.509821) (xy 105.036366 -248.534428) (xy 107.245162 -248.534428)
			(xy 107.249122 -248.485374) (xy 107.260899 -248.43759) (xy 107.28019 -248.392314) (xy 107.306493 -248.350718)
			(xy 107.339128 -248.313881) (xy 107.377249 -248.282756) (xy 107.41987 -248.258149) (xy 107.465886 -248.240697)
			(xy 107.514105 -248.230853) (xy 107.56328 -248.228872) (xy 107.612135 -248.234804) (xy 107.659406 -248.248496)
			(xy 107.703868 -248.269594) (xy 107.744371 -248.29755) (xy 107.779864 -248.331642) (xy 107.809429 -248.370986)
			(xy 107.8323 -248.414563) (xy 107.847884 -248.461244) (xy 107.855779 -248.509821) (xy 107.856274 -248.534428)
			(xy 108.174785 -248.534428) (xy 108.17888 -248.4837) (xy 108.191059 -248.434286) (xy 108.211007 -248.387466)
			(xy 108.238208 -248.344452) (xy 108.271956 -248.306358) (xy 108.311378 -248.274171) (xy 108.355452 -248.248725)
			(xy 108.403038 -248.230678) (xy 108.452902 -248.220498) (xy 108.503754 -248.218449) (xy 108.554275 -248.224583)
			(xy 108.603159 -248.238743) (xy 108.649138 -248.26056) (xy 108.691022 -248.28947) (xy 108.727726 -248.324725)
			(xy 108.758299 -248.365411) (xy 108.78195 -248.410474) (xy 108.798066 -248.458748) (xy 108.80623 -248.508982)
			(xy 108.806742 -248.534428) (xy 109.114839 -248.534428) (xy 109.118934 -248.4837) (xy 109.131113 -248.434286)
			(xy 109.151061 -248.387466) (xy 109.178262 -248.344452) (xy 109.21201 -248.306358) (xy 109.251432 -248.274171)
			(xy 109.295506 -248.248725) (xy 109.343092 -248.230678) (xy 109.392956 -248.220498) (xy 109.443808 -248.218449)
			(xy 109.494329 -248.224583) (xy 109.543213 -248.238743) (xy 109.589192 -248.26056) (xy 109.631076 -248.28947)
			(xy 109.66778 -248.324725) (xy 109.698353 -248.365411) (xy 109.722004 -248.410474) (xy 109.73812 -248.458748)
			(xy 109.746284 -248.508982) (xy 109.746796 -248.534428) (xy 110.065324 -248.534428) (xy 110.069284 -248.485374)
			(xy 110.081061 -248.43759) (xy 110.100352 -248.392314) (xy 110.126655 -248.350718) (xy 110.15929 -248.313881)
			(xy 110.197411 -248.282756) (xy 110.240032 -248.258149) (xy 110.286048 -248.240697) (xy 110.334267 -248.230853)
			(xy 110.383442 -248.228872) (xy 110.432297 -248.234804) (xy 110.479568 -248.248496) (xy 110.52403 -248.269594)
			(xy 110.564533 -248.29755) (xy 110.600026 -248.331642) (xy 110.629591 -248.370986) (xy 110.652462 -248.414563)
			(xy 110.668046 -248.461244) (xy 110.675941 -248.509821) (xy 110.676436 -248.534428) (xy 112.878882 -248.534428)
			(xy 112.882842 -248.485374) (xy 112.894619 -248.43759) (xy 112.91391 -248.392314) (xy 112.940213 -248.350718)
			(xy 112.972848 -248.313881) (xy 113.010969 -248.282756) (xy 113.05359 -248.258149) (xy 113.099606 -248.240697)
			(xy 113.147825 -248.230853) (xy 113.197 -248.228872) (xy 113.245855 -248.234804) (xy 113.293126 -248.248496)
			(xy 113.337588 -248.269594) (xy 113.378091 -248.29755) (xy 113.413584 -248.331642) (xy 113.443149 -248.370986)
			(xy 113.46602 -248.414563) (xy 113.481604 -248.461244) (xy 113.489499 -248.509821) (xy 113.489994 -248.534428)
			(xy 113.818936 -248.534428) (xy 113.822896 -248.485374) (xy 113.834673 -248.43759) (xy 113.853964 -248.392314)
			(xy 113.880267 -248.350718) (xy 113.912902 -248.313881) (xy 113.951023 -248.282756) (xy 113.993644 -248.258149)
			(xy 114.03966 -248.240697) (xy 114.087879 -248.230853) (xy 114.137054 -248.228872) (xy 114.185909 -248.234804)
			(xy 114.23318 -248.248496) (xy 114.277642 -248.269594) (xy 114.318145 -248.29755) (xy 114.353638 -248.331642)
			(xy 114.383203 -248.370986) (xy 114.406074 -248.414563) (xy 114.421658 -248.461244) (xy 114.429553 -248.509821)
			(xy 114.430048 -248.534428) (xy 114.75899 -248.534428) (xy 114.76295 -248.485374) (xy 114.774727 -248.43759)
			(xy 114.794018 -248.392314) (xy 114.820321 -248.350718) (xy 114.852956 -248.313881) (xy 114.891077 -248.282756)
			(xy 114.933698 -248.258149) (xy 114.979714 -248.240697) (xy 115.027933 -248.230853) (xy 115.077108 -248.228872)
			(xy 115.125963 -248.234804) (xy 115.173234 -248.248496) (xy 115.217696 -248.269594) (xy 115.258199 -248.29755)
			(xy 115.293692 -248.331642) (xy 115.323257 -248.370986) (xy 115.346128 -248.414563) (xy 115.361712 -248.461244)
			(xy 115.369607 -248.509821) (xy 115.370102 -248.534428) (xy 115.699044 -248.534428) (xy 115.703004 -248.485374)
			(xy 115.714781 -248.43759) (xy 115.734072 -248.392314) (xy 115.760375 -248.350718) (xy 115.79301 -248.313881)
			(xy 115.831131 -248.282756) (xy 115.873752 -248.258149) (xy 115.919768 -248.240697) (xy 115.967987 -248.230853)
			(xy 116.017162 -248.228872) (xy 116.066017 -248.234804) (xy 116.113288 -248.248496) (xy 116.15775 -248.269594)
			(xy 116.198253 -248.29755) (xy 116.233746 -248.331642) (xy 116.263311 -248.370986) (xy 116.286182 -248.414563)
			(xy 116.301766 -248.461244) (xy 116.309661 -248.509821) (xy 116.310156 -248.534428) (xy 118.518952 -248.534428)
			(xy 118.522912 -248.485374) (xy 118.534689 -248.43759) (xy 118.55398 -248.392314) (xy 118.580283 -248.350718)
			(xy 118.612918 -248.313881) (xy 118.651039 -248.282756) (xy 118.69366 -248.258149) (xy 118.739676 -248.240697)
			(xy 118.787895 -248.230853) (xy 118.83707 -248.228872) (xy 118.885925 -248.234804) (xy 118.933196 -248.248496)
			(xy 118.977658 -248.269594) (xy 119.018161 -248.29755) (xy 119.053654 -248.331642) (xy 119.083219 -248.370986)
			(xy 119.10609 -248.414563) (xy 119.121674 -248.461244) (xy 119.129569 -248.509821) (xy 119.130064 -248.534428)
			(xy 121.33886 -248.534428) (xy 121.34282 -248.485374) (xy 121.354597 -248.43759) (xy 121.373888 -248.392314)
			(xy 121.400191 -248.350718) (xy 121.432826 -248.313881) (xy 121.470947 -248.282756) (xy 121.513568 -248.258149)
			(xy 121.559584 -248.240697) (xy 121.607803 -248.230853) (xy 121.656978 -248.228872) (xy 121.705833 -248.234804)
			(xy 121.753104 -248.248496) (xy 121.797566 -248.269594) (xy 121.838069 -248.29755) (xy 121.873562 -248.331642)
			(xy 121.903127 -248.370986) (xy 121.925998 -248.414563) (xy 121.941582 -248.461244) (xy 121.949477 -248.509821)
			(xy 121.949972 -248.534428) (xy 124.159022 -248.534428) (xy 124.162982 -248.485374) (xy 124.174759 -248.43759)
			(xy 124.19405 -248.392314) (xy 124.220353 -248.350718) (xy 124.252988 -248.313881) (xy 124.291109 -248.282756)
			(xy 124.33373 -248.258149) (xy 124.379746 -248.240697) (xy 124.427965 -248.230853) (xy 124.47714 -248.228872)
			(xy 124.525995 -248.234804) (xy 124.573266 -248.248496) (xy 124.617728 -248.269594) (xy 124.658231 -248.29755)
			(xy 124.693724 -248.331642) (xy 124.723289 -248.370986) (xy 124.74616 -248.414563) (xy 124.761744 -248.461244)
			(xy 124.769639 -248.509821) (xy 124.770134 -248.534428) (xy 124.769639 -248.559035) (xy 124.761744 -248.607612)
			(xy 124.74616 -248.654293) (xy 124.723289 -248.69787) (xy 124.693724 -248.737214) (xy 124.658231 -248.771306)
			(xy 124.617728 -248.799262) (xy 124.573266 -248.82036) (xy 124.525995 -248.834052) (xy 124.47714 -248.839984)
			(xy 124.427965 -248.838003) (xy 124.379746 -248.828159) (xy 124.33373 -248.810707) (xy 124.291109 -248.7861)
			(xy 124.252988 -248.754975) (xy 124.220353 -248.718138) (xy 124.19405 -248.676542) (xy 124.174759 -248.631266)
			(xy 124.162982 -248.583482) (xy 124.159022 -248.534428) (xy 121.949972 -248.534428) (xy 121.949477 -248.559035)
			(xy 121.941582 -248.607612) (xy 121.925998 -248.654293) (xy 121.903127 -248.69787) (xy 121.873562 -248.737214)
			(xy 121.838069 -248.771306) (xy 121.797566 -248.799262) (xy 121.753104 -248.82036) (xy 121.705833 -248.834052)
			(xy 121.656978 -248.839984) (xy 121.607803 -248.838003) (xy 121.559584 -248.828159) (xy 121.513568 -248.810707)
			(xy 121.470947 -248.7861) (xy 121.432826 -248.754975) (xy 121.400191 -248.718138) (xy 121.373888 -248.676542)
			(xy 121.354597 -248.631266) (xy 121.34282 -248.583482) (xy 121.33886 -248.534428) (xy 119.130064 -248.534428)
			(xy 119.129569 -248.559035) (xy 119.121674 -248.607612) (xy 119.10609 -248.654293) (xy 119.083219 -248.69787)
			(xy 119.053654 -248.737214) (xy 119.018161 -248.771306) (xy 118.977658 -248.799262) (xy 118.933196 -248.82036)
			(xy 118.885925 -248.834052) (xy 118.83707 -248.839984) (xy 118.787895 -248.838003) (xy 118.739676 -248.828159)
			(xy 118.69366 -248.810707) (xy 118.651039 -248.7861) (xy 118.612918 -248.754975) (xy 118.580283 -248.718138)
			(xy 118.55398 -248.676542) (xy 118.534689 -248.631266) (xy 118.522912 -248.583482) (xy 118.518952 -248.534428)
			(xy 116.310156 -248.534428) (xy 116.309661 -248.559035) (xy 116.301766 -248.607612) (xy 116.286182 -248.654293)
			(xy 116.263311 -248.69787) (xy 116.233746 -248.737214) (xy 116.198253 -248.771306) (xy 116.15775 -248.799262)
			(xy 116.113288 -248.82036) (xy 116.066017 -248.834052) (xy 116.017162 -248.839984) (xy 115.967987 -248.838003)
			(xy 115.919768 -248.828159) (xy 115.873752 -248.810707) (xy 115.831131 -248.7861) (xy 115.79301 -248.754975)
			(xy 115.760375 -248.718138) (xy 115.734072 -248.676542) (xy 115.714781 -248.631266) (xy 115.703004 -248.583482)
			(xy 115.699044 -248.534428) (xy 115.370102 -248.534428) (xy 115.369607 -248.559035) (xy 115.361712 -248.607612)
			(xy 115.346128 -248.654293) (xy 115.323257 -248.69787) (xy 115.293692 -248.737214) (xy 115.258199 -248.771306)
			(xy 115.217696 -248.799262) (xy 115.173234 -248.82036) (xy 115.125963 -248.834052) (xy 115.077108 -248.839984)
			(xy 115.027933 -248.838003) (xy 114.979714 -248.828159) (xy 114.933698 -248.810707) (xy 114.891077 -248.7861)
			(xy 114.852956 -248.754975) (xy 114.820321 -248.718138) (xy 114.794018 -248.676542) (xy 114.774727 -248.631266)
			(xy 114.76295 -248.583482) (xy 114.75899 -248.534428) (xy 114.430048 -248.534428) (xy 114.429553 -248.559035)
			(xy 114.421658 -248.607612) (xy 114.406074 -248.654293) (xy 114.383203 -248.69787) (xy 114.353638 -248.737214)
			(xy 114.318145 -248.771306) (xy 114.277642 -248.799262) (xy 114.23318 -248.82036) (xy 114.185909 -248.834052)
			(xy 114.137054 -248.839984) (xy 114.087879 -248.838003) (xy 114.03966 -248.828159) (xy 113.993644 -248.810707)
			(xy 113.951023 -248.7861) (xy 113.912902 -248.754975) (xy 113.880267 -248.718138) (xy 113.853964 -248.676542)
			(xy 113.834673 -248.631266) (xy 113.822896 -248.583482) (xy 113.818936 -248.534428) (xy 113.489994 -248.534428)
			(xy 113.489499 -248.559035) (xy 113.481604 -248.607612) (xy 113.46602 -248.654293) (xy 113.443149 -248.69787)
			(xy 113.413584 -248.737214) (xy 113.378091 -248.771306) (xy 113.337588 -248.799262) (xy 113.293126 -248.82036)
			(xy 113.245855 -248.834052) (xy 113.197 -248.839984) (xy 113.147825 -248.838003) (xy 113.099606 -248.828159)
			(xy 113.05359 -248.810707) (xy 113.010969 -248.7861) (xy 112.972848 -248.754975) (xy 112.940213 -248.718138)
			(xy 112.91391 -248.676542) (xy 112.894619 -248.631266) (xy 112.882842 -248.583482) (xy 112.878882 -248.534428)
			(xy 110.676436 -248.534428) (xy 110.675941 -248.559035) (xy 110.668046 -248.607612) (xy 110.652462 -248.654293)
			(xy 110.629591 -248.69787) (xy 110.600026 -248.737214) (xy 110.564533 -248.771306) (xy 110.52403 -248.799262)
			(xy 110.479568 -248.82036) (xy 110.432297 -248.834052) (xy 110.383442 -248.839984) (xy 110.334267 -248.838003)
			(xy 110.286048 -248.828159) (xy 110.240032 -248.810707) (xy 110.197411 -248.7861) (xy 110.15929 -248.754975)
			(xy 110.126655 -248.718138) (xy 110.100352 -248.676542) (xy 110.081061 -248.631266) (xy 110.069284 -248.583482)
			(xy 110.065324 -248.534428) (xy 109.746796 -248.534428) (xy 109.746284 -248.559874) (xy 109.73812 -248.610108)
			(xy 109.722004 -248.658382) (xy 109.698353 -248.703445) (xy 109.66778 -248.744131) (xy 109.631076 -248.779386)
			(xy 109.589192 -248.808296) (xy 109.543213 -248.830113) (xy 109.494329 -248.844273) (xy 109.443808 -248.850407)
			(xy 109.392956 -248.848358) (xy 109.343092 -248.838178) (xy 109.295506 -248.820131) (xy 109.251432 -248.794685)
			(xy 109.21201 -248.762498) (xy 109.178262 -248.724404) (xy 109.151061 -248.68139) (xy 109.131113 -248.63457)
			(xy 109.118934 -248.585156) (xy 109.114839 -248.534428) (xy 108.806742 -248.534428) (xy 108.80623 -248.559874)
			(xy 108.798066 -248.610108) (xy 108.78195 -248.658382) (xy 108.758299 -248.703445) (xy 108.727726 -248.744131)
			(xy 108.691022 -248.779386) (xy 108.649138 -248.808296) (xy 108.603159 -248.830113) (xy 108.554275 -248.844273)
			(xy 108.503754 -248.850407) (xy 108.452902 -248.848358) (xy 108.403038 -248.838178) (xy 108.355452 -248.820131)
			(xy 108.311378 -248.794685) (xy 108.271956 -248.762498) (xy 108.238208 -248.724404) (xy 108.211007 -248.68139)
			(xy 108.191059 -248.63457) (xy 108.17888 -248.585156) (xy 108.174785 -248.534428) (xy 107.856274 -248.534428)
			(xy 107.855779 -248.559035) (xy 107.847884 -248.607612) (xy 107.8323 -248.654293) (xy 107.809429 -248.69787)
			(xy 107.779864 -248.737214) (xy 107.744371 -248.771306) (xy 107.703868 -248.799262) (xy 107.659406 -248.82036)
			(xy 107.612135 -248.834052) (xy 107.56328 -248.839984) (xy 107.514105 -248.838003) (xy 107.465886 -248.828159)
			(xy 107.41987 -248.810707) (xy 107.377249 -248.7861) (xy 107.339128 -248.754975) (xy 107.306493 -248.718138)
			(xy 107.28019 -248.676542) (xy 107.260899 -248.631266) (xy 107.249122 -248.583482) (xy 107.245162 -248.534428)
			(xy 105.036366 -248.534428) (xy 105.035871 -248.559035) (xy 105.027976 -248.607612) (xy 105.012392 -248.654293)
			(xy 104.989521 -248.69787) (xy 104.959956 -248.737214) (xy 104.924463 -248.771306) (xy 104.88396 -248.799262)
			(xy 104.839498 -248.82036) (xy 104.792227 -248.834052) (xy 104.743372 -248.839984) (xy 104.694197 -248.838003)
			(xy 104.645978 -248.828159) (xy 104.599962 -248.810707) (xy 104.557341 -248.7861) (xy 104.51922 -248.754975)
			(xy 104.486585 -248.718138) (xy 104.460282 -248.676542) (xy 104.440991 -248.631266) (xy 104.429214 -248.583482)
			(xy 104.425254 -248.534428) (xy 102.216458 -248.534428) (xy 102.215963 -248.559035) (xy 102.208068 -248.607612)
			(xy 102.192484 -248.654293) (xy 102.169613 -248.69787) (xy 102.140048 -248.737214) (xy 102.104555 -248.771306)
			(xy 102.064052 -248.799262) (xy 102.01959 -248.82036) (xy 101.972319 -248.834052) (xy 101.923464 -248.839984)
			(xy 101.874289 -248.838003) (xy 101.82607 -248.828159) (xy 101.780054 -248.810707) (xy 101.737433 -248.7861)
			(xy 101.699312 -248.754975) (xy 101.666677 -248.718138) (xy 101.640374 -248.676542) (xy 101.621083 -248.631266)
			(xy 101.609306 -248.583482) (xy 101.605346 -248.534428) (xy 99.396296 -248.534428) (xy 99.395801 -248.559035)
			(xy 99.387906 -248.607612) (xy 99.372322 -248.654293) (xy 99.349451 -248.69787) (xy 99.319886 -248.737214)
			(xy 99.284393 -248.771306) (xy 99.24389 -248.799262) (xy 99.199428 -248.82036) (xy 99.152157 -248.834052)
			(xy 99.103302 -248.839984) (xy 99.054127 -248.838003) (xy 99.005908 -248.828159) (xy 98.959892 -248.810707)
			(xy 98.917271 -248.7861) (xy 98.87915 -248.754975) (xy 98.846515 -248.718138) (xy 98.820212 -248.676542)
			(xy 98.800921 -248.631266) (xy 98.789144 -248.583482) (xy 98.785184 -248.534428) (xy 96.576388 -248.534428)
			(xy 96.575893 -248.559035) (xy 96.567998 -248.607612) (xy 96.552414 -248.654293) (xy 96.529543 -248.69787)
			(xy 96.499978 -248.737214) (xy 96.464485 -248.771306) (xy 96.423982 -248.799262) (xy 96.37952 -248.82036)
			(xy 96.332249 -248.834052) (xy 96.283394 -248.839984) (xy 96.234219 -248.838003) (xy 96.186 -248.828159)
			(xy 96.139984 -248.810707) (xy 96.097363 -248.7861) (xy 96.059242 -248.754975) (xy 96.026607 -248.718138)
			(xy 96.000304 -248.676542) (xy 95.981013 -248.631266) (xy 95.969236 -248.583482) (xy 95.965276 -248.534428)
			(xy 95.646748 -248.534428) (xy 95.646236 -248.559874) (xy 95.638072 -248.610108) (xy 95.621956 -248.658382)
			(xy 95.598305 -248.703445) (xy 95.567732 -248.744131) (xy 95.531028 -248.779386) (xy 95.489144 -248.808296)
			(xy 95.443165 -248.830113) (xy 95.394281 -248.844273) (xy 95.34376 -248.850407) (xy 95.292908 -248.848358)
			(xy 95.243044 -248.838178) (xy 95.195458 -248.820131) (xy 95.151384 -248.794685) (xy 95.111962 -248.762498)
			(xy 95.078214 -248.724404) (xy 95.051013 -248.68139) (xy 95.031065 -248.63457) (xy 95.018886 -248.585156)
			(xy 95.014791 -248.534428) (xy 94.70644 -248.534428) (xy 94.705928 -248.560188) (xy 94.697556 -248.611024)
			(xy 94.681039 -248.659825) (xy 94.656817 -248.705296) (xy 94.625531 -248.74623) (xy 94.588012 -248.781539)
			(xy 94.545258 -248.810286) (xy 94.522036 -248.821448) (xy 94.510606 -248.826782) (xy 94.495366 -248.84634)
			(xy 94.48038 -248.933208) (xy 94.479013 -248.9454) (xy 94.486457 -248.968736) (xy 94.494604 -248.977912)
			(xy 94.611952 -249.09526) (xy 94.618662 -249.101372) (xy 94.635185 -249.108855) (xy 94.653276 -249.110164)
			(xy 94.670704 -249.105138) (xy 94.678246 -249.100086) (xy 94.698167 -249.085765) (xy 94.741627 -249.063005)
			(xy 94.78817 -249.047498) (xy 94.836597 -249.039645) (xy 94.861126 -249.039126) (xy 94.885117 -249.039574)
			(xy 94.932507 -249.047084) (xy 94.978139 -249.061916) (xy 95.020889 -249.083703) (xy 95.059705 -249.11191)
			(xy 95.093629 -249.145841) (xy 95.121829 -249.184662) (xy 95.143607 -249.227416) (xy 95.15843 -249.273051)
			(xy 95.165931 -249.320443) (xy 95.166434 -249.344434) (xy 95.484691 -249.344434) (xy 95.488786 -249.293706)
			(xy 95.500965 -249.244292) (xy 95.520913 -249.197472) (xy 95.548114 -249.154458) (xy 95.581862 -249.116364)
			(xy 95.621284 -249.084177) (xy 95.665358 -249.058731) (xy 95.712944 -249.040684) (xy 95.762808 -249.030504)
			(xy 95.81366 -249.028455) (xy 95.864181 -249.034589) (xy 95.913065 -249.048749) (xy 95.959044 -249.070566)
			(xy 96.000928 -249.099476) (xy 96.037632 -249.134731) (xy 96.068205 -249.175417) (xy 96.091856 -249.22048)
			(xy 96.107972 -249.268754) (xy 96.116136 -249.318988) (xy 96.116648 -249.344434) (xy 96.435176 -249.344434)
			(xy 96.439136 -249.29538) (xy 96.450913 -249.247596) (xy 96.470204 -249.20232) (xy 96.496507 -249.160724)
			(xy 96.529142 -249.123887) (xy 96.567263 -249.092762) (xy 96.609884 -249.068155) (xy 96.6559 -249.050703)
			(xy 96.704119 -249.040859) (xy 96.753294 -249.038878) (xy 96.802149 -249.04481) (xy 96.84942 -249.058502)
			(xy 96.893882 -249.0796) (xy 96.934385 -249.107556) (xy 96.969878 -249.141648) (xy 96.999443 -249.180992)
			(xy 97.022314 -249.224569) (xy 97.037898 -249.27125) (xy 97.045793 -249.319827) (xy 97.046288 -249.344434)
			(xy 97.37523 -249.344434) (xy 97.37919 -249.29538) (xy 97.390967 -249.247596) (xy 97.410258 -249.20232)
			(xy 97.436561 -249.160724) (xy 97.469196 -249.123887) (xy 97.507317 -249.092762) (xy 97.549938 -249.068155)
			(xy 97.595954 -249.050703) (xy 97.644173 -249.040859) (xy 97.693348 -249.038878) (xy 97.742203 -249.04481)
			(xy 97.789474 -249.058502) (xy 97.833936 -249.0796) (xy 97.874439 -249.107556) (xy 97.909932 -249.141648)
			(xy 97.939497 -249.180992) (xy 97.962368 -249.224569) (xy 97.977952 -249.27125) (xy 97.985847 -249.319827)
			(xy 97.986342 -249.344434) (xy 98.315284 -249.344434) (xy 98.319244 -249.29538) (xy 98.331021 -249.247596)
			(xy 98.350312 -249.20232) (xy 98.376615 -249.160724) (xy 98.40925 -249.123887) (xy 98.447371 -249.092762)
			(xy 98.489992 -249.068155) (xy 98.536008 -249.050703) (xy 98.584227 -249.040859) (xy 98.633402 -249.038878)
			(xy 98.682257 -249.04481) (xy 98.729528 -249.058502) (xy 98.77399 -249.0796) (xy 98.814493 -249.107556)
			(xy 98.849986 -249.141648) (xy 98.879551 -249.180992) (xy 98.902422 -249.224569) (xy 98.918006 -249.27125)
			(xy 98.925901 -249.319827) (xy 98.926396 -249.344434) (xy 99.255338 -249.344434) (xy 99.259298 -249.29538)
			(xy 99.271075 -249.247596) (xy 99.290366 -249.20232) (xy 99.316669 -249.160724) (xy 99.349304 -249.123887)
			(xy 99.387425 -249.092762) (xy 99.430046 -249.068155) (xy 99.476062 -249.050703) (xy 99.524281 -249.040859)
			(xy 99.573456 -249.038878) (xy 99.622311 -249.04481) (xy 99.669582 -249.058502) (xy 99.714044 -249.0796)
			(xy 99.754547 -249.107556) (xy 99.79004 -249.141648) (xy 99.819605 -249.180992) (xy 99.842476 -249.224569)
			(xy 99.85806 -249.27125) (xy 99.865955 -249.319827) (xy 99.86645 -249.344434) (xy 101.135192 -249.344434)
			(xy 101.139152 -249.29538) (xy 101.150929 -249.247596) (xy 101.17022 -249.20232) (xy 101.196523 -249.160724)
			(xy 101.229158 -249.123887) (xy 101.267279 -249.092762) (xy 101.3099 -249.068155) (xy 101.355916 -249.050703)
			(xy 101.404135 -249.040859) (xy 101.45331 -249.038878) (xy 101.502165 -249.04481) (xy 101.549436 -249.058502)
			(xy 101.593898 -249.0796) (xy 101.634401 -249.107556) (xy 101.669894 -249.141648) (xy 101.699459 -249.180992)
			(xy 101.72233 -249.224569) (xy 101.737914 -249.27125) (xy 101.745809 -249.319827) (xy 101.746304 -249.344434)
			(xy 103.0153 -249.344434) (xy 103.01926 -249.29538) (xy 103.031037 -249.247596) (xy 103.050328 -249.20232)
			(xy 103.076631 -249.160724) (xy 103.109266 -249.123887) (xy 103.147387 -249.092762) (xy 103.190008 -249.068155)
			(xy 103.236024 -249.050703) (xy 103.284243 -249.040859) (xy 103.333418 -249.038878) (xy 103.382273 -249.04481)
			(xy 103.429544 -249.058502) (xy 103.474006 -249.0796) (xy 103.514509 -249.107556) (xy 103.550002 -249.141648)
			(xy 103.579567 -249.180992) (xy 103.602438 -249.224569) (xy 103.618022 -249.27125) (xy 103.625917 -249.319827)
			(xy 103.626412 -249.344434) (xy 104.895154 -249.344434) (xy 104.899114 -249.29538) (xy 104.910891 -249.247596)
			(xy 104.930182 -249.20232) (xy 104.956485 -249.160724) (xy 104.98912 -249.123887) (xy 105.027241 -249.092762)
			(xy 105.069862 -249.068155) (xy 105.115878 -249.050703) (xy 105.164097 -249.040859) (xy 105.213272 -249.038878)
			(xy 105.262127 -249.04481) (xy 105.309398 -249.058502) (xy 105.35386 -249.0796) (xy 105.394363 -249.107556)
			(xy 105.429856 -249.141648) (xy 105.459421 -249.180992) (xy 105.482292 -249.224569) (xy 105.497876 -249.27125)
			(xy 105.505771 -249.319827) (xy 105.506266 -249.344434) (xy 106.775262 -249.344434) (xy 106.779222 -249.29538)
			(xy 106.790999 -249.247596) (xy 106.81029 -249.20232) (xy 106.836593 -249.160724) (xy 106.869228 -249.123887)
			(xy 106.907349 -249.092762) (xy 106.94997 -249.068155) (xy 106.995986 -249.050703) (xy 107.044205 -249.040859)
			(xy 107.09338 -249.038878) (xy 107.142235 -249.04481) (xy 107.189506 -249.058502) (xy 107.233968 -249.0796)
			(xy 107.274471 -249.107556) (xy 107.309964 -249.141648) (xy 107.339529 -249.180992) (xy 107.3624 -249.224569)
			(xy 107.377984 -249.27125) (xy 107.385879 -249.319827) (xy 107.386374 -249.344434) (xy 108.65537 -249.344434)
			(xy 108.65933 -249.29538) (xy 108.671107 -249.247596) (xy 108.690398 -249.20232) (xy 108.716701 -249.160724)
			(xy 108.749336 -249.123887) (xy 108.787457 -249.092762) (xy 108.830078 -249.068155) (xy 108.876094 -249.050703)
			(xy 108.924313 -249.040859) (xy 108.973488 -249.038878) (xy 109.022343 -249.04481) (xy 109.069614 -249.058502)
			(xy 109.114076 -249.0796) (xy 109.154579 -249.107556) (xy 109.190072 -249.141648) (xy 109.219637 -249.180992)
			(xy 109.242508 -249.224569) (xy 109.258092 -249.27125) (xy 109.265987 -249.319827) (xy 109.266482 -249.344434)
			(xy 109.266124 -249.362214) (xy 111.456473 -249.362214) (xy 111.460503 -249.309716) (xy 111.4725 -249.258448)
			(xy 111.492183 -249.209613) (xy 111.519089 -249.164354) (xy 111.552589 -249.123733) (xy 111.591897 -249.088702)
			(xy 111.636092 -249.060082) (xy 111.684137 -249.038543) (xy 111.734908 -249.024591) (xy 111.787213 -249.018553)
			(xy 111.839827 -249.02057) (xy 111.891517 -249.030594) (xy 111.94107 -249.048392) (xy 111.987326 -249.073545)
			(xy 112.0292 -249.105464) (xy 112.065712 -249.143402) (xy 112.096004 -249.186468) (xy 112.119367 -249.233653)
			(xy 112.135253 -249.283852) (xy 112.14329 -249.335888) (xy 112.143454 -249.344434) (xy 113.349036 -249.344434)
			(xy 113.352996 -249.29538) (xy 113.364773 -249.247596) (xy 113.384064 -249.20232) (xy 113.410367 -249.160724)
			(xy 113.443002 -249.123887) (xy 113.481123 -249.092762) (xy 113.523744 -249.068155) (xy 113.56976 -249.050703)
			(xy 113.617979 -249.040859) (xy 113.667154 -249.038878) (xy 113.716009 -249.04481) (xy 113.76328 -249.058502)
			(xy 113.807742 -249.0796) (xy 113.848245 -249.107556) (xy 113.883738 -249.141648) (xy 113.913303 -249.180992)
			(xy 113.936174 -249.224569) (xy 113.951758 -249.27125) (xy 113.959653 -249.319827) (xy 113.960148 -249.344434)
			(xy 115.22889 -249.344434) (xy 115.23285 -249.29538) (xy 115.244627 -249.247596) (xy 115.263918 -249.20232)
			(xy 115.290221 -249.160724) (xy 115.322856 -249.123887) (xy 115.360977 -249.092762) (xy 115.403598 -249.068155)
			(xy 115.449614 -249.050703) (xy 115.497833 -249.040859) (xy 115.547008 -249.038878) (xy 115.595863 -249.04481)
			(xy 115.643134 -249.058502) (xy 115.687596 -249.0796) (xy 115.728099 -249.107556) (xy 115.763592 -249.141648)
			(xy 115.793157 -249.180992) (xy 115.816028 -249.224569) (xy 115.831612 -249.27125) (xy 115.839507 -249.319827)
			(xy 115.840002 -249.344434) (xy 117.108998 -249.344434) (xy 117.112958 -249.29538) (xy 117.124735 -249.247596)
			(xy 117.144026 -249.20232) (xy 117.170329 -249.160724) (xy 117.202964 -249.123887) (xy 117.241085 -249.092762)
			(xy 117.283706 -249.068155) (xy 117.329722 -249.050703) (xy 117.377941 -249.040859) (xy 117.427116 -249.038878)
			(xy 117.475971 -249.04481) (xy 117.523242 -249.058502) (xy 117.567704 -249.0796) (xy 117.608207 -249.107556)
			(xy 117.6437 -249.141648) (xy 117.673265 -249.180992) (xy 117.696136 -249.224569) (xy 117.71172 -249.27125)
			(xy 117.719615 -249.319827) (xy 117.72011 -249.344434) (xy 118.988852 -249.344434) (xy 118.992812 -249.29538)
			(xy 119.004589 -249.247596) (xy 119.02388 -249.20232) (xy 119.050183 -249.160724) (xy 119.082818 -249.123887)
			(xy 119.120939 -249.092762) (xy 119.16356 -249.068155) (xy 119.209576 -249.050703) (xy 119.257795 -249.040859)
			(xy 119.30697 -249.038878) (xy 119.355825 -249.04481) (xy 119.403096 -249.058502) (xy 119.447558 -249.0796)
			(xy 119.488061 -249.107556) (xy 119.523554 -249.141648) (xy 119.553119 -249.180992) (xy 119.57599 -249.224569)
			(xy 119.591574 -249.27125) (xy 119.599469 -249.319827) (xy 119.599964 -249.344434) (xy 120.86896 -249.344434)
			(xy 120.87292 -249.29538) (xy 120.884697 -249.247596) (xy 120.903988 -249.20232) (xy 120.930291 -249.160724)
			(xy 120.962926 -249.123887) (xy 121.001047 -249.092762) (xy 121.043668 -249.068155) (xy 121.089684 -249.050703)
			(xy 121.137903 -249.040859) (xy 121.187078 -249.038878) (xy 121.235933 -249.04481) (xy 121.283204 -249.058502)
			(xy 121.327666 -249.0796) (xy 121.368169 -249.107556) (xy 121.403662 -249.141648) (xy 121.433227 -249.180992)
			(xy 121.456098 -249.224569) (xy 121.471682 -249.27125) (xy 121.479577 -249.319827) (xy 121.480072 -249.344434)
			(xy 122.748814 -249.344434) (xy 122.752774 -249.29538) (xy 122.764551 -249.247596) (xy 122.783842 -249.20232)
			(xy 122.810145 -249.160724) (xy 122.84278 -249.123887) (xy 122.880901 -249.092762) (xy 122.923522 -249.068155)
			(xy 122.969538 -249.050703) (xy 123.017757 -249.040859) (xy 123.066932 -249.038878) (xy 123.115787 -249.04481)
			(xy 123.163058 -249.058502) (xy 123.20752 -249.0796) (xy 123.248023 -249.107556) (xy 123.283516 -249.141648)
			(xy 123.313081 -249.180992) (xy 123.335952 -249.224569) (xy 123.351536 -249.27125) (xy 123.359431 -249.319827)
			(xy 123.359926 -249.344434) (xy 124.628922 -249.344434) (xy 124.632882 -249.29538) (xy 124.644659 -249.247596)
			(xy 124.66395 -249.20232) (xy 124.690253 -249.160724) (xy 124.722888 -249.123887) (xy 124.761009 -249.092762)
			(xy 124.80363 -249.068155) (xy 124.849646 -249.050703) (xy 124.897865 -249.040859) (xy 124.94704 -249.038878)
			(xy 124.995895 -249.04481) (xy 125.043166 -249.058502) (xy 125.087628 -249.0796) (xy 125.128131 -249.107556)
			(xy 125.163624 -249.141648) (xy 125.193189 -249.180992) (xy 125.21606 -249.224569) (xy 125.231644 -249.27125)
			(xy 125.239539 -249.319827) (xy 125.240034 -249.344434) (xy 125.239539 -249.369041) (xy 125.231644 -249.417618)
			(xy 125.21606 -249.464299) (xy 125.193189 -249.507876) (xy 125.163624 -249.54722) (xy 125.128131 -249.581312)
			(xy 125.087628 -249.609268) (xy 125.043166 -249.630366) (xy 124.995895 -249.644058) (xy 124.94704 -249.64999)
			(xy 124.897865 -249.648009) (xy 124.849646 -249.638165) (xy 124.80363 -249.620713) (xy 124.761009 -249.596106)
			(xy 124.722888 -249.564981) (xy 124.690253 -249.528144) (xy 124.66395 -249.486548) (xy 124.644659 -249.441272)
			(xy 124.632882 -249.393488) (xy 124.628922 -249.344434) (xy 123.359926 -249.344434) (xy 123.359431 -249.369041)
			(xy 123.351536 -249.417618) (xy 123.335952 -249.464299) (xy 123.313081 -249.507876) (xy 123.283516 -249.54722)
			(xy 123.248023 -249.581312) (xy 123.20752 -249.609268) (xy 123.163058 -249.630366) (xy 123.115787 -249.644058)
			(xy 123.066932 -249.64999) (xy 123.017757 -249.648009) (xy 122.969538 -249.638165) (xy 122.923522 -249.620713)
			(xy 122.880901 -249.596106) (xy 122.84278 -249.564981) (xy 122.810145 -249.528144) (xy 122.783842 -249.486548)
			(xy 122.764551 -249.441272) (xy 122.752774 -249.393488) (xy 122.748814 -249.344434) (xy 121.480072 -249.344434)
			(xy 121.479577 -249.369041) (xy 121.471682 -249.417618) (xy 121.456098 -249.464299) (xy 121.433227 -249.507876)
			(xy 121.403662 -249.54722) (xy 121.368169 -249.581312) (xy 121.327666 -249.609268) (xy 121.283204 -249.630366)
			(xy 121.235933 -249.644058) (xy 121.187078 -249.64999) (xy 121.137903 -249.648009) (xy 121.089684 -249.638165)
			(xy 121.043668 -249.620713) (xy 121.001047 -249.596106) (xy 120.962926 -249.564981) (xy 120.930291 -249.528144)
			(xy 120.903988 -249.486548) (xy 120.884697 -249.441272) (xy 120.87292 -249.393488) (xy 120.86896 -249.344434)
			(xy 119.599964 -249.344434) (xy 119.599469 -249.369041) (xy 119.591574 -249.417618) (xy 119.57599 -249.464299)
			(xy 119.553119 -249.507876) (xy 119.523554 -249.54722) (xy 119.488061 -249.581312) (xy 119.447558 -249.609268)
			(xy 119.403096 -249.630366) (xy 119.355825 -249.644058) (xy 119.30697 -249.64999) (xy 119.257795 -249.648009)
			(xy 119.209576 -249.638165) (xy 119.16356 -249.620713) (xy 119.120939 -249.596106) (xy 119.082818 -249.564981)
			(xy 119.050183 -249.528144) (xy 119.02388 -249.486548) (xy 119.004589 -249.441272) (xy 118.992812 -249.393488)
			(xy 118.988852 -249.344434) (xy 117.72011 -249.344434) (xy 117.719615 -249.369041) (xy 117.71172 -249.417618)
			(xy 117.696136 -249.464299) (xy 117.673265 -249.507876) (xy 117.6437 -249.54722) (xy 117.608207 -249.581312)
			(xy 117.567704 -249.609268) (xy 117.523242 -249.630366) (xy 117.475971 -249.644058) (xy 117.427116 -249.64999)
			(xy 117.377941 -249.648009) (xy 117.329722 -249.638165) (xy 117.283706 -249.620713) (xy 117.241085 -249.596106)
			(xy 117.202964 -249.564981) (xy 117.170329 -249.528144) (xy 117.144026 -249.486548) (xy 117.124735 -249.441272)
			(xy 117.112958 -249.393488) (xy 117.108998 -249.344434) (xy 115.840002 -249.344434) (xy 115.839507 -249.369041)
			(xy 115.831612 -249.417618) (xy 115.816028 -249.464299) (xy 115.793157 -249.507876) (xy 115.763592 -249.54722)
			(xy 115.728099 -249.581312) (xy 115.687596 -249.609268) (xy 115.643134 -249.630366) (xy 115.595863 -249.644058)
			(xy 115.547008 -249.64999) (xy 115.497833 -249.648009) (xy 115.449614 -249.638165) (xy 115.403598 -249.620713)
			(xy 115.360977 -249.596106) (xy 115.322856 -249.564981) (xy 115.290221 -249.528144) (xy 115.263918 -249.486548)
			(xy 115.244627 -249.441272) (xy 115.23285 -249.393488) (xy 115.22889 -249.344434) (xy 113.960148 -249.344434)
			(xy 113.959653 -249.369041) (xy 113.951758 -249.417618) (xy 113.936174 -249.464299) (xy 113.913303 -249.507876)
			(xy 113.883738 -249.54722) (xy 113.848245 -249.581312) (xy 113.807742 -249.609268) (xy 113.76328 -249.630366)
			(xy 113.716009 -249.644058) (xy 113.667154 -249.64999) (xy 113.617979 -249.648009) (xy 113.56976 -249.638165)
			(xy 113.523744 -249.620713) (xy 113.481123 -249.596106) (xy 113.443002 -249.564981) (xy 113.410367 -249.528144)
			(xy 113.384064 -249.486548) (xy 113.364773 -249.441272) (xy 113.352996 -249.393488) (xy 113.349036 -249.344434)
			(xy 112.143454 -249.344434) (xy 112.143794 -249.362214) (xy 112.14329 -249.38854) (xy 112.135253 -249.440576)
			(xy 112.119367 -249.490775) (xy 112.096004 -249.53796) (xy 112.065712 -249.581026) (xy 112.0292 -249.618964)
			(xy 111.987326 -249.650883) (xy 111.94107 -249.676036) (xy 111.891517 -249.693834) (xy 111.839827 -249.703858)
			(xy 111.787213 -249.705875) (xy 111.734908 -249.699837) (xy 111.684137 -249.685885) (xy 111.636092 -249.664346)
			(xy 111.591897 -249.635726) (xy 111.552589 -249.600695) (xy 111.519089 -249.560074) (xy 111.492183 -249.514815)
			(xy 111.4725 -249.46598) (xy 111.460503 -249.414712) (xy 111.456473 -249.362214) (xy 109.266124 -249.362214)
			(xy 109.265987 -249.369041) (xy 109.258092 -249.417618) (xy 109.242508 -249.464299) (xy 109.219637 -249.507876)
			(xy 109.190072 -249.54722) (xy 109.154579 -249.581312) (xy 109.114076 -249.609268) (xy 109.069614 -249.630366)
			(xy 109.022343 -249.644058) (xy 108.973488 -249.64999) (xy 108.924313 -249.648009) (xy 108.876094 -249.638165)
			(xy 108.830078 -249.620713) (xy 108.787457 -249.596106) (xy 108.749336 -249.564981) (xy 108.716701 -249.528144)
			(xy 108.690398 -249.486548) (xy 108.671107 -249.441272) (xy 108.65933 -249.393488) (xy 108.65537 -249.344434)
			(xy 107.386374 -249.344434) (xy 107.385879 -249.369041) (xy 107.377984 -249.417618) (xy 107.3624 -249.464299)
			(xy 107.339529 -249.507876) (xy 107.309964 -249.54722) (xy 107.274471 -249.581312) (xy 107.233968 -249.609268)
			(xy 107.189506 -249.630366) (xy 107.142235 -249.644058) (xy 107.09338 -249.64999) (xy 107.044205 -249.648009)
			(xy 106.995986 -249.638165) (xy 106.94997 -249.620713) (xy 106.907349 -249.596106) (xy 106.869228 -249.564981)
			(xy 106.836593 -249.528144) (xy 106.81029 -249.486548) (xy 106.790999 -249.441272) (xy 106.779222 -249.393488)
			(xy 106.775262 -249.344434) (xy 105.506266 -249.344434) (xy 105.505771 -249.369041) (xy 105.497876 -249.417618)
			(xy 105.482292 -249.464299) (xy 105.459421 -249.507876) (xy 105.429856 -249.54722) (xy 105.394363 -249.581312)
			(xy 105.35386 -249.609268) (xy 105.309398 -249.630366) (xy 105.262127 -249.644058) (xy 105.213272 -249.64999)
			(xy 105.164097 -249.648009) (xy 105.115878 -249.638165) (xy 105.069862 -249.620713) (xy 105.027241 -249.596106)
			(xy 104.98912 -249.564981) (xy 104.956485 -249.528144) (xy 104.930182 -249.486548) (xy 104.910891 -249.441272)
			(xy 104.899114 -249.393488) (xy 104.895154 -249.344434) (xy 103.626412 -249.344434) (xy 103.625917 -249.369041)
			(xy 103.618022 -249.417618) (xy 103.602438 -249.464299) (xy 103.579567 -249.507876) (xy 103.550002 -249.54722)
			(xy 103.514509 -249.581312) (xy 103.474006 -249.609268) (xy 103.429544 -249.630366) (xy 103.382273 -249.644058)
			(xy 103.333418 -249.64999) (xy 103.284243 -249.648009) (xy 103.236024 -249.638165) (xy 103.190008 -249.620713)
			(xy 103.147387 -249.596106) (xy 103.109266 -249.564981) (xy 103.076631 -249.528144) (xy 103.050328 -249.486548)
			(xy 103.031037 -249.441272) (xy 103.01926 -249.393488) (xy 103.0153 -249.344434) (xy 101.746304 -249.344434)
			(xy 101.745809 -249.369041) (xy 101.737914 -249.417618) (xy 101.72233 -249.464299) (xy 101.699459 -249.507876)
			(xy 101.669894 -249.54722) (xy 101.634401 -249.581312) (xy 101.593898 -249.609268) (xy 101.549436 -249.630366)
			(xy 101.502165 -249.644058) (xy 101.45331 -249.64999) (xy 101.404135 -249.648009) (xy 101.355916 -249.638165)
			(xy 101.3099 -249.620713) (xy 101.267279 -249.596106) (xy 101.229158 -249.564981) (xy 101.196523 -249.528144)
			(xy 101.17022 -249.486548) (xy 101.150929 -249.441272) (xy 101.139152 -249.393488) (xy 101.135192 -249.344434)
			(xy 99.86645 -249.344434) (xy 99.865955 -249.369041) (xy 99.85806 -249.417618) (xy 99.842476 -249.464299)
			(xy 99.819605 -249.507876) (xy 99.79004 -249.54722) (xy 99.754547 -249.581312) (xy 99.714044 -249.609268)
			(xy 99.669582 -249.630366) (xy 99.622311 -249.644058) (xy 99.573456 -249.64999) (xy 99.524281 -249.648009)
			(xy 99.476062 -249.638165) (xy 99.430046 -249.620713) (xy 99.387425 -249.596106) (xy 99.349304 -249.564981)
			(xy 99.316669 -249.528144) (xy 99.290366 -249.486548) (xy 99.271075 -249.441272) (xy 99.259298 -249.393488)
			(xy 99.255338 -249.344434) (xy 98.926396 -249.344434) (xy 98.925901 -249.369041) (xy 98.918006 -249.417618)
			(xy 98.902422 -249.464299) (xy 98.879551 -249.507876) (xy 98.849986 -249.54722) (xy 98.814493 -249.581312)
			(xy 98.77399 -249.609268) (xy 98.729528 -249.630366) (xy 98.682257 -249.644058) (xy 98.633402 -249.64999)
			(xy 98.584227 -249.648009) (xy 98.536008 -249.638165) (xy 98.489992 -249.620713) (xy 98.447371 -249.596106)
			(xy 98.40925 -249.564981) (xy 98.376615 -249.528144) (xy 98.350312 -249.486548) (xy 98.331021 -249.441272)
			(xy 98.319244 -249.393488) (xy 98.315284 -249.344434) (xy 97.986342 -249.344434) (xy 97.985847 -249.369041)
			(xy 97.977952 -249.417618) (xy 97.962368 -249.464299) (xy 97.939497 -249.507876) (xy 97.909932 -249.54722)
			(xy 97.874439 -249.581312) (xy 97.833936 -249.609268) (xy 97.789474 -249.630366) (xy 97.742203 -249.644058)
			(xy 97.693348 -249.64999) (xy 97.644173 -249.648009) (xy 97.595954 -249.638165) (xy 97.549938 -249.620713)
			(xy 97.507317 -249.596106) (xy 97.469196 -249.564981) (xy 97.436561 -249.528144) (xy 97.410258 -249.486548)
			(xy 97.390967 -249.441272) (xy 97.37919 -249.393488) (xy 97.37523 -249.344434) (xy 97.046288 -249.344434)
			(xy 97.045793 -249.369041) (xy 97.037898 -249.417618) (xy 97.022314 -249.464299) (xy 96.999443 -249.507876)
			(xy 96.969878 -249.54722) (xy 96.934385 -249.581312) (xy 96.893882 -249.609268) (xy 96.84942 -249.630366)
			(xy 96.802149 -249.644058) (xy 96.753294 -249.64999) (xy 96.704119 -249.648009) (xy 96.6559 -249.638165)
			(xy 96.609884 -249.620713) (xy 96.567263 -249.596106) (xy 96.529142 -249.564981) (xy 96.496507 -249.528144)
			(xy 96.470204 -249.486548) (xy 96.450913 -249.441272) (xy 96.439136 -249.393488) (xy 96.435176 -249.344434)
			(xy 96.116648 -249.344434) (xy 96.116136 -249.36988) (xy 96.107972 -249.420114) (xy 96.091856 -249.468388)
			(xy 96.068205 -249.513451) (xy 96.037632 -249.554137) (xy 96.000928 -249.589392) (xy 95.959044 -249.618302)
			(xy 95.913065 -249.640119) (xy 95.864181 -249.654279) (xy 95.81366 -249.660413) (xy 95.762808 -249.658364)
			(xy 95.712944 -249.648184) (xy 95.665358 -249.630137) (xy 95.621284 -249.604691) (xy 95.581862 -249.572504)
			(xy 95.548114 -249.53441) (xy 95.520913 -249.491396) (xy 95.500965 -249.444576) (xy 95.488786 -249.395162)
			(xy 95.484691 -249.344434) (xy 95.166434 -249.344434) (xy 95.165921 -249.368962) (xy 95.158037 -249.417381)
			(xy 95.142526 -249.46392) (xy 95.119784 -249.507387) (xy 95.105474 -249.527314) (xy 95.094044 -249.542554)
			(xy 95.096838 -249.580146) (xy 95.350076 -249.833384) (xy 95.364554 -249.840496) (xy 95.37319 -249.841766)
			(xy 95.398593 -249.845705) (xy 95.447746 -249.860748) (xy 95.49381 -249.88356) (xy 95.535566 -249.913539)
			(xy 95.571909 -249.949891) (xy 95.601878 -249.991654) (xy 95.62468 -250.037723) (xy 95.639711 -250.08688)
			(xy 95.6437 -250.112276) (xy 95.64497 -250.120912) (xy 95.652082 -250.13539) (xy 95.671132 -250.15444)
			(xy 95.965276 -250.15444) (xy 95.969236 -250.105386) (xy 95.981013 -250.057602) (xy 96.000304 -250.012326)
			(xy 96.026607 -249.97073) (xy 96.059242 -249.933893) (xy 96.097363 -249.902768) (xy 96.139984 -249.878161)
			(xy 96.186 -249.860709) (xy 96.234219 -249.850865) (xy 96.283394 -249.848884) (xy 96.332249 -249.854816)
			(xy 96.37952 -249.868508) (xy 96.423982 -249.889606) (xy 96.464485 -249.917562) (xy 96.499978 -249.951654)
			(xy 96.529543 -249.990998) (xy 96.552414 -250.034575) (xy 96.567998 -250.081256) (xy 96.575893 -250.129833)
			(xy 96.576388 -250.15444) (xy 96.90533 -250.15444) (xy 96.90929 -250.105386) (xy 96.921067 -250.057602)
			(xy 96.940358 -250.012326) (xy 96.966661 -249.97073) (xy 96.999296 -249.933893) (xy 97.037417 -249.902768)
			(xy 97.080038 -249.878161) (xy 97.126054 -249.860709) (xy 97.174273 -249.850865) (xy 97.223448 -249.848884)
			(xy 97.272303 -249.854816) (xy 97.319574 -249.868508) (xy 97.364036 -249.889606) (xy 97.404539 -249.917562)
			(xy 97.440032 -249.951654) (xy 97.469597 -249.990998) (xy 97.492468 -250.034575) (xy 97.508052 -250.081256)
			(xy 97.515947 -250.129833) (xy 97.516442 -250.15444) (xy 97.84513 -250.15444) (xy 97.84909 -250.105386)
			(xy 97.860867 -250.057602) (xy 97.880158 -250.012326) (xy 97.906461 -249.97073) (xy 97.939096 -249.933893)
			(xy 97.977217 -249.902768) (xy 98.019838 -249.878161) (xy 98.065854 -249.860709) (xy 98.114073 -249.850865)
			(xy 98.163248 -249.848884) (xy 98.212103 -249.854816) (xy 98.259374 -249.868508) (xy 98.303836 -249.889606)
			(xy 98.344339 -249.917562) (xy 98.379832 -249.951654) (xy 98.409397 -249.990998) (xy 98.432268 -250.034575)
			(xy 98.447852 -250.081256) (xy 98.455747 -250.129833) (xy 98.456242 -250.15444) (xy 98.785184 -250.15444)
			(xy 98.789144 -250.105386) (xy 98.800921 -250.057602) (xy 98.820212 -250.012326) (xy 98.846515 -249.97073)
			(xy 98.87915 -249.933893) (xy 98.917271 -249.902768) (xy 98.959892 -249.878161) (xy 99.005908 -249.860709)
			(xy 99.054127 -249.850865) (xy 99.103302 -249.848884) (xy 99.152157 -249.854816) (xy 99.199428 -249.868508)
			(xy 99.24389 -249.889606) (xy 99.284393 -249.917562) (xy 99.319886 -249.951654) (xy 99.349451 -249.990998)
			(xy 99.372322 -250.034575) (xy 99.387906 -250.081256) (xy 99.395801 -250.129833) (xy 99.396296 -250.15444)
			(xy 99.725238 -250.15444) (xy 99.729198 -250.105386) (xy 99.740975 -250.057602) (xy 99.760266 -250.012326)
			(xy 99.786569 -249.97073) (xy 99.819204 -249.933893) (xy 99.857325 -249.902768) (xy 99.899946 -249.878161)
			(xy 99.945962 -249.860709) (xy 99.994181 -249.850865) (xy 100.043356 -249.848884) (xy 100.092211 -249.854816)
			(xy 100.139482 -249.868508) (xy 100.183944 -249.889606) (xy 100.224447 -249.917562) (xy 100.25994 -249.951654)
			(xy 100.289505 -249.990998) (xy 100.312376 -250.034575) (xy 100.32796 -250.081256) (xy 100.335855 -250.129833)
			(xy 100.33635 -250.15444) (xy 101.605346 -250.15444) (xy 101.609306 -250.105386) (xy 101.621083 -250.057602)
			(xy 101.640374 -250.012326) (xy 101.666677 -249.97073) (xy 101.699312 -249.933893) (xy 101.737433 -249.902768)
			(xy 101.780054 -249.878161) (xy 101.82607 -249.860709) (xy 101.874289 -249.850865) (xy 101.923464 -249.848884)
			(xy 101.972319 -249.854816) (xy 102.01959 -249.868508) (xy 102.064052 -249.889606) (xy 102.104555 -249.917562)
			(xy 102.140048 -249.951654) (xy 102.169613 -249.990998) (xy 102.192484 -250.034575) (xy 102.208068 -250.081256)
			(xy 102.215963 -250.129833) (xy 102.216458 -250.15444) (xy 103.4852 -250.15444) (xy 103.48916 -250.105386)
			(xy 103.500937 -250.057602) (xy 103.520228 -250.012326) (xy 103.546531 -249.97073) (xy 103.579166 -249.933893)
			(xy 103.617287 -249.902768) (xy 103.659908 -249.878161) (xy 103.705924 -249.860709) (xy 103.754143 -249.850865)
			(xy 103.803318 -249.848884) (xy 103.852173 -249.854816) (xy 103.899444 -249.868508) (xy 103.943906 -249.889606)
			(xy 103.984409 -249.917562) (xy 104.019902 -249.951654) (xy 104.049467 -249.990998) (xy 104.072338 -250.034575)
			(xy 104.087922 -250.081256) (xy 104.095817 -250.129833) (xy 104.096312 -250.15444) (xy 105.365308 -250.15444)
			(xy 105.369268 -250.105386) (xy 105.381045 -250.057602) (xy 105.400336 -250.012326) (xy 105.426639 -249.97073)
			(xy 105.459274 -249.933893) (xy 105.497395 -249.902768) (xy 105.540016 -249.878161) (xy 105.586032 -249.860709)
			(xy 105.634251 -249.850865) (xy 105.683426 -249.848884) (xy 105.732281 -249.854816) (xy 105.779552 -249.868508)
			(xy 105.824014 -249.889606) (xy 105.864517 -249.917562) (xy 105.90001 -249.951654) (xy 105.929575 -249.990998)
			(xy 105.952446 -250.034575) (xy 105.96803 -250.081256) (xy 105.975925 -250.129833) (xy 105.97642 -250.15444)
			(xy 107.245162 -250.15444) (xy 107.249122 -250.105386) (xy 107.260899 -250.057602) (xy 107.28019 -250.012326)
			(xy 107.306493 -249.97073) (xy 107.339128 -249.933893) (xy 107.377249 -249.902768) (xy 107.41987 -249.878161)
			(xy 107.465886 -249.860709) (xy 107.514105 -249.850865) (xy 107.56328 -249.848884) (xy 107.612135 -249.854816)
			(xy 107.659406 -249.868508) (xy 107.703868 -249.889606) (xy 107.744371 -249.917562) (xy 107.779864 -249.951654)
			(xy 107.809429 -249.990998) (xy 107.8323 -250.034575) (xy 107.847884 -250.081256) (xy 107.855779 -250.129833)
			(xy 107.856274 -250.15444) (xy 109.12527 -250.15444) (xy 109.12923 -250.105386) (xy 109.141007 -250.057602)
			(xy 109.160298 -250.012326) (xy 109.186601 -249.97073) (xy 109.219236 -249.933893) (xy 109.257357 -249.902768)
			(xy 109.299978 -249.878161) (xy 109.345994 -249.860709) (xy 109.394213 -249.850865) (xy 109.443388 -249.848884)
			(xy 109.492243 -249.854816) (xy 109.539514 -249.868508) (xy 109.583976 -249.889606) (xy 109.624479 -249.917562)
			(xy 109.659972 -249.951654) (xy 109.689537 -249.990998) (xy 109.712408 -250.034575) (xy 109.727992 -250.081256)
			(xy 109.735887 -250.129833) (xy 109.736382 -250.15444) (xy 112.878882 -250.15444) (xy 112.882842 -250.105386)
			(xy 112.894619 -250.057602) (xy 112.91391 -250.012326) (xy 112.940213 -249.97073) (xy 112.972848 -249.933893)
			(xy 113.010969 -249.902768) (xy 113.05359 -249.878161) (xy 113.099606 -249.860709) (xy 113.147825 -249.850865)
			(xy 113.197 -249.848884) (xy 113.245855 -249.854816) (xy 113.293126 -249.868508) (xy 113.337588 -249.889606)
			(xy 113.378091 -249.917562) (xy 113.413584 -249.951654) (xy 113.443149 -249.990998) (xy 113.46602 -250.034575)
			(xy 113.481604 -250.081256) (xy 113.489499 -250.129833) (xy 113.489994 -250.15444) (xy 114.75899 -250.15444)
			(xy 114.76295 -250.105386) (xy 114.774727 -250.057602) (xy 114.794018 -250.012326) (xy 114.820321 -249.97073)
			(xy 114.852956 -249.933893) (xy 114.891077 -249.902768) (xy 114.933698 -249.878161) (xy 114.979714 -249.860709)
			(xy 115.027933 -249.850865) (xy 115.077108 -249.848884) (xy 115.125963 -249.854816) (xy 115.173234 -249.868508)
			(xy 115.217696 -249.889606) (xy 115.258199 -249.917562) (xy 115.293692 -249.951654) (xy 115.323257 -249.990998)
			(xy 115.346128 -250.034575) (xy 115.361712 -250.081256) (xy 115.369607 -250.129833) (xy 115.370102 -250.15444)
			(xy 116.638844 -250.15444) (xy 116.642804 -250.105386) (xy 116.654581 -250.057602) (xy 116.673872 -250.012326)
			(xy 116.700175 -249.97073) (xy 116.73281 -249.933893) (xy 116.770931 -249.902768) (xy 116.813552 -249.878161)
			(xy 116.859568 -249.860709) (xy 116.907787 -249.850865) (xy 116.956962 -249.848884) (xy 117.005817 -249.854816)
			(xy 117.053088 -249.868508) (xy 117.09755 -249.889606) (xy 117.138053 -249.917562) (xy 117.173546 -249.951654)
			(xy 117.203111 -249.990998) (xy 117.225982 -250.034575) (xy 117.241566 -250.081256) (xy 117.249461 -250.129833)
			(xy 117.249956 -250.15444) (xy 118.518952 -250.15444) (xy 118.522912 -250.105386) (xy 118.534689 -250.057602)
			(xy 118.55398 -250.012326) (xy 118.580283 -249.97073) (xy 118.612918 -249.933893) (xy 118.651039 -249.902768)
			(xy 118.69366 -249.878161) (xy 118.739676 -249.860709) (xy 118.787895 -249.850865) (xy 118.83707 -249.848884)
			(xy 118.885925 -249.854816) (xy 118.933196 -249.868508) (xy 118.977658 -249.889606) (xy 119.018161 -249.917562)
			(xy 119.053654 -249.951654) (xy 119.083219 -249.990998) (xy 119.10609 -250.034575) (xy 119.121674 -250.081256)
			(xy 119.129569 -250.129833) (xy 119.130064 -250.15444) (xy 120.398806 -250.15444) (xy 120.402766 -250.105386)
			(xy 120.414543 -250.057602) (xy 120.433834 -250.012326) (xy 120.460137 -249.97073) (xy 120.492772 -249.933893)
			(xy 120.530893 -249.902768) (xy 120.573514 -249.878161) (xy 120.61953 -249.860709) (xy 120.667749 -249.850865)
			(xy 120.716924 -249.848884) (xy 120.765779 -249.854816) (xy 120.81305 -249.868508) (xy 120.857512 -249.889606)
			(xy 120.898015 -249.917562) (xy 120.933508 -249.951654) (xy 120.963073 -249.990998) (xy 120.985944 -250.034575)
			(xy 121.001528 -250.081256) (xy 121.009423 -250.129833) (xy 121.009918 -250.15444) (xy 122.278914 -250.15444)
			(xy 122.282874 -250.105386) (xy 122.294651 -250.057602) (xy 122.313942 -250.012326) (xy 122.340245 -249.97073)
			(xy 122.37288 -249.933893) (xy 122.411001 -249.902768) (xy 122.453622 -249.878161) (xy 122.499638 -249.860709)
			(xy 122.547857 -249.850865) (xy 122.597032 -249.848884) (xy 122.645887 -249.854816) (xy 122.693158 -249.868508)
			(xy 122.73762 -249.889606) (xy 122.778123 -249.917562) (xy 122.813616 -249.951654) (xy 122.843181 -249.990998)
			(xy 122.866052 -250.034575) (xy 122.881636 -250.081256) (xy 122.889531 -250.129833) (xy 122.890026 -250.15444)
			(xy 124.159022 -250.15444) (xy 124.162982 -250.105386) (xy 124.174759 -250.057602) (xy 124.19405 -250.012326)
			(xy 124.220353 -249.97073) (xy 124.252988 -249.933893) (xy 124.291109 -249.902768) (xy 124.33373 -249.878161)
			(xy 124.379746 -249.860709) (xy 124.427965 -249.850865) (xy 124.47714 -249.848884) (xy 124.525995 -249.854816)
			(xy 124.573266 -249.868508) (xy 124.617728 -249.889606) (xy 124.658231 -249.917562) (xy 124.693724 -249.951654)
			(xy 124.723289 -249.990998) (xy 124.74616 -250.034575) (xy 124.761744 -250.081256) (xy 124.769639 -250.129833)
			(xy 124.770134 -250.15444) (xy 124.769639 -250.179047) (xy 124.761744 -250.227624) (xy 124.74616 -250.274305)
			(xy 124.723289 -250.317882) (xy 124.693724 -250.357226) (xy 124.658231 -250.391318) (xy 124.617728 -250.419274)
			(xy 124.573266 -250.440372) (xy 124.525995 -250.454064) (xy 124.47714 -250.459996) (xy 124.427965 -250.458015)
			(xy 124.379746 -250.448171) (xy 124.33373 -250.430719) (xy 124.291109 -250.406112) (xy 124.252988 -250.374987)
			(xy 124.220353 -250.33815) (xy 124.19405 -250.296554) (xy 124.174759 -250.251278) (xy 124.162982 -250.203494)
			(xy 124.159022 -250.15444) (xy 122.890026 -250.15444) (xy 122.889531 -250.179047) (xy 122.881636 -250.227624)
			(xy 122.866052 -250.274305) (xy 122.843181 -250.317882) (xy 122.813616 -250.357226) (xy 122.778123 -250.391318)
			(xy 122.73762 -250.419274) (xy 122.693158 -250.440372) (xy 122.645887 -250.454064) (xy 122.597032 -250.459996)
			(xy 122.547857 -250.458015) (xy 122.499638 -250.448171) (xy 122.453622 -250.430719) (xy 122.411001 -250.406112)
			(xy 122.37288 -250.374987) (xy 122.340245 -250.33815) (xy 122.313942 -250.296554) (xy 122.294651 -250.251278)
			(xy 122.282874 -250.203494) (xy 122.278914 -250.15444) (xy 121.009918 -250.15444) (xy 121.009423 -250.179047)
			(xy 121.001528 -250.227624) (xy 120.985944 -250.274305) (xy 120.963073 -250.317882) (xy 120.933508 -250.357226)
			(xy 120.898015 -250.391318) (xy 120.857512 -250.419274) (xy 120.81305 -250.440372) (xy 120.765779 -250.454064)
			(xy 120.716924 -250.459996) (xy 120.667749 -250.458015) (xy 120.61953 -250.448171) (xy 120.573514 -250.430719)
			(xy 120.530893 -250.406112) (xy 120.492772 -250.374987) (xy 120.460137 -250.33815) (xy 120.433834 -250.296554)
			(xy 120.414543 -250.251278) (xy 120.402766 -250.203494) (xy 120.398806 -250.15444) (xy 119.130064 -250.15444)
			(xy 119.129569 -250.179047) (xy 119.121674 -250.227624) (xy 119.10609 -250.274305) (xy 119.083219 -250.317882)
			(xy 119.053654 -250.357226) (xy 119.018161 -250.391318) (xy 118.977658 -250.419274) (xy 118.933196 -250.440372)
			(xy 118.885925 -250.454064) (xy 118.83707 -250.459996) (xy 118.787895 -250.458015) (xy 118.739676 -250.448171)
			(xy 118.69366 -250.430719) (xy 118.651039 -250.406112) (xy 118.612918 -250.374987) (xy 118.580283 -250.33815)
			(xy 118.55398 -250.296554) (xy 118.534689 -250.251278) (xy 118.522912 -250.203494) (xy 118.518952 -250.15444)
			(xy 117.249956 -250.15444) (xy 117.249461 -250.179047) (xy 117.241566 -250.227624) (xy 117.225982 -250.274305)
			(xy 117.203111 -250.317882) (xy 117.173546 -250.357226) (xy 117.138053 -250.391318) (xy 117.09755 -250.419274)
			(xy 117.053088 -250.440372) (xy 117.005817 -250.454064) (xy 116.956962 -250.459996) (xy 116.907787 -250.458015)
			(xy 116.859568 -250.448171) (xy 116.813552 -250.430719) (xy 116.770931 -250.406112) (xy 116.73281 -250.374987)
			(xy 116.700175 -250.33815) (xy 116.673872 -250.296554) (xy 116.654581 -250.251278) (xy 116.642804 -250.203494)
			(xy 116.638844 -250.15444) (xy 115.370102 -250.15444) (xy 115.369607 -250.179047) (xy 115.361712 -250.227624)
			(xy 115.346128 -250.274305) (xy 115.323257 -250.317882) (xy 115.293692 -250.357226) (xy 115.258199 -250.391318)
			(xy 115.217696 -250.419274) (xy 115.173234 -250.440372) (xy 115.125963 -250.454064) (xy 115.077108 -250.459996)
			(xy 115.027933 -250.458015) (xy 114.979714 -250.448171) (xy 114.933698 -250.430719) (xy 114.891077 -250.406112)
			(xy 114.852956 -250.374987) (xy 114.820321 -250.33815) (xy 114.794018 -250.296554) (xy 114.774727 -250.251278)
			(xy 114.76295 -250.203494) (xy 114.75899 -250.15444) (xy 113.489994 -250.15444) (xy 113.489499 -250.179047)
			(xy 113.481604 -250.227624) (xy 113.46602 -250.274305) (xy 113.443149 -250.317882) (xy 113.413584 -250.357226)
			(xy 113.378091 -250.391318) (xy 113.337588 -250.419274) (xy 113.293126 -250.440372) (xy 113.245855 -250.454064)
			(xy 113.197 -250.459996) (xy 113.147825 -250.458015) (xy 113.099606 -250.448171) (xy 113.05359 -250.430719)
			(xy 113.010969 -250.406112) (xy 112.972848 -250.374987) (xy 112.940213 -250.33815) (xy 112.91391 -250.296554)
			(xy 112.894619 -250.251278) (xy 112.882842 -250.203494) (xy 112.878882 -250.15444) (xy 109.736382 -250.15444)
			(xy 109.735887 -250.179047) (xy 109.727992 -250.227624) (xy 109.712408 -250.274305) (xy 109.689537 -250.317882)
			(xy 109.659972 -250.357226) (xy 109.624479 -250.391318) (xy 109.583976 -250.419274) (xy 109.539514 -250.440372)
			(xy 109.492243 -250.454064) (xy 109.443388 -250.459996) (xy 109.394213 -250.458015) (xy 109.345994 -250.448171)
			(xy 109.299978 -250.430719) (xy 109.257357 -250.406112) (xy 109.219236 -250.374987) (xy 109.186601 -250.33815)
			(xy 109.160298 -250.296554) (xy 109.141007 -250.251278) (xy 109.12923 -250.203494) (xy 109.12527 -250.15444)
			(xy 107.856274 -250.15444) (xy 107.855779 -250.179047) (xy 107.847884 -250.227624) (xy 107.8323 -250.274305)
			(xy 107.809429 -250.317882) (xy 107.779864 -250.357226) (xy 107.744371 -250.391318) (xy 107.703868 -250.419274)
			(xy 107.659406 -250.440372) (xy 107.612135 -250.454064) (xy 107.56328 -250.459996) (xy 107.514105 -250.458015)
			(xy 107.465886 -250.448171) (xy 107.41987 -250.430719) (xy 107.377249 -250.406112) (xy 107.339128 -250.374987)
			(xy 107.306493 -250.33815) (xy 107.28019 -250.296554) (xy 107.260899 -250.251278) (xy 107.249122 -250.203494)
			(xy 107.245162 -250.15444) (xy 105.97642 -250.15444) (xy 105.975925 -250.179047) (xy 105.96803 -250.227624)
			(xy 105.952446 -250.274305) (xy 105.929575 -250.317882) (xy 105.90001 -250.357226) (xy 105.864517 -250.391318)
			(xy 105.824014 -250.419274) (xy 105.779552 -250.440372) (xy 105.732281 -250.454064) (xy 105.683426 -250.459996)
			(xy 105.634251 -250.458015) (xy 105.586032 -250.448171) (xy 105.540016 -250.430719) (xy 105.497395 -250.406112)
			(xy 105.459274 -250.374987) (xy 105.426639 -250.33815) (xy 105.400336 -250.296554) (xy 105.381045 -250.251278)
			(xy 105.369268 -250.203494) (xy 105.365308 -250.15444) (xy 104.096312 -250.15444) (xy 104.095817 -250.179047)
			(xy 104.087922 -250.227624) (xy 104.072338 -250.274305) (xy 104.049467 -250.317882) (xy 104.019902 -250.357226)
			(xy 103.984409 -250.391318) (xy 103.943906 -250.419274) (xy 103.899444 -250.440372) (xy 103.852173 -250.454064)
			(xy 103.803318 -250.459996) (xy 103.754143 -250.458015) (xy 103.705924 -250.448171) (xy 103.659908 -250.430719)
			(xy 103.617287 -250.406112) (xy 103.579166 -250.374987) (xy 103.546531 -250.33815) (xy 103.520228 -250.296554)
			(xy 103.500937 -250.251278) (xy 103.48916 -250.203494) (xy 103.4852 -250.15444) (xy 102.216458 -250.15444)
			(xy 102.215963 -250.179047) (xy 102.208068 -250.227624) (xy 102.192484 -250.274305) (xy 102.169613 -250.317882)
			(xy 102.140048 -250.357226) (xy 102.104555 -250.391318) (xy 102.064052 -250.419274) (xy 102.01959 -250.440372)
			(xy 101.972319 -250.454064) (xy 101.923464 -250.459996) (xy 101.874289 -250.458015) (xy 101.82607 -250.448171)
			(xy 101.780054 -250.430719) (xy 101.737433 -250.406112) (xy 101.699312 -250.374987) (xy 101.666677 -250.33815)
			(xy 101.640374 -250.296554) (xy 101.621083 -250.251278) (xy 101.609306 -250.203494) (xy 101.605346 -250.15444)
			(xy 100.33635 -250.15444) (xy 100.335855 -250.179047) (xy 100.32796 -250.227624) (xy 100.312376 -250.274305)
			(xy 100.289505 -250.317882) (xy 100.25994 -250.357226) (xy 100.224447 -250.391318) (xy 100.183944 -250.419274)
			(xy 100.139482 -250.440372) (xy 100.092211 -250.454064) (xy 100.043356 -250.459996) (xy 99.994181 -250.458015)
			(xy 99.945962 -250.448171) (xy 99.899946 -250.430719) (xy 99.857325 -250.406112) (xy 99.819204 -250.374987)
			(xy 99.786569 -250.33815) (xy 99.760266 -250.296554) (xy 99.740975 -250.251278) (xy 99.729198 -250.203494)
			(xy 99.725238 -250.15444) (xy 99.396296 -250.15444) (xy 99.395801 -250.179047) (xy 99.387906 -250.227624)
			(xy 99.372322 -250.274305) (xy 99.349451 -250.317882) (xy 99.319886 -250.357226) (xy 99.284393 -250.391318)
			(xy 99.24389 -250.419274) (xy 99.199428 -250.440372) (xy 99.152157 -250.454064) (xy 99.103302 -250.459996)
			(xy 99.054127 -250.458015) (xy 99.005908 -250.448171) (xy 98.959892 -250.430719) (xy 98.917271 -250.406112)
			(xy 98.87915 -250.374987) (xy 98.846515 -250.33815) (xy 98.820212 -250.296554) (xy 98.800921 -250.251278)
			(xy 98.789144 -250.203494) (xy 98.785184 -250.15444) (xy 98.456242 -250.15444) (xy 98.455747 -250.179047)
			(xy 98.447852 -250.227624) (xy 98.432268 -250.274305) (xy 98.409397 -250.317882) (xy 98.379832 -250.357226)
			(xy 98.344339 -250.391318) (xy 98.303836 -250.419274) (xy 98.259374 -250.440372) (xy 98.212103 -250.454064)
			(xy 98.163248 -250.459996) (xy 98.114073 -250.458015) (xy 98.065854 -250.448171) (xy 98.019838 -250.430719)
			(xy 97.977217 -250.406112) (xy 97.939096 -250.374987) (xy 97.906461 -250.33815) (xy 97.880158 -250.296554)
			(xy 97.860867 -250.251278) (xy 97.84909 -250.203494) (xy 97.84513 -250.15444) (xy 97.516442 -250.15444)
			(xy 97.515947 -250.179047) (xy 97.508052 -250.227624) (xy 97.492468 -250.274305) (xy 97.469597 -250.317882)
			(xy 97.440032 -250.357226) (xy 97.404539 -250.391318) (xy 97.364036 -250.419274) (xy 97.319574 -250.440372)
			(xy 97.272303 -250.454064) (xy 97.223448 -250.459996) (xy 97.174273 -250.458015) (xy 97.126054 -250.448171)
			(xy 97.080038 -250.430719) (xy 97.037417 -250.406112) (xy 96.999296 -250.374987) (xy 96.966661 -250.33815)
			(xy 96.940358 -250.296554) (xy 96.921067 -250.251278) (xy 96.90929 -250.203494) (xy 96.90533 -250.15444)
			(xy 96.576388 -250.15444) (xy 96.575893 -250.179047) (xy 96.567998 -250.227624) (xy 96.552414 -250.274305)
			(xy 96.529543 -250.317882) (xy 96.499978 -250.357226) (xy 96.464485 -250.391318) (xy 96.423982 -250.419274)
			(xy 96.37952 -250.440372) (xy 96.332249 -250.454064) (xy 96.283394 -250.459996) (xy 96.234219 -250.458015)
			(xy 96.186 -250.448171) (xy 96.139984 -250.430719) (xy 96.097363 -250.406112) (xy 96.059242 -250.374987)
			(xy 96.026607 -250.33815) (xy 96.000304 -250.296554) (xy 95.981013 -250.251278) (xy 95.969236 -250.203494)
			(xy 95.965276 -250.15444) (xy 95.671132 -250.15444) (xy 96.329246 -250.812554) (xy 96.33331 -250.816364)
			(xy 96.333564 -250.816364) (xy 96.341625 -250.82221) (xy 96.360706 -250.827835) (xy 96.370648 -250.827286)
			(xy 96.46031 -250.817888) (xy 96.479614 -250.806204) (xy 96.485964 -250.796552) (xy 96.500232 -250.775816)
			(xy 96.534432 -250.738888) (xy 96.574226 -250.708071) (xy 96.618536 -250.6842) (xy 96.666163 -250.667922)
			(xy 96.715814 -250.659678) (xy 96.74098 -250.659138) (xy 96.764973 -250.659583) (xy 96.812368 -250.667087)
			(xy 96.858005 -250.681915) (xy 96.900761 -250.7037) (xy 96.939582 -250.731906) (xy 96.973511 -250.765838)
			(xy 97.001714 -250.804661) (xy 97.023495 -250.847419) (xy 97.038319 -250.893057) (xy 97.045819 -250.940453)
			(xy 97.046288 -250.964446) (xy 97.045707 -250.99131) (xy 97.036263 -251.044203) (xy 97.027492 -251.069602)
			(xy 97.023174 -251.081286) (xy 97.026476 -251.105924) (xy 97.08134 -251.184664) (xy 97.088961 -251.194299)
			(xy 97.110731 -251.205593) (xy 97.122996 -251.206254)
		)
		(stroke
			(width 0)
			(type solid)
		)
		(fill yes)
		(layer "In13.Cu")
		(net "PVDDCR_CPU0_P1")
	)
	(gr_poly
		(pts
			(xy 164.650928 -428.406306) (xy 164.656008 -428.390304) (xy 164.66628 -428.359951) (xy 164.693409 -428.301895)
			(xy 164.727616 -428.247707) (xy 164.768359 -428.198246) (xy 164.814994 -428.154295) (xy 164.866781 -428.116552)
			(xy 164.922899 -428.085613) (xy 164.982459 -428.06197) (xy 165.044518 -428.045996) (xy 165.108091 -428.037946)
			(xy 165.172173 -428.037946) (xy 165.235746 -428.045996) (xy 165.297805 -428.06197) (xy 165.357365 -428.085613)
			(xy 165.413483 -428.116552) (xy 165.46527 -428.154295) (xy 165.511905 -428.198246) (xy 165.552648 -428.247707)
			(xy 165.586855 -428.301895) (xy 165.613984 -428.359951) (xy 165.624256 -428.390304) (xy 165.629336 -428.406306)
			(xy 165.656006 -428.42561) (xy 171.065444 -428.42561) (xy 171.091606 -428.407068) (xy 171.097194 -428.391828)
			(xy 171.10812 -428.362542) (xy 171.136135 -428.306662) (xy 171.170788 -428.254638) (xy 171.211557 -428.207255)
			(xy 171.257828 -428.165227) (xy 171.308902 -428.129188) (xy 171.364008 -428.099682) (xy 171.422317 -428.077154)
			(xy 171.482946 -428.061944) (xy 171.544984 -428.054281) (xy 171.607492 -428.054281) (xy 171.66953 -428.061944)
			(xy 171.730159 -428.077154) (xy 171.788468 -428.099682) (xy 171.843574 -428.129188) (xy 171.894648 -428.165227)
			(xy 171.940919 -428.207255) (xy 171.981688 -428.254638) (xy 172.016341 -428.306662) (xy 172.044356 -428.362542)
			(xy 172.055282 -428.391828) (xy 172.06087 -428.407068) (xy 172.087032 -428.42561) (xy 175.37938 -428.42561)
			(xy 175.388408 -428.425299) (xy 175.405366 -428.419112) (xy 175.419102 -428.4074) (xy 175.42383 -428.399702)
			(xy 175.440801 -428.370631) (xy 175.481243 -428.316821) (xy 175.528431 -428.268815) (xy 175.581538 -428.227452)
			(xy 175.639637 -428.193456) (xy 175.701712 -428.16742) (xy 175.766679 -428.149799) (xy 175.833403 -428.140902)
			(xy 175.86706 -428.140368) (xy 175.898825 -428.140878) (xy 175.961855 -428.148826) (xy 176.023407 -428.164555)
			(xy 176.082524 -428.18782) (xy 176.110646 -428.202598) (xy 176.121568 -428.20844) (xy 176.144936 -428.209202)
			(xy 176.241202 -428.16526) (xy 176.256188 -428.146718) (xy 176.258728 -428.13478) (xy 176.265319 -428.106739)
			(xy 176.285799 -428.052903) (xy 176.314138 -428.002757) (xy 176.349692 -427.957439) (xy 176.391654 -427.917981)
			(xy 176.439071 -427.885278) (xy 176.490864 -427.860074) (xy 176.545857 -427.842941) (xy 176.6028 -427.834268)
			(xy 176.6316 -427.83379) (xy 176.658438 -427.834265) (xy 176.711581 -427.841817) (xy 176.763144 -427.85673)
			(xy 176.78781 -427.867318) (xy 176.79797 -427.87189) (xy 176.819814 -427.871636) (xy 176.909476 -427.830488)
			(xy 176.9237 -427.814232) (xy 176.927002 -427.803564) (xy 176.935187 -427.777618) (xy 176.957885 -427.728174)
			(xy 176.987375 -427.682456) (xy 177.023059 -427.641389) (xy 177.064214 -427.605807) (xy 177.110006 -427.57643)
			(xy 177.159506 -427.553855) (xy 177.21171 -427.538539) (xy 177.26556 -427.530793) (xy 177.292762 -427.53026)
			(xy 177.321623 -427.530809) (xy 177.378682 -427.539539) (xy 177.433777 -427.55676) (xy 177.485651 -427.58208)
			(xy 177.509678 -427.598078) (xy 177.517167 -427.602812) (xy 177.534282 -427.607339) (xy 177.551914 -427.605757)
			(xy 177.56795 -427.598257) (xy 177.574448 -427.592236) (xy 178.872388 -426.294296) (xy 178.879235 -426.286898)
			(xy 178.88697 -426.2683) (xy 178.887374 -426.258228) (xy 178.887374 -423.627804) (xy 178.886684 -423.615641)
			(xy 178.875548 -423.594014) (xy 178.866038 -423.586402) (xy 178.788822 -423.531284) (xy 178.764692 -423.527728)
			(xy 178.752754 -423.531792) (xy 178.726158 -423.540515) (xy 178.671533 -423.552727) (xy 178.615895 -423.558854)
			(xy 178.587908 -423.559224) (xy 178.557176 -423.55876) (xy 178.496161 -423.551353) (xy 178.436483 -423.536645)
			(xy 178.379014 -423.514851) (xy 178.32459 -423.486288) (xy 178.274006 -423.451374) (xy 178.227999 -423.410618)
			(xy 178.18724 -423.364613) (xy 178.152324 -423.31403) (xy 178.123759 -423.259608) (xy 178.101962 -423.202139)
			(xy 178.087251 -423.142463) (xy 178.079841 -423.081448) (xy 178.0794 -423.050716) (xy 178.079849 -423.019895)
			(xy 178.087296 -422.958706) (xy 178.102082 -422.898865) (xy 178.12399 -422.841248) (xy 178.1527 -422.786702)
			(xy 178.187791 -422.736024) (xy 178.228749 -422.689958) (xy 178.274973 -422.649179) (xy 178.300126 -422.631362)
			(xy 178.307094 -422.626248) (xy 178.317342 -422.612345) (xy 178.320192 -422.604184) (xy 178.328574 -422.575482)
			(xy 178.33073 -422.567313) (xy 178.330082 -422.550441) (xy 178.327304 -422.542462) (xy 178.319176 -422.519348)
			(xy 178.31562 -422.50868) (xy 178.300126 -422.49217) (xy 178.206908 -422.454578) (xy 178.184302 -422.455594)
			(xy 178.174396 -422.460928) (xy 178.146596 -422.475314) (xy 178.088231 -422.497936) (xy 178.027529 -422.513214)
			(xy 177.96541 -422.520919) (xy 177.934112 -422.52138) (xy 177.901611 -422.520866) (xy 177.83714 -422.512585)
			(xy 177.774249 -422.496157) (xy 177.713964 -422.471849) (xy 177.657267 -422.440059) (xy 177.605084 -422.401303)
			(xy 177.581306 -422.37914) (xy 177.574452 -422.373063) (xy 177.557659 -422.365781) (xy 177.54854 -422.364916)
			(xy 177.51806 -422.363646) (xy 177.508865 -422.363617) (xy 177.49141 -422.369346) (xy 177.484024 -422.374822)
			(xy 177.456829 -422.395891) (xy 177.397842 -422.431292) (xy 177.334624 -422.458421) (xy 177.268326 -422.476786)
			(xy 177.200159 -422.48605) (xy 177.165762 -422.486582) (xy 177.133804 -422.486078) (xy 177.070393 -422.478063)
			(xy 177.008486 -422.462164) (xy 176.94906 -422.438631) (xy 176.893052 -422.407837) (xy 176.841345 -422.370266)
			(xy 176.794754 -422.326511) (xy 176.754014 -422.277261) (xy 176.719768 -422.223294) (xy 176.692555 -422.165461)
			(xy 176.672805 -422.104673) (xy 176.660829 -422.04189) (xy 176.656815 -421.9781) (xy 176.660829 -421.91431)
			(xy 176.672805 -421.851527) (xy 176.692555 -421.790739) (xy 176.719768 -421.732906) (xy 176.754014 -421.678939)
			(xy 176.794754 -421.629689) (xy 176.841345 -421.585934) (xy 176.893052 -421.548363) (xy 176.94906 -421.517569)
			(xy 177.008486 -421.494036) (xy 177.070393 -421.478137) (xy 177.133804 -421.470122) (xy 177.165762 -421.469566)
			(xy 177.198263 -421.470079) (xy 177.262735 -421.478357) (xy 177.325627 -421.494784) (xy 177.385913 -421.519091)
			(xy 177.442611 -421.550882) (xy 177.494794 -421.589639) (xy 177.518568 -421.611806) (xy 177.525423 -421.617882)
			(xy 177.542215 -421.625166) (xy 177.551334 -421.62603) (xy 177.581814 -421.6273) (xy 177.59101 -421.627333)
			(xy 177.608468 -421.621606) (xy 177.61585 -421.616124) (xy 177.643047 -421.595061) (xy 177.702036 -421.559673)
			(xy 177.765256 -421.532555) (xy 177.831552 -421.514202) (xy 177.899717 -421.504949) (xy 177.934112 -421.504364)
			(xy 177.964843 -421.504829) (xy 178.025857 -421.512238) (xy 178.085533 -421.526948) (xy 178.143001 -421.548743)
			(xy 178.197424 -421.577306) (xy 178.248006 -421.61222) (xy 178.294012 -421.652977) (xy 178.33477 -421.698981)
			(xy 178.369686 -421.749563) (xy 178.39825 -421.803984) (xy 178.420047 -421.861451) (xy 178.434759 -421.921127)
			(xy 178.44217 -421.982141) (xy 178.44262 -422.012872) (xy 178.44262 -422.01338) (xy 178.443037 -422.023402)
			(xy 178.450704 -422.041923) (xy 178.464877 -422.056096) (xy 178.483398 -422.063763) (xy 178.49342 -422.06418)
			(xy 178.505104 -422.06418) (xy 178.515518 -422.0591) (xy 178.541615 -422.047013) (xy 178.596532 -422.02994)
			(xy 178.653387 -422.021286) (xy 178.682142 -422.020746) (xy 178.702755 -422.021013) (xy 178.74374 -422.025473)
			(xy 178.76393 -422.029636) (xy 178.77536 -422.032176) (xy 178.797712 -422.026842) (xy 178.868324 -421.969946)
			(xy 178.876848 -421.962319) (xy 178.886763 -421.941741) (xy 178.887374 -421.930322) (xy 178.887374 -419.699948)
			(xy 178.886984 -419.690456) (xy 178.880096 -419.672764) (xy 178.867274 -419.658762) (xy 178.858926 -419.654228)
			(xy 178.763422 -419.607746) (xy 178.73472 -419.610794) (xy 178.72329 -419.619684) (xy 178.696364 -419.64005)
			(xy 178.638153 -419.674247) (xy 178.575927 -419.700436) (xy 178.510782 -419.718156) (xy 178.443864 -419.727095)
			(xy 178.410108 -419.727634) (xy 178.378144 -419.727153) (xy 178.314719 -419.719142) (xy 178.252799 -419.703244)
			(xy 178.193359 -419.679711) (xy 178.137338 -419.648914) (xy 178.085618 -419.611338) (xy 178.039016 -419.567577)
			(xy 177.998266 -419.518319) (xy 177.964011 -419.464343) (xy 177.936791 -419.406498) (xy 177.917036 -419.345699)
			(xy 177.905057 -419.282902) (xy 177.901042 -419.2191) (xy 177.905057 -419.155298) (xy 177.917036 -419.092501)
			(xy 177.936791 -419.031702) (xy 177.964011 -418.973857) (xy 177.998266 -418.919881) (xy 178.039016 -418.870623)
			(xy 178.085618 -418.826862) (xy 178.137338 -418.789286) (xy 178.193359 -418.758489) (xy 178.252799 -418.734956)
			(xy 178.314719 -418.719058) (xy 178.378144 -418.711047) (xy 178.410108 -418.710618) (xy 178.443864 -418.71117)
			(xy 178.51078 -418.720109) (xy 178.575925 -418.737827) (xy 178.63815 -418.764013) (xy 178.696362 -418.798206)
			(xy 178.72329 -418.818568) (xy 178.73472 -418.827458) (xy 178.763422 -418.830506) (xy 178.858926 -418.784024)
			(xy 178.867301 -418.779514) (xy 178.880179 -418.765531) (xy 178.887057 -418.74781) (xy 178.887374 -418.738304)
			(xy 178.887374 -418.210238) (xy 178.886923 -418.19933) (xy 178.877983 -418.179437) (xy 178.870102 -418.171884)
			(xy 178.804062 -418.114226) (xy 178.783234 -418.10813) (xy 178.772312 -418.1094) (xy 178.755565 -418.111525)
			(xy 178.721882 -418.113816) (xy 178.705002 -418.113972) (xy 178.673042 -418.113491) (xy 178.609625 -418.10548)
			(xy 178.547713 -418.089584) (xy 178.488282 -418.066054) (xy 178.432268 -418.03526) (xy 178.380555 -417.997688)
			(xy 178.333959 -417.953932) (xy 178.293214 -417.904681) (xy 178.258964 -417.850711) (xy 178.231748 -417.792874)
			(xy 178.211996 -417.732082) (xy 178.200018 -417.669294) (xy 178.196004 -417.6055) (xy 178.200018 -417.541706)
			(xy 178.211996 -417.478918) (xy 178.231748 -417.418126) (xy 178.258964 -417.360289) (xy 178.293214 -417.306319)
			(xy 178.333959 -417.257068) (xy 178.380555 -417.213312) (xy 178.432268 -417.17574) (xy 178.488282 -417.144946)
			(xy 178.547713 -417.121416) (xy 178.609625 -417.10552) (xy 178.673042 -417.097509) (xy 178.705002 -417.096956)
			(xy 178.721882 -417.09712) (xy 178.755565 -417.099407) (xy 178.772312 -417.101528) (xy 178.783234 -417.102798)
			(xy 178.804062 -417.096702) (xy 178.870102 -417.039044) (xy 178.87793 -417.031453) (xy 178.88686 -417.011583)
			(xy 178.887374 -417.00069) (xy 178.887374 -416.19805) (xy 178.886941 -416.187984) (xy 178.879211 -416.169396)
			(xy 178.872388 -416.161982) (xy 176.699164 -413.988758) (xy 176.69104 -413.98139) (xy 176.670504 -413.973749)
			(xy 176.65954 -413.974026) (xy 176.571656 -413.980376) (xy 176.552352 -413.991298) (xy 176.545748 -414.000188)
			(xy 176.525107 -414.02718) (xy 176.47782 -414.075976) (xy 176.42446 -414.118045) (xy 176.365976 -414.15264)
			(xy 176.303409 -414.179144) (xy 176.237871 -414.197087) (xy 176.170529 -414.20615) (xy 176.136554 -414.20669)
			(xy 176.105825 -414.206223) (xy 176.044816 -414.19881) (xy 175.985146 -414.184097) (xy 175.927683 -414.1623)
			(xy 175.873267 -414.133735) (xy 175.822691 -414.098819) (xy 175.776692 -414.058063) (xy 175.735941 -414.012058)
			(xy 175.701032 -413.961478) (xy 175.672474 -413.907058) (xy 175.650684 -413.849593) (xy 175.635978 -413.789921)
			(xy 175.628573 -413.728911) (xy 175.628046 -413.698182) (xy 175.628492 -413.66835) (xy 175.635508 -413.609098)
			(xy 175.649407 -413.551074) (xy 175.659288 -413.522922) (xy 175.66386 -413.510476) (xy 175.66005 -413.48533)
			(xy 175.593248 -413.396176) (xy 175.570134 -413.385508) (xy 175.55718 -413.386524) (xy 175.523144 -413.38754)
			(xy 175.491692 -413.387067) (xy 175.429268 -413.379303) (xy 175.368278 -413.363901) (xy 175.309653 -413.341095)
			(xy 175.254287 -413.311234) (xy 175.203027 -413.274773) (xy 175.156653 -413.23227) (xy 175.115875 -413.184372)
			(xy 175.081315 -413.131812) (xy 175.06696 -413.103822) (xy 175.061118 -413.091884) (xy 175.039274 -413.076898)
			(xy 174.926244 -413.066992) (xy 174.902114 -413.077914) (xy 174.89424 -413.088582) (xy 174.870045 -413.120062)
			(xy 174.813528 -413.17582) (xy 174.781718 -413.19958) (xy 174.771558 -413.206692) (xy 174.760382 -413.229044)
			(xy 174.761652 -413.336994) (xy 174.773336 -413.358838) (xy 174.78375 -413.36595) (xy 174.808952 -413.383754)
			(xy 174.855276 -413.424521) (xy 174.896325 -413.470593) (xy 174.931497 -413.521296) (xy 174.960274 -413.575882)
			(xy 174.982234 -413.633549) (xy 174.997053 -413.69345) (xy 175.004514 -413.754704) (xy 175.004984 -413.785558)
			(xy 175.004498 -413.817837) (xy 174.996356 -413.881878) (xy 174.980172 -413.944373) (xy 174.968662 -413.974534)
			(xy 174.965106 -413.98317) (xy 174.964852 -414.001712) (xy 174.993808 -414.082484) (xy 175.005746 -414.096708)
			(xy 175.013874 -414.10128) (xy 175.039144 -414.115774) (xy 175.085357 -414.151237) (xy 175.125636 -414.193319)
			(xy 175.159045 -414.241039) (xy 175.184805 -414.293285) (xy 175.202317 -414.348843) (xy 175.211172 -414.406418)
			(xy 175.21174 -414.435544) (xy 175.211254 -414.462795) (xy 175.203498 -414.516743) (xy 175.188143 -414.569038)
			(xy 175.165501 -414.618615) (xy 175.136035 -414.664465) (xy 175.100344 -414.705656) (xy 175.059153 -414.741347)
			(xy 175.013303 -414.770813) (xy 174.963726 -414.793455) (xy 174.911431 -414.80881) (xy 174.857483 -414.816566)
			(xy 174.802981 -414.816566) (xy 174.749033 -414.80881) (xy 174.696738 -414.793455) (xy 174.647161 -414.770813)
			(xy 174.601311 -414.741347) (xy 174.56012 -414.705656) (xy 174.524429 -414.664465) (xy 174.494963 -414.618615)
			(xy 174.472321 -414.569038) (xy 174.456966 -414.516743) (xy 174.44921 -414.462795) (xy 174.448724 -414.435544)
			(xy 174.448821 -414.424148) (xy 174.450216 -414.401399) (xy 174.451518 -414.390078) (xy 174.452534 -414.38068)
			(xy 174.448216 -414.3629) (xy 174.399194 -414.292034) (xy 174.383954 -414.28162) (xy 174.37481 -414.279334)
			(xy 174.345071 -414.271551) (xy 174.287588 -414.249762) (xy 174.23315 -414.221201) (xy 174.182554 -414.186286)
			(xy 174.136535 -414.145525) (xy 174.095767 -414.099514) (xy 174.060843 -414.048923) (xy 174.032273 -413.99449)
			(xy 174.010474 -413.937011) (xy 173.995765 -413.877322) (xy 173.988358 -413.816295) (xy 173.987968 -413.785558)
			(xy 173.988416 -413.755425) (xy 173.995544 -413.695582) (xy 174.009696 -413.637) (xy 174.030673 -413.580503)
			(xy 174.05818 -413.52688) (xy 174.091833 -413.476885) (xy 174.131159 -413.431218) (xy 174.175608 -413.39052)
			(xy 174.199804 -413.372554) (xy 174.209964 -413.365442) (xy 174.22114 -413.34309) (xy 174.21987 -413.23514)
			(xy 174.208186 -413.213296) (xy 174.197772 -413.206184) (xy 174.172567 -413.188381) (xy 174.126239 -413.147616)
			(xy 174.085185 -413.101545) (xy 174.050009 -413.050843) (xy 174.021226 -412.996257) (xy 173.999262 -412.938589)
			(xy 173.984438 -412.878687) (xy 173.976973 -412.817431) (xy 173.976538 -412.786576) (xy 173.976985 -412.755846)
			(xy 173.984396 -412.694834) (xy 173.999108 -412.63516) (xy 174.020905 -412.577695) (xy 174.049471 -412.523276)
			(xy 174.084387 -412.472698) (xy 174.125146 -412.426697) (xy 174.171153 -412.385944) (xy 174.221736 -412.351035)
			(xy 174.276159 -412.322477) (xy 174.333627 -412.300687) (xy 174.393303 -412.285984) (xy 174.454316 -412.278581)
			(xy 174.485046 -412.278068) (xy 174.5165 -412.27854) (xy 174.578927 -412.286302) (xy 174.63992 -412.301702)
			(xy 174.69855 -412.324505) (xy 174.75392 -412.354362) (xy 174.805187 -412.390819) (xy 174.851567 -412.433319)
			(xy 174.892354 -412.481213) (xy 174.926924 -412.533771) (xy 174.94123 -412.561786) (xy 174.947072 -412.573724)
			(xy 174.968916 -412.58871) (xy 175.081946 -412.598616) (xy 175.106076 -412.587694) (xy 175.11395 -412.577026)
			(xy 175.118268 -412.571438) (xy 175.125634 -412.561532) (xy 175.129952 -412.537656) (xy 175.09871 -412.435294)
			(xy 175.081692 -412.417768) (xy 175.070008 -412.413704) (xy 175.040241 -412.403066) (xy 174.983385 -412.375439)
			(xy 174.93039 -412.340979) (xy 174.882074 -412.300218) (xy 174.839182 -412.253784) (xy 174.802374 -412.202392)
			(xy 174.772218 -412.146836) (xy 174.749179 -412.08797) (xy 174.733612 -412.026704) (xy 174.725758 -411.96398)
			(xy 174.72533 -411.932374) (xy 174.725777 -411.901644) (xy 174.733189 -411.840632) (xy 174.7479 -411.780958)
			(xy 174.769698 -411.723492) (xy 174.798263 -411.669074) (xy 174.83318 -411.618495) (xy 174.873939 -411.572493)
			(xy 174.919945 -411.53174) (xy 174.970528 -411.49683) (xy 175.024951 -411.468272) (xy 175.082419 -411.446481)
			(xy 175.142095 -411.431777) (xy 175.203108 -411.424373) (xy 175.233838 -411.423866) (xy 175.25238 -411.42412)
			(xy 175.261099 -411.424124) (xy 175.277733 -411.418936) (xy 175.284892 -411.41396) (xy 175.308514 -411.39618)
			(xy 175.315276 -411.390665) (xy 175.324885 -411.376115) (xy 175.32731 -411.367732) (xy 175.335092 -411.337993)
			(xy 175.356881 -411.28051) (xy 175.385441 -411.226074) (xy 175.420356 -411.175478) (xy 175.461117 -411.129461)
			(xy 175.507129 -411.088694) (xy 175.55772 -411.053773) (xy 175.612153 -411.025206) (xy 175.669634 -411.003411)
			(xy 175.729323 -410.988705) (xy 175.790349 -410.981303) (xy 175.821086 -410.98089) (xy 175.854065 -410.981413)
			(xy 175.919468 -410.989943) (xy 175.983219 -411.006861) (xy 176.044247 -411.031882) (xy 176.101525 -411.064587)
			(xy 176.154091 -411.104426) (xy 176.177956 -411.127194) (xy 176.189132 -411.138116) (xy 176.21885 -411.143958)
			(xy 176.319688 -411.101794) (xy 176.328786 -411.097565) (xy 176.342942 -411.08337) (xy 176.350565 -411.064829)
			(xy 176.35093 -411.054804) (xy 176.35093 -395.867128) (xy 176.351367 -395.857064) (xy 176.359103 -395.838482)
			(xy 176.365916 -395.83106) (xy 177.386996 -394.80998) (xy 177.394391 -394.803124) (xy 177.412989 -394.795376)
			(xy 177.423064 -394.794994) (xy 183.449468 -394.794994) (xy 183.459533 -394.794558) (xy 183.478118 -394.786826)
			(xy 183.485536 -394.780008) (xy 183.869584 -394.39596) (xy 183.876264 -394.388549) (xy 183.883834 -394.370113)
			(xy 183.884316 -394.360146) (xy 183.884316 -394.35278) (xy 183.884743 -394.342712) (xy 183.892464 -394.324114)
			(xy 183.899302 -394.316712) (xy 188.831728 -389.384286) (xy 188.839124 -389.377435) (xy 188.857723 -389.369697)
			(xy 188.867796 -389.3693) (xy 188.875162 -389.3693) (xy 188.885125 -389.368814) (xy 188.90355 -389.361228)
			(xy 188.910976 -389.354568) (xy 189.01918 -389.246364) (xy 189.02658 -389.239523) (xy 189.045179 -389.231808)
			(xy 189.055248 -389.231378) (xy 193.904108 -389.231378) (xy 193.912749 -389.231046) (xy 193.929047 -389.225301)
			(xy 193.942489 -389.214441) (xy 193.947288 -389.207248) (xy 193.999866 -389.122412) (xy 194.000882 -389.09625)
			(xy 193.994786 -389.084312) (xy 193.976315 -389.046436) (xy 193.945783 -388.967887) (xy 193.922816 -388.886802)
			(xy 193.90762 -388.80391) (xy 193.900331 -388.719951) (xy 193.901014 -388.63568) (xy 193.909664 -388.551851)
			(xy 193.926202 -388.469215) (xy 193.95048 -388.388514) (xy 193.982282 -388.31047) (xy 194.021321 -388.235784)
			(xy 194.067248 -388.165124) (xy 194.119652 -388.099124) (xy 194.178062 -388.038375) (xy 194.241955 -387.983422)
			(xy 194.310759 -387.934758) (xy 194.383856 -387.892818) (xy 194.460592 -387.857979) (xy 194.540278 -387.830553)
			(xy 194.622201 -387.810785) (xy 194.705626 -387.798853) (xy 194.789806 -387.794864) (xy 194.873986 -387.798853)
			(xy 194.957411 -387.810785) (xy 195.039334 -387.830553) (xy 195.11902 -387.857979) (xy 195.195756 -387.892818)
			(xy 195.268853 -387.934758) (xy 195.337657 -387.983422) (xy 195.40155 -388.038375) (xy 195.45996 -388.099124)
			(xy 195.508704 -388.160514) (xy 198.82434 -388.160514) (xy 198.828411 -388.104892) (xy 198.840537 -388.050455)
			(xy 198.86046 -387.998364) (xy 198.887756 -387.949729) (xy 198.921842 -387.905586) (xy 198.961991 -387.866877)
			(xy 199.007349 -387.834426) (xy 199.056949 -387.808925) (xy 199.109733 -387.790918) (xy 199.164576 -387.780788)
			(xy 199.22031 -387.778751) (xy 199.275747 -387.784851) (xy 199.329704 -387.798957) (xy 199.381033 -387.820769)
			(xy 199.428639 -387.849823) (xy 199.471507 -387.885498) (xy 199.508724 -387.927035) (xy 199.539497 -387.973548)
			(xy 199.563169 -388.024045) (xy 199.579237 -388.077452) (xy 199.587357 -388.132628) (xy 199.587866 -388.160514)
			(xy 199.587357 -388.1884) (xy 199.579237 -388.243576) (xy 199.563169 -388.296983) (xy 199.539497 -388.34748)
			(xy 199.508724 -388.393993) (xy 199.471507 -388.43553) (xy 199.428639 -388.471205) (xy 199.381033 -388.500259)
			(xy 199.329704 -388.522071) (xy 199.275747 -388.536177) (xy 199.22031 -388.542277) (xy 199.164576 -388.54024)
			(xy 199.109733 -388.53011) (xy 199.056949 -388.512103) (xy 199.007349 -388.486602) (xy 198.961991 -388.454151)
			(xy 198.921842 -388.415442) (xy 198.887756 -388.371299) (xy 198.86046 -388.322664) (xy 198.840537 -388.270573)
			(xy 198.828411 -388.216136) (xy 198.82434 -388.160514) (xy 195.508704 -388.160514) (xy 195.512364 -388.165124)
			(xy 195.558291 -388.235784) (xy 195.59733 -388.31047) (xy 195.629132 -388.388514) (xy 195.65341 -388.469215)
			(xy 195.669948 -388.551851) (xy 195.671319 -388.565136) (xy 206.936848 -388.565136) (xy 206.937294 -388.534921)
			(xy 206.944478 -388.474918) (xy 206.958725 -388.416191) (xy 206.979834 -388.359566) (xy 207.007508 -388.305844)
			(xy 207.041356 -388.255782) (xy 207.0608 -388.23265) (xy 207.066405 -388.225498) (xy 207.072661 -388.208455)
			(xy 207.072992 -388.199376) (xy 207.072992 -388.168896) (xy 207.07265 -388.159816) (xy 207.066414 -388.142765)
			(xy 207.0608 -388.135622) (xy 207.04134 -388.112504) (xy 207.007502 -388.062434) (xy 206.979836 -388.008708)
			(xy 206.95873 -387.952082) (xy 206.944483 -387.893354) (xy 206.937294 -387.833351) (xy 206.936848 -387.803136)
			(xy 206.93735 -387.771175) (xy 206.945361 -387.707757) (xy 206.961258 -387.645843) (xy 206.98479 -387.58641)
			(xy 207.015584 -387.530395) (xy 207.053157 -387.47868) (xy 207.096914 -387.432083) (xy 207.146167 -387.391338)
			(xy 207.200138 -387.357087) (xy 207.257977 -387.32987) (xy 207.31877 -387.310117) (xy 207.38156 -387.298139)
			(xy 207.445356 -387.294126) (xy 207.509152 -387.298139) (xy 207.571942 -387.310117) (xy 207.632735 -387.32987)
			(xy 207.690574 -387.357087) (xy 207.744545 -387.391338) (xy 207.793798 -387.432083) (xy 207.837555 -387.47868)
			(xy 207.875128 -387.530395) (xy 207.905922 -387.58641) (xy 207.929454 -387.645843) (xy 207.945351 -387.707757)
			(xy 207.953362 -387.771175) (xy 207.953864 -387.803136) (xy 207.953399 -387.833351) (xy 207.946218 -387.893352)
			(xy 207.931975 -387.95208) (xy 207.910869 -388.008704) (xy 207.883199 -388.062426) (xy 207.849355 -388.11249)
			(xy 207.829912 -388.135622) (xy 207.824278 -388.142754) (xy 207.818039 -388.159812) (xy 207.81772 -388.168896)
			(xy 207.81772 -388.199376) (xy 207.818025 -388.20846) (xy 207.824286 -388.225511) (xy 207.829912 -388.23265)
			(xy 207.849361 -388.255777) (xy 207.8832 -388.305845) (xy 207.910867 -388.35957) (xy 207.931975 -388.416194)
			(xy 207.946225 -388.47492) (xy 207.953416 -388.534921) (xy 207.953864 -388.565136) (xy 208.968848 -388.565136)
			(xy 208.969294 -388.534921) (xy 208.976478 -388.474918) (xy 208.990725 -388.416191) (xy 209.011834 -388.359566)
			(xy 209.039508 -388.305844) (xy 209.073356 -388.255782) (xy 209.0928 -388.23265) (xy 209.098405 -388.225498)
			(xy 209.104661 -388.208455) (xy 209.104992 -388.199376) (xy 209.104992 -388.168896) (xy 209.10465 -388.159816)
			(xy 209.098414 -388.142765) (xy 209.0928 -388.135622) (xy 209.07334 -388.112504) (xy 209.039502 -388.062434)
			(xy 209.011836 -388.008708) (xy 208.99073 -387.952082) (xy 208.976483 -387.893354) (xy 208.969294 -387.833351)
			(xy 208.968848 -387.803136) (xy 208.96935 -387.771175) (xy 208.977361 -387.707757) (xy 208.993258 -387.645843)
			(xy 209.01679 -387.58641) (xy 209.047584 -387.530395) (xy 209.085157 -387.47868) (xy 209.128914 -387.432083)
			(xy 209.178167 -387.391338) (xy 209.232138 -387.357087) (xy 209.289977 -387.32987) (xy 209.35077 -387.310117)
			(xy 209.41356 -387.298139) (xy 209.477356 -387.294126) (xy 209.541152 -387.298139) (xy 209.603942 -387.310117)
			(xy 209.664735 -387.32987) (xy 209.722574 -387.357087) (xy 209.776545 -387.391338) (xy 209.825798 -387.432083)
			(xy 209.869555 -387.47868) (xy 209.907128 -387.530395) (xy 209.937922 -387.58641) (xy 209.961454 -387.645843)
			(xy 209.977351 -387.707757) (xy 209.985362 -387.771175) (xy 209.985864 -387.803136) (xy 209.985399 -387.833351)
			(xy 209.978218 -387.893352) (xy 209.963975 -387.95208) (xy 209.942869 -388.008704) (xy 209.915199 -388.062426)
			(xy 209.881355 -388.11249) (xy 209.861912 -388.135622) (xy 209.856278 -388.142754) (xy 209.850039 -388.159812)
			(xy 209.84972 -388.168896) (xy 209.84972 -388.199376) (xy 209.850025 -388.20846) (xy 209.856286 -388.225511)
			(xy 209.861912 -388.23265) (xy 209.881361 -388.255777) (xy 209.9152 -388.305845) (xy 209.942867 -388.35957)
			(xy 209.963975 -388.416194) (xy 209.978225 -388.47492) (xy 209.985416 -388.534921) (xy 209.985864 -388.565136)
			(xy 209.985362 -388.597097) (xy 209.977351 -388.660515) (xy 209.961454 -388.722429) (xy 209.937922 -388.781862)
			(xy 209.907128 -388.837877) (xy 209.869555 -388.889592) (xy 209.825798 -388.936189) (xy 209.776545 -388.976934)
			(xy 209.722574 -389.011185) (xy 209.664735 -389.038402) (xy 209.603942 -389.058155) (xy 209.541152 -389.070133)
			(xy 209.477356 -389.074147) (xy 209.41356 -389.070133) (xy 209.35077 -389.058155) (xy 209.289977 -389.038402)
			(xy 209.232138 -389.011185) (xy 209.178167 -388.976934) (xy 209.128914 -388.936189) (xy 209.085157 -388.889592)
			(xy 209.047584 -388.837877) (xy 209.01679 -388.781862) (xy 208.993258 -388.722429) (xy 208.977361 -388.660515)
			(xy 208.96935 -388.597097) (xy 208.968848 -388.565136) (xy 207.953864 -388.565136) (xy 207.953362 -388.597097)
			(xy 207.945351 -388.660515) (xy 207.929454 -388.722429) (xy 207.905922 -388.781862) (xy 207.875128 -388.837877)
			(xy 207.837555 -388.889592) (xy 207.793798 -388.936189) (xy 207.744545 -388.976934) (xy 207.690574 -389.011185)
			(xy 207.632735 -389.038402) (xy 207.571942 -389.058155) (xy 207.509152 -389.070133) (xy 207.445356 -389.074147)
			(xy 207.38156 -389.070133) (xy 207.31877 -389.058155) (xy 207.257977 -389.038402) (xy 207.200138 -389.011185)
			(xy 207.146167 -388.976934) (xy 207.096914 -388.936189) (xy 207.053157 -388.889592) (xy 207.015584 -388.837877)
			(xy 206.98479 -388.781862) (xy 206.961258 -388.722429) (xy 206.945361 -388.660515) (xy 206.93735 -388.597097)
			(xy 206.936848 -388.565136) (xy 195.671319 -388.565136) (xy 195.678598 -388.63568) (xy 195.679281 -388.719951)
			(xy 195.671992 -388.80391) (xy 195.656796 -388.886802) (xy 195.633829 -388.967887) (xy 195.603297 -389.046436)
			(xy 195.584826 -389.084312) (xy 195.57873 -389.09625) (xy 195.58 -389.122412) (xy 195.632324 -389.207248)
			(xy 195.637188 -389.214434) (xy 195.650716 -389.225284) (xy 195.667086 -389.231009) (xy 195.675758 -389.231378)
			(xy 212.886036 -389.231378) (xy 212.896103 -389.230948) (xy 212.914696 -389.223222) (xy 212.922104 -389.216392)
			(xy 215.138762 -386.999734) (xy 215.145115 -386.992824) (xy 215.152759 -386.975698) (xy 215.153706 -386.956968)
			(xy 215.151208 -386.947918) (xy 215.118442 -386.848096) (xy 215.096598 -386.829554) (xy 215.08212 -386.827522)
			(xy 215.052268 -386.822378) (xy 214.994588 -386.80388) (xy 214.940565 -386.77648) (xy 214.891564 -386.740872)
			(xy 214.869776 -386.719826) (xy 214.862664 -386.712714) (xy 214.844884 -386.705094) (xy 214.754206 -386.70357)
			(xy 214.736172 -386.710428) (xy 214.728806 -386.717286) (xy 214.707502 -386.736313) (xy 214.660302 -386.768475)
			(xy 214.608836 -386.793247) (xy 214.554255 -386.810076) (xy 214.497776 -386.818587) (xy 214.469218 -386.81914)
			(xy 214.440743 -386.818606) (xy 214.384428 -386.810127) (xy 214.33 -386.793369) (xy 214.278668 -386.768705)
			(xy 214.231574 -386.736684) (xy 214.189764 -386.698016) (xy 214.17153 -386.676138) (xy 214.163656 -386.666232)
			(xy 214.141304 -386.656326) (xy 214.033608 -386.662676) (xy 214.012526 -386.675122) (xy 214.005922 -386.68579)
			(xy 213.990878 -386.708904) (xy 213.955189 -386.750947) (xy 213.913819 -386.787414) (xy 213.86763 -386.817546)
			(xy 213.817585 -386.840715) (xy 213.764726 -386.856439) (xy 213.710154 -386.864389) (xy 213.68258 -386.86486)
			(xy 213.652561 -386.864305) (xy 213.593264 -386.854911) (xy 213.536171 -386.836341) (xy 213.482693 -386.809055)
			(xy 213.43415 -386.773727) (xy 213.412578 -386.752846) (xy 213.405466 -386.745734) (xy 213.387686 -386.738114)
			(xy 213.297008 -386.73659) (xy 213.278974 -386.743448) (xy 213.271608 -386.750306) (xy 213.250304 -386.769332)
			(xy 213.203103 -386.801493) (xy 213.151638 -386.826264) (xy 213.097057 -386.843093) (xy 213.040578 -386.851603)
			(xy 213.01202 -386.85216) (xy 212.984767 -386.851698) (xy 212.930817 -386.843943) (xy 212.878519 -386.828588)
			(xy 212.82894 -386.805946) (xy 212.783088 -386.776478) (xy 212.741897 -386.740784) (xy 212.706205 -386.69959)
			(xy 212.67674 -386.653736) (xy 212.654102 -386.604154) (xy 212.638751 -386.551856) (xy 212.631 -386.497905)
			(xy 212.630512 -386.470652) (xy 212.63106 -386.441601) (xy 212.639873 -386.38417) (xy 212.657289 -386.328739)
			(xy 212.682905 -386.276588) (xy 212.716129 -386.228922) (xy 212.756194 -386.186842) (xy 212.778848 -386.168646)
			(xy 212.788246 -386.16128) (xy 212.79866 -386.14096) (xy 212.79993 -386.037582) (xy 212.790278 -386.017008)
			(xy 212.781134 -386.009388) (xy 212.759599 -385.991168) (xy 212.721611 -385.94947) (xy 212.690174 -385.902636)
			(xy 212.665972 -385.851684) (xy 212.649531 -385.797726) (xy 212.64121 -385.741936) (xy 212.640672 -385.713732)
			(xy 212.641133 -385.686477) (xy 212.648886 -385.632522) (xy 212.664239 -385.580219) (xy 212.686879 -385.530633)
			(xy 212.716346 -385.484775) (xy 212.75204 -385.443576) (xy 212.793233 -385.407877) (xy 212.839088 -385.378404)
			(xy 212.88867 -385.355757) (xy 212.940971 -385.340397) (xy 212.994925 -385.332636) (xy 213.02218 -385.332224)
			(xy 213.052197 -385.332783) (xy 213.11149 -385.342186) (xy 213.168577 -385.360761) (xy 213.22205 -385.388052)
			(xy 213.270586 -385.423383) (xy 213.292182 -385.444238) (xy 213.299294 -385.45135) (xy 213.317074 -385.45897)
			(xy 213.407752 -385.460494) (xy 213.425786 -385.453636) (xy 213.433152 -385.446778) (xy 213.454453 -385.427746)
			(xy 213.501652 -385.395573) (xy 213.553116 -385.370791) (xy 213.607698 -385.353953) (xy 213.66418 -385.345434)
			(xy 213.69274 -385.344924) (xy 213.719813 -385.345401) (xy 213.773413 -385.353064) (xy 213.82539 -385.368232)
			(xy 213.8747 -385.390599) (xy 213.92035 -385.419714) (xy 213.961424 -385.454994) (xy 213.997095 -385.495729)
			(xy 214.012272 -385.518152) (xy 214.01913 -385.528312) (xy 214.039704 -385.54025) (xy 214.145876 -385.5466)
			(xy 214.16772 -385.536948) (xy 214.175594 -385.52755) (xy 214.193806 -385.506359) (xy 214.23537 -385.469019)
			(xy 214.281936 -385.438141) (xy 214.332508 -385.414386) (xy 214.386005 -385.398262) (xy 214.441281 -385.390114)
			(xy 214.469218 -385.389628) (xy 214.499237 -385.390182) (xy 214.558535 -385.399576) (xy 214.615628 -385.418145)
			(xy 214.669107 -385.445431) (xy 214.71765 -385.480758) (xy 214.73922 -385.501642) (xy 214.746332 -385.508754)
			(xy 214.764112 -385.516374) (xy 214.85479 -385.517898) (xy 214.872824 -385.51104) (xy 214.88019 -385.504182)
			(xy 214.901494 -385.485156) (xy 214.948696 -385.452996) (xy 215.000161 -385.428226) (xy 215.054742 -385.411397)
			(xy 215.11122 -385.402887) (xy 215.139778 -385.402328) (xy 215.168756 -385.402865) (xy 215.226048 -385.411622)
			(xy 215.281358 -385.428938) (xy 215.333414 -385.454415) (xy 215.381022 -385.487468) (xy 215.423087 -385.527337)
			(xy 215.441276 -385.549902) (xy 215.448896 -385.559808) (xy 215.471756 -385.570222) (xy 215.580976 -385.563364)
			(xy 215.602312 -385.550156) (xy 215.608916 -385.539488) (xy 215.623736 -385.515436) (xy 215.659356 -385.471588)
			(xy 215.701056 -385.433475) (xy 215.747923 -385.401931) (xy 215.798931 -385.377649) (xy 215.852963 -385.361158)
			(xy 215.908837 -385.35282) (xy 215.937084 -385.35229) (xy 215.966879 -385.352862) (xy 216.025744 -385.362122)
			(xy 216.082455 -385.380419) (xy 216.135632 -385.407309) (xy 216.183983 -385.442137) (xy 216.226333 -385.484058)
			(xy 216.244424 -385.507738) (xy 216.25179 -385.517644) (xy 216.273126 -385.528566) (xy 216.379552 -385.528312)
			(xy 216.401142 -385.517644) (xy 216.408254 -385.507738) (xy 216.426361 -385.483976) (xy 216.468721 -385.441855)
			(xy 216.517127 -385.40685) (xy 216.570397 -385.379814) (xy 216.627228 -385.36141) (xy 216.686233 -385.352086)
			(xy 216.716102 -385.351528) (xy 216.726538 -385.351599) (xy 216.747377 -385.352745) (xy 216.757758 -385.353814)
			(xy 216.769442 -385.355084) (xy 216.791032 -385.347464) (xy 242.411758 -359.726738) (xy 242.418599 -359.719338)
			(xy 242.426318 -359.700739) (xy 242.426744 -359.69067) (xy 242.426744 -333.75981) (xy 242.426321 -333.74974)
			(xy 242.418603 -333.731138) (xy 242.411758 -333.723742) (xy 241.307874 -332.619858) (xy 241.300477 -332.613009)
			(xy 241.281878 -332.605275) (xy 241.271806 -332.604872) (xy 241.25809 -332.604872) (xy 241.248021 -332.604446)
			(xy 241.229422 -332.596726) (xy 241.222022 -332.589886) (xy 240.726976 -332.09484) (xy 240.719606 -332.088097)
			(xy 240.701144 -332.080507) (xy 240.691162 -332.080108) (xy 240.495074 -332.080108) (xy 240.471452 -332.079346)
			(xy 240.461721 -332.079287) (xy 240.44333 -332.085592) (xy 240.428594 -332.098276) (xy 240.419622 -332.115524)
			(xy 240.417696 -332.134871) (xy 240.423091 -332.15355) (xy 240.435036 -332.16889) (xy 240.443258 -332.174088)
			(xy 240.471593 -332.191249) (xy 240.523976 -332.231799) (xy 240.570647 -332.278812) (xy 240.610814 -332.331489)
			(xy 240.643797 -332.388939) (xy 240.669036 -332.450187) (xy 240.686103 -332.514195) (xy 240.69471 -332.579878)
			(xy 240.695226 -332.613) (xy 240.694724 -332.644961) (xy 240.686713 -332.708379) (xy 240.670816 -332.770293)
			(xy 240.647284 -332.829726) (xy 240.61649 -332.885741) (xy 240.578917 -332.937456) (xy 240.53516 -332.984053)
			(xy 240.485907 -333.024798) (xy 240.431936 -333.059049) (xy 240.374097 -333.086266) (xy 240.313304 -333.106019)
			(xy 240.250514 -333.117997) (xy 240.186718 -333.122011) (xy 240.122922 -333.117997) (xy 240.060132 -333.106019)
			(xy 239.999339 -333.086266) (xy 239.9415 -333.059049) (xy 239.887529 -333.024798) (xy 239.838276 -332.984053)
			(xy 239.794519 -332.937456) (xy 239.756946 -332.885741) (xy 239.726152 -332.829726) (xy 239.70262 -332.770293)
			(xy 239.686723 -332.708379) (xy 239.678712 -332.644961) (xy 239.67821 -332.613) (xy 239.678717 -332.580624)
			(xy 239.686936 -332.516396) (xy 239.703241 -332.45373) (xy 239.727367 -332.393641) (xy 239.758926 -332.3371)
			(xy 239.797406 -332.285023) (xy 239.842185 -332.23825) (xy 239.892539 -332.19754) (xy 239.947653 -332.16355)
			(xy 240.006635 -332.136831) (xy 240.068531 -332.117814) (xy 240.100358 -332.111858) (xy 240.114582 -332.109318)
			(xy 240.135918 -332.090776) (xy 240.171732 -331.977238) (xy 240.164874 -331.949806) (xy 240.154714 -331.939646)
			(xy 240.153444 -331.93863) (xy 240.022634 -331.807566) (xy 240.015776 -331.80401) (xy 239.986611 -331.78815)
			(xy 239.932289 -331.749986) (xy 239.883401 -331.705071) (xy 239.84078 -331.654171) (xy 239.805152 -331.598153)
			(xy 239.777124 -331.537971) (xy 239.757173 -331.474652) (xy 239.750854 -331.44206) (xy 239.74933 -331.434186)
			(xy 239.742218 -331.42047) (xy 239.661954 -331.340206) (xy 239.655101 -331.33281) (xy 239.647356 -331.314212)
			(xy 239.646968 -331.304138) (xy 239.646968 -326.021954) (xy 239.646536 -326.011888) (xy 239.638806 -325.993299)
			(xy 239.631982 -325.985886) (xy 237.149132 -323.503036) (xy 237.142292 -323.495636) (xy 237.134576 -323.477037)
			(xy 237.134146 -323.466968) (xy 237.134146 -308.221634) (xy 237.133709 -308.21157) (xy 237.125972 -308.192988)
			(xy 237.11916 -308.185566) (xy 236.410754 -307.47716) (xy 236.403356 -307.470314) (xy 236.384757 -307.462587)
			(xy 236.374686 -307.462174) (xy 221.334584 -307.462174) (xy 221.316042 -307.454554) (xy 221.311724 -307.450236)
			(xy 219.776548 -308.985412) (xy 219.769698 -308.992809) (xy 219.76196 -309.011407) (xy 219.761562 -309.02148)
			(xy 219.761562 -317.206376) (xy 222.497902 -317.206376) (xy 222.501973 -317.150754) (xy 222.514099 -317.096317)
			(xy 222.534022 -317.044226) (xy 222.561318 -316.995591) (xy 222.595404 -316.951448) (xy 222.635553 -316.912739)
			(xy 222.680911 -316.880288) (xy 222.730511 -316.854787) (xy 222.783295 -316.83678) (xy 222.838138 -316.82665)
			(xy 222.893872 -316.824613) (xy 222.949309 -316.830713) (xy 223.003266 -316.844819) (xy 223.054595 -316.866631)
			(xy 223.102201 -316.895685) (xy 223.145069 -316.93136) (xy 223.182286 -316.972897) (xy 223.213059 -317.01941)
			(xy 223.236731 -317.069907) (xy 223.252799 -317.123314) (xy 223.260919 -317.17849) (xy 223.261428 -317.206376)
			(xy 223.261076 -317.22568) (xy 223.59747 -317.22568) (xy 223.598019 -317.196764) (xy 223.606738 -317.139593)
			(xy 223.623988 -317.084394) (xy 223.649374 -317.032431) (xy 223.682314 -316.984897) (xy 223.722052 -316.94288)
			(xy 223.744536 -316.92469) (xy 223.753304 -316.917134) (xy 223.763483 -316.896371) (xy 223.764094 -316.884812)
			(xy 223.764094 -316.804548) (xy 223.763498 -316.792983) (xy 223.753322 -316.772212) (xy 223.744536 -316.76467)
			(xy 223.722046 -316.746487) (xy 223.682309 -316.704467) (xy 223.64937 -316.65693) (xy 223.623982 -316.604967)
			(xy 223.606728 -316.549768) (xy 223.598003 -316.492597) (xy 223.59747 -316.46368) (xy 223.597956 -316.436429)
			(xy 223.605712 -316.382481) (xy 223.621067 -316.330186) (xy 223.643709 -316.280609) (xy 223.673175 -316.234759)
			(xy 223.708866 -316.193568) (xy 223.750057 -316.157877) (xy 223.795907 -316.128411) (xy 223.845484 -316.105769)
			(xy 223.897779 -316.090414) (xy 223.951727 -316.082658) (xy 224.006229 -316.082658) (xy 224.060177 -316.090414)
			(xy 224.112472 -316.105769) (xy 224.162049 -316.128411) (xy 224.207899 -316.157877) (xy 224.24909 -316.193568)
			(xy 224.284781 -316.234759) (xy 224.314247 -316.280609) (xy 224.336889 -316.330186) (xy 224.352244 -316.382481)
			(xy 224.36 -316.436429) (xy 224.360486 -316.46368) (xy 224.359959 -316.492597) (xy 224.351232 -316.549768)
			(xy 224.333976 -316.604966) (xy 224.308586 -316.656928) (xy 224.275644 -316.704462) (xy 224.235905 -316.74648)
			(xy 224.21342 -316.76467) (xy 224.204663 -316.772236) (xy 224.19448 -316.792992) (xy 224.193862 -316.804548)
			(xy 224.193862 -316.884812) (xy 224.194404 -316.896384) (xy 224.204617 -316.917156) (xy 224.21342 -316.92469)
			(xy 224.235903 -316.942882) (xy 224.275637 -316.984902) (xy 224.308576 -317.032437) (xy 224.333964 -317.084398)
			(xy 224.351221 -317.139595) (xy 224.35995 -317.196764) (xy 224.360486 -317.22568) (xy 224.360097 -317.252376)
			(xy 224.352672 -317.305248) (xy 224.33795 -317.35657) (xy 224.316218 -317.405338) (xy 224.287901 -317.450601)
			(xy 224.253551 -317.491476) (xy 224.233994 -317.509652) (xy 224.225358 -317.517272) (xy 224.216468 -317.5381)
			(xy 224.22104 -317.6397) (xy 224.231454 -317.659512) (xy 224.240852 -317.66637) (xy 224.264132 -317.684509)
			(xy 224.305326 -317.726766) (xy 224.339526 -317.77486) (xy 224.365916 -317.827644) (xy 224.383868 -317.883861)
			(xy 224.392954 -317.942171) (xy 224.393506 -317.971678) (xy 224.39302 -317.998929) (xy 224.385264 -318.052877)
			(xy 224.369909 -318.105172) (xy 224.347267 -318.154749) (xy 224.317801 -318.200599) (xy 224.28211 -318.24179)
			(xy 224.240919 -318.277481) (xy 224.195069 -318.306947) (xy 224.145492 -318.329589) (xy 224.093197 -318.344944)
			(xy 224.039249 -318.3527) (xy 223.984747 -318.3527) (xy 223.930799 -318.344944) (xy 223.878504 -318.329589)
			(xy 223.828927 -318.306947) (xy 223.783077 -318.277481) (xy 223.741886 -318.24179) (xy 223.706195 -318.200599)
			(xy 223.676729 -318.154749) (xy 223.654087 -318.105172) (xy 223.638732 -318.052877) (xy 223.630976 -317.998929)
			(xy 223.63049 -317.971678) (xy 223.630926 -317.944984) (xy 223.638343 -317.892114) (xy 223.653056 -317.840794)
			(xy 223.674779 -317.792025) (xy 223.703087 -317.746761) (xy 223.737429 -317.705884) (xy 223.756982 -317.687706)
			(xy 223.765618 -317.680086) (xy 223.774508 -317.659258) (xy 223.769936 -317.557658) (xy 223.759522 -317.537846)
			(xy 223.750124 -317.530988) (xy 223.726862 -317.512827) (xy 223.685658 -317.47058) (xy 223.651451 -317.422493)
			(xy 223.625056 -317.369712) (xy 223.607103 -317.313496) (xy 223.598019 -317.255186) (xy 223.59747 -317.22568)
			(xy 223.261076 -317.22568) (xy 223.260919 -317.234262) (xy 223.252799 -317.289438) (xy 223.236731 -317.342845)
			(xy 223.213059 -317.393342) (xy 223.182286 -317.439855) (xy 223.145069 -317.481392) (xy 223.102201 -317.517067)
			(xy 223.054595 -317.546121) (xy 223.003266 -317.567933) (xy 222.949309 -317.582039) (xy 222.893872 -317.588139)
			(xy 222.838138 -317.586102) (xy 222.783295 -317.575972) (xy 222.730511 -317.557965) (xy 222.680911 -317.532464)
			(xy 222.635553 -317.500013) (xy 222.595404 -317.461304) (xy 222.561318 -317.417161) (xy 222.534022 -317.368526)
			(xy 222.514099 -317.316435) (xy 222.501973 -317.261998) (xy 222.497902 -317.206376) (xy 219.761562 -317.206376)
			(xy 219.761562 -318.415162) (xy 219.762261 -318.427027) (xy 219.773 -318.448197) (xy 219.782136 -318.455802)
			(xy 219.857066 -318.511682) (xy 219.880942 -318.515746) (xy 219.892372 -318.512444) (xy 219.928111 -318.502388)
			(xy 220.001556 -318.491543) (xy 220.038676 -318.490854) (xy 220.070642 -318.491334) (xy 220.134069 -318.499344)
			(xy 220.195993 -318.51524) (xy 220.255436 -318.538773) (xy 220.31146 -318.56957) (xy 220.363183 -318.607147)
			(xy 220.409788 -318.65091) (xy 220.45054 -318.700169) (xy 220.453276 -318.70448) (xy 224.841553 -318.70448)
			(xy 224.845286 -318.651226) (xy 224.856405 -318.599012) (xy 224.874694 -318.548858) (xy 224.899795 -318.501743)
			(xy 224.931219 -318.458587) (xy 224.968352 -318.420232) (xy 224.989136 -318.403478) (xy 224.997909 -318.395927)
			(xy 225.008085 -318.37516) (xy 225.008694 -318.3636) (xy 225.008694 -318.283336) (xy 225.008105 -318.271771)
			(xy 224.997924 -318.250999) (xy 224.989136 -318.243458) (xy 224.96664 -318.225282) (xy 224.926904 -318.18326)
			(xy 224.893965 -318.135722) (xy 224.868579 -318.083758) (xy 224.851326 -318.028557) (xy 224.842602 -317.971385)
			(xy 224.84207 -317.942468) (xy 224.842556 -317.915217) (xy 224.850312 -317.861269) (xy 224.865667 -317.808974)
			(xy 224.888309 -317.759397) (xy 224.917775 -317.713547) (xy 224.953466 -317.672356) (xy 224.994657 -317.636665)
			(xy 225.040507 -317.607199) (xy 225.090084 -317.584557) (xy 225.142379 -317.569202) (xy 225.196327 -317.561446)
			(xy 225.250829 -317.561446) (xy 225.304777 -317.569202) (xy 225.357072 -317.584557) (xy 225.406649 -317.607199)
			(xy 225.452499 -317.636665) (xy 225.49369 -317.672356) (xy 225.529381 -317.713547) (xy 225.558847 -317.759397)
			(xy 225.581489 -317.808974) (xy 225.596844 -317.861269) (xy 225.6046 -317.915217) (xy 225.605086 -317.942468)
			(xy 225.60455 -317.971384) (xy 225.595825 -318.028555) (xy 225.578571 -318.083754) (xy 225.553183 -318.135715)
			(xy 225.520242 -318.18325) (xy 225.480504 -318.225267) (xy 225.45802 -318.243458) (xy 225.449268 -318.251029)
			(xy 225.439083 -318.271781) (xy 225.438462 -318.283336) (xy 225.438462 -318.3636) (xy 225.439011 -318.375171)
			(xy 225.449218 -318.395943) (xy 225.45802 -318.403478) (xy 225.478772 -318.420269) (xy 225.515904 -318.458617)
			(xy 225.547327 -318.501766) (xy 225.572428 -318.548875) (xy 225.590717 -318.599024) (xy 225.601836 -318.651232)
			(xy 225.605569 -318.70448) (xy 227.229153 -318.70448) (xy 227.232886 -318.651226) (xy 227.244005 -318.599012)
			(xy 227.262294 -318.548858) (xy 227.287395 -318.501743) (xy 227.318819 -318.458587) (xy 227.355952 -318.420232)
			(xy 227.376736 -318.403478) (xy 227.385509 -318.395927) (xy 227.395685 -318.37516) (xy 227.396294 -318.3636)
			(xy 227.396294 -318.283336) (xy 227.395705 -318.271771) (xy 227.385524 -318.250999) (xy 227.376736 -318.243458)
			(xy 227.35424 -318.225282) (xy 227.314504 -318.18326) (xy 227.281565 -318.135722) (xy 227.256179 -318.083758)
			(xy 227.238926 -318.028557) (xy 227.230202 -317.971385) (xy 227.22967 -317.942468) (xy 227.230166 -317.914873)
			(xy 227.238135 -317.860261) (xy 227.253888 -317.807366) (xy 227.277095 -317.757293) (xy 227.307274 -317.711084)
			(xy 227.343794 -317.669704) (xy 227.385893 -317.634017) (xy 227.432695 -317.604766) (xy 227.457762 -317.593218)
			(xy 227.468176 -317.588646) (xy 227.482908 -317.571628) (xy 227.510594 -317.474092) (xy 227.507038 -317.451994)
			(xy 227.500434 -317.442342) (xy 227.484484 -317.418332) (xy 227.459233 -317.366514) (xy 227.442074 -317.311486)
			(xy 227.433397 -317.254501) (xy 227.43287 -317.22568) (xy 227.433419 -317.196764) (xy 227.442138 -317.139593)
			(xy 227.459388 -317.084394) (xy 227.484774 -317.032431) (xy 227.517714 -316.984897) (xy 227.557452 -316.94288)
			(xy 227.579936 -316.92469) (xy 227.588704 -316.917134) (xy 227.598883 -316.896371) (xy 227.599494 -316.884812)
			(xy 227.599494 -316.804548) (xy 227.598898 -316.792983) (xy 227.588722 -316.772212) (xy 227.579936 -316.76467)
			(xy 227.557446 -316.746487) (xy 227.517709 -316.704467) (xy 227.48477 -316.65693) (xy 227.459382 -316.604967)
			(xy 227.442128 -316.549768) (xy 227.433403 -316.492597) (xy 227.43287 -316.46368) (xy 227.433356 -316.436429)
			(xy 227.441112 -316.382481) (xy 227.456467 -316.330186) (xy 227.479109 -316.280609) (xy 227.508575 -316.234759)
			(xy 227.544266 -316.193568) (xy 227.585457 -316.157877) (xy 227.631307 -316.128411) (xy 227.680884 -316.105769)
			(xy 227.733179 -316.090414) (xy 227.787127 -316.082658) (xy 227.841629 -316.082658) (xy 227.895577 -316.090414)
			(xy 227.947872 -316.105769) (xy 227.997449 -316.128411) (xy 228.043299 -316.157877) (xy 228.08449 -316.193568)
			(xy 228.120181 -316.234759) (xy 228.149647 -316.280609) (xy 228.172289 -316.330186) (xy 228.187644 -316.382481)
			(xy 228.1954 -316.436429) (xy 228.195886 -316.46368) (xy 228.195359 -316.492597) (xy 228.186632 -316.549768)
			(xy 228.169376 -316.604966) (xy 228.143986 -316.656928) (xy 228.111044 -316.704462) (xy 228.071305 -316.74648)
			(xy 228.04882 -316.76467) (xy 228.040063 -316.772236) (xy 228.02988 -316.792992) (xy 228.029262 -316.804548)
			(xy 228.029262 -316.884812) (xy 228.029804 -316.896384) (xy 228.040017 -316.917156) (xy 228.04882 -316.92469)
			(xy 228.071303 -316.942882) (xy 228.111037 -316.984902) (xy 228.143976 -317.032437) (xy 228.169364 -317.084398)
			(xy 228.186621 -317.139595) (xy 228.19535 -317.196764) (xy 228.195886 -317.22568) (xy 229.49027 -317.22568)
			(xy 229.490819 -317.196764) (xy 229.499538 -317.139593) (xy 229.516788 -317.084394) (xy 229.542174 -317.032431)
			(xy 229.575114 -316.984897) (xy 229.614852 -316.94288) (xy 229.637336 -316.92469) (xy 229.646104 -316.917134)
			(xy 229.656283 -316.896371) (xy 229.656894 -316.884812) (xy 229.656894 -316.804548) (xy 229.656298 -316.792983)
			(xy 229.646122 -316.772212) (xy 229.637336 -316.76467) (xy 229.614846 -316.746487) (xy 229.575109 -316.704467)
			(xy 229.54217 -316.65693) (xy 229.516782 -316.604967) (xy 229.499528 -316.549768) (xy 229.490803 -316.492597)
			(xy 229.49027 -316.46368) (xy 229.490756 -316.436429) (xy 229.498512 -316.382481) (xy 229.513867 -316.330186)
			(xy 229.536509 -316.280609) (xy 229.565975 -316.234759) (xy 229.601666 -316.193568) (xy 229.642857 -316.157877)
			(xy 229.688707 -316.128411) (xy 229.738284 -316.105769) (xy 229.790579 -316.090414) (xy 229.844527 -316.082658)
			(xy 229.899029 -316.082658) (xy 229.952977 -316.090414) (xy 230.005272 -316.105769) (xy 230.054849 -316.128411)
			(xy 230.100699 -316.157877) (xy 230.14189 -316.193568) (xy 230.177581 -316.234759) (xy 230.207047 -316.280609)
			(xy 230.229689 -316.330186) (xy 230.245044 -316.382481) (xy 230.2528 -316.436429) (xy 230.253286 -316.46368)
			(xy 230.252759 -316.492597) (xy 230.244032 -316.549768) (xy 230.226776 -316.604966) (xy 230.201386 -316.656928)
			(xy 230.168444 -316.704462) (xy 230.128705 -316.74648) (xy 230.10622 -316.76467) (xy 230.097463 -316.772236)
			(xy 230.08728 -316.792992) (xy 230.086662 -316.804548) (xy 230.086662 -316.884812) (xy 230.087204 -316.896384)
			(xy 230.097417 -316.917156) (xy 230.10622 -316.92469) (xy 230.128703 -316.942882) (xy 230.168437 -316.984902)
			(xy 230.201376 -317.032437) (xy 230.226764 -317.084398) (xy 230.244021 -317.139595) (xy 230.25275 -317.196764)
			(xy 230.253286 -317.22568) (xy 230.25281 -317.25315) (xy 230.244932 -317.307521) (xy 230.229336 -317.3602)
			(xy 230.206345 -317.410097) (xy 230.176434 -317.456179) (xy 230.140221 -317.497495) (xy 230.098457 -317.533188)
			(xy 230.075486 -317.54826) (xy 230.064056 -317.555372) (xy 230.05161 -317.57874) (xy 230.053896 -317.692786)
			(xy 230.067358 -317.715646) (xy 230.079042 -317.72225) (xy 230.103569 -317.736959) (xy 230.148324 -317.772561)
			(xy 230.187265 -317.814443) (xy 230.219521 -317.861668) (xy 230.244368 -317.913176) (xy 230.261251 -317.967816)
			(xy 230.269791 -318.024364) (xy 230.270304 -318.052958) (xy 230.269818 -318.080209) (xy 230.262062 -318.134157)
			(xy 230.246707 -318.186452) (xy 230.224065 -318.236029) (xy 230.194599 -318.281879) (xy 230.158908 -318.32307)
			(xy 230.117717 -318.358761) (xy 230.071867 -318.388227) (xy 230.02229 -318.410869) (xy 229.969995 -318.426224)
			(xy 229.916047 -318.43398) (xy 229.861545 -318.43398) (xy 229.807597 -318.426224) (xy 229.755302 -318.410869)
			(xy 229.705725 -318.388227) (xy 229.659875 -318.358761) (xy 229.618684 -318.32307) (xy 229.582993 -318.281879)
			(xy 229.553527 -318.236029) (xy 229.530885 -318.186452) (xy 229.51553 -318.134157) (xy 229.507774 -318.080209)
			(xy 229.507288 -318.052958) (xy 229.507805 -318.02549) (xy 229.515677 -317.971121) (xy 229.531267 -317.918444)
			(xy 229.554252 -317.868547) (xy 229.584156 -317.822464) (xy 229.620362 -317.781147) (xy 229.66212 -317.745451)
			(xy 229.685088 -317.730378) (xy 229.696518 -317.723266) (xy 229.708964 -317.699898) (xy 229.706678 -317.585852)
			(xy 229.693216 -317.562992) (xy 229.681532 -317.556388) (xy 229.656995 -317.541695) (xy 229.612236 -317.506093)
			(xy 229.573292 -317.46421) (xy 229.541036 -317.416983) (xy 229.51619 -317.365471) (xy 229.499312 -317.310827)
			(xy 229.490779 -317.254276) (xy 229.49027 -317.22568) (xy 228.195886 -317.22568) (xy 228.195372 -317.253275)
			(xy 228.187409 -317.307887) (xy 228.171662 -317.360783) (xy 228.148458 -317.410858) (xy 228.118281 -317.457067)
			(xy 228.081763 -317.498447) (xy 228.039663 -317.534134) (xy 227.992862 -317.563383) (xy 227.967794 -317.57493)
			(xy 227.95738 -317.579502) (xy 227.942648 -317.59652) (xy 227.914962 -317.694056) (xy 227.918518 -317.716154)
			(xy 227.925122 -317.725806) (xy 227.941088 -317.749807) (xy 227.966335 -317.801627) (xy 227.98349 -317.856659)
			(xy 227.992162 -317.913646) (xy 227.992686 -317.942468) (xy 227.99215 -317.971384) (xy 227.983425 -318.028555)
			(xy 227.966171 -318.083754) (xy 227.940783 -318.135715) (xy 227.907842 -318.18325) (xy 227.868104 -318.225267)
			(xy 227.84562 -318.243458) (xy 227.836868 -318.251029) (xy 227.826683 -318.271781) (xy 227.826062 -318.283336)
			(xy 227.826062 -318.3636) (xy 227.826611 -318.375171) (xy 227.836818 -318.395943) (xy 227.84562 -318.403478)
			(xy 227.866372 -318.420269) (xy 227.903504 -318.458617) (xy 227.934927 -318.501766) (xy 227.960028 -318.548875)
			(xy 227.978317 -318.599024) (xy 227.989436 -318.651232) (xy 227.993169 -318.70448) (xy 230.937553 -318.70448)
			(xy 230.941286 -318.651226) (xy 230.952405 -318.599012) (xy 230.970694 -318.548858) (xy 230.995795 -318.501743)
			(xy 231.027219 -318.458587) (xy 231.064352 -318.420232) (xy 231.085136 -318.403478) (xy 231.093909 -318.395927)
			(xy 231.104085 -318.37516) (xy 231.104694 -318.3636) (xy 231.104694 -318.283336) (xy 231.104105 -318.271771)
			(xy 231.093924 -318.250999) (xy 231.085136 -318.243458) (xy 231.06264 -318.225282) (xy 231.022904 -318.18326)
			(xy 230.989965 -318.135722) (xy 230.964579 -318.083758) (xy 230.947326 -318.028557) (xy 230.938602 -317.971385)
			(xy 230.93807 -317.942468) (xy 230.938556 -317.915217) (xy 230.946312 -317.861269) (xy 230.961667 -317.808974)
			(xy 230.984309 -317.759397) (xy 231.013775 -317.713547) (xy 231.049466 -317.672356) (xy 231.090657 -317.636665)
			(xy 231.136507 -317.607199) (xy 231.186084 -317.584557) (xy 231.238379 -317.569202) (xy 231.292327 -317.561446)
			(xy 231.346829 -317.561446) (xy 231.400777 -317.569202) (xy 231.453072 -317.584557) (xy 231.502649 -317.607199)
			(xy 231.548499 -317.636665) (xy 231.58969 -317.672356) (xy 231.625381 -317.713547) (xy 231.654847 -317.759397)
			(xy 231.677489 -317.808974) (xy 231.692844 -317.861269) (xy 231.7006 -317.915217) (xy 231.701086 -317.942468)
			(xy 231.70055 -317.971384) (xy 231.691825 -318.028555) (xy 231.674571 -318.083754) (xy 231.649183 -318.135715)
			(xy 231.616242 -318.18325) (xy 231.576504 -318.225267) (xy 231.55402 -318.243458) (xy 231.545268 -318.251029)
			(xy 231.535083 -318.271781) (xy 231.534462 -318.283336) (xy 231.534462 -318.3636) (xy 231.535011 -318.375171)
			(xy 231.545218 -318.395943) (xy 231.55402 -318.403478) (xy 231.574772 -318.420269) (xy 231.611904 -318.458617)
			(xy 231.643327 -318.501766) (xy 231.668428 -318.548875) (xy 231.686717 -318.599024) (xy 231.697836 -318.651232)
			(xy 231.701569 -318.70448) (xy 233.325153 -318.70448) (xy 233.328886 -318.651226) (xy 233.340005 -318.599012)
			(xy 233.358294 -318.548858) (xy 233.383395 -318.501743) (xy 233.414819 -318.458587) (xy 233.451952 -318.420232)
			(xy 233.472736 -318.403478) (xy 233.481509 -318.395927) (xy 233.491685 -318.37516) (xy 233.492294 -318.3636)
			(xy 233.492294 -318.283336) (xy 233.491705 -318.271771) (xy 233.481524 -318.250999) (xy 233.472736 -318.243458)
			(xy 233.45024 -318.225282) (xy 233.410504 -318.18326) (xy 233.377565 -318.135722) (xy 233.352179 -318.083758)
			(xy 233.334926 -318.028557) (xy 233.326202 -317.971385) (xy 233.32567 -317.942468) (xy 233.326099 -317.915886)
			(xy 233.33349 -317.863237) (xy 233.348124 -317.812126) (xy 233.369717 -317.763544) (xy 233.397851 -317.718433)
			(xy 233.431979 -317.677668) (xy 233.4514 -317.659512) (xy 233.458918 -317.651892) (xy 233.467592 -317.632353)
			(xy 233.468164 -317.621666) (xy 233.468164 -317.546482) (xy 233.467712 -317.535762) (xy 233.459049 -317.516158)
			(xy 233.4514 -317.508636) (xy 233.431978 -317.490482) (xy 233.397855 -317.449715) (xy 233.369728 -317.404603)
			(xy 233.348141 -317.35602) (xy 233.333514 -317.304909) (xy 233.32613 -317.252261) (xy 233.32567 -317.22568)
			(xy 233.326219 -317.196764) (xy 233.334938 -317.139593) (xy 233.352188 -317.084394) (xy 233.377574 -317.032431)
			(xy 233.410514 -316.984897) (xy 233.450252 -316.94288) (xy 233.472736 -316.92469) (xy 233.481504 -316.917134)
			(xy 233.491683 -316.896371) (xy 233.492294 -316.884812) (xy 233.492294 -316.804548) (xy 233.491698 -316.792983)
			(xy 233.481522 -316.772212) (xy 233.472736 -316.76467) (xy 233.450246 -316.746487) (xy 233.410509 -316.704467)
			(xy 233.37757 -316.65693) (xy 233.352182 -316.604967) (xy 233.334928 -316.549768) (xy 233.326203 -316.492597)
			(xy 233.32567 -316.46368) (xy 233.326156 -316.436429) (xy 233.333912 -316.382481) (xy 233.349267 -316.330186)
			(xy 233.371909 -316.280609) (xy 233.401375 -316.234759) (xy 233.437066 -316.193568) (xy 233.478257 -316.157877)
			(xy 233.524107 -316.128411) (xy 233.573684 -316.105769) (xy 233.625979 -316.090414) (xy 233.679927 -316.082658)
			(xy 233.734429 -316.082658) (xy 233.788377 -316.090414) (xy 233.840672 -316.105769) (xy 233.890249 -316.128411)
			(xy 233.936099 -316.157877) (xy 233.97729 -316.193568) (xy 234.012981 -316.234759) (xy 234.042447 -316.280609)
			(xy 234.065089 -316.330186) (xy 234.080444 -316.382481) (xy 234.0882 -316.436429) (xy 234.088686 -316.46368)
			(xy 234.088159 -316.492597) (xy 234.079432 -316.549768) (xy 234.062176 -316.604966) (xy 234.036786 -316.656928)
			(xy 234.003844 -316.704462) (xy 233.964105 -316.74648) (xy 233.94162 -316.76467) (xy 233.932863 -316.772236)
			(xy 233.92268 -316.792992) (xy 233.922062 -316.804548) (xy 233.922062 -316.884812) (xy 233.922604 -316.896384)
			(xy 233.932817 -316.917156) (xy 233.94162 -316.92469) (xy 233.964103 -316.942882) (xy 234.003837 -316.984902)
			(xy 234.036776 -317.032437) (xy 234.062164 -317.084398) (xy 234.079421 -317.139595) (xy 234.08815 -317.196764)
			(xy 234.088686 -317.22568) (xy 234.088204 -317.25226) (xy 234.080821 -317.304906) (xy 234.066196 -317.356015)
			(xy 234.044613 -317.404597) (xy 234.01649 -317.449709) (xy 233.982372 -317.490477) (xy 233.962956 -317.508636)
			(xy 233.955411 -317.516232) (xy 233.946754 -317.53579) (xy 233.946192 -317.546482) (xy 233.946192 -317.621666)
			(xy 233.946601 -317.632392) (xy 233.955292 -317.651997) (xy 233.962956 -317.659512) (xy 233.982363 -317.677681)
			(xy 234.016485 -317.718445) (xy 234.044614 -317.763555) (xy 234.066202 -317.812135) (xy 234.080833 -317.863243)
			(xy 234.088223 -317.915888) (xy 234.088686 -317.942468) (xy 234.08815 -317.971384) (xy 234.079425 -318.028555)
			(xy 234.062171 -318.083754) (xy 234.036783 -318.135715) (xy 234.003842 -318.18325) (xy 233.964104 -318.225267)
			(xy 233.94162 -318.243458) (xy 233.932868 -318.251029) (xy 233.922683 -318.271781) (xy 233.922062 -318.283336)
			(xy 233.922062 -318.3636) (xy 233.922611 -318.375171) (xy 233.932818 -318.395943) (xy 233.94162 -318.403478)
			(xy 233.962372 -318.420269) (xy 233.999504 -318.458617) (xy 234.030927 -318.501766) (xy 234.056028 -318.548875)
			(xy 234.074317 -318.599024) (xy 234.085436 -318.651232) (xy 234.089169 -318.70448) (xy 234.085442 -318.757729)
			(xy 234.074328 -318.809938) (xy 234.056044 -318.860089) (xy 234.030948 -318.9072) (xy 233.999529 -318.950353)
			(xy 233.962401 -318.988705) (xy 233.94162 -319.005458) (xy 233.932868 -319.013029) (xy 233.922683 -319.033781)
			(xy 233.922062 -319.045336) (xy 233.922062 -319.1256) (xy 233.922611 -319.137171) (xy 233.932818 -319.157943)
			(xy 233.94162 -319.165478) (xy 233.964097 -319.183676) (xy 234.003832 -319.225695) (xy 234.036771 -319.273229)
			(xy 234.06216 -319.325188) (xy 234.079418 -319.380384) (xy 234.08815 -319.437553) (xy 234.088686 -319.466468)
			(xy 234.0882 -319.493719) (xy 234.080444 -319.547667) (xy 234.065089 -319.599962) (xy 234.042447 -319.649539)
			(xy 234.012981 -319.695389) (xy 233.97729 -319.73658) (xy 233.936099 -319.772271) (xy 233.890249 -319.801737)
			(xy 233.840672 -319.824379) (xy 233.788377 -319.839734) (xy 233.734429 -319.84749) (xy 233.679927 -319.84749)
			(xy 233.625979 -319.839734) (xy 233.573684 -319.824379) (xy 233.524107 -319.801737) (xy 233.478257 -319.772271)
			(xy 233.437066 -319.73658) (xy 233.401375 -319.695389) (xy 233.371909 -319.649539) (xy 233.349267 -319.599962)
			(xy 233.333912 -319.547667) (xy 233.326156 -319.493719) (xy 233.32567 -319.466468) (xy 233.326211 -319.437552)
			(xy 233.334931 -319.38038) (xy 233.352183 -319.325181) (xy 233.377571 -319.273218) (xy 233.410512 -319.225684)
			(xy 233.450251 -319.183668) (xy 233.472736 -319.165478) (xy 233.481509 -319.157927) (xy 233.491685 -319.13716)
			(xy 233.492294 -319.1256) (xy 233.492294 -319.045336) (xy 233.491705 -319.033771) (xy 233.481524 -319.012999)
			(xy 233.472736 -319.005458) (xy 233.451923 -318.988742) (xy 233.414794 -318.950383) (xy 233.383374 -318.907224)
			(xy 233.358278 -318.860106) (xy 233.339994 -318.80995) (xy 233.32888 -318.757735) (xy 233.325153 -318.70448)
			(xy 231.701569 -318.70448) (xy 231.697842 -318.757729) (xy 231.686728 -318.809938) (xy 231.668444 -318.860089)
			(xy 231.643348 -318.9072) (xy 231.611929 -318.950353) (xy 231.574801 -318.988705) (xy 231.55402 -319.005458)
			(xy 231.545268 -319.013029) (xy 231.535083 -319.033781) (xy 231.534462 -319.045336) (xy 231.534462 -319.1256)
			(xy 231.535011 -319.137171) (xy 231.545218 -319.157943) (xy 231.55402 -319.165478) (xy 231.576497 -319.183676)
			(xy 231.616232 -319.225695) (xy 231.649171 -319.273229) (xy 231.67456 -319.325188) (xy 231.691818 -319.380384)
			(xy 231.70055 -319.437553) (xy 231.701086 -319.466468) (xy 231.7006 -319.493719) (xy 231.692844 -319.547667)
			(xy 231.677489 -319.599962) (xy 231.654847 -319.649539) (xy 231.625381 -319.695389) (xy 231.58969 -319.73658)
			(xy 231.548499 -319.772271) (xy 231.502649 -319.801737) (xy 231.453072 -319.824379) (xy 231.400777 -319.839734)
			(xy 231.346829 -319.84749) (xy 231.292327 -319.84749) (xy 231.238379 -319.839734) (xy 231.186084 -319.824379)
			(xy 231.136507 -319.801737) (xy 231.090657 -319.772271) (xy 231.049466 -319.73658) (xy 231.013775 -319.695389)
			(xy 230.984309 -319.649539) (xy 230.961667 -319.599962) (xy 230.946312 -319.547667) (xy 230.938556 -319.493719)
			(xy 230.93807 -319.466468) (xy 230.938611 -319.437552) (xy 230.947331 -319.38038) (xy 230.964583 -319.325181)
			(xy 230.989971 -319.273218) (xy 231.022912 -319.225684) (xy 231.062651 -319.183668) (xy 231.085136 -319.165478)
			(xy 231.093909 -319.157927) (xy 231.104085 -319.13716) (xy 231.104694 -319.1256) (xy 231.104694 -319.045336)
			(xy 231.104105 -319.033771) (xy 231.093924 -319.012999) (xy 231.085136 -319.005458) (xy 231.064323 -318.988742)
			(xy 231.027194 -318.950383) (xy 230.995774 -318.907224) (xy 230.970678 -318.860106) (xy 230.952394 -318.80995)
			(xy 230.94128 -318.757735) (xy 230.937553 -318.70448) (xy 227.993169 -318.70448) (xy 227.989442 -318.757729)
			(xy 227.978328 -318.809938) (xy 227.960044 -318.860089) (xy 227.934948 -318.9072) (xy 227.903529 -318.950353)
			(xy 227.866401 -318.988705) (xy 227.84562 -319.005458) (xy 227.836868 -319.013029) (xy 227.826683 -319.033781)
			(xy 227.826062 -319.045336) (xy 227.826062 -319.1256) (xy 227.826611 -319.137171) (xy 227.836818 -319.157943)
			(xy 227.84562 -319.165478) (xy 227.868097 -319.183676) (xy 227.907832 -319.225695) (xy 227.940771 -319.273229)
			(xy 227.96616 -319.325188) (xy 227.983418 -319.380384) (xy 227.99215 -319.437553) (xy 227.992686 -319.466468)
			(xy 227.9922 -319.493719) (xy 227.984444 -319.547667) (xy 227.969089 -319.599962) (xy 227.946447 -319.649539)
			(xy 227.916981 -319.695389) (xy 227.88129 -319.73658) (xy 227.840099 -319.772271) (xy 227.794249 -319.801737)
			(xy 227.744672 -319.824379) (xy 227.692377 -319.839734) (xy 227.638429 -319.84749) (xy 227.583927 -319.84749)
			(xy 227.529979 -319.839734) (xy 227.477684 -319.824379) (xy 227.428107 -319.801737) (xy 227.382257 -319.772271)
			(xy 227.341066 -319.73658) (xy 227.305375 -319.695389) (xy 227.275909 -319.649539) (xy 227.253267 -319.599962)
			(xy 227.237912 -319.547667) (xy 227.230156 -319.493719) (xy 227.22967 -319.466468) (xy 227.230211 -319.437552)
			(xy 227.238931 -319.38038) (xy 227.256183 -319.325181) (xy 227.281571 -319.273218) (xy 227.314512 -319.225684)
			(xy 227.354251 -319.183668) (xy 227.376736 -319.165478) (xy 227.385509 -319.157927) (xy 227.395685 -319.13716)
			(xy 227.396294 -319.1256) (xy 227.396294 -319.045336) (xy 227.395705 -319.033771) (xy 227.385524 -319.012999)
			(xy 227.376736 -319.005458) (xy 227.355923 -318.988742) (xy 227.318794 -318.950383) (xy 227.287374 -318.907224)
			(xy 227.262278 -318.860106) (xy 227.243994 -318.80995) (xy 227.23288 -318.757735) (xy 227.229153 -318.70448)
			(xy 225.605569 -318.70448) (xy 225.601842 -318.757729) (xy 225.590728 -318.809938) (xy 225.572444 -318.860089)
			(xy 225.547348 -318.9072) (xy 225.515929 -318.950353) (xy 225.478801 -318.988705) (xy 225.45802 -319.005458)
			(xy 225.449268 -319.013029) (xy 225.439083 -319.033781) (xy 225.438462 -319.045336) (xy 225.438462 -319.1256)
			(xy 225.439011 -319.137171) (xy 225.449218 -319.157943) (xy 225.45802 -319.165478) (xy 225.480497 -319.183676)
			(xy 225.520232 -319.225695) (xy 225.553171 -319.273229) (xy 225.57856 -319.325188) (xy 225.595818 -319.380384)
			(xy 225.60455 -319.437553) (xy 225.605086 -319.466468) (xy 225.6046 -319.493719) (xy 225.596844 -319.547667)
			(xy 225.581489 -319.599962) (xy 225.558847 -319.649539) (xy 225.529381 -319.695389) (xy 225.49369 -319.73658)
			(xy 225.452499 -319.772271) (xy 225.406649 -319.801737) (xy 225.357072 -319.824379) (xy 225.304777 -319.839734)
			(xy 225.250829 -319.84749) (xy 225.196327 -319.84749) (xy 225.142379 -319.839734) (xy 225.090084 -319.824379)
			(xy 225.040507 -319.801737) (xy 224.994657 -319.772271) (xy 224.953466 -319.73658) (xy 224.917775 -319.695389)
			(xy 224.888309 -319.649539) (xy 224.865667 -319.599962) (xy 224.850312 -319.547667) (xy 224.842556 -319.493719)
			(xy 224.84207 -319.466468) (xy 224.842611 -319.437552) (xy 224.851331 -319.38038) (xy 224.868583 -319.325181)
			(xy 224.893971 -319.273218) (xy 224.926912 -319.225684) (xy 224.966651 -319.183668) (xy 224.989136 -319.165478)
			(xy 224.997909 -319.157927) (xy 225.008085 -319.13716) (xy 225.008694 -319.1256) (xy 225.008694 -319.045336)
			(xy 225.008105 -319.033771) (xy 224.997924 -319.012999) (xy 224.989136 -319.005458) (xy 224.968323 -318.988742)
			(xy 224.931194 -318.950383) (xy 224.899774 -318.907224) (xy 224.874678 -318.860106) (xy 224.856394 -318.80995)
			(xy 224.84528 -318.757735) (xy 224.841553 -318.70448) (xy 220.453276 -318.70448) (xy 220.484797 -318.754147)
			(xy 220.512019 -318.811994) (xy 220.531775 -318.872796) (xy 220.543755 -318.935595) (xy 220.54777 -318.9994)
			(xy 220.543755 -319.063205) (xy 220.531775 -319.126004) (xy 220.512019 -319.186806) (xy 220.484797 -319.244653)
			(xy 220.45054 -319.298631) (xy 220.409788 -319.34789) (xy 220.363183 -319.391653) (xy 220.31146 -319.42923)
			(xy 220.255436 -319.460027) (xy 220.195993 -319.48356) (xy 220.134069 -319.499456) (xy 220.070642 -319.507466)
			(xy 220.038676 -319.50787) (xy 220.001556 -319.507177) (xy 219.92811 -319.496337) (xy 219.892372 -319.48628)
			(xy 219.880942 -319.482978) (xy 219.857066 -319.487042) (xy 219.782136 -319.542922) (xy 219.772948 -319.550483)
			(xy 219.762204 -319.571681) (xy 219.761562 -319.583562) (xy 219.761562 -321.672161) (xy 232.438442 -321.672161)
			(xy 232.438442 -321.608239) (xy 232.446453 -321.544821) (xy 232.46235 -321.482907) (xy 232.485882 -321.423474)
			(xy 232.516676 -321.367459) (xy 232.554249 -321.315744) (xy 232.598006 -321.269147) (xy 232.647259 -321.228402)
			(xy 232.70123 -321.194151) (xy 232.759069 -321.166934) (xy 232.819862 -321.147181) (xy 232.882652 -321.135203)
			(xy 232.946448 -321.13119) (xy 233.010244 -321.135203) (xy 233.073034 -321.147181) (xy 233.133827 -321.166934)
			(xy 233.191666 -321.194151) (xy 233.245637 -321.228402) (xy 233.29489 -321.269147) (xy 233.338647 -321.315744)
			(xy 233.37622 -321.367459) (xy 233.407014 -321.423474) (xy 233.430546 -321.482907) (xy 233.446443 -321.544821)
			(xy 233.454454 -321.608239) (xy 233.454956 -321.6402) (xy 233.454768 -321.652138) (xy 235.520736 -321.652138)
			(xy 235.524807 -321.596516) (xy 235.536933 -321.542079) (xy 235.556856 -321.489988) (xy 235.584152 -321.441353)
			(xy 235.618238 -321.39721) (xy 235.658387 -321.358501) (xy 235.703745 -321.32605) (xy 235.753345 -321.300549)
			(xy 235.806129 -321.282542) (xy 235.860972 -321.272412) (xy 235.916706 -321.270375) (xy 235.972143 -321.276475)
			(xy 236.0261 -321.290581) (xy 236.077429 -321.312393) (xy 236.125035 -321.341447) (xy 236.167903 -321.377122)
			(xy 236.20512 -321.418659) (xy 236.235893 -321.465172) (xy 236.259565 -321.515669) (xy 236.275633 -321.569076)
			(xy 236.283753 -321.624252) (xy 236.284262 -321.652138) (xy 236.283753 -321.680024) (xy 236.275633 -321.7352)
			(xy 236.259565 -321.788607) (xy 236.235893 -321.839104) (xy 236.20512 -321.885617) (xy 236.167903 -321.927154)
			(xy 236.125035 -321.962829) (xy 236.077429 -321.991883) (xy 236.0261 -322.013695) (xy 235.972143 -322.027801)
			(xy 235.916706 -322.033901) (xy 235.860972 -322.031864) (xy 235.806129 -322.021734) (xy 235.753345 -322.003727)
			(xy 235.703745 -321.978226) (xy 235.658387 -321.945775) (xy 235.618238 -321.907066) (xy 235.584152 -321.862923)
			(xy 235.556856 -321.814288) (xy 235.536933 -321.762197) (xy 235.524807 -321.70776) (xy 235.520736 -321.652138)
			(xy 233.454768 -321.652138) (xy 233.454454 -321.672161) (xy 233.446443 -321.735579) (xy 233.430546 -321.797493)
			(xy 233.407014 -321.856926) (xy 233.37622 -321.912941) (xy 233.338647 -321.964656) (xy 233.29489 -322.011253)
			(xy 233.245637 -322.051998) (xy 233.191666 -322.086249) (xy 233.133827 -322.113466) (xy 233.073034 -322.133219)
			(xy 233.010244 -322.145197) (xy 232.946448 -322.149211) (xy 232.882652 -322.145197) (xy 232.819862 -322.133219)
			(xy 232.759069 -322.113466) (xy 232.70123 -322.086249) (xy 232.647259 -322.051998) (xy 232.598006 -322.011253)
			(xy 232.554249 -321.964656) (xy 232.516676 -321.912941) (xy 232.485882 -321.856926) (xy 232.46235 -321.797493)
			(xy 232.446453 -321.735579) (xy 232.438442 -321.672161) (xy 219.761562 -321.672161) (xy 219.761562 -322.17868)
			(xy 229.228902 -322.17868) (xy 229.232973 -322.123058) (xy 229.245099 -322.068621) (xy 229.265022 -322.01653)
			(xy 229.292318 -321.967895) (xy 229.326404 -321.923752) (xy 229.366553 -321.885043) (xy 229.411911 -321.852592)
			(xy 229.461511 -321.827091) (xy 229.514295 -321.809084) (xy 229.569138 -321.798954) (xy 229.624872 -321.796917)
			(xy 229.680309 -321.803017) (xy 229.734266 -321.817123) (xy 229.785595 -321.838935) (xy 229.833201 -321.867989)
			(xy 229.876069 -321.903664) (xy 229.913286 -321.945201) (xy 229.944059 -321.991714) (xy 229.967731 -322.042211)
			(xy 229.983799 -322.095618) (xy 229.991919 -322.150794) (xy 229.992428 -322.17868) (xy 229.991919 -322.206566)
			(xy 229.983799 -322.261742) (xy 229.967731 -322.315149) (xy 229.944059 -322.365646) (xy 229.913286 -322.412159)
			(xy 229.876069 -322.453696) (xy 229.833201 -322.489371) (xy 229.785595 -322.518425) (xy 229.734266 -322.540237)
			(xy 229.680309 -322.554343) (xy 229.624872 -322.560443) (xy 229.569138 -322.558406) (xy 229.514295 -322.548276)
			(xy 229.461511 -322.530269) (xy 229.411911 -322.504768) (xy 229.366553 -322.472317) (xy 229.326404 -322.433608)
			(xy 229.292318 -322.389465) (xy 229.265022 -322.34083) (xy 229.245099 -322.288739) (xy 229.232973 -322.234302)
			(xy 229.228902 -322.17868) (xy 219.761562 -322.17868) (xy 219.761562 -323.263768) (xy 229.240078 -323.263768)
			(xy 229.244149 -323.208146) (xy 229.256275 -323.153709) (xy 229.276198 -323.101618) (xy 229.303494 -323.052983)
			(xy 229.33758 -323.00884) (xy 229.377729 -322.970131) (xy 229.423087 -322.93768) (xy 229.472687 -322.912179)
			(xy 229.525471 -322.894172) (xy 229.580314 -322.884042) (xy 229.636048 -322.882005) (xy 229.691485 -322.888105)
			(xy 229.745442 -322.902211) (xy 229.796771 -322.924023) (xy 229.844377 -322.953077) (xy 229.887245 -322.988752)
			(xy 229.924462 -323.030289) (xy 229.955235 -323.076802) (xy 229.978907 -323.127299) (xy 229.994975 -323.180706)
			(xy 230.003095 -323.235882) (xy 230.003604 -323.263768) (xy 230.003095 -323.291654) (xy 229.994975 -323.34683)
			(xy 229.978907 -323.400237) (xy 229.955235 -323.450734) (xy 229.924462 -323.497247) (xy 229.887245 -323.538784)
			(xy 229.844377 -323.574459) (xy 229.796771 -323.603513) (xy 229.745442 -323.625325) (xy 229.691485 -323.639431)
			(xy 229.636048 -323.645531) (xy 229.580314 -323.643494) (xy 229.525471 -323.633364) (xy 229.472687 -323.615357)
			(xy 229.423087 -323.589856) (xy 229.377729 -323.557405) (xy 229.33758 -323.518696) (xy 229.303494 -323.474553)
			(xy 229.276198 -323.425918) (xy 229.256275 -323.373827) (xy 229.244149 -323.31939) (xy 229.240078 -323.263768)
			(xy 219.761562 -323.263768) (xy 219.761562 -323.913754) (xy 232.44175 -323.913754) (xy 232.442263 -323.881462)
			(xy 232.450427 -323.817396) (xy 232.466644 -323.754882) (xy 232.490651 -323.694926) (xy 232.522062 -323.638495)
			(xy 232.56037 -323.5865) (xy 232.604958 -323.539778) (xy 232.655107 -323.499082) (xy 232.710008 -323.465069)
			(xy 232.739184 -323.45122) (xy 232.751884 -323.445378) (xy 232.767886 -323.422264) (xy 232.775252 -323.304662)
			(xy 232.762552 -323.27977) (xy 232.75036 -323.272404) (xy 232.723216 -323.254933) (xy 232.673127 -323.214212)
			(xy 232.628592 -323.167481) (xy 232.590329 -323.11549) (xy 232.558952 -323.059076) (xy 232.534965 -322.999145)
			(xy 232.518754 -322.93666) (xy 232.51058 -322.872627) (xy 232.510076 -322.84035) (xy 232.510578 -322.808389)
			(xy 232.518589 -322.744971) (xy 232.534486 -322.683057) (xy 232.558018 -322.623624) (xy 232.588812 -322.567609)
			(xy 232.626385 -322.515894) (xy 232.670142 -322.469297) (xy 232.719395 -322.428552) (xy 232.773366 -322.394301)
			(xy 232.831205 -322.367084) (xy 232.891998 -322.347331) (xy 232.954788 -322.335353) (xy 233.018584 -322.33134)
			(xy 233.08238 -322.335353) (xy 233.14517 -322.347331) (xy 233.205963 -322.367084) (xy 233.263802 -322.394301)
			(xy 233.317773 -322.428552) (xy 233.367026 -322.469297) (xy 233.410783 -322.515894) (xy 233.448356 -322.567609)
			(xy 233.47915 -322.623624) (xy 233.502682 -322.683057) (xy 233.50283 -322.683632) (xy 235.558836 -322.683632)
			(xy 235.562907 -322.62801) (xy 235.575033 -322.573573) (xy 235.594956 -322.521482) (xy 235.622252 -322.472847)
			(xy 235.656338 -322.428704) (xy 235.696487 -322.389995) (xy 235.741845 -322.357544) (xy 235.791445 -322.332043)
			(xy 235.844229 -322.314036) (xy 235.899072 -322.303906) (xy 235.954806 -322.301869) (xy 236.010243 -322.307969)
			(xy 236.0642 -322.322075) (xy 236.115529 -322.343887) (xy 236.163135 -322.372941) (xy 236.206003 -322.408616)
			(xy 236.24322 -322.450153) (xy 236.273993 -322.496666) (xy 236.297665 -322.547163) (xy 236.313733 -322.60057)
			(xy 236.321853 -322.655746) (xy 236.322362 -322.683632) (xy 236.321853 -322.711518) (xy 236.313733 -322.766694)
			(xy 236.297665 -322.820101) (xy 236.273993 -322.870598) (xy 236.24322 -322.917111) (xy 236.206003 -322.958648)
			(xy 236.163135 -322.994323) (xy 236.115529 -323.023377) (xy 236.0642 -323.045189) (xy 236.010243 -323.059295)
			(xy 235.954806 -323.065395) (xy 235.899072 -323.063358) (xy 235.844229 -323.053228) (xy 235.791445 -323.035221)
			(xy 235.741845 -323.00972) (xy 235.696487 -322.977269) (xy 235.656338 -322.93856) (xy 235.622252 -322.894417)
			(xy 235.594956 -322.845782) (xy 235.575033 -322.793691) (xy 235.562907 -322.739254) (xy 235.558836 -322.683632)
			(xy 233.50283 -322.683632) (xy 233.518579 -322.744971) (xy 233.52659 -322.808389) (xy 233.527092 -322.84035)
			(xy 233.526616 -322.872643) (xy 233.51845 -322.936712) (xy 233.502231 -322.999229) (xy 233.478221 -323.059187)
			(xy 233.446805 -323.115618) (xy 233.408492 -323.167614) (xy 233.363899 -323.214335) (xy 233.313744 -323.255028)
			(xy 233.258837 -323.289038) (xy 233.229658 -323.302884) (xy 233.216958 -323.308726) (xy 233.200956 -323.33184)
			(xy 233.19359 -323.449442) (xy 233.20629 -323.474334) (xy 233.218482 -323.4817) (xy 233.245638 -323.499154)
			(xy 233.295725 -323.539879) (xy 233.340257 -323.586613) (xy 233.378519 -323.638607) (xy 233.409894 -323.695023)
			(xy 233.43034 -323.746114) (xy 235.54639 -323.746114) (xy 235.550461 -323.690492) (xy 235.562587 -323.636055)
			(xy 235.58251 -323.583964) (xy 235.609806 -323.535329) (xy 235.643892 -323.491186) (xy 235.684041 -323.452477)
			(xy 235.729399 -323.420026) (xy 235.778999 -323.394525) (xy 235.831783 -323.376518) (xy 235.886626 -323.366388)
			(xy 235.94236 -323.364351) (xy 235.997797 -323.370451) (xy 236.051754 -323.384557) (xy 236.103083 -323.406369)
			(xy 236.150689 -323.435423) (xy 236.193557 -323.471098) (xy 236.230774 -323.512635) (xy 236.261547 -323.559148)
			(xy 236.285219 -323.609645) (xy 236.301287 -323.663052) (xy 236.309407 -323.718228) (xy 236.309916 -323.746114)
			(xy 236.309407 -323.774) (xy 236.301287 -323.829176) (xy 236.285219 -323.882583) (xy 236.261547 -323.93308)
			(xy 236.230774 -323.979593) (xy 236.193557 -324.02113) (xy 236.150689 -324.056805) (xy 236.103083 -324.085859)
			(xy 236.051754 -324.107671) (xy 235.997797 -324.121777) (xy 235.94236 -324.127877) (xy 235.886626 -324.12584)
			(xy 235.831783 -324.11571) (xy 235.778999 -324.097703) (xy 235.729399 -324.072202) (xy 235.684041 -324.039751)
			(xy 235.643892 -324.001042) (xy 235.609806 -323.956899) (xy 235.58251 -323.908264) (xy 235.562587 -323.856173)
			(xy 235.550461 -323.801736) (xy 235.54639 -323.746114) (xy 233.43034 -323.746114) (xy 233.433879 -323.754956)
			(xy 233.450089 -323.817442) (xy 233.458263 -323.881477) (xy 233.458766 -323.913754) (xy 233.458227 -323.947343)
			(xy 233.449387 -324.013937) (xy 233.431854 -324.078786) (xy 233.405935 -324.140762) (xy 233.37208 -324.198786)
			(xy 233.330879 -324.251845) (xy 233.28305 -324.299018) (xy 233.229425 -324.339481) (xy 233.200448 -324.356476)
			(xy 233.188256 -324.363334) (xy 233.17454 -324.38721) (xy 233.175302 -324.503796) (xy 233.189526 -324.527418)
			(xy 233.201718 -324.534276) (xy 233.228082 -324.549152) (xy 233.277406 -324.584252) (xy 233.322212 -324.624961)
			(xy 233.361867 -324.670702) (xy 233.39581 -324.720828) (xy 233.423561 -324.774631) (xy 233.430454 -324.793102)
			(xy 235.578648 -324.793102) (xy 235.582719 -324.73748) (xy 235.594845 -324.683043) (xy 235.614768 -324.630952)
			(xy 235.642064 -324.582317) (xy 235.67615 -324.538174) (xy 235.716299 -324.499465) (xy 235.761657 -324.467014)
			(xy 235.811257 -324.441513) (xy 235.864041 -324.423506) (xy 235.918884 -324.413376) (xy 235.974618 -324.411339)
			(xy 236.030055 -324.417439) (xy 236.084012 -324.431545) (xy 236.135341 -324.453357) (xy 236.182947 -324.482411)
			(xy 236.225815 -324.518086) (xy 236.263032 -324.559623) (xy 236.293805 -324.606136) (xy 236.317477 -324.656633)
			(xy 236.333545 -324.71004) (xy 236.341665 -324.765216) (xy 236.342174 -324.793102) (xy 236.341665 -324.820988)
			(xy 236.333545 -324.876164) (xy 236.317477 -324.929571) (xy 236.293805 -324.980068) (xy 236.263032 -325.026581)
			(xy 236.225815 -325.068118) (xy 236.182947 -325.103793) (xy 236.135341 -325.132847) (xy 236.084012 -325.154659)
			(xy 236.030055 -325.168765) (xy 235.974618 -325.174865) (xy 235.918884 -325.172828) (xy 235.864041 -325.162698)
			(xy 235.811257 -325.144691) (xy 235.761657 -325.11919) (xy 235.716299 -325.086739) (xy 235.67615 -325.04803)
			(xy 235.642064 -325.003887) (xy 235.614768 -324.955252) (xy 235.594845 -324.903161) (xy 235.582719 -324.848724)
			(xy 235.578648 -324.793102) (xy 233.430454 -324.793102) (xy 233.444726 -324.831348) (xy 233.459007 -324.890177)
			(xy 233.466201 -324.950285) (xy 233.46664 -324.980554) (xy 233.466241 -325.011065) (xy 233.458939 -325.071648)
			(xy 233.444435 -325.130921) (xy 233.422937 -325.18803) (xy 233.394755 -325.242154) (xy 233.360294 -325.292514)
			(xy 233.320051 -325.338385) (xy 233.274604 -325.379106) (xy 233.224608 -325.414092) (xy 233.197908 -325.428864)
			(xy 233.185208 -325.435722) (xy 233.17073 -325.461122) (xy 233.17581 -325.582026) (xy 233.19232 -325.605902)
			(xy 233.205782 -325.611744) (xy 233.235794 -325.625236) (xy 233.292357 -325.658859) (xy 233.344113 -325.699494)
			(xy 233.390197 -325.746463) (xy 233.429841 -325.798982) (xy 233.462382 -325.856174) (xy 233.47792 -325.894192)
			(xy 235.54004 -325.894192) (xy 235.544111 -325.83857) (xy 235.556237 -325.784133) (xy 235.57616 -325.732042)
			(xy 235.603456 -325.683407) (xy 235.637542 -325.639264) (xy 235.677691 -325.600555) (xy 235.723049 -325.568104)
			(xy 235.772649 -325.542603) (xy 235.825433 -325.524596) (xy 235.880276 -325.514466) (xy 235.93601 -325.512429)
			(xy 235.991447 -325.518529) (xy 236.045404 -325.532635) (xy 236.096733 -325.554447) (xy 236.144339 -325.583501)
			(xy 236.187207 -325.619176) (xy 236.224424 -325.660713) (xy 236.255197 -325.707226) (xy 236.278869 -325.757723)
			(xy 236.294937 -325.81113) (xy 236.303057 -325.866306) (xy 236.303566 -325.894192) (xy 236.303057 -325.922078)
			(xy 236.294937 -325.977254) (xy 236.278869 -326.030661) (xy 236.255197 -326.081158) (xy 236.224424 -326.127671)
			(xy 236.187207 -326.169208) (xy 236.144339 -326.204883) (xy 236.096733 -326.233937) (xy 236.045404 -326.255749)
			(xy 235.991447 -326.269855) (xy 235.93601 -326.275955) (xy 235.880276 -326.273918) (xy 235.825433 -326.263788)
			(xy 235.772649 -326.245781) (xy 235.723049 -326.22028) (xy 235.677691 -326.187829) (xy 235.637542 -326.14912)
			(xy 235.603456 -326.104977) (xy 235.57616 -326.056342) (xy 235.556237 -326.004251) (xy 235.544111 -325.949814)
			(xy 235.54004 -325.894192) (xy 233.47792 -325.894192) (xy 233.487277 -325.917085) (xy 233.50411 -325.980697)
			(xy 233.512601 -326.045949) (xy 233.513122 -326.07885) (xy 233.51262 -326.110811) (xy 233.504609 -326.174229)
			(xy 233.488712 -326.236143) (xy 233.46518 -326.295576) (xy 233.434386 -326.351591) (xy 233.396813 -326.403306)
			(xy 233.353056 -326.449903) (xy 233.303803 -326.490648) (xy 233.249832 -326.524899) (xy 233.191993 -326.552116)
			(xy 233.1312 -326.571869) (xy 233.06841 -326.583847) (xy 233.004614 -326.587861) (xy 232.940818 -326.583847)
			(xy 232.878028 -326.571869) (xy 232.817235 -326.552116) (xy 232.759396 -326.524899) (xy 232.705425 -326.490648)
			(xy 232.656172 -326.449903) (xy 232.612415 -326.403306) (xy 232.574842 -326.351591) (xy 232.544048 -326.295576)
			(xy 232.520516 -326.236143) (xy 232.504619 -326.174229) (xy 232.496608 -326.110811) (xy 232.496106 -326.07885)
			(xy 232.496537 -326.04834) (xy 232.503837 -325.987759) (xy 232.518339 -325.928489) (xy 232.539834 -325.871381)
			(xy 232.568012 -325.817257) (xy 232.602469 -325.766898) (xy 232.642707 -325.721026) (xy 232.688149 -325.680303)
			(xy 232.73814 -325.645314) (xy 232.764838 -325.63054) (xy 232.777538 -325.623682) (xy 232.792016 -325.598282)
			(xy 232.786936 -325.477378) (xy 232.770426 -325.453502) (xy 232.756964 -325.44766) (xy 232.726942 -325.434191)
			(xy 232.67038 -325.400564) (xy 232.618626 -325.359924) (xy 232.572544 -325.312951) (xy 232.532902 -325.260429)
			(xy 232.500363 -325.203235) (xy 232.475469 -325.142322) (xy 232.458636 -325.078708) (xy 232.450145 -325.013455)
			(xy 232.449624 -324.980554) (xy 232.450174 -324.946965) (xy 232.459013 -324.880373) (xy 232.476545 -324.815523)
			(xy 232.502463 -324.753548) (xy 232.536316 -324.695524) (xy 232.577515 -324.642464) (xy 232.625343 -324.595292)
			(xy 232.678966 -324.554828) (xy 232.707942 -324.537832) (xy 232.720134 -324.530974) (xy 232.73385 -324.507098)
			(xy 232.733088 -324.390512) (xy 232.718864 -324.36689) (xy 232.706672 -324.360032) (xy 232.680309 -324.345154)
			(xy 232.630986 -324.310054) (xy 232.58618 -324.269345) (xy 232.546525 -324.223604) (xy 232.512582 -324.173478)
			(xy 232.484831 -324.119676) (xy 232.463666 -324.062959) (xy 232.449384 -324.004131) (xy 232.44219 -323.944023)
			(xy 232.44175 -323.913754) (xy 219.761562 -323.913754) (xy 219.761562 -324.349872) (xy 229.22052 -324.349872)
			(xy 229.224591 -324.29425) (xy 229.236717 -324.239813) (xy 229.25664 -324.187722) (xy 229.283936 -324.139087)
			(xy 229.318022 -324.094944) (xy 229.358171 -324.056235) (xy 229.403529 -324.023784) (xy 229.453129 -323.998283)
			(xy 229.505913 -323.980276) (xy 229.560756 -323.970146) (xy 229.61649 -323.968109) (xy 229.671927 -323.974209)
			(xy 229.725884 -323.988315) (xy 229.777213 -324.010127) (xy 229.824819 -324.039181) (xy 229.867687 -324.074856)
			(xy 229.904904 -324.116393) (xy 229.935677 -324.162906) (xy 229.959349 -324.213403) (xy 229.975417 -324.26681)
			(xy 229.983537 -324.321986) (xy 229.984046 -324.349872) (xy 229.983537 -324.377758) (xy 229.975417 -324.432934)
			(xy 229.959349 -324.486341) (xy 229.935677 -324.536838) (xy 229.904904 -324.583351) (xy 229.867687 -324.624888)
			(xy 229.824819 -324.660563) (xy 229.777213 -324.689617) (xy 229.725884 -324.711429) (xy 229.671927 -324.725535)
			(xy 229.61649 -324.731635) (xy 229.560756 -324.729598) (xy 229.505913 -324.719468) (xy 229.453129 -324.701461)
			(xy 229.403529 -324.67596) (xy 229.358171 -324.643509) (xy 229.318022 -324.6048) (xy 229.283936 -324.560657)
			(xy 229.25664 -324.512022) (xy 229.236717 -324.459931) (xy 229.224591 -324.405494) (xy 229.22052 -324.349872)
			(xy 219.761562 -324.349872) (xy 219.761562 -325.425562) (xy 229.208328 -325.425562) (xy 229.212399 -325.36994)
			(xy 229.224525 -325.315503) (xy 229.244448 -325.263412) (xy 229.271744 -325.214777) (xy 229.30583 -325.170634)
			(xy 229.345979 -325.131925) (xy 229.391337 -325.099474) (xy 229.440937 -325.073973) (xy 229.493721 -325.055966)
			(xy 229.548564 -325.045836) (xy 229.604298 -325.043799) (xy 229.659735 -325.049899) (xy 229.713692 -325.064005)
			(xy 229.765021 -325.085817) (xy 229.812627 -325.114871) (xy 229.855495 -325.150546) (xy 229.892712 -325.192083)
			(xy 229.923485 -325.238596) (xy 229.947157 -325.289093) (xy 229.963225 -325.3425) (xy 229.971345 -325.397676)
			(xy 229.971854 -325.425562) (xy 229.971345 -325.453448) (xy 229.963225 -325.508624) (xy 229.947157 -325.562031)
			(xy 229.923485 -325.612528) (xy 229.892712 -325.659041) (xy 229.855495 -325.700578) (xy 229.812627 -325.736253)
			(xy 229.765021 -325.765307) (xy 229.713692 -325.787119) (xy 229.659735 -325.801225) (xy 229.604298 -325.807325)
			(xy 229.548564 -325.805288) (xy 229.493721 -325.795158) (xy 229.440937 -325.777151) (xy 229.391337 -325.75165)
			(xy 229.345979 -325.719199) (xy 229.30583 -325.68049) (xy 229.271744 -325.636347) (xy 229.244448 -325.587712)
			(xy 229.224525 -325.535621) (xy 229.212399 -325.481184) (xy 229.208328 -325.425562) (xy 219.761562 -325.425562)
			(xy 219.761562 -326.49668) (xy 229.220012 -326.49668) (xy 229.224083 -326.441058) (xy 229.236209 -326.386621)
			(xy 229.256132 -326.33453) (xy 229.283428 -326.285895) (xy 229.317514 -326.241752) (xy 229.357663 -326.203043)
			(xy 229.403021 -326.170592) (xy 229.452621 -326.145091) (xy 229.505405 -326.127084) (xy 229.560248 -326.116954)
			(xy 229.615982 -326.114917) (xy 229.671419 -326.121017) (xy 229.725376 -326.135123) (xy 229.776705 -326.156935)
			(xy 229.824311 -326.185989) (xy 229.867179 -326.221664) (xy 229.904396 -326.263201) (xy 229.935169 -326.309714)
			(xy 229.958841 -326.360211) (xy 229.974909 -326.413618) (xy 229.983029 -326.468794) (xy 229.983538 -326.49668)
			(xy 229.983029 -326.524566) (xy 229.974909 -326.579742) (xy 229.958841 -326.633149) (xy 229.935169 -326.683646)
			(xy 229.904396 -326.730159) (xy 229.867179 -326.771696) (xy 229.824311 -326.807371) (xy 229.776705 -326.836425)
			(xy 229.725376 -326.858237) (xy 229.671419 -326.872343) (xy 229.615982 -326.878443) (xy 229.560248 -326.876406)
			(xy 229.505405 -326.866276) (xy 229.452621 -326.848269) (xy 229.403021 -326.822768) (xy 229.357663 -326.790317)
			(xy 229.317514 -326.751608) (xy 229.283428 -326.707465) (xy 229.256132 -326.65883) (xy 229.236209 -326.606739)
			(xy 229.224083 -326.552302) (xy 229.220012 -326.49668) (xy 219.761562 -326.49668) (xy 219.761562 -326.497442)
			(xy 219.76113 -326.507508) (xy 219.753401 -326.526098) (xy 219.746576 -326.53351) (xy 218.714066 -327.56602)
			(xy 229.214424 -327.56602) (xy 229.218495 -327.510398) (xy 229.230621 -327.455961) (xy 229.250544 -327.40387)
			(xy 229.27784 -327.355235) (xy 229.311926 -327.311092) (xy 229.352075 -327.272383) (xy 229.397433 -327.239932)
			(xy 229.447033 -327.214431) (xy 229.499817 -327.196424) (xy 229.55466 -327.186294) (xy 229.610394 -327.184257)
			(xy 229.665831 -327.190357) (xy 229.719788 -327.204463) (xy 229.771117 -327.226275) (xy 229.818723 -327.255329)
			(xy 229.861591 -327.291004) (xy 229.898808 -327.332541) (xy 229.929581 -327.379054) (xy 229.953253 -327.429551)
			(xy 229.969321 -327.482958) (xy 229.977441 -327.538134) (xy 229.97795 -327.56602) (xy 229.977441 -327.593906)
			(xy 229.969321 -327.649082) (xy 229.953253 -327.702489) (xy 229.929581 -327.752986) (xy 229.898808 -327.799499)
			(xy 229.861591 -327.841036) (xy 229.818723 -327.876711) (xy 229.771117 -327.905765) (xy 229.719788 -327.927577)
			(xy 229.665831 -327.941683) (xy 229.610394 -327.947783) (xy 229.55466 -327.945746) (xy 229.499817 -327.935616)
			(xy 229.447033 -327.917609) (xy 229.397433 -327.892108) (xy 229.352075 -327.859657) (xy 229.311926 -327.820948)
			(xy 229.27784 -327.776805) (xy 229.250544 -327.72817) (xy 229.230621 -327.676079) (xy 229.218495 -327.621642)
			(xy 229.214424 -327.56602) (xy 218.714066 -327.56602) (xy 218.028266 -328.25182) (xy 232.382822 -328.25182)
			(xy 232.383345 -328.218264) (xy 232.392159 -328.151735) (xy 232.40965 -328.086943) (xy 232.435514 -328.025017)
			(xy 232.469301 -327.967031) (xy 232.510424 -327.913995) (xy 232.558167 -327.866831) (xy 232.611701 -327.826359)
			(xy 232.640632 -327.809352) (xy 232.65257 -327.802748) (xy 232.666032 -327.780396) (xy 232.669842 -327.666858)
			(xy 232.657904 -327.64349) (xy 232.646728 -327.636124) (xy 232.620747 -327.618478) (xy 232.572966 -327.577715)
			(xy 232.53057 -327.531376) (xy 232.494205 -327.480167) (xy 232.464426 -327.424869) (xy 232.441686 -327.366323)
			(xy 232.426331 -327.305422) (xy 232.418595 -327.243093) (xy 232.418128 -327.21169) (xy 232.41863 -327.179729)
			(xy 232.426641 -327.116311) (xy 232.442538 -327.054397) (xy 232.46607 -326.994964) (xy 232.496864 -326.938949)
			(xy 232.534437 -326.887234) (xy 232.578194 -326.840637) (xy 232.627447 -326.799892) (xy 232.681418 -326.765641)
			(xy 232.739257 -326.738424) (xy 232.80005 -326.718671) (xy 232.86284 -326.706693) (xy 232.926636 -326.70268)
			(xy 232.990432 -326.706693) (xy 233.053222 -326.718671) (xy 233.114015 -326.738424) (xy 233.171854 -326.765641)
			(xy 233.225825 -326.799892) (xy 233.275078 -326.840637) (xy 233.318835 -326.887234) (xy 233.356408 -326.938949)
			(xy 233.360846 -326.947022) (xy 235.565694 -326.947022) (xy 235.569765 -326.8914) (xy 235.581891 -326.836963)
			(xy 235.601814 -326.784872) (xy 235.62911 -326.736237) (xy 235.663196 -326.692094) (xy 235.703345 -326.653385)
			(xy 235.748703 -326.620934) (xy 235.798303 -326.595433) (xy 235.851087 -326.577426) (xy 235.90593 -326.567296)
			(xy 235.961664 -326.565259) (xy 236.017101 -326.571359) (xy 236.071058 -326.585465) (xy 236.122387 -326.607277)
			(xy 236.169993 -326.636331) (xy 236.212861 -326.672006) (xy 236.250078 -326.713543) (xy 236.280851 -326.760056)
			(xy 236.304523 -326.810553) (xy 236.320591 -326.86396) (xy 236.328711 -326.919136) (xy 236.32922 -326.947022)
			(xy 236.328711 -326.974908) (xy 236.320591 -327.030084) (xy 236.304523 -327.083491) (xy 236.280851 -327.133988)
			(xy 236.250078 -327.180501) (xy 236.212861 -327.222038) (xy 236.169993 -327.257713) (xy 236.122387 -327.286767)
			(xy 236.071058 -327.308579) (xy 236.017101 -327.322685) (xy 235.961664 -327.328785) (xy 235.90593 -327.326748)
			(xy 235.851087 -327.316618) (xy 235.798303 -327.298611) (xy 235.748703 -327.27311) (xy 235.703345 -327.240659)
			(xy 235.663196 -327.20195) (xy 235.62911 -327.157807) (xy 235.601814 -327.109172) (xy 235.581891 -327.057081)
			(xy 235.569765 -327.002644) (xy 235.565694 -326.947022) (xy 233.360846 -326.947022) (xy 233.387202 -326.994964)
			(xy 233.410734 -327.054397) (xy 233.426631 -327.116311) (xy 233.434642 -327.179729) (xy 233.435144 -327.21169)
			(xy 233.434647 -327.245247) (xy 233.42583 -327.311778) (xy 233.408336 -327.376571) (xy 233.382469 -327.438498)
			(xy 233.348679 -327.496484) (xy 233.307552 -327.549519) (xy 233.259805 -327.596682) (xy 233.206267 -327.637153)
			(xy 233.177334 -327.654158) (xy 233.165396 -327.660762) (xy 233.151934 -327.683114) (xy 233.151414 -327.698608)
			(xy 238.484918 -327.698608) (xy 238.485394 -327.66603) (xy 238.493734 -327.601411) (xy 238.510253 -327.538384)
			(xy 238.534682 -327.477981) (xy 238.566619 -327.42119) (xy 238.605544 -327.368939) (xy 238.650819 -327.322084)
			(xy 238.701704 -327.28139) (xy 238.729266 -327.264014) (xy 238.740442 -327.25741) (xy 238.753142 -327.23582)
			(xy 238.757714 -327.12533) (xy 238.746792 -327.102724) (xy 238.736124 -327.095104) (xy 238.712145 -327.07713)
			(xy 238.668154 -327.036432) (xy 238.629249 -326.990847) (xy 238.595968 -326.941009) (xy 238.568772 -326.887605)
			(xy 238.548038 -326.831377) (xy 238.534053 -326.773103) (xy 238.52701 -326.713589) (xy 238.526574 -326.683624)
			(xy 238.527076 -326.651663) (xy 238.535087 -326.588245) (xy 238.550984 -326.526331) (xy 238.574516 -326.466898)
			(xy 238.60531 -326.410883) (xy 238.642883 -326.359168) (xy 238.68664 -326.312571) (xy 238.735893 -326.271826)
			(xy 238.789864 -326.237575) (xy 238.847703 -326.210358) (xy 238.908496 -326.190605) (xy 238.971286 -326.178627)
			(xy 239.035082 -326.174614) (xy 239.098878 -326.178627) (xy 239.161668 -326.190605) (xy 239.222461 -326.210358)
			(xy 239.2803 -326.237575) (xy 239.334271 -326.271826) (xy 239.383524 -326.312571) (xy 239.427281 -326.359168)
			(xy 239.464854 -326.410883) (xy 239.495648 -326.466898) (xy 239.51918 -326.526331) (xy 239.535077 -326.588245)
			(xy 239.543088 -326.651663) (xy 239.54359 -326.683624) (xy 239.543057 -326.7162) (xy 239.534725 -326.780817)
			(xy 239.518214 -326.843842) (xy 239.493794 -326.904244) (xy 239.461865 -326.961036) (xy 239.422947 -327.013287)
			(xy 239.377679 -327.060144) (xy 239.326801 -327.10084) (xy 239.299242 -327.118218) (xy 239.288066 -327.124822)
			(xy 239.275366 -327.146412) (xy 239.270794 -327.256902) (xy 239.281716 -327.279508) (xy 239.292384 -327.287128)
			(xy 239.31638 -327.30508) (xy 239.36037 -327.345782) (xy 239.399274 -327.39137) (xy 239.432553 -327.441212)
			(xy 239.459747 -327.494618) (xy 239.480478 -327.550849) (xy 239.49446 -327.609126) (xy 239.5015 -327.668642)
			(xy 239.501934 -327.698608) (xy 239.50141 -327.730215) (xy 239.49357 -327.79294) (xy 239.478013 -327.854209)
			(xy 239.454979 -327.913076) (xy 239.424822 -327.968633) (xy 239.388009 -328.020021) (xy 239.345109 -328.066448)
			(xy 239.296782 -328.107197) (xy 239.27054 -328.12482) (xy 239.259872 -328.131932) (xy 239.247426 -328.154792)
			(xy 239.247934 -328.266044) (xy 239.26038 -328.28865) (xy 239.271302 -328.295762) (xy 239.297922 -328.31334)
			(xy 239.347014 -328.354075) (xy 239.390623 -328.400632) (xy 239.428063 -328.45228) (xy 239.458747 -328.508207)
			(xy 239.482192 -328.567534) (xy 239.498028 -328.629328) (xy 239.506009 -328.692618) (xy 239.506506 -328.724514)
			(xy 239.506004 -328.756475) (xy 239.497993 -328.819893) (xy 239.482096 -328.881807) (xy 239.458564 -328.94124)
			(xy 239.42777 -328.997255) (xy 239.390197 -329.04897) (xy 239.34644 -329.095567) (xy 239.297187 -329.136312)
			(xy 239.243216 -329.170563) (xy 239.185377 -329.19778) (xy 239.124584 -329.217533) (xy 239.061794 -329.229511)
			(xy 238.997998 -329.233525) (xy 238.934202 -329.229511) (xy 238.871412 -329.217533) (xy 238.810619 -329.19778)
			(xy 238.75278 -329.170563) (xy 238.698809 -329.136312) (xy 238.649556 -329.095567) (xy 238.605799 -329.04897)
			(xy 238.568226 -328.997255) (xy 238.537432 -328.94124) (xy 238.5139 -328.881807) (xy 238.498003 -328.819893)
			(xy 238.489992 -328.756475) (xy 238.48949 -328.724514) (xy 238.489943 -328.692905) (xy 238.497792 -328.630176)
			(xy 238.513359 -328.568905) (xy 238.536404 -328.510037) (xy 238.56657 -328.454481) (xy 238.603393 -328.403093)
			(xy 238.646303 -328.356669) (xy 238.694638 -328.315923) (xy 238.720884 -328.298302) (xy 238.731552 -328.29119)
			(xy 238.743998 -328.26833) (xy 238.74349 -328.157078) (xy 238.731044 -328.134472) (xy 238.720122 -328.12736)
			(xy 238.693472 -328.109826) (xy 238.644379 -328.069086) (xy 238.600771 -328.022522) (xy 238.563332 -327.970868)
			(xy 238.532652 -327.914934) (xy 238.509213 -327.855601) (xy 238.493383 -327.793801) (xy 238.485411 -327.730506)
			(xy 238.484918 -327.698608) (xy 233.151414 -327.698608) (xy 233.148124 -327.796652) (xy 233.160062 -327.82002)
			(xy 233.171238 -327.827386) (xy 233.197216 -327.845036) (xy 233.244998 -327.885798) (xy 233.287396 -327.932136)
			(xy 233.323761 -327.983343) (xy 233.353541 -328.038641) (xy 233.371822 -328.085704) (xy 235.560106 -328.085704)
			(xy 235.564177 -328.030082) (xy 235.576303 -327.975645) (xy 235.596226 -327.923554) (xy 235.623522 -327.874919)
			(xy 235.657608 -327.830776) (xy 235.697757 -327.792067) (xy 235.743115 -327.759616) (xy 235.792715 -327.734115)
			(xy 235.845499 -327.716108) (xy 235.900342 -327.705978) (xy 235.956076 -327.703941) (xy 236.011513 -327.710041)
			(xy 236.06547 -327.724147) (xy 236.116799 -327.745959) (xy 236.164405 -327.775013) (xy 236.207273 -327.810688)
			(xy 236.24449 -327.852225) (xy 236.275263 -327.898738) (xy 236.298935 -327.949235) (xy 236.315003 -328.002642)
			(xy 236.323123 -328.057818) (xy 236.323632 -328.085704) (xy 236.323123 -328.11359) (xy 236.315003 -328.168766)
			(xy 236.298935 -328.222173) (xy 236.275263 -328.27267) (xy 236.24449 -328.319183) (xy 236.207273 -328.36072)
			(xy 236.164405 -328.396395) (xy 236.116799 -328.425449) (xy 236.06547 -328.447261) (xy 236.011513 -328.461367)
			(xy 235.956076 -328.467467) (xy 235.900342 -328.46543) (xy 235.845499 -328.4553) (xy 235.792715 -328.437293)
			(xy 235.743115 -328.411792) (xy 235.697757 -328.379341) (xy 235.657608 -328.340632) (xy 235.623522 -328.296489)
			(xy 235.596226 -328.247854) (xy 235.576303 -328.195763) (xy 235.564177 -328.141326) (xy 235.560106 -328.085704)
			(xy 233.371822 -328.085704) (xy 233.376282 -328.097187) (xy 233.391637 -328.158088) (xy 233.399372 -328.220417)
			(xy 233.399838 -328.25182) (xy 233.399313 -328.28397) (xy 233.391194 -328.347756) (xy 233.375099 -328.410009)
			(xy 233.351287 -328.469738) (xy 233.320136 -328.525989) (xy 233.282144 -328.577865) (xy 233.237916 -328.624538)
			(xy 233.188158 -328.665265) (xy 233.133664 -328.699396) (xy 233.10469 -328.713338) (xy 233.090974 -328.719688)
			(xy 233.074972 -328.745088) (xy 233.076496 -328.86777) (xy 233.093006 -328.892662) (xy 233.106722 -328.898758)
			(xy 233.136596 -328.91232) (xy 233.192907 -328.945988) (xy 233.24442 -328.986621) (xy 233.290278 -329.033541)
			(xy 233.329719 -329.085971) (xy 233.362088 -329.143039) (xy 233.37433 -329.173078) (xy 235.579664 -329.173078)
			(xy 235.583735 -329.117456) (xy 235.595861 -329.063019) (xy 235.615784 -329.010928) (xy 235.64308 -328.962293)
			(xy 235.677166 -328.91815) (xy 235.717315 -328.879441) (xy 235.762673 -328.84699) (xy 235.812273 -328.821489)
			(xy 235.865057 -328.803482) (xy 235.9199 -328.793352) (xy 235.975634 -328.791315) (xy 236.031071 -328.797415)
			(xy 236.085028 -328.811521) (xy 236.136357 -328.833333) (xy 236.183963 -328.862387) (xy 236.226831 -328.898062)
			(xy 236.264048 -328.939599) (xy 236.294821 -328.986112) (xy 236.318493 -329.036609) (xy 236.334561 -329.090016)
			(xy 236.342681 -329.145192) (xy 236.34319 -329.173078) (xy 236.342681 -329.200964) (xy 236.334561 -329.25614)
			(xy 236.318493 -329.309547) (xy 236.294821 -329.360044) (xy 236.264048 -329.406557) (xy 236.226831 -329.448094)
			(xy 236.183963 -329.483769) (xy 236.136357 -329.512823) (xy 236.085028 -329.534635) (xy 236.031071 -329.548741)
			(xy 235.975634 -329.554841) (xy 235.9199 -329.552804) (xy 235.865057 -329.542674) (xy 235.812273 -329.524667)
			(xy 235.762673 -329.499166) (xy 235.717315 -329.466715) (xy 235.677166 -329.428006) (xy 235.64308 -329.383863)
			(xy 235.615784 -329.335228) (xy 235.595861 -329.283137) (xy 235.583735 -329.2287) (xy 235.579664 -329.173078)
			(xy 233.37433 -329.173078) (xy 233.386848 -329.203796) (xy 233.403586 -329.267234) (xy 233.412025 -329.332298)
			(xy 233.412538 -329.365102) (xy 233.412036 -329.397063) (xy 233.404025 -329.460481) (xy 233.388128 -329.522395)
			(xy 233.364596 -329.581828) (xy 233.333802 -329.637843) (xy 233.296229 -329.689558) (xy 233.252472 -329.736155)
			(xy 233.203219 -329.7769) (xy 233.149248 -329.811151) (xy 233.091409 -329.838368) (xy 233.030616 -329.858121)
			(xy 232.967826 -329.870099) (xy 232.90403 -329.874113) (xy 232.840234 -329.870099) (xy 232.777444 -329.858121)
			(xy 232.716651 -329.838368) (xy 232.658812 -329.811151) (xy 232.604841 -329.7769) (xy 232.555588 -329.736155)
			(xy 232.511831 -329.689558) (xy 232.474258 -329.637843) (xy 232.443464 -329.581828) (xy 232.419932 -329.522395)
			(xy 232.404035 -329.460481) (xy 232.396024 -329.397063) (xy 232.395522 -329.365102) (xy 232.396088 -329.332953)
			(xy 232.404204 -329.26917) (xy 232.420295 -329.206919) (xy 232.444103 -329.147192) (xy 232.475248 -329.090942)
			(xy 232.513235 -329.039065) (xy 232.557457 -328.992391) (xy 232.60721 -328.951662) (xy 232.661699 -328.917528)
			(xy 232.69067 -328.903584) (xy 232.704386 -328.897234) (xy 232.720388 -328.871834) (xy 232.718864 -328.749152)
			(xy 232.702354 -328.72426) (xy 232.688638 -328.718164) (xy 232.658763 -328.704604) (xy 232.602454 -328.670933)
			(xy 232.550943 -328.6303) (xy 232.505086 -328.583378) (xy 232.465646 -328.530948) (xy 232.433277 -328.473881)
			(xy 232.408517 -328.413124) (xy 232.391777 -328.349687) (xy 232.383336 -328.284624) (xy 232.382822 -328.25182)
			(xy 218.028266 -328.25182) (xy 217.641424 -328.638662) (xy 229.145336 -328.638662) (xy 229.149407 -328.58304)
			(xy 229.161533 -328.528603) (xy 229.181456 -328.476512) (xy 229.208752 -328.427877) (xy 229.242838 -328.383734)
			(xy 229.282987 -328.345025) (xy 229.328345 -328.312574) (xy 229.377945 -328.287073) (xy 229.430729 -328.269066)
			(xy 229.485572 -328.258936) (xy 229.541306 -328.256899) (xy 229.596743 -328.262999) (xy 229.6507 -328.277105)
			(xy 229.702029 -328.298917) (xy 229.749635 -328.327971) (xy 229.792503 -328.363646) (xy 229.82972 -328.405183)
			(xy 229.860493 -328.451696) (xy 229.884165 -328.502193) (xy 229.900233 -328.5556) (xy 229.908353 -328.610776)
			(xy 229.908862 -328.638662) (xy 229.908353 -328.666548) (xy 229.900233 -328.721724) (xy 229.884165 -328.775131)
			(xy 229.860493 -328.825628) (xy 229.82972 -328.872141) (xy 229.792503 -328.913678) (xy 229.749635 -328.949353)
			(xy 229.702029 -328.978407) (xy 229.6507 -329.000219) (xy 229.596743 -329.014325) (xy 229.541306 -329.020425)
			(xy 229.485572 -329.018388) (xy 229.430729 -329.008258) (xy 229.377945 -328.990251) (xy 229.328345 -328.96475)
			(xy 229.282987 -328.932299) (xy 229.242838 -328.89359) (xy 229.208752 -328.849447) (xy 229.181456 -328.800812)
			(xy 229.161533 -328.748721) (xy 229.149407 -328.694284) (xy 229.145336 -328.638662) (xy 217.641424 -328.638662)
			(xy 216.581228 -329.698858) (xy 229.155242 -329.698858) (xy 229.159313 -329.643236) (xy 229.171439 -329.588799)
			(xy 229.191362 -329.536708) (xy 229.218658 -329.488073) (xy 229.252744 -329.44393) (xy 229.292893 -329.405221)
			(xy 229.338251 -329.37277) (xy 229.387851 -329.347269) (xy 229.440635 -329.329262) (xy 229.495478 -329.319132)
			(xy 229.551212 -329.317095) (xy 229.606649 -329.323195) (xy 229.660606 -329.337301) (xy 229.711935 -329.359113)
			(xy 229.759541 -329.388167) (xy 229.802409 -329.423842) (xy 229.839626 -329.465379) (xy 229.870399 -329.511892)
			(xy 229.894071 -329.562389) (xy 229.910139 -329.615796) (xy 229.918259 -329.670972) (xy 229.918768 -329.698858)
			(xy 229.918259 -329.726744) (xy 229.910139 -329.78192) (xy 229.894071 -329.835327) (xy 229.870399 -329.885824)
			(xy 229.839626 -329.932337) (xy 229.802409 -329.973874) (xy 229.759541 -330.009549) (xy 229.711935 -330.038603)
			(xy 229.660606 -330.060415) (xy 229.606649 -330.074521) (xy 229.551212 -330.080621) (xy 229.495478 -330.078584)
			(xy 229.440635 -330.068454) (xy 229.387851 -330.050447) (xy 229.338251 -330.024946) (xy 229.292893 -329.992495)
			(xy 229.252744 -329.953786) (xy 229.218658 -329.909643) (xy 229.191362 -329.861008) (xy 229.171439 -329.808917)
			(xy 229.159313 -329.75448) (xy 229.155242 -329.698858) (xy 216.581228 -329.698858) (xy 216.252552 -330.027534)
			(xy 216.245934 -330.034705) (xy 216.238233 -330.052616) (xy 216.237829 -330.072108) (xy 216.240868 -330.081382)
			(xy 216.27846 -330.181966) (xy 216.302082 -330.199746) (xy 216.317068 -330.200762) (xy 216.348742 -330.203507)
			(xy 216.411103 -330.215886) (xy 216.471435 -330.235944) (xy 216.528795 -330.263365) (xy 216.58229 -330.297724)
			(xy 216.631085 -330.338482) (xy 216.674418 -330.385006) (xy 216.711613 -330.436568) (xy 216.74209 -330.492365)
			(xy 216.765375 -330.551527) (xy 216.781102 -330.613129) (xy 216.789028 -330.676211) (xy 216.789508 -330.708)
			(xy 216.789046 -330.738693) (xy 216.781656 -330.799634) (xy 216.766983 -330.859241) (xy 216.74524 -330.916648)
			(xy 216.716745 -330.97102) (xy 216.68191 -331.021566) (xy 216.641244 -331.067551) (xy 216.618566 -331.088238)
			(xy 216.610692 -331.09535) (xy 216.601802 -331.1144) (xy 216.599008 -331.209396) (xy 216.606882 -331.228954)
			(xy 216.614248 -331.23632) (xy 216.637558 -331.260245) (xy 216.678344 -331.313145) (xy 216.711847 -331.370934)
			(xy 216.737487 -331.432614) (xy 216.754824 -331.497123) (xy 216.763558 -331.563347) (xy 216.764108 -331.596746)
			(xy 216.763606 -331.628707) (xy 216.755595 -331.692125) (xy 216.739698 -331.754039) (xy 216.716166 -331.813472)
			(xy 216.685372 -331.869487) (xy 216.647799 -331.921202) (xy 216.604042 -331.967799) (xy 216.554789 -332.008544)
			(xy 216.500818 -332.042795) (xy 216.442979 -332.070012) (xy 216.382186 -332.089765) (xy 216.319396 -332.101743)
			(xy 216.267631 -332.105) (xy 224.407982 -332.105) (xy 224.412053 -332.049378) (xy 224.424179 -331.994941)
			(xy 224.444102 -331.94285) (xy 224.471398 -331.894215) (xy 224.505484 -331.850072) (xy 224.545633 -331.811363)
			(xy 224.590991 -331.778912) (xy 224.640591 -331.753411) (xy 224.693375 -331.735404) (xy 224.748218 -331.725274)
			(xy 224.803952 -331.723237) (xy 224.859389 -331.729337) (xy 224.913346 -331.743443) (xy 224.964675 -331.765255)
			(xy 225.012281 -331.794309) (xy 225.055149 -331.829984) (xy 225.092366 -331.871521) (xy 225.123139 -331.918034)
			(xy 225.146811 -331.968531) (xy 225.162879 -332.021938) (xy 225.170999 -332.077114) (xy 225.171508 -332.105)
			(xy 225.170999 -332.132886) (xy 225.170399 -332.136961) (xy 226.059994 -332.136961) (xy 226.059994 -332.073039)
			(xy 226.068005 -332.009621) (xy 226.083902 -331.947707) (xy 226.107434 -331.888274) (xy 226.138228 -331.832259)
			(xy 226.175801 -331.780544) (xy 226.219558 -331.733947) (xy 226.268811 -331.693202) (xy 226.322782 -331.658951)
			(xy 226.380621 -331.631734) (xy 226.441414 -331.611981) (xy 226.504204 -331.600003) (xy 226.568 -331.59599)
			(xy 226.631796 -331.600003) (xy 226.694586 -331.611981) (xy 226.755379 -331.631734) (xy 226.813218 -331.658951)
			(xy 226.867189 -331.693202) (xy 226.904418 -331.724) (xy 234.314492 -331.724) (xy 234.314911 -331.69272)
			(xy 234.322575 -331.630631) (xy 234.337801 -331.569953) (xy 234.360358 -331.511601) (xy 234.389904 -331.456458)
			(xy 234.425995 -331.405358) (xy 234.468083 -331.359072) (xy 234.515532 -331.318301) (xy 234.541314 -331.300582)
			(xy 234.551474 -331.29313) (xy 234.56346 -331.270999) (xy 234.564174 -331.258418) (xy 234.564174 -331.173582)
			(xy 234.563494 -331.160999) (xy 234.551472 -331.13888) (xy 234.541314 -331.131418) (xy 234.515567 -331.113656)
			(xy 234.468139 -331.072876) (xy 234.426068 -331.026589) (xy 234.38999 -330.975492) (xy 234.36045 -330.920358)
			(xy 234.337892 -330.862017) (xy 234.322657 -330.801351) (xy 234.314976 -330.739275) (xy 234.314492 -330.708)
			(xy 234.314994 -330.676039) (xy 234.323005 -330.612621) (xy 234.338902 -330.550707) (xy 234.362434 -330.491274)
			(xy 234.393228 -330.435259) (xy 234.430801 -330.383544) (xy 234.474558 -330.336947) (xy 234.523811 -330.296202)
			(xy 234.577782 -330.261951) (xy 234.635621 -330.234734) (xy 234.696414 -330.214981) (xy 234.759204 -330.203003)
			(xy 234.823 -330.19899) (xy 234.886796 -330.203003) (xy 234.949586 -330.214981) (xy 235.010379 -330.234734)
			(xy 235.068218 -330.261951) (xy 235.122189 -330.296202) (xy 235.171442 -330.336947) (xy 235.215199 -330.383544)
			(xy 235.252772 -330.435259) (xy 235.283566 -330.491274) (xy 235.307098 -330.550707) (xy 235.322995 -330.612621)
			(xy 235.331006 -330.676039) (xy 235.331508 -330.708) (xy 235.331089 -330.73928) (xy 235.323425 -330.801369)
			(xy 235.308199 -330.862047) (xy 235.285642 -330.920399) (xy 235.256096 -330.975542) (xy 235.220005 -331.026642)
			(xy 235.177917 -331.072928) (xy 235.130468 -331.113699) (xy 235.104686 -331.131418) (xy 235.094526 -331.13887)
			(xy 235.08254 -331.161001) (xy 235.081826 -331.173582) (xy 235.081826 -331.258418) (xy 235.082506 -331.271001)
			(xy 235.094528 -331.29312) (xy 235.104686 -331.300582) (xy 235.130433 -331.318344) (xy 235.159108 -331.343)
			(xy 237.870492 -331.343) (xy 237.870975 -331.314081) (xy 237.879707 -331.256907) (xy 237.896969 -331.201706)
			(xy 237.922367 -331.149744) (xy 237.955319 -331.102211) (xy 237.995068 -331.060197) (xy 238.017558 -331.04201)
			(xy 238.026321 -331.034449) (xy 238.036501 -331.013689) (xy 238.037116 -331.002132) (xy 238.037116 -330.921868)
			(xy 238.036501 -330.910306) (xy 238.026337 -330.889535) (xy 238.017558 -330.88199) (xy 237.995061 -330.863815)
			(xy 237.955329 -330.821791) (xy 237.922392 -330.774252) (xy 237.897007 -330.722288) (xy 237.879753 -330.667088)
			(xy 237.871026 -330.609917) (xy 237.870492 -330.581) (xy 237.870978 -330.553749) (xy 237.878734 -330.499801)
			(xy 237.894089 -330.447506) (xy 237.916731 -330.397929) (xy 237.946197 -330.352079) (xy 237.981888 -330.310888)
			(xy 238.023079 -330.275197) (xy 238.068929 -330.245731) (xy 238.118506 -330.223089) (xy 238.170801 -330.207734)
			(xy 238.224749 -330.199978) (xy 238.279251 -330.199978) (xy 238.333199 -330.207734) (xy 238.385494 -330.223089)
			(xy 238.435071 -330.245731) (xy 238.480921 -330.275197) (xy 238.522112 -330.310888) (xy 238.557803 -330.352079)
			(xy 238.587269 -330.397929) (xy 238.609911 -330.447506) (xy 238.625266 -330.499801) (xy 238.633022 -330.553749)
			(xy 238.633508 -330.581) (xy 238.633025 -330.609919) (xy 238.624293 -330.667093) (xy 238.607031 -330.722294)
			(xy 238.581633 -330.774256) (xy 238.548681 -330.821789) (xy 238.508932 -330.863803) (xy 238.486442 -330.88199)
			(xy 238.477679 -330.889551) (xy 238.467499 -330.910311) (xy 238.466884 -330.921868) (xy 238.466884 -331.002132)
			(xy 238.467499 -331.013694) (xy 238.477663 -331.034465) (xy 238.486442 -331.04201) (xy 238.508939 -331.060185)
			(xy 238.548671 -331.102209) (xy 238.581608 -331.149748) (xy 238.606993 -331.201712) (xy 238.624247 -331.256912)
			(xy 238.632974 -331.314083) (xy 238.633508 -331.343) (xy 238.633022 -331.370251) (xy 238.625266 -331.424199)
			(xy 238.609911 -331.476494) (xy 238.587269 -331.526071) (xy 238.557803 -331.571921) (xy 238.522112 -331.613112)
			(xy 238.480921 -331.648803) (xy 238.435071 -331.678269) (xy 238.385494 -331.700911) (xy 238.333199 -331.716266)
			(xy 238.279251 -331.724022) (xy 238.224749 -331.724022) (xy 238.170801 -331.716266) (xy 238.118506 -331.700911)
			(xy 238.068929 -331.678269) (xy 238.023079 -331.648803) (xy 237.981888 -331.613112) (xy 237.946197 -331.571921)
			(xy 237.916731 -331.526071) (xy 237.894089 -331.476494) (xy 237.878734 -331.424199) (xy 237.870978 -331.370251)
			(xy 237.870492 -331.343) (xy 235.159108 -331.343) (xy 235.177861 -331.359124) (xy 235.219932 -331.405411)
			(xy 235.25601 -331.456508) (xy 235.28555 -331.511642) (xy 235.308108 -331.569983) (xy 235.323343 -331.630649)
			(xy 235.331024 -331.692725) (xy 235.331508 -331.724) (xy 235.331006 -331.755961) (xy 235.322995 -331.819379)
			(xy 235.307098 -331.881293) (xy 235.283566 -331.940726) (xy 235.252772 -331.996741) (xy 235.215199 -332.048456)
			(xy 235.171442 -332.095053) (xy 235.122189 -332.135798) (xy 235.068218 -332.170049) (xy 235.010379 -332.197266)
			(xy 234.949586 -332.217019) (xy 234.886796 -332.228997) (xy 234.823 -332.233011) (xy 234.759204 -332.228997)
			(xy 234.696414 -332.217019) (xy 234.635621 -332.197266) (xy 234.577782 -332.170049) (xy 234.523811 -332.135798)
			(xy 234.474558 -332.095053) (xy 234.430801 -332.048456) (xy 234.393228 -331.996741) (xy 234.362434 -331.940726)
			(xy 234.338902 -331.881293) (xy 234.323005 -331.819379) (xy 234.314994 -331.755961) (xy 234.314492 -331.724)
			(xy 226.904418 -331.724) (xy 226.916442 -331.733947) (xy 226.960199 -331.780544) (xy 226.997772 -331.832259)
			(xy 227.028566 -331.888274) (xy 227.052098 -331.947707) (xy 227.067995 -332.009621) (xy 227.076006 -332.073039)
			(xy 227.076508 -332.105) (xy 227.076006 -332.136961) (xy 227.067995 -332.200379) (xy 227.052098 -332.262293)
			(xy 227.028566 -332.321726) (xy 226.997772 -332.377741) (xy 226.960199 -332.429456) (xy 226.916442 -332.476053)
			(xy 226.867189 -332.516798) (xy 226.813218 -332.551049) (xy 226.755379 -332.578266) (xy 226.694586 -332.598019)
			(xy 226.631796 -332.609997) (xy 226.568 -332.614011) (xy 226.504204 -332.609997) (xy 226.441414 -332.598019)
			(xy 226.380621 -332.578266) (xy 226.322782 -332.551049) (xy 226.268811 -332.516798) (xy 226.219558 -332.476053)
			(xy 226.175801 -332.429456) (xy 226.138228 -332.377741) (xy 226.107434 -332.321726) (xy 226.083902 -332.262293)
			(xy 226.068005 -332.200379) (xy 226.059994 -332.136961) (xy 225.170399 -332.136961) (xy 225.162879 -332.188062)
			(xy 225.146811 -332.241469) (xy 225.123139 -332.291966) (xy 225.092366 -332.338479) (xy 225.055149 -332.380016)
			(xy 225.012281 -332.415691) (xy 224.964675 -332.444745) (xy 224.913346 -332.466557) (xy 224.859389 -332.480663)
			(xy 224.803952 -332.486763) (xy 224.748218 -332.484726) (xy 224.693375 -332.474596) (xy 224.640591 -332.456589)
			(xy 224.590991 -332.431088) (xy 224.545633 -332.398637) (xy 224.505484 -332.359928) (xy 224.471398 -332.315785)
			(xy 224.444102 -332.26715) (xy 224.424179 -332.215059) (xy 224.412053 -332.160622) (xy 224.407982 -332.105)
			(xy 216.267631 -332.105) (xy 216.2556 -332.105757) (xy 216.191804 -332.101743) (xy 216.129014 -332.089765)
			(xy 216.068221 -332.070012) (xy 216.010382 -332.042795) (xy 215.956411 -332.008544) (xy 215.907158 -331.967799)
			(xy 215.863401 -331.921202) (xy 215.825828 -331.869487) (xy 215.795034 -331.813472) (xy 215.771502 -331.754039)
			(xy 215.755605 -331.692125) (xy 215.747594 -331.628707) (xy 215.747092 -331.596746) (xy 215.747557 -331.566054)
			(xy 215.754953 -331.505117) (xy 215.769631 -331.445514) (xy 215.791378 -331.388111) (xy 215.819877 -331.333743)
			(xy 215.854714 -331.283202) (xy 215.895382 -331.237223) (xy 215.918034 -331.216508) (xy 215.925908 -331.209396)
			(xy 215.934798 -331.190346) (xy 215.937592 -331.09535) (xy 215.929718 -331.075792) (xy 215.922352 -331.068426)
			(xy 215.901127 -331.046676) (xy 215.863466 -330.998979) (xy 215.831753 -330.947137) (xy 215.80644 -330.891887)
			(xy 215.787885 -330.834016) (xy 215.776355 -330.774347) (xy 215.773762 -330.744068) (xy 215.772746 -330.729082)
			(xy 215.754966 -330.70546) (xy 215.654382 -330.667868) (xy 215.645109 -330.664877) (xy 215.625648 -330.665347)
			(xy 215.60775 -330.673003) (xy 215.600534 -330.679552) (xy 215.009476 -331.27061) (xy 215.002081 -331.277463)
			(xy 214.983481 -331.285202) (xy 214.973408 -331.285596) (xy 214.341456 -331.285596) (xy 214.331477 -331.28603)
			(xy 214.313001 -331.293564) (xy 214.298807 -331.307587) (xy 214.294466 -331.316584) (xy 214.252048 -331.416914)
			(xy 214.25789 -331.446886) (xy 214.268558 -331.458062) (xy 214.288694 -331.479551) (xy 214.322773 -331.527574)
			(xy 214.349067 -331.580264) (xy 214.366952 -331.636369) (xy 214.376001 -331.694557) (xy 214.376508 -331.724)
			(xy 214.376022 -331.751251) (xy 214.368266 -331.805199) (xy 214.352911 -331.857494) (xy 214.330269 -331.907071)
			(xy 214.300803 -331.952921) (xy 214.265112 -331.994112) (xy 214.223921 -332.029803) (xy 214.178071 -332.059269)
			(xy 214.128494 -332.081911) (xy 214.076199 -332.097266) (xy 214.022251 -332.105022) (xy 213.967749 -332.105022)
			(xy 213.913801 -332.097266) (xy 213.861506 -332.081911) (xy 213.811929 -332.059269) (xy 213.766079 -332.029803)
			(xy 213.724888 -331.994112) (xy 213.689197 -331.952921) (xy 213.659731 -331.907071) (xy 213.637089 -331.857494)
			(xy 213.621734 -331.805199) (xy 213.613978 -331.751251) (xy 213.613492 -331.724) (xy 213.614038 -331.694558)
			(xy 213.623083 -331.636373) (xy 213.640958 -331.580269) (xy 213.667239 -331.527575) (xy 213.701303 -331.479545)
			(xy 213.721442 -331.458062) (xy 213.73211 -331.446886) (xy 213.737952 -331.416914) (xy 213.695534 -331.316584)
			(xy 213.691191 -331.307594) (xy 213.676985 -331.293593) (xy 213.658518 -331.286055) (xy 213.648544 -331.285596)
			(xy 208.618328 -331.285596) (xy 208.608264 -331.286032) (xy 208.589678 -331.293765) (xy 208.58226 -331.300582)
			(xy 207.606646 -332.276196) (xy 207.599794 -332.283592) (xy 207.592051 -332.302191) (xy 207.59166 -332.312264)
			(xy 207.59166 -332.74) (xy 213.612982 -332.74) (xy 213.617053 -332.684378) (xy 213.629179 -332.629941)
			(xy 213.649102 -332.57785) (xy 213.676398 -332.529215) (xy 213.710484 -332.485072) (xy 213.750633 -332.446363)
			(xy 213.795991 -332.413912) (xy 213.845591 -332.388411) (xy 213.898375 -332.370404) (xy 213.953218 -332.360274)
			(xy 214.008952 -332.358237) (xy 214.064389 -332.364337) (xy 214.118346 -332.378443) (xy 214.169675 -332.400255)
			(xy 214.217281 -332.429309) (xy 214.260149 -332.464984) (xy 214.297366 -332.506521) (xy 214.328139 -332.553034)
			(xy 214.351811 -332.603531) (xy 214.367879 -332.656938) (xy 214.375999 -332.712114) (xy 214.376508 -332.74)
			(xy 214.375999 -332.767886) (xy 214.375399 -332.771961) (xy 215.56573 -332.771961) (xy 215.56573 -332.708039)
			(xy 215.573741 -332.644621) (xy 215.589638 -332.582707) (xy 215.61317 -332.523274) (xy 215.643964 -332.467259)
			(xy 215.681537 -332.415544) (xy 215.725294 -332.368947) (xy 215.774547 -332.328202) (xy 215.828518 -332.293951)
			(xy 215.886357 -332.266734) (xy 215.94715 -332.246981) (xy 216.00994 -332.235003) (xy 216.073736 -332.23099)
			(xy 216.137532 -332.235003) (xy 216.200322 -332.246981) (xy 216.261115 -332.266734) (xy 216.318954 -332.293951)
			(xy 216.372925 -332.328202) (xy 216.422178 -332.368947) (xy 216.465935 -332.415544) (xy 216.503508 -332.467259)
			(xy 216.534302 -332.523274) (xy 216.557834 -332.582707) (xy 216.573731 -332.644621) (xy 216.581742 -332.708039)
			(xy 216.582244 -332.74) (xy 216.581742 -332.771961) (xy 231.266994 -332.771961) (xy 231.266994 -332.708039)
			(xy 231.275005 -332.644621) (xy 231.290902 -332.582707) (xy 231.314434 -332.523274) (xy 231.345228 -332.467259)
			(xy 231.382801 -332.415544) (xy 231.426558 -332.368947) (xy 231.475811 -332.328202) (xy 231.529782 -332.293951)
			(xy 231.587621 -332.266734) (xy 231.648414 -332.246981) (xy 231.711204 -332.235003) (xy 231.775 -332.23099)
			(xy 231.838796 -332.235003) (xy 231.901586 -332.246981) (xy 231.962379 -332.266734) (xy 232.020218 -332.293951)
			(xy 232.074189 -332.328202) (xy 232.123442 -332.368947) (xy 232.167199 -332.415544) (xy 232.204772 -332.467259)
			(xy 232.235566 -332.523274) (xy 232.259098 -332.582707) (xy 232.274995 -332.644621) (xy 232.283006 -332.708039)
			(xy 232.283508 -332.74) (xy 234.313982 -332.74) (xy 234.318053 -332.684378) (xy 234.330179 -332.629941)
			(xy 234.350102 -332.57785) (xy 234.377398 -332.529215) (xy 234.411484 -332.485072) (xy 234.451633 -332.446363)
			(xy 234.496991 -332.413912) (xy 234.546591 -332.388411) (xy 234.599375 -332.370404) (xy 234.654218 -332.360274)
			(xy 234.709952 -332.358237) (xy 234.765389 -332.364337) (xy 234.819346 -332.378443) (xy 234.870675 -332.400255)
			(xy 234.918281 -332.429309) (xy 234.961149 -332.464984) (xy 234.998366 -332.506521) (xy 235.029139 -332.553034)
			(xy 235.052811 -332.603531) (xy 235.05566 -332.613) (xy 237.869982 -332.613) (xy 237.874053 -332.557378)
			(xy 237.886179 -332.502941) (xy 237.906102 -332.45085) (xy 237.933398 -332.402215) (xy 237.967484 -332.358072)
			(xy 238.007633 -332.319363) (xy 238.052991 -332.286912) (xy 238.102591 -332.261411) (xy 238.155375 -332.243404)
			(xy 238.210218 -332.233274) (xy 238.265952 -332.231237) (xy 238.321389 -332.237337) (xy 238.375346 -332.251443)
			(xy 238.426675 -332.273255) (xy 238.474281 -332.302309) (xy 238.517149 -332.337984) (xy 238.554366 -332.379521)
			(xy 238.585139 -332.426034) (xy 238.608811 -332.476531) (xy 238.624879 -332.529938) (xy 238.632999 -332.585114)
			(xy 238.633508 -332.613) (xy 238.632999 -332.640886) (xy 238.624879 -332.696062) (xy 238.608811 -332.749469)
			(xy 238.585139 -332.799966) (xy 238.554366 -332.846479) (xy 238.517149 -332.888016) (xy 238.474281 -332.923691)
			(xy 238.426675 -332.952745) (xy 238.375346 -332.974557) (xy 238.321389 -332.988663) (xy 238.265952 -332.994763)
			(xy 238.210218 -332.992726) (xy 238.155375 -332.982596) (xy 238.102591 -332.964589) (xy 238.052991 -332.939088)
			(xy 238.007633 -332.906637) (xy 237.967484 -332.867928) (xy 237.933398 -332.823785) (xy 237.906102 -332.77515)
			(xy 237.886179 -332.723059) (xy 237.874053 -332.668622) (xy 237.869982 -332.613) (xy 235.05566 -332.613)
			(xy 235.068879 -332.656938) (xy 235.076999 -332.712114) (xy 235.077508 -332.74) (xy 235.076999 -332.767886)
			(xy 235.068879 -332.823062) (xy 235.052811 -332.876469) (xy 235.029139 -332.926966) (xy 234.998366 -332.973479)
			(xy 234.961149 -333.015016) (xy 234.918281 -333.050691) (xy 234.870675 -333.079745) (xy 234.819346 -333.101557)
			(xy 234.765389 -333.115663) (xy 234.709952 -333.121763) (xy 234.654218 -333.119726) (xy 234.599375 -333.109596)
			(xy 234.546591 -333.091589) (xy 234.496991 -333.066088) (xy 234.451633 -333.033637) (xy 234.411484 -332.994928)
			(xy 234.377398 -332.950785) (xy 234.350102 -332.90215) (xy 234.330179 -332.850059) (xy 234.318053 -332.795622)
			(xy 234.313982 -332.74) (xy 232.283508 -332.74) (xy 232.283006 -332.771961) (xy 232.274995 -332.835379)
			(xy 232.259098 -332.897293) (xy 232.235566 -332.956726) (xy 232.204772 -333.012741) (xy 232.167199 -333.064456)
			(xy 232.123442 -333.111053) (xy 232.074189 -333.151798) (xy 232.020218 -333.186049) (xy 231.962379 -333.213266)
			(xy 231.901586 -333.233019) (xy 231.838796 -333.244997) (xy 231.775 -333.249011) (xy 231.711204 -333.244997)
			(xy 231.648414 -333.233019) (xy 231.587621 -333.213266) (xy 231.529782 -333.186049) (xy 231.475811 -333.151798)
			(xy 231.426558 -333.111053) (xy 231.382801 -333.064456) (xy 231.345228 -333.012741) (xy 231.314434 -332.956726)
			(xy 231.290902 -332.897293) (xy 231.275005 -332.835379) (xy 231.266994 -332.771961) (xy 216.581742 -332.771961)
			(xy 216.573731 -332.835379) (xy 216.557834 -332.897293) (xy 216.534302 -332.956726) (xy 216.503508 -333.012741)
			(xy 216.465935 -333.064456) (xy 216.422178 -333.111053) (xy 216.372925 -333.151798) (xy 216.318954 -333.186049)
			(xy 216.261115 -333.213266) (xy 216.200322 -333.233019) (xy 216.137532 -333.244997) (xy 216.073736 -333.249011)
			(xy 216.00994 -333.244997) (xy 215.94715 -333.233019) (xy 215.886357 -333.213266) (xy 215.828518 -333.186049)
			(xy 215.774547 -333.151798) (xy 215.725294 -333.111053) (xy 215.681537 -333.064456) (xy 215.643964 -333.012741)
			(xy 215.61317 -332.956726) (xy 215.589638 -332.897293) (xy 215.573741 -332.835379) (xy 215.56573 -332.771961)
			(xy 214.375399 -332.771961) (xy 214.367879 -332.823062) (xy 214.351811 -332.876469) (xy 214.328139 -332.926966)
			(xy 214.297366 -332.973479) (xy 214.260149 -333.015016) (xy 214.217281 -333.050691) (xy 214.169675 -333.079745)
			(xy 214.118346 -333.101557) (xy 214.064389 -333.115663) (xy 214.008952 -333.121763) (xy 213.953218 -333.119726)
			(xy 213.898375 -333.109596) (xy 213.845591 -333.091589) (xy 213.795991 -333.066088) (xy 213.750633 -333.033637)
			(xy 213.710484 -332.994928) (xy 213.676398 -332.950785) (xy 213.649102 -332.90215) (xy 213.629179 -332.850059)
			(xy 213.617053 -332.795622) (xy 213.612982 -332.74) (xy 207.59166 -332.74) (xy 207.59166 -333.365305)
			(xy 222.487738 -333.365305) (xy 222.487738 -333.301383) (xy 222.495749 -333.237965) (xy 222.511646 -333.176051)
			(xy 222.535178 -333.116618) (xy 222.565972 -333.060603) (xy 222.603545 -333.008888) (xy 222.647302 -332.962291)
			(xy 222.696555 -332.921546) (xy 222.750526 -332.887295) (xy 222.808365 -332.860078) (xy 222.869158 -332.840325)
			(xy 222.931948 -332.828347) (xy 222.995744 -332.824334) (xy 223.05954 -332.828347) (xy 223.12233 -332.840325)
			(xy 223.183123 -332.860078) (xy 223.240962 -332.887295) (xy 223.294933 -332.921546) (xy 223.344186 -332.962291)
			(xy 223.387943 -333.008888) (xy 223.425516 -333.060603) (xy 223.45631 -333.116618) (xy 223.479842 -333.176051)
			(xy 223.495739 -333.237965) (xy 223.50375 -333.301383) (xy 223.504252 -333.333344) (xy 223.50375 -333.365305)
			(xy 223.498488 -333.406961) (xy 232.663994 -333.406961) (xy 232.663994 -333.343039) (xy 232.672005 -333.279621)
			(xy 232.687902 -333.217707) (xy 232.711434 -333.158274) (xy 232.742228 -333.102259) (xy 232.779801 -333.050544)
			(xy 232.823558 -333.003947) (xy 232.872811 -332.963202) (xy 232.926782 -332.928951) (xy 232.984621 -332.901734)
			(xy 233.045414 -332.881981) (xy 233.108204 -332.870003) (xy 233.172 -332.86599) (xy 233.235796 -332.870003)
			(xy 233.298586 -332.881981) (xy 233.359379 -332.901734) (xy 233.417218 -332.928951) (xy 233.471189 -332.963202)
			(xy 233.520442 -333.003947) (xy 233.564199 -333.050544) (xy 233.601772 -333.102259) (xy 233.632566 -333.158274)
			(xy 233.656098 -333.217707) (xy 233.671995 -333.279621) (xy 233.680006 -333.343039) (xy 233.680508 -333.375)
			(xy 233.680006 -333.406961) (xy 233.671995 -333.470379) (xy 233.656098 -333.532293) (xy 233.632566 -333.591726)
			(xy 233.601772 -333.647741) (xy 233.564199 -333.699456) (xy 233.520442 -333.746053) (xy 233.471189 -333.786798)
			(xy 233.417218 -333.821049) (xy 233.359379 -333.848266) (xy 233.298586 -333.868019) (xy 233.235796 -333.879997)
			(xy 233.172 -333.884011) (xy 233.108204 -333.879997) (xy 233.045414 -333.868019) (xy 232.984621 -333.848266)
			(xy 232.926782 -333.821049) (xy 232.872811 -333.786798) (xy 232.823558 -333.746053) (xy 232.779801 -333.699456)
			(xy 232.742228 -333.647741) (xy 232.711434 -333.591726) (xy 232.687902 -333.532293) (xy 232.672005 -333.470379)
			(xy 232.663994 -333.406961) (xy 223.498488 -333.406961) (xy 223.495739 -333.428723) (xy 223.479842 -333.490637)
			(xy 223.45631 -333.55007) (xy 223.425516 -333.606085) (xy 223.387943 -333.6578) (xy 223.344186 -333.704397)
			(xy 223.294933 -333.745142) (xy 223.240962 -333.779393) (xy 223.183123 -333.80661) (xy 223.12233 -333.826363)
			(xy 223.05954 -333.838341) (xy 222.995744 -333.842355) (xy 222.931948 -333.838341) (xy 222.869158 -333.826363)
			(xy 222.808365 -333.80661) (xy 222.750526 -333.779393) (xy 222.696555 -333.745142) (xy 222.647302 -333.704397)
			(xy 222.603545 -333.6578) (xy 222.565972 -333.606085) (xy 222.535178 -333.55007) (xy 222.511646 -333.490637)
			(xy 222.495749 -333.428723) (xy 222.487738 -333.365305) (xy 207.59166 -333.365305) (xy 207.59166 -334.099408)
			(xy 234.558078 -334.099408) (xy 234.55858 -334.067447) (xy 234.566591 -334.004029) (xy 234.582488 -333.942115)
			(xy 234.60602 -333.882682) (xy 234.636814 -333.826667) (xy 234.674387 -333.774952) (xy 234.718144 -333.728355)
			(xy 234.767397 -333.68761) (xy 234.821368 -333.653359) (xy 234.879207 -333.626142) (xy 234.94 -333.606389)
			(xy 235.00279 -333.594411) (xy 235.066586 -333.590398) (xy 235.130382 -333.594411) (xy 235.193172 -333.606389)
			(xy 235.253965 -333.626142) (xy 235.311804 -333.653359) (xy 235.365775 -333.68761) (xy 235.415028 -333.728355)
			(xy 235.458785 -333.774952) (xy 235.496358 -333.826667) (xy 235.527152 -333.882682) (xy 235.550684 -333.942115)
			(xy 235.566581 -334.004029) (xy 235.574592 -334.067447) (xy 235.575094 -334.099408) (xy 235.573824 -334.133952)
			(xy 235.573316 -334.14462) (xy 235.580174 -334.164432) (xy 235.64596 -334.234282) (xy 235.665264 -334.24241)
			(xy 235.678726 -334.24241) (xy 235.705979 -334.242854) (xy 235.711722 -334.24368) (xy 236.610906 -334.24368)
			(xy 236.611449 -334.214834) (xy 236.620125 -334.157797) (xy 236.63729 -334.102718) (xy 236.662554 -334.050851)
			(xy 236.69534 -334.003379) (xy 236.7349 -333.961387) (xy 236.780332 -333.925829) (xy 236.830601 -333.897519)
			(xy 236.88456 -333.877101) (xy 236.912658 -333.870554) (xy 236.922056 -333.868522) (xy 236.937804 -333.858108)
			(xy 236.988858 -333.786734) (xy 236.99343 -333.768446) (xy 236.992414 -333.759048) (xy 236.990644 -333.743679)
			(xy 236.988738 -333.712796) (xy 236.988604 -333.697326) (xy 236.989106 -333.665365) (xy 236.997117 -333.601947)
			(xy 237.013014 -333.540033) (xy 237.036546 -333.4806) (xy 237.06734 -333.424585) (xy 237.104913 -333.37287)
			(xy 237.14867 -333.326273) (xy 237.197923 -333.285528) (xy 237.251894 -333.251277) (xy 237.309733 -333.22406)
			(xy 237.370526 -333.204307) (xy 237.433316 -333.192329) (xy 237.497112 -333.188316) (xy 237.560908 -333.192329)
			(xy 237.623698 -333.204307) (xy 237.684491 -333.22406) (xy 237.74233 -333.251277) (xy 237.796301 -333.285528)
			(xy 237.845554 -333.326273) (xy 237.889311 -333.37287) (xy 237.926884 -333.424585) (xy 237.957678 -333.4806)
			(xy 237.98121 -333.540033) (xy 237.997107 -333.601947) (xy 238.005118 -333.665365) (xy 238.00562 -333.697326)
			(xy 238.005168 -333.727441) (xy 237.998054 -333.78725) (xy 237.983928 -333.845801) (xy 237.962988 -333.902275)
			(xy 237.935527 -333.955882) (xy 237.90193 -334.005871) (xy 237.862665 -334.051544) (xy 237.840774 -334.07223)
			(xy 237.832138 -334.080104) (xy 237.823502 -334.10144) (xy 237.831122 -334.204564) (xy 237.842552 -334.224376)
			(xy 237.852204 -334.23098) (xy 237.877525 -334.248772) (xy 237.924097 -334.289528) (xy 237.965378 -334.335636)
			(xy 238.000756 -334.386413) (xy 238.029709 -334.44111) (xy 238.051809 -334.498916) (xy 238.066728 -334.558978)
			(xy 238.074246 -334.620407) (xy 238.074708 -334.65135) (xy 238.074291 -334.682082) (xy 238.066877 -334.743098)
			(xy 238.052163 -334.802774) (xy 238.030363 -334.860243) (xy 238.001795 -334.914665) (xy 237.966877 -334.965247)
			(xy 237.926116 -335.011251) (xy 237.880107 -335.052008) (xy 237.829522 -335.086921) (xy 237.775097 -335.115484)
			(xy 237.717627 -335.137278) (xy 237.657948 -335.151986) (xy 237.596932 -335.159394) (xy 237.5662 -335.159858)
			(xy 237.534637 -335.159433) (xy 237.472 -335.151597) (xy 237.410814 -335.136069) (xy 237.35202 -335.113089)
			(xy 237.296521 -335.08301) (xy 237.245172 -335.046295) (xy 237.198761 -335.003507) (xy 237.158001 -334.955304)
			(xy 237.12352 -334.902428) (xy 237.095847 -334.845691) (xy 237.075408 -334.785966) (xy 237.062517 -334.724171)
			(xy 237.05947 -334.692752) (xy 237.058192 -334.683388) (xy 237.049863 -334.666446) (xy 237.043214 -334.659732)
			(xy 237.020354 -334.63865) (xy 237.013254 -334.632693) (xy 236.996074 -334.625784) (xy 236.986826 -334.625188)
			(xy 236.959834 -334.624383) (xy 236.906492 -334.615975) (xy 236.854867 -334.600131) (xy 236.805991 -334.577168)
			(xy 236.760841 -334.547543) (xy 236.720319 -334.511849) (xy 236.685234 -334.470798) (xy 236.656286 -334.425211)
			(xy 236.634054 -334.375998) (xy 236.618983 -334.324143) (xy 236.611372 -334.270681) (xy 236.610906 -334.24368)
			(xy 235.711722 -334.24368) (xy 235.759929 -334.250614) (xy 235.812226 -334.265974) (xy 235.861804 -334.288619)
			(xy 235.907655 -334.31809) (xy 235.948846 -334.353786) (xy 235.984537 -334.39498) (xy 236.014002 -334.440835)
			(xy 236.036642 -334.490416) (xy 236.051995 -334.542714) (xy 236.059749 -334.596665) (xy 236.060234 -334.623918)
			(xy 236.059753 -334.651065) (xy 236.052054 -334.704811) (xy 236.036813 -334.756922) (xy 236.014338 -334.806347)
			(xy 235.985083 -334.852086) (xy 235.94964 -334.893216) (xy 235.908724 -334.928906) (xy 235.863162 -334.958435)
			(xy 235.813873 -334.981206) (xy 235.761854 -334.996761) (xy 235.708156 -335.004783) (xy 235.681012 -335.005426)
			(xy 235.671614 -335.005426) (xy 235.65485 -335.01203) (xy 235.590842 -335.068418) (xy 235.582206 -335.084166)
			(xy 235.580936 -335.093564) (xy 235.575966 -335.126432) (xy 235.558634 -335.190606) (xy 235.533086 -335.251974)
			(xy 235.499758 -335.309489) (xy 235.459218 -335.36217) (xy 235.412158 -335.409118) (xy 235.359381 -335.449532)
			(xy 235.301787 -335.482723) (xy 235.240359 -335.508125) (xy 235.176143 -335.525304) (xy 235.110237 -335.533967)
			(xy 235.077 -335.534508) (xy 235.046269 -335.534044) (xy 234.985255 -335.526635) (xy 234.925579 -335.511927)
			(xy 234.868111 -335.490132) (xy 234.813689 -335.461569) (xy 234.763107 -335.426655) (xy 234.717102 -335.385898)
			(xy 234.676345 -335.339893) (xy 234.641431 -335.289311) (xy 234.612868 -335.234889) (xy 234.591073 -335.177421)
			(xy 234.576365 -335.117745) (xy 234.568956 -335.056731) (xy 234.568492 -335.026) (xy 234.568997 -334.995064)
			(xy 234.576504 -334.933648) (xy 234.591406 -334.873597) (xy 234.613483 -334.815798) (xy 234.64241 -334.761104)
			(xy 234.677758 -334.710323) (xy 234.719006 -334.664206) (xy 234.741974 -334.643476) (xy 234.750356 -334.63611)
			(xy 234.759246 -334.616044) (xy 234.75823 -334.516476) (xy 234.748578 -334.49641) (xy 234.740196 -334.489298)
			(xy 234.716136 -334.468576) (xy 234.672892 -334.422074) (xy 234.635778 -334.370548) (xy 234.605371 -334.314801)
			(xy 234.582144 -334.2557) (xy 234.566459 -334.194167) (xy 234.558561 -334.131159) (xy 234.558078 -334.099408)
			(xy 207.59166 -334.099408) (xy 207.59166 -335.9658) (xy 231.731589 -335.9658) (xy 231.735603 -335.902005)
			(xy 231.74758 -335.839217) (xy 231.767332 -335.778425) (xy 231.794548 -335.720587) (xy 231.828798 -335.666617)
			(xy 231.869541 -335.617365) (xy 231.916137 -335.573607) (xy 231.967849 -335.536034) (xy 232.023862 -335.505239)
			(xy 232.083293 -335.481707) (xy 232.145205 -335.465808) (xy 232.208622 -335.457795) (xy 232.240582 -335.457292)
			(xy 232.271924 -335.457748) (xy 232.334132 -335.465459) (xy 232.394922 -335.480752) (xy 232.453373 -335.503397)
			(xy 232.508599 -335.533051) (xy 232.53446 -335.550764) (xy 232.544366 -335.557876) (xy 232.568242 -335.561432)
			(xy 232.668826 -335.528666) (xy 232.685844 -335.511648) (xy 232.689654 -335.500218) (xy 232.700129 -335.470222)
			(xy 232.727559 -335.412911) (xy 232.761918 -335.359465) (xy 232.80267 -335.310719) (xy 232.849179 -335.267431)
			(xy 232.900721 -335.230277) (xy 232.956492 -335.199836) (xy 233.015621 -335.176584) (xy 233.077188 -335.160882)
			(xy 233.140231 -335.152976) (xy 233.172 -335.152492) (xy 233.206492 -335.153055) (xy 233.274843 -335.162393)
			(xy 233.341304 -335.180883) (xy 233.404656 -335.208186) (xy 233.463736 -335.243802) (xy 233.51746 -335.287076)
			(xy 233.54157 -335.31175) (xy 233.54825 -335.318272) (xy 233.56507 -335.326341) (xy 233.574336 -335.327498)
			(xy 233.605324 -335.330038) (xy 233.614472 -335.330347) (xy 233.632044 -335.325276) (xy 233.639614 -335.320132)
			(xy 233.664485 -335.302408) (xy 233.71866 -335.274226) (xy 233.776631 -335.255026) (xy 233.836918 -335.245298)
			(xy 233.867452 -335.244694) (xy 233.894704 -335.2452) (xy 233.948653 -335.25295) (xy 234.00095 -335.2683)
			(xy 234.050531 -335.290938) (xy 234.096384 -335.320401) (xy 234.137577 -335.35609) (xy 234.173272 -335.397279)
			(xy 234.20274 -335.443129) (xy 234.225383 -335.492706) (xy 234.24074 -335.545002) (xy 234.248497 -335.59895)
			(xy 234.24896 -335.626202) (xy 234.248781 -335.64209) (xy 234.24611 -335.673754) (xy 234.243626 -335.689448)
			(xy 234.242102 -335.698846) (xy 234.245912 -335.717388) (xy 234.29341 -335.790794) (xy 234.30865 -335.80197)
			(xy 234.318048 -335.804256) (xy 234.350165 -335.81337) (xy 234.411912 -335.838748) (xy 234.469809 -335.871986)
			(xy 234.52286 -335.912512) (xy 234.570153 -335.959631) (xy 234.610875 -336.012533) (xy 234.641365 -336.065195)
			(xy 236.020034 -336.065195) (xy 236.022643 -336.002172) (xy 236.033028 -335.939956) (xy 236.051029 -335.879503)
			(xy 236.076369 -335.82174) (xy 236.108659 -335.767555) (xy 236.147403 -335.71778) (xy 236.192007 -335.673179)
			(xy 236.241784 -335.634439) (xy 236.295972 -335.602152) (xy 236.353736 -335.576816) (xy 236.414191 -335.55882)
			(xy 236.476408 -335.54844) (xy 236.539431 -335.545834) (xy 236.602292 -335.551045) (xy 236.664026 -335.56399)
			(xy 236.723684 -335.584472) (xy 236.780351 -335.612176) (xy 236.833157 -335.646677) (xy 236.881289 -335.687444)
			(xy 236.924009 -335.733851) (xy 236.960661 -335.785187) (xy 236.990682 -335.840661) (xy 237.01361 -335.899423)
			(xy 237.029094 -335.960569) (xy 237.036896 -336.023162) (xy 237.037372 -336.0547) (xy 237.036967 -336.084051)
			(xy 237.03022 -336.142364) (xy 237.02391 -336.171032) (xy 237.021116 -336.182462) (xy 237.02645 -336.205322)
			(xy 237.091474 -336.286094) (xy 237.112556 -336.296) (xy 237.124494 -336.295746) (xy 237.130844 -336.295746)
			(xy 237.15809 -336.296327) (xy 237.212026 -336.304088) (xy 237.264309 -336.319445) (xy 237.313875 -336.342086)
			(xy 237.359714 -336.37155) (xy 237.400894 -336.407237) (xy 237.436577 -336.448421) (xy 237.466035 -336.494264)
			(xy 237.488671 -336.543832) (xy 237.504022 -336.596117) (xy 237.511776 -336.650054) (xy 237.511776 -336.704546)
			(xy 237.504022 -336.758483) (xy 237.488671 -336.810768) (xy 237.466035 -336.860336) (xy 237.436577 -336.906179)
			(xy 237.400894 -336.947363) (xy 237.359714 -336.98305) (xy 237.313875 -337.012514) (xy 237.264309 -337.035155)
			(xy 237.212026 -337.050512) (xy 237.15809 -337.058273) (xy 237.130844 -337.058762) (xy 237.109254 -337.058254)
			(xy 237.095538 -337.057492) (xy 237.071408 -337.06943) (xy 237.007908 -337.165696) (xy 237.006384 -337.192366)
			(xy 237.01248 -337.204812) (xy 237.025095 -337.231209) (xy 237.04486 -337.286276) (xy 237.058187 -337.343244)
			(xy 237.064899 -337.401365) (xy 237.065312 -337.430618) (xy 237.064813 -337.462158) (xy 237.057009 -337.524753)
			(xy 237.041521 -337.585901) (xy 237.01859 -337.644665) (xy 236.988565 -337.700141) (xy 236.95191 -337.751477)
			(xy 236.909186 -337.797884) (xy 236.861049 -337.838651) (xy 236.80824 -337.873151) (xy 236.75157 -337.900853)
			(xy 236.691907 -337.921333) (xy 236.63017 -337.934277) (xy 236.567306 -337.939484) (xy 236.50428 -337.936876)
			(xy 236.442061 -337.926492) (xy 236.381605 -337.908491) (xy 236.323839 -337.883151) (xy 236.269651 -337.85086)
			(xy 236.219873 -337.812115) (xy 236.17527 -337.76751) (xy 236.136527 -337.717731) (xy 236.104239 -337.663541)
			(xy 236.078901 -337.605775) (xy 236.060903 -337.545317) (xy 236.050522 -337.483098) (xy 236.047916 -337.420072)
			(xy 236.053126 -337.357208) (xy 236.066072 -337.295471) (xy 236.086555 -337.23581) (xy 236.11426 -337.17914)
			(xy 236.148762 -337.126333) (xy 236.189531 -337.078198) (xy 236.235941 -337.035476) (xy 236.287278 -336.998823)
			(xy 236.342755 -336.968801) (xy 236.40152 -336.945872) (xy 236.462669 -336.930387) (xy 236.525264 -336.922585)
			(xy 236.556804 -336.92211) (xy 236.581217 -336.922418) (xy 236.629815 -336.927122) (xy 236.653832 -336.931508)
			(xy 236.667294 -336.934048) (xy 236.692694 -336.925412) (xy 236.768386 -336.838544) (xy 236.77372 -336.812128)
			(xy 236.769402 -336.799174) (xy 236.760059 -336.769562) (xy 236.74997 -336.708298) (xy 236.749336 -336.677254)
			(xy 236.749844 -336.658204) (xy 236.750352 -336.646266) (xy 236.741208 -336.62493) (xy 236.662722 -336.556858)
			(xy 236.640116 -336.551016) (xy 236.628432 -336.553302) (xy 236.603801 -336.557937) (xy 236.553925 -336.562896)
			(xy 236.528864 -336.563208) (xy 236.497326 -336.562694) (xy 236.434734 -336.554888) (xy 236.373588 -336.539399)
			(xy 236.314828 -336.516467) (xy 236.259356 -336.486442) (xy 236.208023 -336.449786) (xy 236.161619 -336.407063)
			(xy 236.120855 -336.358928) (xy 236.086359 -336.30612) (xy 236.058659 -336.249451) (xy 236.038181 -336.189791)
			(xy 236.025239 -336.128056) (xy 236.020034 -336.065195) (xy 234.641365 -336.065195) (xy 234.644325 -336.070307)
			(xy 234.669929 -336.131961) (xy 234.687248 -336.196435) (xy 234.695982 -336.26262) (xy 234.696508 -336.296)
			(xy 234.696089 -336.32728) (xy 234.688425 -336.389369) (xy 234.673199 -336.450047) (xy 234.650642 -336.508399)
			(xy 234.621096 -336.563542) (xy 234.585005 -336.614642) (xy 234.542917 -336.660928) (xy 234.495468 -336.701699)
			(xy 234.469686 -336.719418) (xy 234.459526 -336.72687) (xy 234.44754 -336.749001) (xy 234.446826 -336.761582)
			(xy 234.446826 -336.846418) (xy 234.447506 -336.859001) (xy 234.459528 -336.88112) (xy 234.469686 -336.888582)
			(xy 234.495433 -336.906344) (xy 234.542861 -336.947124) (xy 234.584932 -336.993411) (xy 234.62101 -337.044508)
			(xy 234.65055 -337.099642) (xy 234.673108 -337.157983) (xy 234.688343 -337.218649) (xy 234.696024 -337.280725)
			(xy 234.696508 -337.312) (xy 234.696006 -337.343961) (xy 234.687995 -337.407379) (xy 234.672098 -337.469293)
			(xy 234.648566 -337.528726) (xy 234.617772 -337.584741) (xy 234.580199 -337.636456) (xy 234.536442 -337.683053)
			(xy 234.487189 -337.723798) (xy 234.433218 -337.758049) (xy 234.375379 -337.785266) (xy 234.314586 -337.805019)
			(xy 234.251796 -337.816997) (xy 234.188 -337.821011) (xy 234.124204 -337.816997) (xy 234.061414 -337.805019)
			(xy 234.000621 -337.785266) (xy 233.942782 -337.758049) (xy 233.888811 -337.723798) (xy 233.839558 -337.683053)
			(xy 233.795801 -337.636456) (xy 233.758228 -337.584741) (xy 233.727434 -337.528726) (xy 233.703902 -337.469293)
			(xy 233.688005 -337.407379) (xy 233.679994 -337.343961) (xy 233.679492 -337.312) (xy 233.679911 -337.28072)
			(xy 233.687575 -337.218631) (xy 233.702801 -337.157953) (xy 233.725358 -337.099601) (xy 233.754904 -337.044458)
			(xy 233.790995 -336.993358) (xy 233.833083 -336.947072) (xy 233.880532 -336.906301) (xy 233.906314 -336.888582)
			(xy 233.916474 -336.88113) (xy 233.92846 -336.858999) (xy 233.929174 -336.846418) (xy 233.929174 -336.761582)
			(xy 233.928494 -336.748999) (xy 233.916472 -336.72688) (xy 233.906314 -336.719418) (xy 233.880567 -336.701656)
			(xy 233.833139 -336.660876) (xy 233.791068 -336.614589) (xy 233.75499 -336.563492) (xy 233.72545 -336.508358)
			(xy 233.702892 -336.450017) (xy 233.687657 -336.389351) (xy 233.679976 -336.327275) (xy 233.679492 -336.296)
			(xy 233.680089 -336.260403) (xy 233.690046 -336.189907) (xy 233.709723 -336.121485) (xy 233.723688 -336.088736)
			(xy 233.727498 -336.0801) (xy 233.728514 -336.06105) (xy 233.701082 -335.977992) (xy 233.68889 -335.963514)
			(xy 233.680508 -335.958942) (xy 233.671364 -335.953354) (xy 233.663264 -335.948993) (xy 233.64517 -335.945739)
			(xy 233.636058 -335.947004) (xy 233.605832 -335.952592) (xy 233.596645 -335.954611) (xy 233.580599 -335.964405)
			(xy 233.57459 -335.971642) (xy 233.553887 -335.997597) (xy 233.506833 -336.044435) (xy 233.454083 -336.084751)
			(xy 233.396534 -336.117859) (xy 233.335167 -336.143195) (xy 233.271024 -336.160329) (xy 233.205196 -336.16897)
			(xy 233.172 -336.169508) (xy 233.140659 -336.169009) (xy 233.078453 -336.161309) (xy 233.017664 -336.146025)
			(xy 232.959212 -336.12339) (xy 232.903984 -336.093745) (xy 232.878122 -336.076036) (xy 232.868216 -336.068924)
			(xy 232.84434 -336.065368) (xy 232.743756 -336.098134) (xy 232.726738 -336.115152) (xy 232.722928 -336.126582)
			(xy 232.712382 -336.156551) (xy 232.684958 -336.213859) (xy 232.650606 -336.267302) (xy 232.609862 -336.316048)
			(xy 232.56336 -336.359337) (xy 232.511827 -336.396493) (xy 232.456065 -336.426937) (xy 232.396943 -336.450195)
			(xy 232.335385 -336.465904) (xy 232.272348 -336.473819) (xy 232.240582 -336.474308) (xy 232.208622 -336.473805)
			(xy 232.145205 -336.465792) (xy 232.083293 -336.449893) (xy 232.023862 -336.426361) (xy 231.967849 -336.395566)
			(xy 231.916137 -336.357993) (xy 231.869541 -336.314235) (xy 231.828798 -336.264983) (xy 231.794548 -336.211013)
			(xy 231.767332 -336.153175) (xy 231.74758 -336.092383) (xy 231.735603 -336.029595) (xy 231.731589 -335.9658)
			(xy 207.59166 -335.9658) (xy 207.59166 -337.859624) (xy 211.265516 -337.859624) (xy 211.266018 -337.827663)
			(xy 211.274029 -337.764245) (xy 211.289926 -337.702331) (xy 211.313458 -337.642898) (xy 211.344252 -337.586883)
			(xy 211.381825 -337.535168) (xy 211.425582 -337.488571) (xy 211.474835 -337.447826) (xy 211.528806 -337.413575)
			(xy 211.586645 -337.386358) (xy 211.647438 -337.366605) (xy 211.710228 -337.354627) (xy 211.774024 -337.350614)
			(xy 211.83782 -337.354627) (xy 211.90061 -337.366605) (xy 211.961403 -337.386358) (xy 212.019242 -337.413575)
			(xy 212.073213 -337.447826) (xy 212.122466 -337.488571) (xy 212.166223 -337.535168) (xy 212.203796 -337.586883)
			(xy 212.23459 -337.642898) (xy 212.239461 -337.6552) (xy 231.764222 -337.6552) (xy 231.768237 -337.591392)
			(xy 231.780218 -337.52859) (xy 231.799976 -337.467785) (xy 231.827199 -337.409937) (xy 231.861459 -337.355956)
			(xy 231.902214 -337.306696) (xy 231.948823 -337.262932) (xy 232.000549 -337.225355) (xy 232.056577 -337.194558)
			(xy 232.116023 -337.171027) (xy 232.17795 -337.155132) (xy 232.241381 -337.147124) (xy 232.273348 -337.146646)
			(xy 232.303866 -337.147067) (xy 232.364464 -337.154357) (xy 232.423754 -337.16885) (xy 232.480882 -337.190338)
			(xy 232.535026 -337.218511) (xy 232.585408 -337.252965) (xy 232.631301 -337.293203) (xy 232.672047 -337.338647)
			(xy 232.707058 -337.388643) (xy 232.735831 -337.442471) (xy 232.747312 -337.47075) (xy 232.751376 -337.481672)
			(xy 232.767886 -337.497166) (xy 232.86466 -337.528408) (xy 232.887012 -337.525614) (xy 232.896918 -337.519264)
			(xy 232.921598 -337.503896) (xy 232.973775 -337.478242) (xy 233.028535 -337.458704) (xy 233.085166 -337.445535)
			(xy 233.142929 -337.438907) (xy 233.172 -337.438492) (xy 233.203961 -337.438994) (xy 233.267379 -337.447005)
			(xy 233.329293 -337.462902) (xy 233.388726 -337.486434) (xy 233.444741 -337.517228) (xy 233.496456 -337.554801)
			(xy 233.543053 -337.598558) (xy 233.583798 -337.647811) (xy 233.618049 -337.701782) (xy 233.645266 -337.759621)
			(xy 233.665019 -337.820414) (xy 233.676997 -337.883204) (xy 233.681011 -337.947) (xy 233.676997 -338.010796)
			(xy 233.665019 -338.073586) (xy 233.645266 -338.134379) (xy 233.618049 -338.192218) (xy 233.583798 -338.246189)
			(xy 233.543053 -338.295442) (xy 233.496456 -338.339199) (xy 233.444741 -338.376772) (xy 233.388726 -338.407566)
			(xy 233.329293 -338.431098) (xy 233.267379 -338.446995) (xy 233.203961 -338.455006) (xy 233.172 -338.455508)
			(xy 233.141485 -338.455011) (xy 233.08089 -338.447728) (xy 233.021604 -338.433242) (xy 232.964478 -338.411762)
			(xy 232.910335 -338.383596) (xy 232.859954 -338.349151) (xy 232.81406 -338.308921) (xy 232.773312 -338.263486)
			(xy 232.738298 -338.213499) (xy 232.70952 -338.159679) (xy 232.698036 -338.131404) (xy 232.693972 -338.120482)
			(xy 232.677462 -338.104988) (xy 232.580688 -338.073746) (xy 232.558336 -338.07654) (xy 232.54843 -338.08289)
			(xy 232.523741 -338.098244) (xy 232.471567 -338.123899) (xy 232.416808 -338.14344) (xy 232.36018 -338.156612)
			(xy 232.302418 -338.163244) (xy 232.273348 -338.163662) (xy 232.241381 -338.163276) (xy 232.17795 -338.155268)
			(xy 232.116023 -338.139373) (xy 232.056577 -338.115842) (xy 232.000549 -338.085045) (xy 231.948823 -338.047468)
			(xy 231.902214 -338.003704) (xy 231.861459 -337.954444) (xy 231.827199 -337.900463) (xy 231.799976 -337.842615)
			(xy 231.780218 -337.78181) (xy 231.768237 -337.719008) (xy 231.764222 -337.6552) (xy 212.239461 -337.6552)
			(xy 212.258122 -337.702331) (xy 212.274019 -337.764245) (xy 212.28203 -337.827663) (xy 212.282532 -337.859624)
			(xy 212.281951 -337.893506) (xy 212.272942 -337.960669) (xy 212.255099 -338.026042) (xy 212.228738 -338.088469)
			(xy 212.194326 -338.146845) (xy 212.152471 -338.200138) (xy 212.103913 -338.247405) (xy 212.077046 -338.268056)
			(xy 212.067394 -338.275168) (xy 212.056726 -338.29625) (xy 212.055456 -338.400898) (xy 212.065616 -338.422234)
			(xy 212.075014 -338.4296) (xy 212.097457 -338.447792) (xy 212.137132 -338.489785) (xy 212.170018 -338.537282)
			(xy 212.195363 -338.589197) (xy 212.212587 -338.64434) (xy 212.221296 -338.701451) (xy 212.221826 -338.730336)
			(xy 212.22138 -338.756952) (xy 212.213976 -338.809666) (xy 212.199303 -338.860835) (xy 212.177646 -338.909462)
			(xy 212.163914 -338.932266) (xy 212.159476 -338.939997) (xy 212.15584 -338.957439) (xy 212.156802 -338.966302)
			(xy 212.160866 -338.996274) (xy 212.162473 -339.005223) (xy 212.171059 -339.021233) (xy 212.17763 -339.027516)
			(xy 212.200295 -339.048256) (xy 212.241031 -339.094244) (xy 212.275927 -339.144807) (xy 212.304475 -339.199207)
			(xy 212.326258 -339.256651) (xy 212.340959 -339.316302) (xy 212.348363 -339.37729) (xy 212.348826 -339.408008)
			(xy 212.348335 -339.439776) (xy 212.340425 -339.502818) (xy 212.32473 -339.564384) (xy 212.301493 -339.623518)
			(xy 212.271075 -339.6793) (xy 212.233951 -339.730862) (xy 212.212682 -339.754464) (xy 212.206078 -339.761322)
			(xy 212.19922 -339.778594) (xy 212.197696 -339.865716) (xy 212.198427 -339.867705) (xy 225.26091 -339.867705)
			(xy 225.26091 -339.803783) (xy 225.268921 -339.740365) (xy 225.284818 -339.678451) (xy 225.30835 -339.619018)
			(xy 225.339144 -339.563003) (xy 225.376717 -339.511288) (xy 225.420474 -339.464691) (xy 225.469727 -339.423946)
			(xy 225.523698 -339.389695) (xy 225.581537 -339.362478) (xy 225.64233 -339.342725) (xy 225.70512 -339.330747)
			(xy 225.768916 -339.326734) (xy 225.832712 -339.330747) (xy 225.895502 -339.342725) (xy 225.956295 -339.362478)
			(xy 226.014134 -339.389695) (xy 226.068105 -339.423946) (xy 226.117358 -339.464691) (xy 226.161115 -339.511288)
			(xy 226.198688 -339.563003) (xy 226.229482 -339.619018) (xy 226.253014 -339.678451) (xy 226.268911 -339.740365)
			(xy 226.276922 -339.803783) (xy 226.277424 -339.835744) (xy 226.276922 -339.867705) (xy 226.268911 -339.931123)
			(xy 226.253014 -339.993037) (xy 226.229482 -340.05247) (xy 226.198688 -340.108485) (xy 226.161115 -340.1602)
			(xy 226.117358 -340.206797) (xy 226.068105 -340.247542) (xy 226.014134 -340.281793) (xy 225.956295 -340.30901)
			(xy 225.895502 -340.328763) (xy 225.832712 -340.340741) (xy 225.768916 -340.344755) (xy 225.70512 -340.340741)
			(xy 225.64233 -340.328763) (xy 225.581537 -340.30901) (xy 225.523698 -340.281793) (xy 225.469727 -340.247542)
			(xy 225.420474 -340.206797) (xy 225.376717 -340.1602) (xy 225.339144 -340.108485) (xy 225.30835 -340.05247)
			(xy 225.284818 -339.993037) (xy 225.268921 -339.931123) (xy 225.26091 -339.867705) (xy 212.198427 -339.867705)
			(xy 212.204046 -339.882988) (xy 212.210396 -339.8901) (xy 212.229981 -339.913284) (xy 212.264072 -339.963497)
			(xy 212.291938 -340.017413) (xy 212.313182 -340.074266) (xy 212.3275 -340.133245) (xy 212.334689 -340.19351)
			(xy 212.33511 -340.223856) (xy 212.334667 -340.254655) (xy 212.327241 -340.315803) (xy 212.312479 -340.375606)
			(xy 212.295149 -340.421214) (xy 222.375982 -340.421214) (xy 222.380053 -340.365592) (xy 222.392179 -340.311155)
			(xy 222.412102 -340.259064) (xy 222.439398 -340.210429) (xy 222.473484 -340.166286) (xy 222.513633 -340.127577)
			(xy 222.558991 -340.095126) (xy 222.608591 -340.069625) (xy 222.661375 -340.051618) (xy 222.716218 -340.041488)
			(xy 222.771952 -340.039451) (xy 222.827389 -340.045551) (xy 222.881346 -340.059657) (xy 222.932675 -340.081469)
			(xy 222.980281 -340.110523) (xy 223.023149 -340.146198) (xy 223.060366 -340.187735) (xy 223.091139 -340.234248)
			(xy 223.114811 -340.284745) (xy 223.130879 -340.338152) (xy 223.138999 -340.393328) (xy 223.139508 -340.421214)
			(xy 223.138999 -340.4491) (xy 223.130879 -340.504276) (xy 223.118807 -340.5444) (xy 231.737193 -340.5444)
			(xy 231.741207 -340.480607) (xy 231.753184 -340.41782) (xy 231.772935 -340.357029) (xy 231.80015 -340.299193)
			(xy 231.834398 -340.245223) (xy 231.87514 -340.195972) (xy 231.921734 -340.152214) (xy 231.973444 -340.114642)
			(xy 232.029456 -340.083846) (xy 232.088885 -340.060313) (xy 232.150796 -340.044414) (xy 232.21421 -340.0364)
			(xy 232.24617 -340.035896) (xy 232.27689 -340.036384) (xy 232.337883 -340.043779) (xy 232.397541 -340.058466)
			(xy 232.454997 -340.080231) (xy 232.509413 -340.108757) (xy 232.534968 -340.125812) (xy 232.544874 -340.13267)
			(xy 232.568242 -340.135972) (xy 232.668572 -340.10219) (xy 232.685082 -340.085426) (xy 232.688892 -340.073996)
			(xy 232.699327 -340.043881) (xy 232.726665 -339.986306) (xy 232.760985 -339.932599) (xy 232.801747 -339.883602)
			(xy 232.848313 -339.840084) (xy 232.899952 -339.802725) (xy 232.955856 -339.772113) (xy 233.015146 -339.748727)
			(xy 233.076894 -339.732934) (xy 233.140132 -339.724982) (xy 233.172 -339.724492) (xy 233.203961 -339.724994)
			(xy 233.267379 -339.733005) (xy 233.329293 -339.748902) (xy 233.388726 -339.772434) (xy 233.444741 -339.803228)
			(xy 233.496456 -339.840801) (xy 233.543053 -339.884558) (xy 233.583798 -339.933811) (xy 233.618049 -339.987782)
			(xy 233.645266 -340.045621) (xy 233.665019 -340.106414) (xy 233.676997 -340.169204) (xy 233.681011 -340.233)
			(xy 233.676997 -340.296796) (xy 233.665019 -340.359586) (xy 233.645266 -340.420379) (xy 233.618049 -340.478218)
			(xy 233.583798 -340.532189) (xy 233.543053 -340.581442) (xy 233.496456 -340.625199) (xy 233.444741 -340.662772)
			(xy 233.388726 -340.693566) (xy 233.329293 -340.717098) (xy 233.267379 -340.732995) (xy 233.203961 -340.741006)
			(xy 233.172 -340.741508) (xy 233.14128 -340.741035) (xy 233.080286 -340.733636) (xy 233.020627 -340.718945)
			(xy 232.963172 -340.697177) (xy 232.908756 -340.668648) (xy 232.883202 -340.651592) (xy 232.873296 -340.644734)
			(xy 232.849928 -340.641432) (xy 232.749598 -340.675214) (xy 232.733088 -340.691978) (xy 232.729278 -340.703408)
			(xy 232.718785 -340.733502) (xy 232.691451 -340.791073) (xy 232.657137 -340.844778) (xy 232.61638 -340.893774)
			(xy 232.569821 -340.937293) (xy 232.518189 -340.974653) (xy 232.462293 -341.005268) (xy 232.403009 -341.028659)
			(xy 232.341268 -341.044458) (xy 232.278036 -341.052418) (xy 232.24617 -341.052912) (xy 232.21421 -341.0524)
			(xy 232.150796 -341.044386) (xy 232.088885 -341.028487) (xy 232.029456 -341.004954) (xy 231.973444 -340.974158)
			(xy 231.921734 -340.936586) (xy 231.87514 -340.892828) (xy 231.834398 -340.843577) (xy 231.80015 -340.789607)
			(xy 231.772935 -340.731771) (xy 231.753184 -340.67098) (xy 231.741207 -340.608193) (xy 231.737193 -340.5444)
			(xy 223.118807 -340.5444) (xy 223.114811 -340.557683) (xy 223.091139 -340.60818) (xy 223.060366 -340.654693)
			(xy 223.023149 -340.69623) (xy 222.980281 -340.731905) (xy 222.932675 -340.760959) (xy 222.881346 -340.782771)
			(xy 222.827389 -340.796877) (xy 222.771952 -340.802977) (xy 222.716218 -340.80094) (xy 222.661375 -340.79081)
			(xy 222.608591 -340.772803) (xy 222.558991 -340.747302) (xy 222.513633 -340.714851) (xy 222.473484 -340.676142)
			(xy 222.439398 -340.631999) (xy 222.412102 -340.583364) (xy 222.392179 -340.531273) (xy 222.380053 -340.476836)
			(xy 222.375982 -340.421214) (xy 212.295149 -340.421214) (xy 212.290599 -340.433187) (xy 212.261921 -340.487701)
			(xy 212.226865 -340.538351) (xy 212.185946 -340.584393) (xy 212.163152 -340.60511) (xy 212.155786 -340.611714)
			(xy 212.146896 -340.628986) (xy 212.139276 -340.718648) (xy 212.145118 -340.73719) (xy 212.151214 -340.74481)
			(xy 212.167109 -340.765228) (xy 212.193802 -340.809555) (xy 212.214264 -340.857082) (xy 212.228117 -340.906937)
			(xy 212.23511 -340.958206) (xy 212.235542 -340.984078) (xy 212.23503 -341.011787) (xy 212.227021 -341.066623)
			(xy 212.211155 -341.11972) (xy 212.196397 -341.151421) (xy 225.709474 -341.151421) (xy 225.709474 -341.087499)
			(xy 225.717485 -341.024081) (xy 225.733382 -340.962167) (xy 225.756914 -340.902734) (xy 225.787708 -340.846719)
			(xy 225.825281 -340.795004) (xy 225.869038 -340.748407) (xy 225.918291 -340.707662) (xy 225.972262 -340.673411)
			(xy 226.030101 -340.646194) (xy 226.090894 -340.626441) (xy 226.153684 -340.614463) (xy 226.21748 -340.61045)
			(xy 226.281276 -340.614463) (xy 226.344066 -340.626441) (xy 226.404859 -340.646194) (xy 226.462698 -340.673411)
			(xy 226.516669 -340.707662) (xy 226.565922 -340.748407) (xy 226.609679 -340.795004) (xy 226.647252 -340.846719)
			(xy 226.678046 -340.902734) (xy 226.701578 -340.962167) (xy 226.717475 -341.024081) (xy 226.725486 -341.087499)
			(xy 226.725988 -341.11946) (xy 226.725486 -341.151421) (xy 226.717475 -341.214839) (xy 226.701578 -341.276753)
			(xy 226.678046 -341.336186) (xy 226.647252 -341.392201) (xy 226.609679 -341.443916) (xy 226.565922 -341.490513)
			(xy 226.516669 -341.531258) (xy 226.462698 -341.565509) (xy 226.404859 -341.592726) (xy 226.344066 -341.612479)
			(xy 226.281276 -341.624457) (xy 226.21748 -341.628471) (xy 226.153684 -341.624457) (xy 226.090894 -341.612479)
			(xy 226.030101 -341.592726) (xy 225.972262 -341.565509) (xy 225.918291 -341.531258) (xy 225.869038 -341.490513)
			(xy 225.825281 -341.443916) (xy 225.787708 -341.392201) (xy 225.756914 -341.336186) (xy 225.733382 -341.276753)
			(xy 225.717485 -341.214839) (xy 225.709474 -341.151421) (xy 212.196397 -341.151421) (xy 212.187766 -341.16996)
			(xy 212.157348 -341.216283) (xy 212.120541 -341.257712) (xy 212.099652 -341.275924) (xy 212.090508 -341.283544)
			(xy 212.081364 -341.304372) (xy 212.084158 -341.407496) (xy 212.094572 -341.427816) (xy 212.10397 -341.434928)
			(xy 212.130556 -341.455605) (xy 212.17861 -341.502795) (xy 212.220014 -341.555916) (xy 212.254042 -341.614038)
			(xy 212.280099 -341.676144) (xy 212.297729 -341.741146) (xy 212.306623 -341.807907) (xy 212.30717 -341.841582)
			(xy 212.306668 -341.873543) (xy 212.306181 -341.877396) (xy 212.588094 -341.877396) (xy 212.588596 -341.845435)
			(xy 212.596607 -341.782017) (xy 212.612504 -341.720103) (xy 212.636036 -341.66067) (xy 212.66683 -341.604655)
			(xy 212.704403 -341.55294) (xy 212.74816 -341.506343) (xy 212.797413 -341.465598) (xy 212.851384 -341.431347)
			(xy 212.909223 -341.40413) (xy 212.970016 -341.384377) (xy 213.032806 -341.372399) (xy 213.096602 -341.368386)
			(xy 213.160398 -341.372399) (xy 213.223188 -341.384377) (xy 213.283981 -341.40413) (xy 213.34182 -341.431347)
			(xy 213.395791 -341.465598) (xy 213.445044 -341.506343) (xy 213.488801 -341.55294) (xy 213.526374 -341.604655)
			(xy 213.557168 -341.66067) (xy 213.5807 -341.720103) (xy 213.596597 -341.782017) (xy 213.604608 -341.845435)
			(xy 213.60511 -341.877396) (xy 213.604553 -341.911396) (xy 213.595503 -341.978792) (xy 213.577549 -342.044379)
			(xy 213.551012 -342.106988) (xy 213.516366 -342.1655) (xy 213.47423 -342.218872) (xy 213.45017 -342.242902)
			(xy 213.443058 -342.24976) (xy 213.435184 -342.267286) (xy 213.433247 -342.309661) (xy 231.718098 -342.309661)
			(xy 231.718098 -342.245739) (xy 231.726109 -342.182321) (xy 231.742006 -342.120407) (xy 231.765538 -342.060974)
			(xy 231.796332 -342.004959) (xy 231.833905 -341.953244) (xy 231.877662 -341.906647) (xy 231.926915 -341.865902)
			(xy 231.980886 -341.831651) (xy 232.038725 -341.804434) (xy 232.099518 -341.784681) (xy 232.162308 -341.772703)
			(xy 232.226104 -341.76869) (xy 232.2899 -341.772703) (xy 232.35269 -341.784681) (xy 232.413483 -341.804434)
			(xy 232.471322 -341.831651) (xy 232.525293 -341.865902) (xy 232.574546 -341.906647) (xy 232.618303 -341.953244)
			(xy 232.655876 -342.004959) (xy 232.68667 -342.060974) (xy 232.710202 -342.120407) (xy 232.726099 -342.182321)
			(xy 232.73411 -342.245739) (xy 232.734612 -342.2777) (xy 232.73411 -342.309661) (xy 232.726099 -342.373079)
			(xy 232.710202 -342.434993) (xy 232.68667 -342.494426) (xy 232.655876 -342.550441) (xy 232.618303 -342.602156)
			(xy 232.574546 -342.648753) (xy 232.547957 -342.670749) (xy 233.237414 -342.670749) (xy 233.237416 -342.616235)
			(xy 233.245175 -342.562277) (xy 233.260535 -342.509972) (xy 233.283183 -342.460385) (xy 233.312657 -342.414527)
			(xy 233.348358 -342.37333) (xy 233.389559 -342.337633) (xy 233.43542 -342.308164) (xy 233.485009 -342.285521)
			(xy 233.537316 -342.270167) (xy 233.591275 -342.262413) (xy 233.618532 -342.261952) (xy 233.639106 -342.26246)
			(xy 233.652822 -342.263222) (xy 233.676698 -342.25103) (xy 233.739944 -342.154002) (xy 233.741214 -342.127332)
			(xy 233.734864 -342.114886) (xy 233.721654 -342.087988) (xy 233.700943 -342.031753) (xy 233.686971 -341.973477)
			(xy 233.67993 -341.913964) (xy 233.679492 -341.884) (xy 233.679911 -341.85272) (xy 233.687575 -341.790631)
			(xy 233.702801 -341.729953) (xy 233.725358 -341.671601) (xy 233.754904 -341.616458) (xy 233.790995 -341.565358)
			(xy 233.833083 -341.519072) (xy 233.880532 -341.478301) (xy 233.906314 -341.460582) (xy 233.916474 -341.45313)
			(xy 233.92846 -341.430999) (xy 233.929174 -341.418418) (xy 233.929174 -341.333582) (xy 233.928494 -341.320999)
			(xy 233.916472 -341.29888) (xy 233.906314 -341.291418) (xy 233.880567 -341.273656) (xy 233.833139 -341.232876)
			(xy 233.791068 -341.186589) (xy 233.75499 -341.135492) (xy 233.72545 -341.080358) (xy 233.702892 -341.022017)
			(xy 233.687657 -340.961351) (xy 233.679976 -340.899275) (xy 233.679492 -340.868) (xy 233.679956 -340.837269)
			(xy 233.687365 -340.776255) (xy 233.702073 -340.716579) (xy 233.723868 -340.659111) (xy 233.752431 -340.604689)
			(xy 233.787345 -340.554107) (xy 233.828102 -340.508102) (xy 233.874107 -340.467345) (xy 233.924689 -340.432431)
			(xy 233.979111 -340.403868) (xy 234.036579 -340.382073) (xy 234.096255 -340.367365) (xy 234.157269 -340.359956)
			(xy 234.188 -340.359492) (xy 234.188254 -340.359492) (xy 234.198273 -340.359043) (xy 234.216791 -340.351386)
			(xy 234.230965 -340.337223) (xy 234.238635 -340.318711) (xy 234.239054 -340.308692) (xy 234.239054 -340.304628)
			(xy 234.238292 -340.30031) (xy 234.235901 -340.284864) (xy 234.233358 -340.253709) (xy 234.233212 -340.23808)
			(xy 234.233708 -340.210224) (xy 234.241835 -340.155107) (xy 234.257884 -340.101755) (xy 234.281514 -340.051302)
			(xy 234.312224 -340.004817) (xy 234.349363 -339.963288) (xy 234.392141 -339.927595) (xy 234.439651 -339.898497)
			(xy 234.490886 -339.876611) (xy 234.517692 -339.869018) (xy 234.527598 -339.866478) (xy 234.544108 -339.854032)
			(xy 234.589828 -339.772498) (xy 234.592368 -339.751924) (xy 234.58932 -339.742018) (xy 234.579577 -339.706814)
			(xy 234.569124 -339.634522) (xy 234.568492 -339.598) (xy 234.568911 -339.56672) (xy 234.576575 -339.504631)
			(xy 234.591801 -339.443953) (xy 234.614358 -339.385601) (xy 234.643904 -339.330458) (xy 234.679995 -339.279358)
			(xy 234.722083 -339.233072) (xy 234.769532 -339.192301) (xy 234.795314 -339.174582) (xy 234.805474 -339.16713)
			(xy 234.81746 -339.144999) (xy 234.818174 -339.132418) (xy 234.818174 -339.047582) (xy 234.817494 -339.034999)
			(xy 234.805472 -339.01288) (xy 234.795314 -339.005418) (xy 234.769567 -338.987656) (xy 234.722139 -338.946876)
			(xy 234.680068 -338.900589) (xy 234.64399 -338.849492) (xy 234.61445 -338.794358) (xy 234.591892 -338.736017)
			(xy 234.576657 -338.675351) (xy 234.568976 -338.613275) (xy 234.568492 -338.582) (xy 234.568994 -338.550039)
			(xy 234.577005 -338.486621) (xy 234.592902 -338.424707) (xy 234.616434 -338.365274) (xy 234.647228 -338.309259)
			(xy 234.684801 -338.257544) (xy 234.728558 -338.210947) (xy 234.777811 -338.170202) (xy 234.831782 -338.135951)
			(xy 234.889621 -338.108734) (xy 234.950414 -338.088981) (xy 235.013204 -338.077003) (xy 235.077 -338.07299)
			(xy 235.140796 -338.077003) (xy 235.203586 -338.088981) (xy 235.264379 -338.108734) (xy 235.322218 -338.135951)
			(xy 235.376189 -338.170202) (xy 235.425442 -338.210947) (xy 235.469199 -338.257544) (xy 235.506772 -338.309259)
			(xy 235.537566 -338.365274) (xy 235.561098 -338.424707) (xy 235.576995 -338.486621) (xy 235.585006 -338.550039)
			(xy 235.585508 -338.582) (xy 235.585089 -338.61328) (xy 235.577425 -338.675369) (xy 235.562199 -338.736047)
			(xy 235.539642 -338.794399) (xy 235.510096 -338.849542) (xy 235.474005 -338.900642) (xy 235.431917 -338.946928)
			(xy 235.384468 -338.987699) (xy 235.358686 -339.005418) (xy 235.348526 -339.01287) (xy 235.33654 -339.035001)
			(xy 235.335826 -339.047582) (xy 235.335826 -339.132418) (xy 235.336506 -339.145001) (xy 235.348528 -339.16712)
			(xy 235.358686 -339.174582) (xy 235.384433 -339.192344) (xy 235.431861 -339.233124) (xy 235.473932 -339.279411)
			(xy 235.51001 -339.330508) (xy 235.53955 -339.385642) (xy 235.562108 -339.443983) (xy 235.577343 -339.504649)
			(xy 235.585024 -339.566725) (xy 235.585508 -339.598) (xy 235.585 -339.630606) (xy 235.576663 -339.695283)
			(xy 235.560127 -339.758363) (xy 235.535661 -339.818811) (xy 235.503668 -339.875636) (xy 235.464674 -339.927904)
			(xy 235.419317 -339.974758) (xy 235.368342 -340.015429) (xy 235.312586 -340.04925) (xy 235.252964 -340.075665)
			(xy 235.190454 -340.094242) (xy 235.126082 -340.104674) (xy 235.09351 -340.106254) (xy 235.08335 -340.106508)
			(xy 235.064554 -340.115144) (xy 235.001562 -340.184486) (xy 234.994704 -340.20379) (xy 234.995466 -340.214204)
			(xy 234.996228 -340.23808) (xy 234.995817 -340.26431) (xy 234.988619 -340.316273) (xy 234.974371 -340.366761)
			(xy 234.95334 -340.41482) (xy 234.925924 -340.459545) (xy 234.892638 -340.500093) (xy 234.854112 -340.535698)
			(xy 234.811072 -340.56569) (xy 234.764328 -340.589502) (xy 234.739688 -340.598506) (xy 234.73029 -340.601808)
			(xy 234.715558 -340.614508) (xy 234.67441 -340.694518) (xy 234.672632 -340.713822) (xy 234.675426 -340.723474)
			(xy 234.685274 -340.758791) (xy 234.695853 -340.831341) (xy 234.696508 -340.868) (xy 234.696089 -340.89928)
			(xy 234.688425 -340.961369) (xy 234.673199 -341.022047) (xy 234.650642 -341.080399) (xy 234.621096 -341.135542)
			(xy 234.585005 -341.186642) (xy 234.542917 -341.232928) (xy 234.495468 -341.273699) (xy 234.469686 -341.291418)
			(xy 234.459526 -341.29887) (xy 234.44754 -341.321001) (xy 234.446826 -341.333582) (xy 234.446826 -341.418418)
			(xy 234.447506 -341.431001) (xy 234.459528 -341.45312) (xy 234.469686 -341.460582) (xy 234.495433 -341.478344)
			(xy 234.542861 -341.519124) (xy 234.584932 -341.565411) (xy 234.62101 -341.616508) (xy 234.65055 -341.671642)
			(xy 234.673108 -341.729983) (xy 234.688343 -341.790649) (xy 234.696024 -341.852725) (xy 234.696508 -341.884)
			(xy 234.696044 -341.914731) (xy 234.688635 -341.975745) (xy 234.673927 -342.035421) (xy 234.652132 -342.092889)
			(xy 234.623569 -342.147311) (xy 234.588655 -342.197893) (xy 234.547898 -342.243898) (xy 234.501893 -342.284655)
			(xy 234.451311 -342.319569) (xy 234.396889 -342.348132) (xy 234.339421 -342.369927) (xy 234.279745 -342.384635)
			(xy 234.218731 -342.392044) (xy 234.188 -342.392508) (xy 234.16417 -342.392249) (xy 234.11672 -342.387795)
			(xy 234.093258 -342.383618) (xy 234.079542 -342.381078) (xy 234.054396 -342.389968) (xy 233.978958 -342.477598)
			(xy 233.973878 -342.504014) (xy 233.97845 -342.516968) (xy 233.988506 -342.547621) (xy 233.999363 -342.611207)
			(xy 234.00004 -342.64346) (xy 233.999588 -342.670717) (xy 233.991835 -342.724676) (xy 233.976482 -342.776983)
			(xy 233.95384 -342.826573) (xy 233.924372 -342.872435) (xy 233.888676 -342.913636) (xy 233.84748 -342.949338)
			(xy 233.801622 -342.978813) (xy 233.752036 -343.001462) (xy 233.699731 -343.016823) (xy 233.645773 -343.024584)
			(xy 233.591259 -343.024586) (xy 233.5373 -343.01683) (xy 233.484994 -343.001473) (xy 233.435406 -342.978829)
			(xy 233.389546 -342.949357) (xy 233.348347 -342.913659) (xy 233.312648 -342.872461) (xy 233.283175 -342.826601)
			(xy 233.26053 -342.777013) (xy 233.245172 -342.724708) (xy 233.237414 -342.670749) (xy 232.547957 -342.670749)
			(xy 232.525293 -342.689498) (xy 232.471322 -342.723749) (xy 232.413483 -342.750966) (xy 232.35269 -342.770719)
			(xy 232.2899 -342.782697) (xy 232.226104 -342.786711) (xy 232.162308 -342.782697) (xy 232.099518 -342.770719)
			(xy 232.038725 -342.750966) (xy 231.980886 -342.723749) (xy 231.926915 -342.689498) (xy 231.877662 -342.648753)
			(xy 231.833905 -342.602156) (xy 231.796332 -342.550441) (xy 231.765538 -342.494426) (xy 231.742006 -342.434993)
			(xy 231.726109 -342.373079) (xy 231.718098 -342.309661) (xy 213.433247 -342.309661) (xy 213.43112 -342.356186)
			(xy 213.437216 -342.374474) (xy 213.443566 -342.38184) (xy 213.460769 -342.402692) (xy 213.489776 -342.448305)
			(xy 213.512055 -342.497555) (xy 213.527161 -342.549456) (xy 213.53479 -342.60297) (xy 213.53526 -342.629998)
			(xy 213.534799 -342.65637) (xy 213.527515 -342.708608) (xy 213.5131 -342.759344) (xy 213.491828 -342.807609)
			(xy 213.464107 -342.85248) (xy 213.44763 -342.873076) (xy 213.441026 -342.881204) (xy 213.435184 -342.901524)
			(xy 213.447122 -342.996012) (xy 213.45779 -343.014046) (xy 213.466426 -343.020142) (xy 213.490453 -343.038107)
			(xy 213.534545 -343.078793) (xy 213.573544 -343.124384) (xy 213.606908 -343.174246) (xy 213.634173 -343.227688)
			(xy 213.654961 -343.283967) (xy 213.668984 -343.3423) (xy 213.676045 -343.401878) (xy 213.676484 -343.431876)
			(xy 213.675982 -343.463837) (xy 213.667971 -343.527255) (xy 213.652074 -343.589169) (xy 213.628542 -343.648602)
			(xy 213.597748 -343.704617) (xy 213.560175 -343.756332) (xy 213.516418 -343.802929) (xy 213.467165 -343.843674)
			(xy 213.413194 -343.877925) (xy 213.355355 -343.905142) (xy 213.294562 -343.924895) (xy 213.231772 -343.936873)
			(xy 213.167976 -343.940887) (xy 213.10418 -343.936873) (xy 213.04139 -343.924895) (xy 212.980597 -343.905142)
			(xy 212.922758 -343.877925) (xy 212.868787 -343.843674) (xy 212.819534 -343.802929) (xy 212.775777 -343.756332)
			(xy 212.738204 -343.704617) (xy 212.70741 -343.648602) (xy 212.683878 -343.589169) (xy 212.667981 -343.527255)
			(xy 212.65997 -343.463837) (xy 212.659468 -343.431876) (xy 212.65999 -343.398887) (xy 212.668527 -343.333463)
			(xy 212.685452 -343.269692) (xy 212.710483 -343.208646) (xy 212.743199 -343.15135) (xy 212.783051 -343.098767)
			(xy 212.829368 -343.051779) (xy 212.855048 -343.031064) (xy 212.86343 -343.02446) (xy 212.87359 -343.006172)
			(xy 212.882226 -342.911176) (xy 212.875622 -342.891364) (xy 212.86851 -342.88349) (xy 212.85046 -342.86243)
			(xy 212.820046 -342.816047) (xy 212.796654 -342.765756) (xy 212.780776 -342.712612) (xy 212.772746 -342.657731)
			(xy 212.772244 -342.629998) (xy 212.772694 -342.603467) (xy 212.780037 -342.550916) (xy 212.794581 -342.499886)
			(xy 212.816047 -342.45136) (xy 212.829648 -342.428576) (xy 212.834982 -342.420194) (xy 212.838284 -342.401144)
			(xy 212.820758 -342.314022) (xy 212.81009 -342.297766) (xy 212.802216 -342.292178) (xy 212.777752 -342.274264)
			(xy 212.732845 -342.233519) (xy 212.693099 -342.187725) (xy 212.659078 -342.137532) (xy 212.631263 -342.08365)
			(xy 212.61005 -342.026845) (xy 212.595739 -341.967922) (xy 212.588532 -341.907714) (xy 212.588094 -341.877396)
			(xy 212.306181 -341.877396) (xy 212.298657 -341.936961) (xy 212.28276 -341.998875) (xy 212.259228 -342.058308)
			(xy 212.228434 -342.114323) (xy 212.190861 -342.166038) (xy 212.147104 -342.212635) (xy 212.097851 -342.25338)
			(xy 212.04388 -342.287631) (xy 211.986041 -342.314848) (xy 211.925248 -342.334601) (xy 211.862458 -342.346579)
			(xy 211.798662 -342.350593) (xy 211.734866 -342.346579) (xy 211.672076 -342.334601) (xy 211.611283 -342.314848)
			(xy 211.553444 -342.287631) (xy 211.499473 -342.25338) (xy 211.45022 -342.212635) (xy 211.406463 -342.166038)
			(xy 211.36889 -342.114323) (xy 211.338096 -342.058308) (xy 211.314564 -341.998875) (xy 211.298667 -341.936961)
			(xy 211.290656 -341.873543) (xy 211.290154 -341.841582) (xy 211.290736 -341.808017) (xy 211.299552 -341.74147)
			(xy 211.317054 -341.676663) (xy 211.342938 -341.614725) (xy 211.376753 -341.556735) (xy 211.41791 -341.503703)
			(xy 211.465692 -341.456552) (xy 211.519267 -341.416104) (xy 211.548218 -341.399114) (xy 211.558378 -341.393272)
			(xy 211.571332 -341.374476) (xy 211.587588 -341.272622) (xy 211.580984 -341.250778) (xy 211.572856 -341.241888)
			(xy 211.554102 -341.220656) (xy 211.522401 -341.173711) (xy 211.497994 -341.122592) (xy 211.48142 -341.068425)
			(xy 211.473042 -341.012401) (xy 211.472526 -340.984078) (xy 211.473036 -340.955183) (xy 211.481745 -340.898055)
			(xy 211.498975 -340.842894) (xy 211.524332 -340.790966) (xy 211.540344 -340.766908) (xy 211.545932 -340.75878)
			(xy 211.55025 -340.739984) (xy 211.53628 -340.65083) (xy 211.526374 -340.63432) (xy 211.5185 -340.628224)
			(xy 211.492221 -340.607576) (xy 211.444803 -340.56048) (xy 211.403968 -340.507572) (xy 211.370423 -340.449769)
			(xy 211.344745 -340.388066) (xy 211.327378 -340.323529) (xy 211.318621 -340.257272) (xy 211.318094 -340.223856)
			(xy 211.318557 -340.192087) (xy 211.326472 -340.129044) (xy 211.342172 -340.067477) (xy 211.365415 -340.008343)
			(xy 211.395837 -339.952562) (xy 211.432966 -339.901001) (xy 211.454238 -339.8774) (xy 211.460842 -339.870542)
			(xy 211.4677 -339.85327) (xy 211.469224 -339.766148) (xy 211.462874 -339.748876) (xy 211.456524 -339.741764)
			(xy 211.436957 -339.718566) (xy 211.402866 -339.668355) (xy 211.374998 -339.614441) (xy 211.353752 -339.557591)
			(xy 211.339429 -339.498616) (xy 211.332234 -339.438353) (xy 211.33181 -339.408008) (xy 211.332263 -339.37729)
			(xy 211.339675 -339.316302) (xy 211.35438 -339.256651) (xy 211.376163 -339.199206) (xy 211.404708 -339.144804)
			(xy 211.439599 -339.094236) (xy 211.480327 -339.04824) (xy 211.503006 -339.027516) (xy 211.509575 -339.02123)
			(xy 211.51817 -339.005224) (xy 211.51977 -338.996274) (xy 211.523834 -338.966302) (xy 211.524704 -338.957445)
			(xy 211.521061 -338.940037) (xy 211.516722 -338.932266) (xy 211.503016 -338.90945) (xy 211.481391 -338.860816)
			(xy 211.466722 -338.809652) (xy 211.459293 -338.756948) (xy 211.45881 -338.730336) (xy 211.459349 -338.70149)
			(xy 211.468025 -338.644454) (xy 211.4852 -338.589377) (xy 211.51048 -338.537519) (xy 211.543289 -338.490064)
			(xy 211.562696 -338.468716) (xy 211.570824 -338.459826) (xy 211.577936 -338.43722) (xy 211.560664 -338.333842)
			(xy 211.546948 -338.314792) (xy 211.53628 -338.309204) (xy 211.509404 -338.294474) (xy 211.459069 -338.259507)
			(xy 211.413301 -338.218744) (xy 211.372762 -338.172777) (xy 211.33804 -338.122273) (xy 211.309638 -338.067962)
			(xy 211.287967 -338.010632) (xy 211.273343 -337.951113) (xy 211.265975 -337.890268) (xy 211.265516 -337.859624)
			(xy 207.59166 -337.859624) (xy 207.59166 -344.952828) (xy 213.115398 -344.952828) (xy 213.1159 -344.920867)
			(xy 213.123911 -344.857449) (xy 213.139808 -344.795535) (xy 213.16334 -344.736102) (xy 213.194134 -344.680087)
			(xy 213.231707 -344.628372) (xy 213.275464 -344.581775) (xy 213.324717 -344.54103) (xy 213.378688 -344.506779)
			(xy 213.436527 -344.479562) (xy 213.49732 -344.459809) (xy 213.56011 -344.447831) (xy 213.623906 -344.443818)
			(xy 213.687702 -344.447831) (xy 213.750492 -344.459809) (xy 213.811285 -344.479562) (xy 213.869124 -344.506779)
			(xy 213.923095 -344.54103) (xy 213.972348 -344.581775) (xy 214.016105 -344.628372) (xy 214.053678 -344.680087)
			(xy 214.084472 -344.736102) (xy 214.108004 -344.795535) (xy 214.123901 -344.857449) (xy 214.131912 -344.920867)
			(xy 214.132414 -344.952828) (xy 214.131913 -344.986106) (xy 214.123242 -345.052094) (xy 214.106038 -345.116387)
			(xy 214.080595 -345.177888) (xy 214.047349 -345.235545) (xy 214.006866 -345.288372) (xy 213.959839 -345.335469)
			(xy 213.933786 -345.35618) (xy 213.924642 -345.363038) (xy 213.914482 -345.382596) (xy 213.909656 -345.482672)
			(xy 213.917784 -345.503246) (xy 213.926166 -345.510866) (xy 213.944893 -345.52897) (xy 213.977735 -345.569397)
			(xy 214.004773 -345.613916) (xy 214.025504 -345.661699) (xy 214.039543 -345.711858) (xy 214.046628 -345.763461)
			(xy 214.04707 -345.789504) (xy 214.046597 -345.817473) (xy 214.03844 -345.872812) (xy 214.022287 -345.926367)
			(xy 213.998484 -345.976987) (xy 213.967542 -346.023588) (xy 213.930126 -346.065169) (xy 213.908894 -346.083382)
			(xy 213.89848 -346.092018) (xy 213.889082 -346.116402) (xy 213.905338 -346.228924) (xy 213.92134 -346.249752)
			(xy 213.933786 -346.255086) (xy 213.963905 -346.268523) (xy 214.020685 -346.302079) (xy 214.07265 -346.342692)
			(xy 214.118929 -346.389683) (xy 214.158746 -346.442261) (xy 214.191432 -346.499545) (xy 214.216439 -346.560574)
			(xy 214.233347 -346.624323) (xy 214.241872 -346.689723) (xy 214.242396 -346.7227) (xy 214.241894 -346.754661)
			(xy 214.233883 -346.818079) (xy 214.217986 -346.879993) (xy 214.194454 -346.939426) (xy 214.16366 -346.995441)
			(xy 214.126087 -347.047156) (xy 214.08233 -347.093753) (xy 214.033077 -347.134498) (xy 213.979106 -347.168749)
			(xy 213.921267 -347.195966) (xy 213.860474 -347.215719) (xy 213.797684 -347.227697) (xy 213.733888 -347.231711)
			(xy 213.670092 -347.227697) (xy 213.607302 -347.215719) (xy 213.546509 -347.195966) (xy 213.48867 -347.168749)
			(xy 213.434699 -347.134498) (xy 213.385446 -347.093753) (xy 213.341689 -347.047156) (xy 213.304116 -346.995441)
			(xy 213.273322 -346.939426) (xy 213.24979 -346.879993) (xy 213.233893 -346.818079) (xy 213.225882 -346.754661)
			(xy 213.22538 -346.7227) (xy 213.225901 -346.690239) (xy 213.234164 -346.625844) (xy 213.250557 -346.563025)
			(xy 213.274812 -346.502803) (xy 213.306534 -346.446158) (xy 213.345209 -346.394012) (xy 213.390206 -346.347212)
			(xy 213.440794 -346.30652) (xy 213.468204 -346.289122) (xy 213.479634 -346.28201) (xy 213.492334 -346.259404)
			(xy 213.49208 -346.145358) (xy 213.47938 -346.122752) (xy 213.467696 -346.11564) (xy 213.444063 -346.100696)
			(xy 213.400994 -346.06504) (xy 213.363593 -346.023477) (xy 213.332662 -345.976899) (xy 213.308864 -345.926303)
			(xy 213.29271 -345.872774) (xy 213.284544 -345.817461) (xy 213.284054 -345.789504) (xy 213.284543 -345.762041)
			(xy 213.292402 -345.70768) (xy 213.307974 -345.655008) (xy 213.330935 -345.605112) (xy 213.360813 -345.559023)
			(xy 213.378542 -345.538044) (xy 213.386162 -345.529662) (xy 213.392258 -345.508326) (xy 213.377526 -345.409266)
			(xy 213.365334 -345.390724) (xy 213.355682 -345.384882) (xy 213.328533 -345.367418) (xy 213.278443 -345.326697)
			(xy 213.233908 -345.279965) (xy 213.195645 -345.227973) (xy 213.164268 -345.171558) (xy 213.140282 -345.111625)
			(xy 213.124073 -345.04914) (xy 213.1159 -344.985105) (xy 213.115398 -344.952828) (xy 207.59166 -344.952828)
			(xy 207.59166 -352.49993) (xy 231.378258 -352.49993) (xy 231.382272 -352.294246) (xy 231.394308 -352.088876)
			(xy 231.414347 -351.884132) (xy 231.44236 -351.680325) (xy 231.478303 -351.477766) (xy 231.522122 -351.276764)
			(xy 231.573749 -351.077625) (xy 231.633107 -350.880652) (xy 231.700105 -350.686144) (xy 231.774641 -350.494399)
			(xy 231.856601 -350.305708) (xy 231.945861 -350.120358) (xy 232.042284 -349.938632) (xy 232.145725 -349.760806)
			(xy 232.256024 -349.587152) (xy 232.373015 -349.417933) (xy 232.496519 -349.253407) (xy 232.626348 -349.093826)
			(xy 232.762305 -348.939431) (xy 232.904182 -348.790459) (xy 233.051763 -348.647135) (xy 233.204824 -348.509679)
			(xy 233.363131 -348.378299) (xy 233.526444 -348.253196) (xy 233.694513 -348.134559) (xy 233.867083 -348.022571)
			(xy 234.043891 -347.9174) (xy 234.224668 -347.819209) (xy 234.409138 -347.728145) (xy 234.59702 -347.644348)
			(xy 234.78803 -347.567945) (xy 234.981874 -347.499052) (xy 235.178259 -347.437775) (xy 235.376885 -347.384207)
			(xy 235.57745 -347.33843) (xy 235.779648 -347.300512) (xy 235.983172 -347.270513) (xy 236.187711 -347.248476)
			(xy 236.392954 -347.234437) (xy 236.598589 -347.228417) (xy 236.804302 -347.230424) (xy 237.00978 -347.240456)
			(xy 237.21471 -347.258497) (xy 237.41878 -347.28452) (xy 237.62168 -347.318485) (xy 237.8231 -347.36034)
			(xy 238.022733 -347.410022) (xy 238.220276 -347.467456) (xy 238.415428 -347.532553) (xy 238.607892 -347.605214)
			(xy 238.797374 -347.68533) (xy 238.983585 -347.772777) (xy 239.166244 -347.867423) (xy 239.34507 -347.969123)
			(xy 239.519792 -348.077723) (xy 239.690145 -348.193058) (xy 239.855867 -348.314951) (xy 240.016708 -348.443217)
			(xy 240.172421 -348.57766) (xy 240.322771 -348.718077) (xy 240.467528 -348.864253) (xy 240.606471 -349.015965)
			(xy 240.739389 -349.172983) (xy 240.86608 -349.335068) (xy 240.98635 -349.501971) (xy 241.100017 -349.673441)
			(xy 241.206907 -349.849214) (xy 241.306858 -350.029024) (xy 241.399717 -350.212597) (xy 241.485344 -350.399653)
			(xy 241.563606 -350.589908) (xy 241.634387 -350.783071) (xy 241.697577 -350.978849) (xy 241.75308 -351.176943)
			(xy 241.800812 -351.377052) (xy 241.840701 -351.57887) (xy 241.872685 -351.782092) (xy 241.896715 -351.986406)
			(xy 241.912756 -352.191502) (xy 241.920782 -352.397069) (xy 241.921284 -352.49993) (xy 241.920782 -352.602791)
			(xy 241.912756 -352.808358) (xy 241.896715 -353.013454) (xy 241.872685 -353.217768) (xy 241.840701 -353.42099)
			(xy 241.800812 -353.622808) (xy 241.75308 -353.822917) (xy 241.697577 -354.021011) (xy 241.634387 -354.216789)
			(xy 241.563606 -354.409952) (xy 241.485344 -354.600207) (xy 241.399717 -354.787263) (xy 241.306858 -354.970836)
			(xy 241.206907 -355.150646) (xy 241.100017 -355.326419) (xy 240.98635 -355.497889) (xy 240.86608 -355.664792)
			(xy 240.739389 -355.826877) (xy 240.606471 -355.983895) (xy 240.467528 -356.135607) (xy 240.322771 -356.281783)
			(xy 240.172421 -356.4222) (xy 240.016708 -356.556643) (xy 239.855867 -356.684909) (xy 239.690145 -356.806802)
			(xy 239.519792 -356.922137) (xy 239.34507 -357.030737) (xy 239.166244 -357.132437) (xy 238.983585 -357.227083)
			(xy 238.797374 -357.31453) (xy 238.607892 -357.394646) (xy 238.415428 -357.467307) (xy 238.220276 -357.532404)
			(xy 238.022733 -357.589838) (xy 237.8231 -357.63952) (xy 237.62168 -357.681375) (xy 237.41878 -357.71534)
			(xy 237.21471 -357.741363) (xy 237.00978 -357.759404) (xy 236.804302 -357.769436) (xy 236.598589 -357.771443)
			(xy 236.392954 -357.765423) (xy 236.187711 -357.751384) (xy 235.983172 -357.729347) (xy 235.779648 -357.699348)
			(xy 235.57745 -357.66143) (xy 235.376885 -357.615653) (xy 235.178259 -357.562085) (xy 234.981874 -357.500808)
			(xy 234.78803 -357.431915) (xy 234.59702 -357.355512) (xy 234.409138 -357.271715) (xy 234.224668 -357.180651)
			(xy 234.043891 -357.08246) (xy 233.867083 -356.977289) (xy 233.694513 -356.865301) (xy 233.526444 -356.746664)
			(xy 233.363131 -356.621561) (xy 233.204824 -356.490181) (xy 233.051763 -356.352725) (xy 232.904182 -356.209401)
			(xy 232.762305 -356.060429) (xy 232.626348 -355.906034) (xy 232.496519 -355.746453) (xy 232.373015 -355.581927)
			(xy 232.256024 -355.412708) (xy 232.145725 -355.239054) (xy 232.042284 -355.061228) (xy 231.945861 -354.879502)
			(xy 231.856601 -354.694152) (xy 231.774641 -354.505461) (xy 231.700105 -354.313716) (xy 231.633107 -354.119208)
			(xy 231.573749 -353.922235) (xy 231.522122 -353.723096) (xy 231.478303 -353.522094) (xy 231.44236 -353.319535)
			(xy 231.414347 -353.115728) (xy 231.394308 -352.910984) (xy 231.382272 -352.705614) (xy 231.378258 -352.49993)
			(xy 207.59166 -352.49993) (xy 207.59166 -355.412294) (xy 207.591237 -355.422364) (xy 207.583519 -355.440966)
			(xy 207.576674 -355.448362) (xy 202.260962 -360.764074) (xy 207.859636 -360.764074) (xy 207.863654 -360.547918)
			(xy 207.875705 -360.332061) (xy 207.89577 -360.116801) (xy 207.923823 -359.902435) (xy 207.959824 -359.689261)
			(xy 208.003725 -359.477572) (xy 208.055463 -359.267661) (xy 208.114968 -359.059818) (xy 208.182158 -358.85433)
			(xy 208.256939 -358.651482) (xy 208.339208 -358.451554) (xy 208.428852 -358.254822) (xy 208.525746 -358.061558)
			(xy 208.629757 -357.872029) (xy 208.740741 -357.686497) (xy 208.858544 -357.505219) (xy 208.983004 -357.328444)
			(xy 209.113949 -357.156418) (xy 209.251198 -356.989378) (xy 209.39456 -356.827555) (xy 209.543839 -356.671173)
			(xy 209.698827 -356.520447) (xy 209.859311 -356.375587) (xy 210.025068 -356.236792) (xy 210.195869 -356.104254)
			(xy 210.371479 -355.978156) (xy 210.551655 -355.858673) (xy 210.736147 -355.745969) (xy 210.924701 -355.640201)
			(xy 211.117056 -355.541514) (xy 211.312947 -355.450046) (xy 211.512102 -355.365922) (xy 211.714246 -355.289259)
			(xy 211.9191 -355.220163) (xy 212.126381 -355.158728) (xy 212.335802 -355.105041) (xy 212.547074 -355.059175)
			(xy 212.759905 -355.021194) (xy 212.974 -354.99115) (xy 213.189064 -354.969084) (xy 213.4048 -354.955028)
			(xy 213.620909 -354.949001) (xy 213.837093 -354.95101) (xy 214.053053 -354.961054) (xy 214.26849 -354.979118)
			(xy 214.483107 -355.005177) (xy 214.696607 -355.039195) (xy 214.908695 -355.081126) (xy 215.119078 -355.130911)
			(xy 215.327465 -355.188482) (xy 215.533568 -355.253759) (xy 215.737102 -355.326651) (xy 215.937787 -355.407059)
			(xy 216.135344 -355.49487) (xy 216.3295 -355.589964) (xy 216.519987 -355.692209) (xy 216.706543 -355.801463)
			(xy 216.888908 -355.917577) (xy 217.066832 -356.040389) (xy 217.240068 -356.169729) (xy 217.408376 -356.305419)
			(xy 217.571524 -356.447271) (xy 217.729287 -356.59509) (xy 217.881447 -356.74867) (xy 218.027793 -356.907801)
			(xy 218.168123 -357.07226) (xy 218.302243 -357.241823) (xy 218.429967 -357.416253) (xy 218.55112 -357.59531)
			(xy 218.665533 -357.778747) (xy 218.773049 -357.96631) (xy 218.873519 -358.15774) (xy 218.918612 -358.252014)
			(xy 221.738698 -358.252014) (xy 221.739177 -358.220503) (xy 221.74697 -358.157963) (xy 221.762426 -358.096865)
			(xy 221.785308 -358.038142) (xy 221.815266 -357.982695) (xy 221.851841 -357.931371) (xy 221.87281 -357.907844)
			(xy 221.87916 -357.900986) (xy 221.886018 -357.883714) (xy 221.887542 -357.797354) (xy 221.881192 -357.779828)
			(xy 221.874842 -357.772716) (xy 221.855455 -357.749586) (xy 221.82173 -357.699531) (xy 221.794164 -357.645838)
			(xy 221.773144 -357.589261) (xy 221.758966 -357.530594) (xy 221.751827 -357.470662) (xy 221.751398 -357.440484)
			(xy 221.7519 -357.408523) (xy 221.759911 -357.345105) (xy 221.775808 -357.283191) (xy 221.79934 -357.223758)
			(xy 221.830134 -357.167743) (xy 221.867707 -357.116028) (xy 221.911464 -357.069431) (xy 221.960717 -357.028686)
			(xy 222.014688 -356.994435) (xy 222.072527 -356.967218) (xy 222.13332 -356.947465) (xy 222.19611 -356.935487)
			(xy 222.259906 -356.931474) (xy 222.323702 -356.935487) (xy 222.386492 -356.947465) (xy 222.447285 -356.967218)
			(xy 222.505124 -356.994435) (xy 222.559095 -357.028686) (xy 222.608348 -357.069431) (xy 222.652105 -357.116028)
			(xy 222.689678 -357.167743) (xy 222.720472 -357.223758) (xy 222.744004 -357.283191) (xy 222.759901 -357.345105)
			(xy 222.767912 -357.408523) (xy 222.768414 -357.440484) (xy 222.76793 -357.471995) (xy 222.760138 -357.534534)
			(xy 222.744683 -357.595633) (xy 222.721802 -357.654355) (xy 222.691845 -357.709803) (xy 222.65527 -357.761127)
			(xy 222.634302 -357.784654) (xy 222.627952 -357.791512) (xy 222.621094 -357.808784) (xy 222.61957 -357.895144)
			(xy 222.62592 -357.91267) (xy 222.63227 -357.919782) (xy 222.651658 -357.942911) (xy 222.685382 -357.992967)
			(xy 222.712948 -358.04666) (xy 222.733967 -358.103237) (xy 222.748146 -358.161904) (xy 222.755285 -358.221836)
			(xy 222.755714 -358.252014) (xy 222.755212 -358.283975) (xy 222.747201 -358.347393) (xy 222.731304 -358.409307)
			(xy 222.707772 -358.46874) (xy 222.676978 -358.524755) (xy 222.639405 -358.57647) (xy 222.595648 -358.623067)
			(xy 222.546395 -358.663812) (xy 222.492424 -358.698063) (xy 222.434585 -358.72528) (xy 222.373792 -358.745033)
			(xy 222.311002 -358.757011) (xy 222.247206 -358.761025) (xy 222.18341 -358.757011) (xy 222.12062 -358.745033)
			(xy 222.059827 -358.72528) (xy 222.001988 -358.698063) (xy 221.948017 -358.663812) (xy 221.898764 -358.623067)
			(xy 221.855007 -358.57647) (xy 221.817434 -358.524755) (xy 221.78664 -358.46874) (xy 221.763108 -358.409307)
			(xy 221.747211 -358.347393) (xy 221.7392 -358.283975) (xy 221.738698 -358.252014) (xy 218.918612 -358.252014)
			(xy 218.966805 -358.352771) (xy 219.052776 -358.551136) (xy 219.131315 -358.752559) (xy 219.202312 -358.956762)
			(xy 219.26567 -359.163463) (xy 219.321302 -359.372376) (xy 219.369129 -359.583212) (xy 219.409087 -359.795681)
			(xy 219.44112 -360.009488) (xy 219.465183 -360.224338) (xy 219.481244 -360.439934) (xy 219.48928 -360.655977)
			(xy 219.489782 -360.764074) (xy 219.48928 -360.872171) (xy 219.481244 -361.088214) (xy 219.478995 -361.118404)
			(xy 223.844358 -361.118404) (xy 223.84477 -361.08805) (xy 223.851988 -361.027774) (xy 223.866332 -360.968786)
			(xy 223.8876 -360.911927) (xy 223.915488 -360.858005) (xy 223.9496 -360.807788) (xy 223.989449 -360.761991)
			(xy 224.034468 -360.721265) (xy 224.058988 -360.703368) (xy 224.068894 -360.69651) (xy 224.08007 -360.675682)
			(xy 224.082864 -360.569764) (xy 224.072704 -360.548428) (xy 224.063052 -360.540808) (xy 224.037629 -360.520103)
			(xy 223.991832 -360.47318) (xy 223.952446 -360.42076) (xy 223.920124 -360.363713) (xy 223.895403 -360.302984)
			(xy 223.878691 -360.239582) (xy 223.870268 -360.174558) (xy 223.869758 -360.141774) (xy 223.87026 -360.109813)
			(xy 223.878271 -360.046395) (xy 223.894168 -359.984481) (xy 223.9177 -359.925048) (xy 223.948494 -359.869033)
			(xy 223.986067 -359.817318) (xy 224.029824 -359.770721) (xy 224.079077 -359.729976) (xy 224.133048 -359.695725)
			(xy 224.190887 -359.668508) (xy 224.25168 -359.648755) (xy 224.31447 -359.636777) (xy 224.378266 -359.632764)
			(xy 224.442062 -359.636777) (xy 224.504852 -359.648755) (xy 224.565645 -359.668508) (xy 224.623484 -359.695725)
			(xy 224.677455 -359.729976) (xy 224.726708 -359.770721) (xy 224.770465 -359.817318) (xy 224.808038 -359.869033)
			(xy 224.838832 -359.925048) (xy 224.862364 -359.984481) (xy 224.878261 -360.046395) (xy 224.886272 -360.109813)
			(xy 224.886774 -360.141774) (xy 224.886332 -360.172127) (xy 224.879117 -360.232401) (xy 224.864776 -360.291388)
			(xy 224.843512 -360.348247) (xy 224.815628 -360.402168) (xy 224.781521 -360.452386) (xy 224.741677 -360.498184)
			(xy 224.696661 -360.538911) (xy 224.672144 -360.55681) (xy 224.662238 -360.563668) (xy 224.651062 -360.584496)
			(xy 224.648268 -360.690414) (xy 224.658428 -360.71175) (xy 224.66808 -360.71937) (xy 224.693499 -360.740079)
			(xy 224.739295 -360.787002) (xy 224.77868 -360.839422) (xy 224.811002 -360.896469) (xy 224.835724 -360.957196)
			(xy 224.852437 -361.020597) (xy 224.860863 -361.085621) (xy 224.861374 -361.118404) (xy 224.860872 -361.150365)
			(xy 224.852861 -361.213783) (xy 224.836964 -361.275697) (xy 224.813432 -361.33513) (xy 224.782638 -361.391145)
			(xy 224.745065 -361.44286) (xy 224.701308 -361.489457) (xy 224.652055 -361.530202) (xy 224.598084 -361.564453)
			(xy 224.540245 -361.59167) (xy 224.479452 -361.611423) (xy 224.416662 -361.623401) (xy 224.352866 -361.627415)
			(xy 224.28907 -361.623401) (xy 224.22628 -361.611423) (xy 224.165487 -361.59167) (xy 224.107648 -361.564453)
			(xy 224.053677 -361.530202) (xy 224.004424 -361.489457) (xy 223.960667 -361.44286) (xy 223.923094 -361.391145)
			(xy 223.8923 -361.33513) (xy 223.868768 -361.275697) (xy 223.852871 -361.213783) (xy 223.84486 -361.150365)
			(xy 223.844358 -361.118404) (xy 219.478995 -361.118404) (xy 219.465183 -361.30381) (xy 219.44112 -361.51866)
			(xy 219.409087 -361.732467) (xy 219.369129 -361.944936) (xy 219.360672 -361.982215) (xy 222.86569 -361.982215)
			(xy 222.86569 -361.918293) (xy 222.873701 -361.854875) (xy 222.889598 -361.792961) (xy 222.91313 -361.733528)
			(xy 222.943924 -361.677513) (xy 222.981497 -361.625798) (xy 223.025254 -361.579201) (xy 223.074507 -361.538456)
			(xy 223.128478 -361.504205) (xy 223.186317 -361.476988) (xy 223.24711 -361.457235) (xy 223.3099 -361.445257)
			(xy 223.373696 -361.441244) (xy 223.437492 -361.445257) (xy 223.500282 -361.457235) (xy 223.561075 -361.476988)
			(xy 223.618914 -361.504205) (xy 223.672885 -361.538456) (xy 223.722138 -361.579201) (xy 223.765895 -361.625798)
			(xy 223.803468 -361.677513) (xy 223.834262 -361.733528) (xy 223.857794 -361.792961) (xy 223.873691 -361.854875)
			(xy 223.881702 -361.918293) (xy 223.882204 -361.950254) (xy 223.881702 -361.982215) (xy 223.873691 -362.045633)
			(xy 223.857794 -362.107547) (xy 223.834262 -362.16698) (xy 223.803468 -362.222995) (xy 223.765895 -362.27471)
			(xy 223.722138 -362.321307) (xy 223.672885 -362.362052) (xy 223.618914 -362.396303) (xy 223.561075 -362.42352)
			(xy 223.500282 -362.443273) (xy 223.437492 -362.455251) (xy 223.373696 -362.459265) (xy 223.3099 -362.455251)
			(xy 223.24711 -362.443273) (xy 223.186317 -362.42352) (xy 223.128478 -362.396303) (xy 223.074507 -362.362052)
			(xy 223.025254 -362.321307) (xy 222.981497 -362.27471) (xy 222.943924 -362.222995) (xy 222.91313 -362.16698)
			(xy 222.889598 -362.107547) (xy 222.873701 -362.045633) (xy 222.86569 -361.982215) (xy 219.360672 -361.982215)
			(xy 219.321302 -362.155772) (xy 219.26567 -362.364685) (xy 219.202312 -362.571386) (xy 219.131315 -362.775589)
			(xy 219.052776 -362.977012) (xy 218.966805 -363.175377) (xy 218.873519 -363.370408) (xy 218.773049 -363.561838)
			(xy 218.749581 -363.602778) (xy 224.128838 -363.602778) (xy 224.129307 -363.570652) (xy 224.137415 -363.506913)
			(xy 224.153486 -363.444703) (xy 224.177266 -363.385013) (xy 224.208373 -363.328793) (xy 224.246314 -363.276939)
			(xy 224.290485 -363.230277) (xy 224.34018 -363.189549) (xy 224.39461 -363.155405) (xy 224.452906 -363.128389)
			(xy 224.514141 -363.108931) (xy 224.545652 -363.102652) (xy 224.55505 -363.100874) (xy 224.570798 -363.091222)
			(xy 224.624138 -363.022642) (xy 224.629472 -363.004862) (xy 224.62871 -362.995464) (xy 224.62744 -362.959142)
			(xy 224.627942 -362.927181) (xy 224.635953 -362.863763) (xy 224.65185 -362.801849) (xy 224.675382 -362.742416)
			(xy 224.706176 -362.686401) (xy 224.743749 -362.634686) (xy 224.787506 -362.588089) (xy 224.836759 -362.547344)
			(xy 224.89073 -362.513093) (xy 224.948569 -362.485876) (xy 225.009362 -362.466123) (xy 225.072152 -362.454145)
			(xy 225.135948 -362.450132) (xy 225.199744 -362.454145) (xy 225.262534 -362.466123) (xy 225.323327 -362.485876)
			(xy 225.381166 -362.513093) (xy 225.435137 -362.547344) (xy 225.48439 -362.588089) (xy 225.528147 -362.634686)
			(xy 225.56572 -362.686401) (xy 225.596514 -362.742416) (xy 225.620046 -362.801849) (xy 225.635943 -362.863763)
			(xy 225.643954 -362.927181) (xy 225.644456 -362.959142) (xy 225.643918 -362.991266) (xy 225.63582 -363.055003)
			(xy 225.619758 -363.117211) (xy 225.595987 -363.176901) (xy 225.564887 -363.233121) (xy 225.526953 -363.284976)
			(xy 225.482789 -363.331639) (xy 225.433099 -363.372368) (xy 225.378674 -363.406513) (xy 225.320382 -363.43353)
			(xy 225.259151 -363.452989) (xy 225.227642 -363.459268) (xy 225.218244 -363.461046) (xy 225.202496 -363.470698)
			(xy 225.149156 -363.539278) (xy 225.143822 -363.557058) (xy 225.144584 -363.566456) (xy 225.145854 -363.602778)
			(xy 225.145352 -363.634739) (xy 225.137341 -363.698157) (xy 225.121444 -363.760071) (xy 225.097912 -363.819504)
			(xy 225.067118 -363.875519) (xy 225.029545 -363.927234) (xy 224.985788 -363.973831) (xy 224.936535 -364.014576)
			(xy 224.882564 -364.048827) (xy 224.824725 -364.076044) (xy 224.763932 -364.095797) (xy 224.701142 -364.107775)
			(xy 224.637346 -364.111789) (xy 224.57355 -364.107775) (xy 224.51076 -364.095797) (xy 224.449967 -364.076044)
			(xy 224.392128 -364.048827) (xy 224.338157 -364.014576) (xy 224.288904 -363.973831) (xy 224.245147 -363.927234)
			(xy 224.207574 -363.875519) (xy 224.17678 -363.819504) (xy 224.153248 -363.760071) (xy 224.137351 -363.698157)
			(xy 224.12934 -363.634739) (xy 224.128838 -363.602778) (xy 218.749581 -363.602778) (xy 218.665533 -363.749401)
			(xy 218.55112 -363.932838) (xy 218.429967 -364.111895) (xy 218.302243 -364.286325) (xy 218.168123 -364.455888)
			(xy 218.027793 -364.620347) (xy 217.881447 -364.779478) (xy 217.729287 -364.933058) (xy 217.571524 -365.080877)
			(xy 217.408376 -365.222729) (xy 217.240068 -365.358419) (xy 217.066832 -365.487759) (xy 216.888908 -365.610571)
			(xy 216.706543 -365.726685) (xy 216.519987 -365.835939) (xy 216.3295 -365.938184) (xy 216.135344 -366.033278)
			(xy 215.937787 -366.121089) (xy 215.737102 -366.201497) (xy 215.667401 -366.226459) (xy 220.783373 -366.226459)
			(xy 220.783373 -366.098741) (xy 220.791393 -365.971275) (xy 220.8074 -365.844564) (xy 220.831332 -365.719108)
			(xy 220.863094 -365.595402) (xy 220.902561 -365.473935) (xy 220.949578 -365.355185) (xy 221.003958 -365.239623)
			(xy 221.065486 -365.127702) (xy 221.133921 -365.019866) (xy 221.208992 -364.91654) (xy 221.290403 -364.818132)
			(xy 221.377832 -364.725029) (xy 221.470935 -364.6376) (xy 221.569343 -364.55619) (xy 221.67267 -364.481119)
			(xy 221.780506 -364.412684) (xy 221.892426 -364.351156) (xy 222.007989 -364.296776) (xy 222.126739 -364.24976)
			(xy 222.248206 -364.210293) (xy 222.371912 -364.178531) (xy 222.497368 -364.154599) (xy 222.624079 -364.138592)
			(xy 222.751545 -364.130573) (xy 222.815404 -364.130082) (xy 222.879318 -364.130518) (xy 223.006893 -364.138558)
			(xy 223.133711 -364.154599) (xy 223.259271 -364.178577) (xy 223.383075 -364.210399) (xy 223.504634 -364.249939)
			(xy 223.623469 -364.297039) (xy 223.739109 -364.351514) (xy 223.851096 -364.413148) (xy 223.95899 -364.481699)
			(xy 224.062362 -364.556894) (xy 224.160804 -364.638436) (xy 224.253927 -364.726004) (xy 224.341363 -364.819251)
			(xy 224.422767 -364.917809) (xy 224.455289 -364.962651) (xy 224.819712 -364.962651) (xy 224.819712 -364.898729)
			(xy 224.827723 -364.835311) (xy 224.84362 -364.773397) (xy 224.867152 -364.713964) (xy 224.897946 -364.657949)
			(xy 224.935519 -364.606234) (xy 224.979276 -364.559637) (xy 225.028529 -364.518892) (xy 225.0825 -364.484641)
			(xy 225.140339 -364.457424) (xy 225.201132 -364.437671) (xy 225.263922 -364.425693) (xy 225.327718 -364.42168)
			(xy 225.391514 -364.425693) (xy 225.454304 -364.437671) (xy 225.515097 -364.457424) (xy 225.572936 -364.484641)
			(xy 225.626907 -364.518892) (xy 225.67616 -364.559637) (xy 225.719917 -364.606234) (xy 225.75749 -364.657949)
			(xy 225.788284 -364.713964) (xy 225.811816 -364.773397) (xy 225.827713 -364.835311) (xy 225.835724 -364.898729)
			(xy 225.836226 -364.93069) (xy 225.835724 -364.962651) (xy 225.827713 -365.026069) (xy 225.811816 -365.087983)
			(xy 225.788284 -365.147416) (xy 225.758996 -365.200692) (xy 228.296724 -365.200692) (xy 228.297176 -365.170819)
			(xy 228.304178 -365.111483) (xy 228.318085 -365.053377) (xy 228.338704 -364.997301) (xy 228.365753 -364.944027)
			(xy 228.398857 -364.89429) (xy 228.417882 -364.871254) (xy 228.424933 -364.862133) (xy 228.430715 -364.839839)
			(xy 228.426188 -364.817256) (xy 228.41966 -364.807754) (xy 228.400124 -364.781135) (xy 228.367366 -364.723805)
			(xy 228.342303 -364.662718) (xy 228.325355 -364.598902) (xy 228.316809 -364.533428) (xy 228.316282 -364.500414)
			(xy 228.316784 -364.468453) (xy 228.324795 -364.405035) (xy 228.340692 -364.343121) (xy 228.364224 -364.283688)
			(xy 228.395018 -364.227673) (xy 228.432591 -364.175958) (xy 228.476348 -364.129361) (xy 228.525601 -364.088616)
			(xy 228.579572 -364.054365) (xy 228.637411 -364.027148) (xy 228.698204 -364.007395) (xy 228.760994 -363.995417)
			(xy 228.82479 -363.991404) (xy 228.888586 -363.995417) (xy 228.951376 -364.007395) (xy 229.012169 -364.027148)
			(xy 229.070008 -364.054365) (xy 229.123979 -364.088616) (xy 229.173232 -364.129361) (xy 229.216989 -364.175958)
			(xy 229.254562 -364.227673) (xy 229.285356 -364.283688) (xy 229.308888 -364.343121) (xy 229.324785 -364.405035)
			(xy 229.332796 -364.468453) (xy 229.333298 -364.500414) (xy 229.332844 -364.530287) (xy 229.325842 -364.589622)
			(xy 229.311935 -364.647728) (xy 229.291316 -364.703804) (xy 229.264268 -364.757078) (xy 229.231164 -364.806816)
			(xy 229.21214 -364.829852) (xy 229.205083 -364.83897) (xy 229.199299 -364.861266) (xy 229.203831 -364.88385)
			(xy 229.210362 -364.893352) (xy 229.229891 -364.919976) (xy 229.262652 -364.977304) (xy 229.287718 -365.038389)
			(xy 229.304667 -365.102205) (xy 229.313213 -365.167678) (xy 229.31374 -365.200692) (xy 229.313238 -365.232653)
			(xy 229.305227 -365.296071) (xy 229.28933 -365.357985) (xy 229.265798 -365.417418) (xy 229.235004 -365.473433)
			(xy 229.197431 -365.525148) (xy 229.153674 -365.571745) (xy 229.104421 -365.61249) (xy 229.05045 -365.646741)
			(xy 228.992611 -365.673958) (xy 228.931818 -365.693711) (xy 228.869028 -365.705689) (xy 228.805232 -365.709703)
			(xy 228.741436 -365.705689) (xy 228.678646 -365.693711) (xy 228.617853 -365.673958) (xy 228.560014 -365.646741)
			(xy 228.506043 -365.61249) (xy 228.45679 -365.571745) (xy 228.413033 -365.525148) (xy 228.37546 -365.473433)
			(xy 228.344666 -365.417418) (xy 228.321134 -365.357985) (xy 228.305237 -365.296071) (xy 228.297226 -365.232653)
			(xy 228.296724 -365.200692) (xy 225.758996 -365.200692) (xy 225.75749 -365.203431) (xy 225.719917 -365.255146)
			(xy 225.67616 -365.301743) (xy 225.626907 -365.342488) (xy 225.572936 -365.376739) (xy 225.515097 -365.403956)
			(xy 225.454304 -365.423709) (xy 225.391514 -365.435687) (xy 225.327718 -365.439701) (xy 225.263922 -365.435687)
			(xy 225.201132 -365.423709) (xy 225.140339 -365.403956) (xy 225.0825 -365.376739) (xy 225.028529 -365.342488)
			(xy 224.979276 -365.301743) (xy 224.935519 -365.255146) (xy 224.897946 -365.203431) (xy 224.867152 -365.147416)
			(xy 224.84362 -365.087983) (xy 224.827723 -365.026069) (xy 224.819712 -364.962651) (xy 224.455289 -364.962651)
			(xy 224.497816 -365.021287) (xy 224.566214 -365.129277) (xy 224.62769 -365.241352) (xy 224.682001 -365.357068)
			(xy 224.705926 -365.416338) (xy 224.708776 -365.423026) (xy 224.717693 -365.434505) (xy 224.723452 -365.438944)
			(xy 224.747454 -365.456904) (xy 224.791499 -365.497574) (xy 224.830453 -365.543143) (xy 224.863778 -365.592977)
			(xy 224.891009 -365.646384) (xy 224.91177 -365.702624) (xy 224.925772 -365.760916) (xy 224.932821 -365.820449)
			(xy 224.933256 -365.850424) (xy 224.932666 -365.886025) (xy 224.931243 -365.8961) (xy 230.641412 -365.8961)
			(xy 230.645426 -365.832306) (xy 230.657404 -365.769518) (xy 230.677157 -365.708726) (xy 230.704373 -365.650889)
			(xy 230.738624 -365.59692) (xy 230.779369 -365.547669) (xy 230.825965 -365.503913) (xy 230.877678 -365.466343)
			(xy 230.933693 -365.43555) (xy 230.993125 -365.412021) (xy 231.055037 -365.396126) (xy 231.118454 -365.388116)
			(xy 231.150414 -365.387636) (xy 231.180288 -365.388082) (xy 231.239623 -365.395085) (xy 231.29773 -365.408992)
			(xy 231.353806 -365.429613) (xy 231.407079 -365.456663) (xy 231.456816 -365.489768) (xy 231.479852 -365.508794)
			(xy 231.487218 -365.51489) (xy 231.50449 -365.520986) (xy 231.592374 -365.518192) (xy 231.609392 -365.510826)
			(xy 231.61625 -365.504222) (xy 231.640051 -365.481821) (xy 231.692382 -365.442661) (xy 231.749299 -365.410529)
			(xy 231.809864 -365.385954) (xy 231.873078 -365.369341) (xy 231.9379 -365.360964) (xy 231.97058 -365.360458)
			(xy 232.002541 -365.361006) (xy 232.065959 -365.369015) (xy 232.127874 -365.38491) (xy 232.187308 -365.408439)
			(xy 232.243324 -365.439232) (xy 232.295039 -365.476804) (xy 232.341637 -365.52056) (xy 232.382383 -365.569812)
			(xy 232.416635 -365.623783) (xy 232.443852 -365.681621) (xy 232.463606 -365.742414) (xy 232.475584 -365.805204)
			(xy 232.479598 -365.869) (xy 232.475584 -365.932796) (xy 232.463606 -365.995586) (xy 232.443852 -366.056379)
			(xy 232.416635 -366.114217) (xy 232.382383 -366.168188) (xy 232.341637 -366.21744) (xy 232.295039 -366.261196)
			(xy 232.243324 -366.298768) (xy 232.187308 -366.329561) (xy 232.127874 -366.35309) (xy 232.065959 -366.368985)
			(xy 232.002541 -366.376994) (xy 231.97058 -366.377474) (xy 231.940706 -366.377029) (xy 231.881371 -366.370026)
			(xy 231.823265 -366.356118) (xy 231.767188 -366.335497) (xy 231.713915 -366.308447) (xy 231.664178 -366.275341)
			(xy 231.641142 -366.256316) (xy 231.633776 -366.25022) (xy 231.616504 -366.244124) (xy 231.52862 -366.246918)
			(xy 231.511602 -366.254284) (xy 231.504744 -366.260888) (xy 231.480947 -366.283293) (xy 231.428615 -366.322453)
			(xy 231.371697 -366.354584) (xy 231.311132 -366.379159) (xy 231.247917 -366.395771) (xy 231.183095 -366.404147)
			(xy 231.150414 -366.404652) (xy 231.118454 -366.404084) (xy 231.055037 -366.396074) (xy 230.993125 -366.380179)
			(xy 230.933693 -366.35665) (xy 230.877678 -366.325857) (xy 230.825965 -366.288287) (xy 230.779369 -366.244531)
			(xy 230.738624 -366.19528) (xy 230.704373 -366.141311) (xy 230.677157 -366.083474) (xy 230.657404 -366.022682)
			(xy 230.645426 -365.959894) (xy 230.641412 -365.8961) (xy 224.931243 -365.8961) (xy 224.92271 -365.956528)
			(xy 224.903009 -366.024951) (xy 224.87395 -366.089953) (xy 224.855532 -366.120426) (xy 224.851899 -366.126685)
			(xy 224.848027 -366.140622) (xy 224.847912 -366.147858) (xy 224.847912 -366.16259) (xy 224.847411 -366.225485)
			(xy 224.839639 -366.351034) (xy 224.824117 -366.475862) (xy 224.800906 -366.599491) (xy 224.770094 -366.721448)
			(xy 224.731798 -366.841266) (xy 224.686166 -366.958487) (xy 224.660206 -367.015776) (xy 224.655126 -367.026698)
			(xy 224.655634 -367.049558) (xy 224.701862 -367.141506) (xy 224.719896 -367.155476) (xy 224.73158 -367.158016)
			(xy 224.749001 -367.161886) (xy 224.783092 -367.172446) (xy 224.799652 -367.179098) (xy 224.813114 -367.184686)
			(xy 224.841308 -367.180114) (xy 224.931986 -367.101628) (xy 224.940622 -367.07445) (xy 224.937066 -367.060226)
			(xy 224.929706 -367.02938) (xy 224.921805 -366.966458) (xy 224.921318 -366.93475) (xy 224.921821 -366.903213)
			(xy 224.929628 -366.840624) (xy 224.945118 -366.779482) (xy 224.96805 -366.720725) (xy 224.998075 -366.665255)
			(xy 225.03473 -366.613926) (xy 225.077452 -366.567524) (xy 225.125586 -366.526763) (xy 225.178391 -366.492268)
			(xy 225.235058 -366.46457) (xy 225.294715 -366.444093) (xy 225.356448 -366.431153) (xy 225.419306 -366.425948)
			(xy 225.482326 -366.428557) (xy 225.544539 -366.438941) (xy 225.60499 -366.456941) (xy 225.662751 -366.48228)
			(xy 225.716934 -366.514568) (xy 225.766707 -366.55331) (xy 225.811306 -366.597911) (xy 225.850046 -366.647686)
			(xy 225.882331 -366.70187) (xy 225.907667 -366.759632) (xy 225.925664 -366.820084) (xy 225.936045 -366.882298)
			(xy 225.938652 -366.945318) (xy 225.933443 -367.008176) (xy 225.9205 -367.069908) (xy 225.900021 -367.129564)
			(xy 225.87232 -367.18623) (xy 225.837823 -367.239034) (xy 225.797059 -367.287165) (xy 225.750656 -367.329885)
			(xy 225.699324 -367.366538) (xy 225.643853 -367.39656) (xy 225.585095 -367.41949) (xy 225.523952 -367.434976)
			(xy 225.461363 -367.442781) (xy 225.429826 -367.443258) (xy 225.397414 -367.442745) (xy 225.333112 -367.434547)
			(xy 225.270374 -367.418242) (xy 225.210216 -367.394096) (xy 225.181668 -367.378742) (xy 225.168968 -367.37163)
			(xy 225.14052 -367.372646) (xy 225.041206 -367.44021) (xy 225.029522 -367.466372) (xy 225.031554 -367.48085)
			(xy 225.033121 -367.493427) (xy 225.034771 -367.518722) (xy 225.034856 -367.531396) (xy 225.034319 -367.558645)
			(xy 225.026564 -367.612588) (xy 225.011212 -367.664879) (xy 224.988575 -367.714453) (xy 224.959113 -367.760301)
			(xy 224.923427 -367.80149) (xy 224.882243 -367.837182) (xy 224.836399 -367.86665) (xy 224.786828 -367.889294)
			(xy 224.734539 -367.904653) (xy 224.680597 -367.912415) (xy 224.653348 -367.912904) (xy 224.615248 -367.910872)
			(xy 224.602294 -367.909602) (xy 224.578672 -367.919508) (xy 224.509076 -368.006122) (xy 224.506031 -368.021827)
			(xy 230.498136 -368.021827) (xy 230.498136 -367.957905) (xy 230.506147 -367.894487) (xy 230.522044 -367.832573)
			(xy 230.545576 -367.77314) (xy 230.57637 -367.717125) (xy 230.613943 -367.66541) (xy 230.6577 -367.618813)
			(xy 230.706953 -367.578068) (xy 230.760924 -367.543817) (xy 230.818763 -367.5166) (xy 230.879556 -367.496847)
			(xy 230.942346 -367.484869) (xy 231.006142 -367.480856) (xy 231.069938 -367.484869) (xy 231.132728 -367.496847)
			(xy 231.193521 -367.5166) (xy 231.25136 -367.543817) (xy 231.305331 -367.578068) (xy 231.354584 -367.618813)
			(xy 231.398341 -367.66541) (xy 231.435914 -367.717125) (xy 231.466708 -367.77314) (xy 231.49024 -367.832573)
			(xy 231.506137 -367.894487) (xy 231.514148 -367.957905) (xy 231.51465 -367.989866) (xy 231.514148 -368.021827)
			(xy 231.506137 -368.085245) (xy 231.49024 -368.147159) (xy 231.466708 -368.206592) (xy 231.435914 -368.262607)
			(xy 231.398341 -368.314322) (xy 231.354584 -368.360919) (xy 231.305331 -368.401664) (xy 231.25136 -368.435915)
			(xy 231.193521 -368.463132) (xy 231.132728 -368.482885) (xy 231.069938 -368.494863) (xy 231.006142 -368.498877)
			(xy 230.942346 -368.494863) (xy 230.879556 -368.482885) (xy 230.818763 -368.463132) (xy 230.760924 -368.435915)
			(xy 230.706953 -368.401664) (xy 230.6577 -368.360919) (xy 230.613943 -368.314322) (xy 230.57637 -368.262607)
			(xy 230.545576 -368.206592) (xy 230.522044 -368.147159) (xy 230.506147 -368.085245) (xy 230.498136 -368.021827)
			(xy 224.506031 -368.021827) (xy 224.50425 -368.031014) (xy 224.508314 -368.04346) (xy 224.519893 -368.081669)
			(xy 224.532401 -368.160516) (xy 224.533206 -368.200432) (xy 224.532774 -368.231164) (xy 224.525362 -368.292179)
			(xy 224.510649 -368.351855) (xy 224.488851 -368.409324) (xy 224.460285 -368.463746) (xy 224.425368 -368.514328)
			(xy 224.384609 -368.560333) (xy 224.338601 -368.601089) (xy 224.288017 -368.636003) (xy 224.233593 -368.664565)
			(xy 224.176123 -368.68636) (xy 224.116445 -368.701068) (xy 224.05543 -368.708476) (xy 224.024698 -368.70894)
			(xy 223.991758 -368.708467) (xy 223.92643 -368.699971) (xy 223.862745 -368.68311) (xy 223.801772 -368.658164)
			(xy 223.744531 -368.625553) (xy 223.691981 -368.585823) (xy 223.645002 -368.539638) (xy 223.604382 -368.487773)
			(xy 223.5708 -368.431096) (xy 223.544819 -368.370556) (xy 223.526874 -368.307168) (xy 223.517266 -368.241994)
			(xy 223.51619 -368.209068) (xy 223.515936 -368.19713) (xy 223.505268 -368.176048) (xy 223.42094 -368.114072)
			(xy 223.397572 -368.110008) (xy 223.386142 -368.11331) (xy 223.3305 -368.129165) (xy 223.217775 -368.155289)
			(xy 223.103747 -368.174957) (xy 222.988784 -368.188104) (xy 222.87326 -368.194689) (xy 222.815404 -368.195098)
			(xy 222.751545 -368.194627) (xy 222.624079 -368.186608) (xy 222.497368 -368.170601) (xy 222.371912 -368.146669)
			(xy 222.248206 -368.114907) (xy 222.126739 -368.07544) (xy 222.007989 -368.028424) (xy 221.892426 -367.974044)
			(xy 221.780506 -367.912516) (xy 221.67267 -367.844081) (xy 221.569343 -367.76901) (xy 221.470935 -367.6876)
			(xy 221.377832 -367.600171) (xy 221.290403 -367.507068) (xy 221.208992 -367.40866) (xy 221.133921 -367.305334)
			(xy 221.065486 -367.197498) (xy 221.003958 -367.085577) (xy 220.949578 -366.970015) (xy 220.902561 -366.851265)
			(xy 220.863094 -366.729798) (xy 220.831332 -366.606092) (xy 220.8074 -366.480636) (xy 220.791393 -366.353925)
			(xy 220.783373 -366.226459) (xy 215.667401 -366.226459) (xy 215.533568 -366.274389) (xy 215.327465 -366.339666)
			(xy 215.119078 -366.397237) (xy 214.908695 -366.447022) (xy 214.696607 -366.488953) (xy 214.483107 -366.522971)
			(xy 214.26849 -366.54903) (xy 214.053053 -366.567094) (xy 213.837093 -366.577138) (xy 213.620909 -366.579147)
			(xy 213.4048 -366.57312) (xy 213.189064 -366.559064) (xy 212.974 -366.536998) (xy 212.759905 -366.506954)
			(xy 212.547074 -366.468973) (xy 212.335802 -366.423107) (xy 212.126381 -366.36942) (xy 211.9191 -366.307985)
			(xy 211.714246 -366.238889) (xy 211.512102 -366.162226) (xy 211.312947 -366.078102) (xy 211.117056 -365.986634)
			(xy 210.924701 -365.887947) (xy 210.736147 -365.782179) (xy 210.551655 -365.669475) (xy 210.371479 -365.549992)
			(xy 210.195869 -365.423894) (xy 210.025068 -365.291356) (xy 209.859311 -365.152561) (xy 209.698827 -365.007701)
			(xy 209.543839 -364.856975) (xy 209.39456 -364.700593) (xy 209.251198 -364.53877) (xy 209.113949 -364.37173)
			(xy 208.983004 -364.199704) (xy 208.858544 -364.022929) (xy 208.740741 -363.841651) (xy 208.629757 -363.656119)
			(xy 208.525746 -363.46659) (xy 208.428852 -363.273326) (xy 208.339208 -363.076594) (xy 208.256939 -362.876666)
			(xy 208.182158 -362.673818) (xy 208.114968 -362.46833) (xy 208.055463 -362.260487) (xy 208.003725 -362.050576)
			(xy 207.959824 -361.838887) (xy 207.923823 -361.625713) (xy 207.89577 -361.411347) (xy 207.875705 -361.196087)
			(xy 207.863654 -360.98023) (xy 207.859636 -360.764074) (xy 202.260962 -360.764074) (xy 196.28739 -366.737646)
			(xy 196.279994 -366.744497) (xy 196.261395 -366.752236) (xy 196.251322 -366.752632) (xy 179.75326 -366.752632)
			(xy 179.743194 -366.753063) (xy 179.724603 -366.760791) (xy 179.717192 -366.767618) (xy 179.534609 -366.950201)
			(xy 218.883224 -366.950201) (xy 218.883224 -366.886279) (xy 218.891235 -366.822861) (xy 218.907132 -366.760947)
			(xy 218.930664 -366.701514) (xy 218.961458 -366.645499) (xy 218.999031 -366.593784) (xy 219.042788 -366.547187)
			(xy 219.092041 -366.506442) (xy 219.146012 -366.472191) (xy 219.203851 -366.444974) (xy 219.264644 -366.425221)
			(xy 219.327434 -366.413243) (xy 219.39123 -366.40923) (xy 219.455026 -366.413243) (xy 219.517816 -366.425221)
			(xy 219.578609 -366.444974) (xy 219.636448 -366.472191) (xy 219.690419 -366.506442) (xy 219.739672 -366.547187)
			(xy 219.783429 -366.593784) (xy 219.821002 -366.645499) (xy 219.851796 -366.701514) (xy 219.875328 -366.760947)
			(xy 219.891225 -366.822861) (xy 219.899236 -366.886279) (xy 219.899738 -366.91824) (xy 219.899236 -366.950201)
			(xy 219.891225 -367.013619) (xy 219.875328 -367.075533) (xy 219.851796 -367.134966) (xy 219.821002 -367.190981)
			(xy 219.783429 -367.242696) (xy 219.739672 -367.289293) (xy 219.690419 -367.330038) (xy 219.636448 -367.364289)
			(xy 219.578609 -367.391506) (xy 219.517816 -367.411259) (xy 219.455026 -367.423237) (xy 219.39123 -367.427251)
			(xy 219.327434 -367.423237) (xy 219.264644 -367.411259) (xy 219.203851 -367.391506) (xy 219.146012 -367.364289)
			(xy 219.092041 -367.330038) (xy 219.042788 -367.289293) (xy 218.999031 -367.242696) (xy 218.961458 -367.190981)
			(xy 218.930664 -367.134966) (xy 218.907132 -367.075533) (xy 218.891235 -367.013619) (xy 218.883224 -366.950201)
			(xy 179.534609 -366.950201) (xy 179.294282 -367.190528) (xy 179.287431 -367.197924) (xy 179.279694 -367.216523)
			(xy 179.279296 -367.226596) (xy 179.279296 -367.692643) (xy 180.91378 -367.692643) (xy 180.91378 -367.628721)
			(xy 180.921791 -367.565303) (xy 180.937688 -367.503389) (xy 180.96122 -367.443956) (xy 180.992014 -367.387941)
			(xy 181.029587 -367.336226) (xy 181.073344 -367.289629) (xy 181.122597 -367.248884) (xy 181.176568 -367.214633)
			(xy 181.234407 -367.187416) (xy 181.2952 -367.167663) (xy 181.35799 -367.155685) (xy 181.421786 -367.151672)
			(xy 181.485582 -367.155685) (xy 181.548372 -367.167663) (xy 181.609165 -367.187416) (xy 181.667004 -367.214633)
			(xy 181.720975 -367.248884) (xy 181.770228 -367.289629) (xy 181.813985 -367.336226) (xy 181.851558 -367.387941)
			(xy 181.882352 -367.443956) (xy 181.905884 -367.503389) (xy 181.921781 -367.565303) (xy 181.929792 -367.628721)
			(xy 181.930294 -367.660682) (xy 181.929792 -367.692643) (xy 181.921781 -367.756061) (xy 181.905884 -367.817975)
			(xy 181.882352 -367.877408) (xy 181.851558 -367.933423) (xy 181.813985 -367.985138) (xy 181.770228 -368.031735)
			(xy 181.720975 -368.07248) (xy 181.667004 -368.106731) (xy 181.609165 -368.133948) (xy 181.548372 -368.153701)
			(xy 181.485582 -368.165679) (xy 181.421786 -368.169693) (xy 181.35799 -368.165679) (xy 181.2952 -368.153701)
			(xy 181.234407 -368.133948) (xy 181.176568 -368.106731) (xy 181.122597 -368.07248) (xy 181.073344 -368.031735)
			(xy 181.029587 -367.985138) (xy 180.992014 -367.933423) (xy 180.96122 -367.877408) (xy 180.937688 -367.817975)
			(xy 180.921791 -367.756061) (xy 180.91378 -367.692643) (xy 179.279296 -367.692643) (xy 179.279296 -370.417555)
			(xy 187.353188 -370.417555) (xy 187.353188 -370.353633) (xy 187.361199 -370.290215) (xy 187.377096 -370.228301)
			(xy 187.400628 -370.168868) (xy 187.431422 -370.112853) (xy 187.468995 -370.061138) (xy 187.512752 -370.014541)
			(xy 187.562005 -369.973796) (xy 187.615976 -369.939545) (xy 187.673815 -369.912328) (xy 187.734608 -369.892575)
			(xy 187.797398 -369.880597) (xy 187.861194 -369.876584) (xy 187.92499 -369.880597) (xy 187.98778 -369.892575)
			(xy 188.048573 -369.912328) (xy 188.106412 -369.939545) (xy 188.160383 -369.973796) (xy 188.160715 -369.974071)
			(xy 228.695752 -369.974071) (xy 228.695752 -369.910149) (xy 228.703763 -369.846731) (xy 228.71966 -369.784817)
			(xy 228.743192 -369.725384) (xy 228.773986 -369.669369) (xy 228.811559 -369.617654) (xy 228.855316 -369.571057)
			(xy 228.904569 -369.530312) (xy 228.95854 -369.496061) (xy 229.016379 -369.468844) (xy 229.077172 -369.449091)
			(xy 229.139962 -369.437113) (xy 229.203758 -369.4331) (xy 229.267554 -369.437113) (xy 229.330344 -369.449091)
			(xy 229.391137 -369.468844) (xy 229.448976 -369.496061) (xy 229.502947 -369.530312) (xy 229.5522 -369.571057)
			(xy 229.595957 -369.617654) (xy 229.63353 -369.669369) (xy 229.664324 -369.725384) (xy 229.687856 -369.784817)
			(xy 229.703753 -369.846731) (xy 229.711764 -369.910149) (xy 229.712266 -369.94211) (xy 229.711764 -369.974071)
			(xy 229.703753 -370.037489) (xy 229.687856 -370.099403) (xy 229.664324 -370.158836) (xy 229.658937 -370.168635)
			(xy 229.877868 -370.168635) (xy 229.877868 -370.104713) (xy 229.885879 -370.041295) (xy 229.901776 -369.979381)
			(xy 229.925308 -369.919948) (xy 229.956102 -369.863933) (xy 229.993675 -369.812218) (xy 230.037432 -369.765621)
			(xy 230.086685 -369.724876) (xy 230.140656 -369.690625) (xy 230.198495 -369.663408) (xy 230.259288 -369.643655)
			(xy 230.322078 -369.631677) (xy 230.385874 -369.627664) (xy 230.44967 -369.631677) (xy 230.51246 -369.643655)
			(xy 230.573253 -369.663408) (xy 230.631092 -369.690625) (xy 230.685063 -369.724876) (xy 230.734316 -369.765621)
			(xy 230.778073 -369.812218) (xy 230.815646 -369.863933) (xy 230.84644 -369.919948) (xy 230.869972 -369.979381)
			(xy 230.885869 -370.041295) (xy 230.89388 -370.104713) (xy 230.894382 -370.136674) (xy 230.89388 -370.168635)
			(xy 230.885869 -370.232053) (xy 230.869972 -370.293967) (xy 230.84644 -370.3534) (xy 230.815646 -370.409415)
			(xy 230.778073 -370.46113) (xy 230.734316 -370.507727) (xy 230.685063 -370.548472) (xy 230.631092 -370.582723)
			(xy 230.573253 -370.60994) (xy 230.51246 -370.629693) (xy 230.44967 -370.641671) (xy 230.385874 -370.645685)
			(xy 230.322078 -370.641671) (xy 230.259288 -370.629693) (xy 230.198495 -370.60994) (xy 230.140656 -370.582723)
			(xy 230.086685 -370.548472) (xy 230.037432 -370.507727) (xy 229.993675 -370.46113) (xy 229.956102 -370.409415)
			(xy 229.925308 -370.3534) (xy 229.901776 -370.293967) (xy 229.885879 -370.232053) (xy 229.877868 -370.168635)
			(xy 229.658937 -370.168635) (xy 229.63353 -370.214851) (xy 229.595957 -370.266566) (xy 229.5522 -370.313163)
			(xy 229.502947 -370.353908) (xy 229.448976 -370.388159) (xy 229.391137 -370.415376) (xy 229.330344 -370.435129)
			(xy 229.267554 -370.447107) (xy 229.203758 -370.451121) (xy 229.139962 -370.447107) (xy 229.077172 -370.435129)
			(xy 229.016379 -370.415376) (xy 228.95854 -370.388159) (xy 228.904569 -370.353908) (xy 228.855316 -370.313163)
			(xy 228.811559 -370.266566) (xy 228.773986 -370.214851) (xy 228.743192 -370.158836) (xy 228.71966 -370.099403)
			(xy 228.703763 -370.037489) (xy 228.695752 -369.974071) (xy 188.160715 -369.974071) (xy 188.209636 -370.014541)
			(xy 188.253393 -370.061138) (xy 188.290966 -370.112853) (xy 188.32176 -370.168868) (xy 188.345292 -370.228301)
			(xy 188.361189 -370.290215) (xy 188.3692 -370.353633) (xy 188.369702 -370.385594) (xy 188.3692 -370.417555)
			(xy 188.361189 -370.480973) (xy 188.345292 -370.542887) (xy 188.32176 -370.60232) (xy 188.290966 -370.658335)
			(xy 188.253393 -370.71005) (xy 188.209636 -370.756647) (xy 188.160383 -370.797392) (xy 188.106412 -370.831643)
			(xy 188.048573 -370.85886) (xy 187.98778 -370.878613) (xy 187.92499 -370.890591) (xy 187.861194 -370.894605)
			(xy 187.797398 -370.890591) (xy 187.734608 -370.878613) (xy 187.673815 -370.85886) (xy 187.615976 -370.831643)
			(xy 187.562005 -370.797392) (xy 187.512752 -370.756647) (xy 187.468995 -370.71005) (xy 187.431422 -370.658335)
			(xy 187.400628 -370.60232) (xy 187.377096 -370.542887) (xy 187.361199 -370.480973) (xy 187.353188 -370.417555)
			(xy 179.279296 -370.417555) (xy 179.279296 -371.425173) (xy 198.79792 -371.425173) (xy 198.79792 -371.361251)
			(xy 198.805931 -371.297833) (xy 198.821828 -371.235919) (xy 198.84536 -371.176486) (xy 198.876154 -371.120471)
			(xy 198.913727 -371.068756) (xy 198.957484 -371.022159) (xy 199.006737 -370.981414) (xy 199.060708 -370.947163)
			(xy 199.118547 -370.919946) (xy 199.17934 -370.900193) (xy 199.24213 -370.888215) (xy 199.305926 -370.884202)
			(xy 199.369722 -370.888215) (xy 199.432512 -370.900193) (xy 199.493305 -370.919946) (xy 199.551144 -370.947163)
			(xy 199.605115 -370.981414) (xy 199.654368 -371.022159) (xy 199.698125 -371.068756) (xy 199.735698 -371.120471)
			(xy 199.766492 -371.176486) (xy 199.790024 -371.235919) (xy 199.805921 -371.297833) (xy 199.813932 -371.361251)
			(xy 199.814434 -371.393212) (xy 199.813932 -371.425173) (xy 199.805921 -371.488591) (xy 199.790024 -371.550505)
			(xy 199.766492 -371.609938) (xy 199.735698 -371.665953) (xy 199.698125 -371.717668) (xy 199.654368 -371.764265)
			(xy 199.605115 -371.80501) (xy 199.551144 -371.839261) (xy 199.493305 -371.866478) (xy 199.432512 -371.886231)
			(xy 199.369722 -371.898209) (xy 199.305926 -371.902223) (xy 199.24213 -371.898209) (xy 199.17934 -371.886231)
			(xy 199.118547 -371.866478) (xy 199.060708 -371.839261) (xy 199.006737 -371.80501) (xy 198.957484 -371.764265)
			(xy 198.913727 -371.717668) (xy 198.876154 -371.665953) (xy 198.84536 -371.609938) (xy 198.821828 -371.550505)
			(xy 198.805931 -371.488591) (xy 198.79792 -371.425173) (xy 179.279296 -371.425173) (xy 179.279296 -372.439438)
			(xy 179.279726 -372.449505) (xy 179.28745 -372.4681) (xy 179.294282 -372.475506) (xy 179.352405 -372.533629)
			(xy 220.78035 -372.533629) (xy 220.78035 -372.469707) (xy 220.788361 -372.406289) (xy 220.804258 -372.344375)
			(xy 220.82779 -372.284942) (xy 220.858584 -372.228927) (xy 220.896157 -372.177212) (xy 220.939914 -372.130615)
			(xy 220.989167 -372.08987) (xy 221.043138 -372.055619) (xy 221.100977 -372.028402) (xy 221.16177 -372.008649)
			(xy 221.22456 -371.996671) (xy 221.288356 -371.992658) (xy 221.352152 -371.996671) (xy 221.414942 -372.008649)
			(xy 221.475735 -372.028402) (xy 221.533574 -372.055619) (xy 221.587545 -372.08987) (xy 221.636798 -372.130615)
			(xy 221.680555 -372.177212) (xy 221.718128 -372.228927) (xy 221.748922 -372.284942) (xy 221.772454 -372.344375)
			(xy 221.788351 -372.406289) (xy 221.796362 -372.469707) (xy 221.796864 -372.501668) (xy 221.796362 -372.533629)
			(xy 221.788351 -372.597047) (xy 221.772454 -372.658961) (xy 221.748922 -372.718394) (xy 221.718128 -372.774409)
			(xy 221.680555 -372.826124) (xy 221.636798 -372.872721) (xy 221.587545 -372.913466) (xy 221.533574 -372.947717)
			(xy 221.475735 -372.974934) (xy 221.414942 -372.994687) (xy 221.352152 -373.006665) (xy 221.288356 -373.010679)
			(xy 221.22456 -373.006665) (xy 221.16177 -372.994687) (xy 221.100977 -372.974934) (xy 221.043138 -372.947717)
			(xy 220.989167 -372.913466) (xy 220.939914 -372.872721) (xy 220.896157 -372.826124) (xy 220.858584 -372.774409)
			(xy 220.82779 -372.718394) (xy 220.804258 -372.658961) (xy 220.788361 -372.597047) (xy 220.78035 -372.533629)
			(xy 179.352405 -372.533629) (xy 179.605686 -372.78691) (xy 179.611782 -372.790466) (xy 179.693848 -372.83793)
			(xy 179.854161 -372.939168) (xy 180.00982 -373.047427) (xy 180.11899 -373.130783) (xy 190.098166 -373.130783)
			(xy 190.098166 -373.066861) (xy 190.106177 -373.003443) (xy 190.122074 -372.941529) (xy 190.145606 -372.882096)
			(xy 190.1764 -372.826081) (xy 190.213973 -372.774366) (xy 190.25773 -372.727769) (xy 190.306983 -372.687024)
			(xy 190.360954 -372.652773) (xy 190.418793 -372.625556) (xy 190.479586 -372.605803) (xy 190.542376 -372.593825)
			(xy 190.606172 -372.589812) (xy 190.669968 -372.593825) (xy 190.732758 -372.605803) (xy 190.793551 -372.625556)
			(xy 190.85139 -372.652773) (xy 190.905361 -372.687024) (xy 190.954614 -372.727769) (xy 190.998371 -372.774366)
			(xy 191.035944 -372.826081) (xy 191.066738 -372.882096) (xy 191.09027 -372.941529) (xy 191.106167 -373.003443)
			(xy 191.114178 -373.066861) (xy 191.11468 -373.098822) (xy 191.114178 -373.130783) (xy 191.106167 -373.194201)
			(xy 191.09027 -373.256115) (xy 191.066738 -373.315548) (xy 191.035944 -373.371563) (xy 190.998371 -373.423278)
			(xy 190.954614 -373.469875) (xy 190.905361 -373.51062) (xy 190.85139 -373.544871) (xy 190.793551 -373.572088)
			(xy 190.732758 -373.591841) (xy 190.669968 -373.603819) (xy 190.606172 -373.607833) (xy 190.542376 -373.603819)
			(xy 190.479586 -373.591841) (xy 190.418793 -373.572088) (xy 190.360954 -373.544871) (xy 190.306983 -373.51062)
			(xy 190.25773 -373.469875) (xy 190.213973 -373.423278) (xy 190.1764 -373.371563) (xy 190.145606 -373.315548)
			(xy 190.122074 -373.256115) (xy 190.106177 -373.194201) (xy 190.098166 -373.130783) (xy 180.11899 -373.130783)
			(xy 180.160518 -373.162491) (xy 180.305957 -373.284134) (xy 180.44585 -373.412116) (xy 180.579921 -373.546185)
			(xy 180.707906 -373.686076) (xy 180.829553 -373.831512) (xy 180.94462 -373.982207) (xy 181.052882 -374.137864)
			(xy 181.154124 -374.298175) (xy 181.201568 -374.380252) (xy 181.205124 -374.386348) (xy 181.344824 -374.526048)
			(xy 181.351671 -374.533445) (xy 181.3594 -374.552044) (xy 181.35981 -374.562116) (xy 181.35981 -374.685052)
			(xy 181.364636 -374.695466) (xy 181.403419 -374.779966) (xy 181.474485 -374.951798) (xy 181.537999 -375.126561)
			(xy 181.593842 -375.303926) (xy 181.641906 -375.483554) (xy 181.682102 -375.665105) (xy 181.714353 -375.848234)
			(xy 181.738596 -376.032594) (xy 181.754788 -376.217836) (xy 181.762896 -376.403606) (xy 181.763416 -376.49658)
			(xy 181.76313 -376.548607) (xy 190.237866 -376.548607) (xy 190.237866 -376.484685) (xy 190.245877 -376.421267)
			(xy 190.261774 -376.359353) (xy 190.285306 -376.29992) (xy 190.3161 -376.243905) (xy 190.353673 -376.19219)
			(xy 190.39743 -376.145593) (xy 190.446683 -376.104848) (xy 190.500654 -376.070597) (xy 190.558493 -376.04338)
			(xy 190.619286 -376.023627) (xy 190.682076 -376.011649) (xy 190.745872 -376.007636) (xy 190.809668 -376.011649)
			(xy 190.872458 -376.023627) (xy 190.933251 -376.04338) (xy 190.99109 -376.070597) (xy 191.045061 -376.104848)
			(xy 191.094314 -376.145593) (xy 191.138071 -376.19219) (xy 191.175644 -376.243905) (xy 191.206438 -376.29992)
			(xy 191.22997 -376.359353) (xy 191.245867 -376.421267) (xy 191.24829 -376.440446) (xy 192.195448 -376.440446)
			(xy 192.199519 -376.384824) (xy 192.211645 -376.330387) (xy 192.231568 -376.278296) (xy 192.258864 -376.229661)
			(xy 192.29295 -376.185518) (xy 192.333099 -376.146809) (xy 192.378457 -376.114358) (xy 192.428057 -376.088857)
			(xy 192.480841 -376.07085) (xy 192.535684 -376.06072) (xy 192.591418 -376.058683) (xy 192.646855 -376.064783)
			(xy 192.700812 -376.078889) (xy 192.752141 -376.100701) (xy 192.799747 -376.129755) (xy 192.842615 -376.16543)
			(xy 192.879832 -376.206967) (xy 192.910605 -376.25348) (xy 192.934277 -376.303977) (xy 192.950345 -376.357384)
			(xy 192.958465 -376.41256) (xy 192.958974 -376.440446) (xy 198.820276 -376.440446) (xy 198.824347 -376.384824)
			(xy 198.836473 -376.330387) (xy 198.856396 -376.278296) (xy 198.883692 -376.229661) (xy 198.917778 -376.185518)
			(xy 198.957927 -376.146809) (xy 199.003285 -376.114358) (xy 199.052885 -376.088857) (xy 199.105669 -376.07085)
			(xy 199.160512 -376.06072) (xy 199.216246 -376.058683) (xy 199.271683 -376.064783) (xy 199.32564 -376.078889)
			(xy 199.376969 -376.100701) (xy 199.424575 -376.129755) (xy 199.467443 -376.16543) (xy 199.50466 -376.206967)
			(xy 199.535433 -376.25348) (xy 199.559105 -376.303977) (xy 199.575173 -376.357384) (xy 199.583293 -376.41256)
			(xy 199.583802 -376.440446) (xy 199.583293 -376.468332) (xy 199.575173 -376.523508) (xy 199.559105 -376.576915)
			(xy 199.535433 -376.627412) (xy 199.50466 -376.673925) (xy 199.467443 -376.715462) (xy 199.424575 -376.751137)
			(xy 199.376969 -376.780191) (xy 199.32564 -376.802003) (xy 199.271683 -376.816109) (xy 199.216246 -376.822209)
			(xy 199.160512 -376.820172) (xy 199.105669 -376.810042) (xy 199.052885 -376.792035) (xy 199.003285 -376.766534)
			(xy 198.957927 -376.734083) (xy 198.917778 -376.695374) (xy 198.883692 -376.651231) (xy 198.856396 -376.602596)
			(xy 198.836473 -376.550505) (xy 198.824347 -376.496068) (xy 198.820276 -376.440446) (xy 192.958974 -376.440446)
			(xy 192.958465 -376.468332) (xy 192.950345 -376.523508) (xy 192.934277 -376.576915) (xy 192.910605 -376.627412)
			(xy 192.879832 -376.673925) (xy 192.842615 -376.715462) (xy 192.799747 -376.751137) (xy 192.752141 -376.780191)
			(xy 192.700812 -376.802003) (xy 192.646855 -376.816109) (xy 192.591418 -376.822209) (xy 192.535684 -376.820172)
			(xy 192.480841 -376.810042) (xy 192.428057 -376.792035) (xy 192.378457 -376.766534) (xy 192.333099 -376.734083)
			(xy 192.29295 -376.695374) (xy 192.258864 -376.651231) (xy 192.231568 -376.602596) (xy 192.211645 -376.550505)
			(xy 192.199519 -376.496068) (xy 192.195448 -376.440446) (xy 191.24829 -376.440446) (xy 191.253878 -376.484685)
			(xy 191.25438 -376.516646) (xy 191.253878 -376.548607) (xy 191.245867 -376.612025) (xy 191.22997 -376.673939)
			(xy 191.206438 -376.733372) (xy 191.175644 -376.789387) (xy 191.138071 -376.841102) (xy 191.094314 -376.887699)
			(xy 191.045061 -376.928444) (xy 190.99109 -376.962695) (xy 190.933251 -376.989912) (xy 190.872458 -377.009665)
			(xy 190.809668 -377.021643) (xy 190.745872 -377.025657) (xy 190.682076 -377.021643) (xy 190.619286 -377.009665)
			(xy 190.558493 -376.989912) (xy 190.500654 -376.962695) (xy 190.446683 -376.928444) (xy 190.39743 -376.887699)
			(xy 190.353673 -376.841102) (xy 190.3161 -376.789387) (xy 190.285306 -376.733372) (xy 190.261774 -376.673939)
			(xy 190.245877 -376.612025) (xy 190.237866 -376.548607) (xy 181.76313 -376.548607) (xy 181.762905 -376.589554)
			(xy 181.754794 -376.775324) (xy 181.7386 -376.960565) (xy 181.714354 -377.144925) (xy 181.682101 -377.328054)
			(xy 181.641903 -377.509604) (xy 181.596738 -377.678385) (xy 193.900548 -377.678385) (xy 193.900548 -377.593663)
			(xy 193.908601 -377.509326) (xy 193.924635 -377.426136) (xy 193.948503 -377.344846) (xy 193.979991 -377.266194)
			(xy 194.018813 -377.190891) (xy 194.064616 -377.119619) (xy 194.116987 -377.053023) (xy 194.175452 -376.991708)
			(xy 194.23948 -376.936227) (xy 194.308492 -376.887084) (xy 194.381862 -376.844724) (xy 194.458927 -376.809529)
			(xy 194.538989 -376.78182) (xy 194.621322 -376.761846) (xy 194.705181 -376.749789) (xy 194.789806 -376.745758)
			(xy 194.874431 -376.749789) (xy 194.95829 -376.761846) (xy 195.040623 -376.78182) (xy 195.120685 -376.809529)
			(xy 195.19775 -376.844724) (xy 195.27112 -376.887084) (xy 195.340132 -376.936227) (xy 195.40416 -376.991708)
			(xy 195.462625 -377.053023) (xy 195.514996 -377.119619) (xy 195.560799 -377.190891) (xy 195.599621 -377.266194)
			(xy 195.631109 -377.344846) (xy 195.654977 -377.426136) (xy 195.671011 -377.509326) (xy 195.679064 -377.593663)
			(xy 195.679568 -377.636024) (xy 195.679064 -377.678385) (xy 195.671011 -377.762722) (xy 195.654977 -377.845912)
			(xy 195.631109 -377.927202) (xy 195.599621 -378.005854) (xy 195.560799 -378.081157) (xy 195.514996 -378.152429)
			(xy 195.508622 -378.160534) (xy 199.950322 -378.160534) (xy 199.954393 -378.104912) (xy 199.966519 -378.050475)
			(xy 199.986442 -377.998384) (xy 200.013738 -377.949749) (xy 200.047824 -377.905606) (xy 200.087973 -377.866897)
			(xy 200.133331 -377.834446) (xy 200.182931 -377.808945) (xy 200.235715 -377.790938) (xy 200.290558 -377.780808)
			(xy 200.346292 -377.778771) (xy 200.401729 -377.784871) (xy 200.455686 -377.798977) (xy 200.507015 -377.820789)
			(xy 200.552966 -377.848833) (xy 201.918564 -377.848833) (xy 201.918564 -377.784911) (xy 201.926575 -377.721493)
			(xy 201.942472 -377.659579) (xy 201.966004 -377.600146) (xy 201.996798 -377.544131) (xy 202.034371 -377.492416)
			(xy 202.078128 -377.445819) (xy 202.127381 -377.405074) (xy 202.181352 -377.370823) (xy 202.239191 -377.343606)
			(xy 202.299984 -377.323853) (xy 202.362774 -377.311875) (xy 202.42657 -377.307862) (xy 202.490366 -377.311875)
			(xy 202.553156 -377.323853) (xy 202.613949 -377.343606) (xy 202.671788 -377.370823) (xy 202.725759 -377.405074)
			(xy 202.775012 -377.445819) (xy 202.818769 -377.492416) (xy 202.856342 -377.544131) (xy 202.887136 -377.600146)
			(xy 202.910668 -377.659579) (xy 202.926565 -377.721493) (xy 202.934576 -377.784911) (xy 202.935078 -377.816872)
			(xy 202.934576 -377.848833) (xy 202.926565 -377.912251) (xy 202.910668 -377.974165) (xy 202.887136 -378.033598)
			(xy 202.856342 -378.089613) (xy 202.818769 -378.141328) (xy 202.775012 -378.187925) (xy 202.725759 -378.22867)
			(xy 202.671788 -378.262921) (xy 202.613949 -378.290138) (xy 202.553156 -378.309891) (xy 202.490366 -378.321869)
			(xy 202.42657 -378.325883) (xy 202.362774 -378.321869) (xy 202.299984 -378.309891) (xy 202.239191 -378.290138)
			(xy 202.181352 -378.262921) (xy 202.127381 -378.22867) (xy 202.078128 -378.187925) (xy 202.034371 -378.141328)
			(xy 201.996798 -378.089613) (xy 201.966004 -378.033598) (xy 201.942472 -377.974165) (xy 201.926575 -377.912251)
			(xy 201.918564 -377.848833) (xy 200.552966 -377.848833) (xy 200.554621 -377.849843) (xy 200.597489 -377.885518)
			(xy 200.634706 -377.927055) (xy 200.665479 -377.973568) (xy 200.689151 -378.024065) (xy 200.705219 -378.077472)
			(xy 200.713339 -378.132648) (xy 200.713848 -378.160534) (xy 200.713339 -378.18842) (xy 200.705219 -378.243596)
			(xy 200.689151 -378.297003) (xy 200.665479 -378.3475) (xy 200.634706 -378.394013) (xy 200.597489 -378.43555)
			(xy 200.554621 -378.471225) (xy 200.507015 -378.500279) (xy 200.455686 -378.522091) (xy 200.401729 -378.536197)
			(xy 200.346292 -378.542297) (xy 200.290558 -378.54026) (xy 200.235715 -378.53013) (xy 200.182931 -378.512123)
			(xy 200.133331 -378.486622) (xy 200.087973 -378.454171) (xy 200.047824 -378.415462) (xy 200.013738 -378.371319)
			(xy 199.986442 -378.322684) (xy 199.966519 -378.270593) (xy 199.954393 -378.216156) (xy 199.950322 -378.160534)
			(xy 195.508622 -378.160534) (xy 195.462625 -378.219025) (xy 195.40416 -378.28034) (xy 195.340132 -378.335821)
			(xy 195.27112 -378.384964) (xy 195.19775 -378.427324) (xy 195.120685 -378.462519) (xy 195.040623 -378.490228)
			(xy 194.95829 -378.510202) (xy 194.874431 -378.522259) (xy 194.789806 -378.526291) (xy 194.705181 -378.522259)
			(xy 194.621322 -378.510202) (xy 194.538989 -378.490228) (xy 194.458927 -378.462519) (xy 194.381862 -378.427324)
			(xy 194.308492 -378.384964) (xy 194.23948 -378.335821) (xy 194.175452 -378.28034) (xy 194.116987 -378.219025)
			(xy 194.064616 -378.152429) (xy 194.018813 -378.081157) (xy 193.979991 -378.005854) (xy 193.948503 -377.927202)
			(xy 193.924635 -377.845912) (xy 193.908601 -377.762722) (xy 193.900548 -377.678385) (xy 181.596738 -377.678385)
			(xy 181.593836 -377.689231) (xy 181.537991 -377.866595) (xy 181.474475 -378.041358) (xy 181.403407 -378.213188)
			(xy 181.364636 -378.297694) (xy 181.35981 -378.308108) (xy 181.35981 -378.745496) (xy 181.359388 -378.755567)
			(xy 181.351676 -378.774173) (xy 181.344824 -378.781564) (xy 179.438046 -380.688342) (xy 179.430647 -380.695186)
			(xy 179.412049 -380.70291) (xy 179.401978 -380.703328) (xy 178.215036 -380.703328) (xy 178.210718 -380.70409)
			(xy 178.122073 -380.71866) (xy 177.943831 -380.741247) (xy 177.764797 -380.756314) (xy 177.585288 -380.763834)
			(xy 177.495454 -380.764288) (xy 177.40562 -380.763839) (xy 177.226111 -380.756321) (xy 177.047076 -380.741253)
			(xy 176.868835 -380.718663) (xy 176.78019 -380.70409) (xy 176.775872 -380.703328) (xy 174.482252 -380.703328)
			(xy 174.472186 -380.703761) (xy 174.453597 -380.71149) (xy 174.446184 -380.718314) (xy 174.382938 -380.78156)
			(xy 174.375538 -380.788401) (xy 174.356939 -380.796119) (xy 174.34687 -380.796546) (xy 171.865544 -380.796546)
			(xy 171.855758 -380.796994) (xy 171.837603 -380.80431) (xy 171.830238 -380.81077) (xy 171.808774 -380.830612)
			(xy 171.760938 -380.864201) (xy 171.708544 -380.890109) (xy 171.652814 -380.907731) (xy 171.595049 -380.916656)
			(xy 171.565824 -380.917196) (xy 171.541751 -380.916848) (xy 171.493985 -380.910821) (xy 171.447359 -380.898824)
			(xy 171.424854 -380.890272) (xy 171.412408 -380.885192) (xy 171.3865 -380.888494) (xy 171.295822 -380.955296)
			(xy 171.2849 -380.978918) (xy 171.285916 -380.992126) (xy 171.286932 -381.020828) (xy 171.286446 -381.048079)
			(xy 171.27869 -381.102027) (xy 171.263335 -381.154322) (xy 171.240693 -381.203899) (xy 171.211227 -381.249749)
			(xy 171.196099 -381.267208) (xy 188.971428 -381.267208) (xy 188.97193 -381.235247) (xy 188.979941 -381.171829)
			(xy 188.995838 -381.109915) (xy 189.01937 -381.050482) (xy 189.050164 -380.994467) (xy 189.087737 -380.942752)
			(xy 189.131494 -380.896155) (xy 189.180747 -380.85541) (xy 189.234718 -380.821159) (xy 189.292557 -380.793942)
			(xy 189.35335 -380.774189) (xy 189.41614 -380.762211) (xy 189.479936 -380.758198) (xy 189.543732 -380.762211)
			(xy 189.606522 -380.774189) (xy 189.667315 -380.793942) (xy 189.725154 -380.821159) (xy 189.779125 -380.85541)
			(xy 189.828378 -380.896155) (xy 189.872135 -380.942752) (xy 189.909708 -380.994467) (xy 189.940502 -381.050482)
			(xy 189.964034 -381.109915) (xy 189.979931 -381.171829) (xy 189.987942 -381.235247) (xy 189.988444 -381.267208)
			(xy 189.988 -381.296633) (xy 189.981212 -381.35509) (xy 189.967728 -381.412375) (xy 189.947728 -381.467722)
			(xy 189.921478 -381.520393) (xy 189.889329 -381.569686) (xy 189.870842 -381.592582) (xy 189.865192 -381.600046)
			(xy 189.859202 -381.617765) (xy 189.859158 -381.627126) (xy 189.860428 -381.65786) (xy 189.861238 -381.6672)
			(xy 189.868659 -381.684398) (xy 189.874906 -381.691388) (xy 189.897613 -381.715229) (xy 189.937316 -381.76775)
			(xy 189.969906 -381.824958) (xy 189.994836 -381.885895) (xy 190.01169 -381.949541) (xy 190.020185 -382.01483)
			(xy 190.020702 -382.04775) (xy 190.020207 -382.08012) (xy 190.011988 -382.144337) (xy 189.99569 -382.206992)
			(xy 189.971576 -382.267074) (xy 189.940036 -382.323611) (xy 189.901578 -382.375691) (xy 189.856825 -382.422472)
			(xy 189.83198 -382.443228) (xy 189.824779 -382.449573) (xy 189.815383 -382.466292) (xy 189.813692 -382.47574)
			(xy 189.809374 -382.506728) (xy 189.80848 -382.516156) (xy 189.812922 -382.534554) (xy 189.81801 -382.542542)
			(xy 189.834106 -382.56668) (xy 189.859647 -382.618768) (xy 189.877009 -382.674123) (xy 189.885793 -382.731467)
			(xy 189.886336 -382.760474) (xy 189.88585 -382.787725) (xy 189.878094 -382.841673) (xy 189.862739 -382.893968)
			(xy 189.840097 -382.943545) (xy 189.810631 -382.989395) (xy 189.77494 -383.030586) (xy 189.733749 -383.066277)
			(xy 189.687899 -383.095743) (xy 189.638322 -383.118385) (xy 189.586027 -383.13374) (xy 189.532079 -383.141496)
			(xy 189.477577 -383.141496) (xy 189.423629 -383.13374) (xy 189.371334 -383.118385) (xy 189.321757 -383.095743)
			(xy 189.275907 -383.066277) (xy 189.234716 -383.030586) (xy 189.199025 -382.989395) (xy 189.169559 -382.943545)
			(xy 189.146917 -382.893968) (xy 189.131562 -382.841673) (xy 189.123806 -382.787725) (xy 189.12332 -382.760474)
			(xy 189.123886 -382.730487) (xy 189.133272 -382.671252) (xy 189.151809 -382.614214) (xy 189.179041 -382.560779)
			(xy 189.196218 -382.536192) (xy 189.201488 -382.528266) (xy 189.206318 -382.50987) (xy 189.205616 -382.500378)
			(xy 189.20206 -382.46939) (xy 189.200523 -382.459868) (xy 189.191379 -382.4429) (xy 189.18428 -382.43637)
			(xy 189.16041 -382.415645) (xy 189.117518 -382.369205) (xy 189.080715 -382.317805) (xy 189.050568 -382.262239)
			(xy 189.027543 -382.203364) (xy 189.011994 -382.142089) (xy 189.004163 -382.079359) (xy 189.003686 -382.04775)
			(xy 189.004099 -382.018324) (xy 189.010892 -381.959865) (xy 189.024382 -381.90258) (xy 189.044388 -381.847233)
			(xy 189.070643 -381.794562) (xy 189.102798 -381.745271) (xy 189.121288 -381.722376) (xy 189.126916 -381.714898)
			(xy 189.132919 -381.69719) (xy 189.132972 -381.687832) (xy 189.131702 -381.657098) (xy 189.130904 -381.647756)
			(xy 189.123474 -381.630559) (xy 189.117224 -381.62357) (xy 189.094533 -381.599715) (xy 189.05483 -381.547196)
			(xy 189.02224 -381.48999) (xy 188.997307 -381.429056) (xy 188.980449 -381.365413) (xy 188.971949 -381.300127)
			(xy 188.971428 -381.267208) (xy 171.196099 -381.267208) (xy 171.175536 -381.29094) (xy 171.134345 -381.326631)
			(xy 171.088495 -381.356097) (xy 171.038918 -381.378739) (xy 170.986623 -381.394094) (xy 170.932675 -381.40185)
			(xy 170.878173 -381.40185) (xy 170.824225 -381.394094) (xy 170.77193 -381.378739) (xy 170.722353 -381.356097)
			(xy 170.676503 -381.326631) (xy 170.635312 -381.29094) (xy 170.599621 -381.249749) (xy 170.570155 -381.203899)
			(xy 170.547513 -381.154322) (xy 170.532158 -381.102027) (xy 170.524402 -381.048079) (xy 170.523916 -381.020828)
			(xy 170.524932 -380.992126) (xy 170.525948 -380.978918) (xy 170.515026 -380.955296) (xy 170.424348 -380.888494)
			(xy 170.39844 -380.885192) (xy 170.385994 -380.890272) (xy 170.363484 -380.898807) (xy 170.316858 -380.910794)
			(xy 170.269095 -380.91683) (xy 170.245024 -380.917196) (xy 170.21777 -380.916734) (xy 170.163817 -380.90898)
			(xy 170.111517 -380.893626) (xy 170.061935 -380.870985) (xy 170.01608 -380.841517) (xy 169.974885 -380.805823)
			(xy 169.93919 -380.76463) (xy 169.909721 -380.718776) (xy 169.887078 -380.669194) (xy 169.871723 -380.616894)
			(xy 169.863967 -380.562942) (xy 169.863516 -380.535688) (xy 169.863958 -380.508517) (xy 169.871606 -380.454717)
			(xy 169.878756 -380.4285) (xy 169.88282 -380.415038) (xy 169.875962 -380.388368) (xy 169.565066 -380.077472)
			(xy 169.558217 -380.070075) (xy 169.550482 -380.051476) (xy 169.55008 -380.041404) (xy 169.55008 -377.048522)
			(xy 169.549642 -377.038459) (xy 169.541906 -377.019877) (xy 169.535094 -377.012454) (xy 167.934386 -375.411746)
			(xy 167.926989 -375.404897) (xy 167.90839 -375.39716) (xy 167.898318 -375.39676) (xy 144.892522 -375.39676)
			(xy 144.882459 -375.397199) (xy 144.863881 -375.40494) (xy 144.856454 -375.411746) (xy 142.841726 -377.426474)
			(xy 142.834325 -377.433312) (xy 142.815726 -377.441023) (xy 142.805658 -377.44146) (xy 142.7988 -377.44146)
			(xy 142.080742 -378.159518) (xy 142.073894 -378.166915) (xy 142.066159 -378.185514) (xy 142.065756 -378.195586)
			(xy 142.065756 -380.83744) (xy 142.584422 -380.83744) (xy 142.588493 -380.781818) (xy 142.600619 -380.727381)
			(xy 142.620542 -380.67529) (xy 142.647838 -380.626655) (xy 142.681924 -380.582512) (xy 142.722073 -380.543803)
			(xy 142.767431 -380.511352) (xy 142.817031 -380.485851) (xy 142.869815 -380.467844) (xy 142.924658 -380.457714)
			(xy 142.980392 -380.455677) (xy 143.035829 -380.461777) (xy 143.089786 -380.475883) (xy 143.141115 -380.497695)
			(xy 143.188721 -380.526749) (xy 143.231589 -380.562424) (xy 143.268806 -380.603961) (xy 143.299579 -380.650474)
			(xy 143.323251 -380.700971) (xy 143.339319 -380.754378) (xy 143.347439 -380.809554) (xy 143.347948 -380.83744)
			(xy 143.347439 -380.865326) (xy 143.339319 -380.920502) (xy 143.323251 -380.973909) (xy 143.299579 -381.024406)
			(xy 143.268806 -381.070919) (xy 143.231589 -381.112456) (xy 143.188721 -381.148131) (xy 143.141115 -381.177185)
			(xy 143.089786 -381.198997) (xy 143.035829 -381.213103) (xy 142.980392 -381.219203) (xy 142.924658 -381.217166)
			(xy 142.869815 -381.207036) (xy 142.817031 -381.189029) (xy 142.767431 -381.163528) (xy 142.722073 -381.131077)
			(xy 142.681924 -381.092368) (xy 142.647838 -381.048225) (xy 142.620542 -380.99959) (xy 142.600619 -380.947499)
			(xy 142.588493 -380.893062) (xy 142.584422 -380.83744) (xy 142.065756 -380.83744) (xy 142.065756 -381.171196)
			(xy 142.06982 -381.180848) (xy 142.079463 -381.204553) (xy 142.09303 -381.253897) (xy 142.099875 -381.304612)
			(xy 142.099875 -381.355788) (xy 142.09303 -381.406503) (xy 142.079463 -381.455847) (xy 142.06982 -381.479552)
			(xy 142.065756 -381.489204) (xy 142.065756 -382.237488) (xy 168.720516 -382.237488) (xy 168.720977 -382.211274)
			(xy 168.728133 -382.159337) (xy 168.742337 -382.10887) (xy 168.76332 -382.060824) (xy 168.790688 -382.016106)
			(xy 168.823923 -381.975559) (xy 168.862399 -381.939946) (xy 168.905391 -381.909941) (xy 168.928542 -381.897636)
			(xy 168.941375 -381.890569) (xy 168.962611 -381.870402) (xy 168.977251 -381.845038) (xy 168.984089 -381.816562)
			(xy 168.982565 -381.787316) (xy 168.972803 -381.759705) (xy 168.955605 -381.736) (xy 168.94429 -381.726694)
			(xy 168.921524 -381.708518) (xy 168.881256 -381.666423) (xy 168.847857 -381.618695) (xy 168.822104 -381.566443)
			(xy 168.804597 -381.510883) (xy 168.795742 -381.453307) (xy 168.795192 -381.42418) (xy 168.795678 -381.396929)
			(xy 168.803434 -381.342981) (xy 168.818789 -381.290686) (xy 168.841431 -381.241109) (xy 168.870897 -381.195259)
			(xy 168.906588 -381.154068) (xy 168.947779 -381.118377) (xy 168.993629 -381.088911) (xy 169.043206 -381.066269)
			(xy 169.095501 -381.050914) (xy 169.149449 -381.043158) (xy 169.203951 -381.043158) (xy 169.257899 -381.050914)
			(xy 169.310194 -381.066269) (xy 169.359771 -381.088911) (xy 169.405621 -381.118377) (xy 169.446812 -381.154068)
			(xy 169.482503 -381.195259) (xy 169.511969 -381.241109) (xy 169.534611 -381.290686) (xy 169.549966 -381.342981)
			(xy 169.557722 -381.396929) (xy 169.558208 -381.42418) (xy 169.55779 -381.450395) (xy 169.550625 -381.502334)
			(xy 169.536414 -381.552801) (xy 169.515423 -381.600846) (xy 169.48805 -381.645564) (xy 169.45481 -381.686111)
			(xy 169.41633 -381.721722) (xy 169.373334 -381.751728) (xy 169.350182 -381.764032) (xy 169.337377 -381.771139)
			(xy 169.316157 -381.791304) (xy 169.301528 -381.816659) (xy 169.294691 -381.845123) (xy 169.296208 -381.874356)
			(xy 169.305955 -381.901959) (xy 169.32313 -381.925663) (xy 169.334434 -381.934974) (xy 169.35719 -381.953162)
			(xy 169.397457 -381.995255) (xy 169.430857 -382.042981) (xy 169.456611 -382.09523) (xy 169.474121 -382.150788)
			(xy 169.48298 -382.208362) (xy 169.483532 -382.237488) (xy 169.483046 -382.264739) (xy 169.47529 -382.318687)
			(xy 169.459935 -382.370982) (xy 169.437293 -382.420559) (xy 169.407827 -382.466409) (xy 169.372136 -382.5076)
			(xy 169.330945 -382.543291) (xy 169.285095 -382.572757) (xy 169.235518 -382.595399) (xy 169.183223 -382.610754)
			(xy 169.129275 -382.61851) (xy 169.074773 -382.61851) (xy 169.020825 -382.610754) (xy 168.96853 -382.595399)
			(xy 168.918953 -382.572757) (xy 168.873103 -382.543291) (xy 168.831912 -382.5076) (xy 168.796221 -382.466409)
			(xy 168.766755 -382.420559) (xy 168.744113 -382.370982) (xy 168.728758 -382.318687) (xy 168.721002 -382.264739)
			(xy 168.720516 -382.237488) (xy 142.065756 -382.237488) (xy 142.065756 -382.385316) (xy 142.06982 -382.394968)
			(xy 142.079461 -382.418673) (xy 142.093026 -382.468017) (xy 142.099869 -382.518731) (xy 142.099866 -382.569906)
			(xy 142.093019 -382.62062) (xy 142.079449 -382.669962) (xy 142.06982 -382.693672) (xy 142.065756 -382.703324)
			(xy 142.065756 -382.796034) (xy 142.065325 -382.8061) (xy 142.057597 -382.824692) (xy 142.05077 -382.832102)
			(xy 141.949581 -382.933291) (xy 144.656761 -382.933291) (xy 144.656761 -382.881309) (xy 144.664893 -382.829967)
			(xy 144.680957 -382.78053) (xy 144.704556 -382.734214) (xy 144.735111 -382.69216) (xy 144.771868 -382.655404)
			(xy 144.813923 -382.624851) (xy 144.860239 -382.601253) (xy 144.909677 -382.585191) (xy 144.961019 -382.57706)
			(xy 144.98701 -382.576578) (xy 145.010208 -382.576961) (xy 145.056148 -382.583453) (xy 145.100733 -382.596294)
			(xy 145.143088 -382.615233) (xy 145.182384 -382.639899) (xy 145.20037 -382.654556) (xy 145.207482 -382.660652)
			(xy 145.225008 -382.666748) (xy 145.310606 -382.66497) (xy 145.327878 -382.657858) (xy 145.334736 -382.651508)
			(xy 145.353153 -382.63516) (xy 145.393934 -382.607556) (xy 145.438357 -382.586303) (xy 145.48544 -382.571872)
			(xy 145.534142 -382.56458) (xy 145.558764 -382.564132) (xy 145.583601 -382.564579) (xy 145.632718 -382.571998)
			(xy 145.68017 -382.586689) (xy 145.724886 -382.608322) (xy 145.765858 -382.636407) (xy 145.784316 -382.653032)
			(xy 145.791392 -382.659057) (xy 145.808574 -382.6661) (xy 145.817844 -382.666748) (xy 145.849086 -382.66751)
			(xy 145.858341 -382.667354) (xy 145.875794 -382.661229) (xy 145.883122 -382.655572) (xy 145.905655 -382.637365)
			(xy 145.955796 -382.608358) (xy 146.010219 -382.588516) (xy 146.067264 -382.578443) (xy 146.096228 -382.577848)
			(xy 146.12221 -382.578448) (xy 146.173534 -382.586581) (xy 146.222955 -382.602642) (xy 146.269254 -382.626236)
			(xy 146.311293 -382.656783) (xy 146.348036 -382.693529) (xy 146.378578 -382.73557) (xy 146.402168 -382.781871)
			(xy 146.418226 -382.831293) (xy 146.425768 -382.878917) (xy 147.114008 -382.878917) (xy 147.114008 -382.826943)
			(xy 147.122138 -382.775608) (xy 147.138199 -382.726178) (xy 147.161795 -382.679868) (xy 147.192345 -382.63782)
			(xy 147.229096 -382.601069) (xy 147.271144 -382.570519) (xy 147.317454 -382.546923) (xy 147.366884 -382.530862)
			(xy 147.418219 -382.522732) (xy 147.470193 -382.522732) (xy 147.521528 -382.530862) (xy 147.570958 -382.546923)
			(xy 147.617268 -382.570519) (xy 147.659316 -382.601069) (xy 147.696067 -382.63782) (xy 147.726617 -382.679868)
			(xy 147.750213 -382.726178) (xy 147.766274 -382.775608) (xy 147.774404 -382.826943) (xy 147.774914 -382.85293)
			(xy 147.774404 -382.878917) (xy 148.314158 -382.878917) (xy 148.314158 -382.826943) (xy 148.322288 -382.775608)
			(xy 148.338349 -382.726178) (xy 148.361945 -382.679868) (xy 148.392495 -382.63782) (xy 148.429246 -382.601069)
			(xy 148.471294 -382.570519) (xy 148.517604 -382.546923) (xy 148.567034 -382.530862) (xy 148.618369 -382.522732)
			(xy 148.670343 -382.522732) (xy 148.721678 -382.530862) (xy 148.771108 -382.546923) (xy 148.817418 -382.570519)
			(xy 148.859466 -382.601069) (xy 148.896217 -382.63782) (xy 148.926767 -382.679868) (xy 148.950363 -382.726178)
			(xy 148.966424 -382.775608) (xy 148.974554 -382.826943) (xy 148.975064 -382.85293) (xy 148.974554 -382.878917)
			(xy 149.514054 -382.878917) (xy 149.514054 -382.826943) (xy 149.522184 -382.775608) (xy 149.538245 -382.726178)
			(xy 149.561841 -382.679868) (xy 149.592391 -382.63782) (xy 149.629142 -382.601069) (xy 149.67119 -382.570519)
			(xy 149.7175 -382.546923) (xy 149.76693 -382.530862) (xy 149.818265 -382.522732) (xy 149.870239 -382.522732)
			(xy 149.921574 -382.530862) (xy 149.971004 -382.546923) (xy 150.017314 -382.570519) (xy 150.059362 -382.601069)
			(xy 150.096113 -382.63782) (xy 150.126663 -382.679868) (xy 150.150259 -382.726178) (xy 150.16632 -382.775608)
			(xy 150.17445 -382.826943) (xy 150.17496 -382.85293) (xy 150.17445 -382.878917) (xy 150.71395 -382.878917)
			(xy 150.71395 -382.826943) (xy 150.72208 -382.775608) (xy 150.738141 -382.726178) (xy 150.761737 -382.679868)
			(xy 150.792287 -382.63782) (xy 150.829038 -382.601069) (xy 150.871086 -382.570519) (xy 150.917396 -382.546923)
			(xy 150.966826 -382.530862) (xy 151.018161 -382.522732) (xy 151.070135 -382.522732) (xy 151.12147 -382.530862)
			(xy 151.1709 -382.546923) (xy 151.21721 -382.570519) (xy 151.259258 -382.601069) (xy 151.296009 -382.63782)
			(xy 151.326559 -382.679868) (xy 151.350155 -382.726178) (xy 151.366216 -382.775608) (xy 151.374346 -382.826943)
			(xy 151.374856 -382.85293) (xy 151.374346 -382.878917) (xy 151.9141 -382.878917) (xy 151.9141 -382.826943)
			(xy 151.92223 -382.775608) (xy 151.938291 -382.726178) (xy 151.961887 -382.679868) (xy 151.992437 -382.63782)
			(xy 152.029188 -382.601069) (xy 152.071236 -382.570519) (xy 152.117546 -382.546923) (xy 152.166976 -382.530862)
			(xy 152.218311 -382.522732) (xy 152.270285 -382.522732) (xy 152.32162 -382.530862) (xy 152.37105 -382.546923)
			(xy 152.41736 -382.570519) (xy 152.459408 -382.601069) (xy 152.496159 -382.63782) (xy 152.526709 -382.679868)
			(xy 152.550305 -382.726178) (xy 152.566366 -382.775608) (xy 152.574496 -382.826943) (xy 152.575006 -382.85293)
			(xy 152.574496 -382.878917) (xy 153.113996 -382.878917) (xy 153.113996 -382.826943) (xy 153.122126 -382.775608)
			(xy 153.138187 -382.726178) (xy 153.161783 -382.679868) (xy 153.192333 -382.63782) (xy 153.229084 -382.601069)
			(xy 153.271132 -382.570519) (xy 153.317442 -382.546923) (xy 153.366872 -382.530862) (xy 153.418207 -382.522732)
			(xy 153.470181 -382.522732) (xy 153.521516 -382.530862) (xy 153.570946 -382.546923) (xy 153.617256 -382.570519)
			(xy 153.659304 -382.601069) (xy 153.696055 -382.63782) (xy 153.726605 -382.679868) (xy 153.750201 -382.726178)
			(xy 153.766262 -382.775608) (xy 153.774392 -382.826943) (xy 153.774902 -382.85293) (xy 153.774392 -382.878917)
			(xy 154.314146 -382.878917) (xy 154.314146 -382.826943) (xy 154.322276 -382.775608) (xy 154.338337 -382.726178)
			(xy 154.361933 -382.679868) (xy 154.392483 -382.63782) (xy 154.429234 -382.601069) (xy 154.471282 -382.570519)
			(xy 154.517592 -382.546923) (xy 154.567022 -382.530862) (xy 154.618357 -382.522732) (xy 154.670331 -382.522732)
			(xy 154.721666 -382.530862) (xy 154.771096 -382.546923) (xy 154.817406 -382.570519) (xy 154.859454 -382.601069)
			(xy 154.896205 -382.63782) (xy 154.926755 -382.679868) (xy 154.950351 -382.726178) (xy 154.966412 -382.775608)
			(xy 154.974542 -382.826943) (xy 154.975052 -382.85293) (xy 154.974542 -382.878917) (xy 155.514042 -382.878917)
			(xy 155.514042 -382.826943) (xy 155.522172 -382.775608) (xy 155.538233 -382.726178) (xy 155.561829 -382.679868)
			(xy 155.592379 -382.63782) (xy 155.62913 -382.601069) (xy 155.671178 -382.570519) (xy 155.717488 -382.546923)
			(xy 155.766918 -382.530862) (xy 155.818253 -382.522732) (xy 155.870227 -382.522732) (xy 155.921562 -382.530862)
			(xy 155.970992 -382.546923) (xy 156.017302 -382.570519) (xy 156.05935 -382.601069) (xy 156.096101 -382.63782)
			(xy 156.126651 -382.679868) (xy 156.150247 -382.726178) (xy 156.166308 -382.775608) (xy 156.174438 -382.826943)
			(xy 156.174948 -382.85293) (xy 156.174438 -382.878917) (xy 156.713938 -382.878917) (xy 156.713938 -382.826943)
			(xy 156.722068 -382.775608) (xy 156.738129 -382.726178) (xy 156.761725 -382.679868) (xy 156.792275 -382.63782)
			(xy 156.829026 -382.601069) (xy 156.871074 -382.570519) (xy 156.917384 -382.546923) (xy 156.966814 -382.530862)
			(xy 157.018149 -382.522732) (xy 157.070123 -382.522732) (xy 157.121458 -382.530862) (xy 157.170888 -382.546923)
			(xy 157.217198 -382.570519) (xy 157.259246 -382.601069) (xy 157.295997 -382.63782) (xy 157.326547 -382.679868)
			(xy 157.350143 -382.726178) (xy 157.366204 -382.775608) (xy 157.374334 -382.826943) (xy 157.374844 -382.85293)
			(xy 157.374334 -382.878917) (xy 157.914088 -382.878917) (xy 157.914088 -382.826943) (xy 157.922218 -382.775608)
			(xy 157.938279 -382.726178) (xy 157.961875 -382.679868) (xy 157.992425 -382.63782) (xy 158.029176 -382.601069)
			(xy 158.071224 -382.570519) (xy 158.117534 -382.546923) (xy 158.166964 -382.530862) (xy 158.218299 -382.522732)
			(xy 158.270273 -382.522732) (xy 158.321608 -382.530862) (xy 158.371038 -382.546923) (xy 158.417348 -382.570519)
			(xy 158.459396 -382.601069) (xy 158.496147 -382.63782) (xy 158.526697 -382.679868) (xy 158.550293 -382.726178)
			(xy 158.566354 -382.775608) (xy 158.574484 -382.826943) (xy 158.574994 -382.85293) (xy 158.574484 -382.878917)
			(xy 159.113984 -382.878917) (xy 159.113984 -382.826943) (xy 159.122114 -382.775608) (xy 159.138175 -382.726178)
			(xy 159.161771 -382.679868) (xy 159.192321 -382.63782) (xy 159.229072 -382.601069) (xy 159.27112 -382.570519)
			(xy 159.31743 -382.546923) (xy 159.36686 -382.530862) (xy 159.418195 -382.522732) (xy 159.470169 -382.522732)
			(xy 159.521504 -382.530862) (xy 159.570934 -382.546923) (xy 159.617244 -382.570519) (xy 159.659292 -382.601069)
			(xy 159.696043 -382.63782) (xy 159.726593 -382.679868) (xy 159.750189 -382.726178) (xy 159.76625 -382.775608)
			(xy 159.77438 -382.826943) (xy 159.77489 -382.85293) (xy 159.77438 -382.878917) (xy 160.314134 -382.878917)
			(xy 160.314134 -382.826943) (xy 160.322264 -382.775608) (xy 160.338325 -382.726178) (xy 160.361921 -382.679868)
			(xy 160.392471 -382.63782) (xy 160.429222 -382.601069) (xy 160.47127 -382.570519) (xy 160.51758 -382.546923)
			(xy 160.56701 -382.530862) (xy 160.618345 -382.522732) (xy 160.670319 -382.522732) (xy 160.721654 -382.530862)
			(xy 160.771084 -382.546923) (xy 160.817394 -382.570519) (xy 160.859442 -382.601069) (xy 160.896193 -382.63782)
			(xy 160.926743 -382.679868) (xy 160.950339 -382.726178) (xy 160.9664 -382.775608) (xy 160.97453 -382.826943)
			(xy 160.97504 -382.85293) (xy 160.97453 -382.878917) (xy 161.51403 -382.878917) (xy 161.51403 -382.826943)
			(xy 161.52216 -382.775608) (xy 161.538221 -382.726178) (xy 161.561817 -382.679868) (xy 161.592367 -382.63782)
			(xy 161.629118 -382.601069) (xy 161.671166 -382.570519) (xy 161.717476 -382.546923) (xy 161.766906 -382.530862)
			(xy 161.818241 -382.522732) (xy 161.870215 -382.522732) (xy 161.92155 -382.530862) (xy 161.97098 -382.546923)
			(xy 162.01729 -382.570519) (xy 162.059338 -382.601069) (xy 162.096089 -382.63782) (xy 162.126639 -382.679868)
			(xy 162.150235 -382.726178) (xy 162.166296 -382.775608) (xy 162.174426 -382.826943) (xy 162.174936 -382.85293)
			(xy 162.174426 -382.878917) (xy 162.713926 -382.878917) (xy 162.713926 -382.826943) (xy 162.722056 -382.775608)
			(xy 162.738117 -382.726178) (xy 162.761713 -382.679868) (xy 162.792263 -382.63782) (xy 162.829014 -382.601069)
			(xy 162.871062 -382.570519) (xy 162.917372 -382.546923) (xy 162.966802 -382.530862) (xy 163.018137 -382.522732)
			(xy 163.070111 -382.522732) (xy 163.121446 -382.530862) (xy 163.170876 -382.546923) (xy 163.217186 -382.570519)
			(xy 163.259234 -382.601069) (xy 163.295985 -382.63782) (xy 163.326535 -382.679868) (xy 163.350131 -382.726178)
			(xy 163.366192 -382.775608) (xy 163.374322 -382.826943) (xy 163.374832 -382.85293) (xy 163.374322 -382.878917)
			(xy 163.914076 -382.878917) (xy 163.914076 -382.826943) (xy 163.922206 -382.775608) (xy 163.938267 -382.726178)
			(xy 163.961863 -382.679868) (xy 163.992413 -382.63782) (xy 164.029164 -382.601069) (xy 164.071212 -382.570519)
			(xy 164.117522 -382.546923) (xy 164.166952 -382.530862) (xy 164.218287 -382.522732) (xy 164.270261 -382.522732)
			(xy 164.321596 -382.530862) (xy 164.371026 -382.546923) (xy 164.417336 -382.570519) (xy 164.459384 -382.601069)
			(xy 164.496135 -382.63782) (xy 164.526685 -382.679868) (xy 164.550281 -382.726178) (xy 164.566342 -382.775608)
			(xy 164.574472 -382.826943) (xy 164.574982 -382.85293) (xy 164.574472 -382.878917) (xy 165.113972 -382.878917)
			(xy 165.113972 -382.826943) (xy 165.122102 -382.775608) (xy 165.138163 -382.726178) (xy 165.161759 -382.679868)
			(xy 165.192309 -382.63782) (xy 165.22906 -382.601069) (xy 165.271108 -382.570519) (xy 165.317418 -382.546923)
			(xy 165.366848 -382.530862) (xy 165.418183 -382.522732) (xy 165.470157 -382.522732) (xy 165.521492 -382.530862)
			(xy 165.570922 -382.546923) (xy 165.617232 -382.570519) (xy 165.65928 -382.601069) (xy 165.696031 -382.63782)
			(xy 165.726581 -382.679868) (xy 165.750177 -382.726178) (xy 165.766238 -382.775608) (xy 165.774368 -382.826943)
			(xy 165.774878 -382.85293) (xy 165.774368 -382.878917) (xy 165.771949 -382.894193) (xy 166.180945 -382.894193)
			(xy 166.180945 -382.842207) (xy 166.189078 -382.790862) (xy 166.205143 -382.741421) (xy 166.228745 -382.695102)
			(xy 166.259303 -382.653045) (xy 166.296064 -382.616287) (xy 166.338122 -382.585733) (xy 166.384443 -382.562134)
			(xy 166.433885 -382.546072) (xy 166.485231 -382.537943) (xy 166.511224 -382.537462) (xy 166.534999 -382.537839)
			(xy 166.58206 -382.544648) (xy 166.627658 -382.558135) (xy 166.67085 -382.578021) (xy 166.710744 -382.603897)
			(xy 166.728902 -382.61925) (xy 166.736006 -382.624959) (xy 166.753069 -382.631329) (xy 166.762176 -382.631696)
			(xy 166.793672 -382.631696) (xy 166.802771 -382.631288) (xy 166.819822 -382.624923) (xy 166.826946 -382.61925)
			(xy 166.845129 -382.603931) (xy 166.885024 -382.57807) (xy 166.928211 -382.55819) (xy 166.973801 -382.5447)
			(xy 167.020852 -382.53788) (xy 167.044624 -382.537462) (xy 167.070608 -382.538033) (xy 167.121935 -382.546166)
			(xy 167.171357 -382.562228) (xy 167.217659 -382.585823) (xy 167.2597 -382.61637) (xy 167.296445 -382.653118)
			(xy 167.32699 -382.695161) (xy 167.350581 -382.741465) (xy 167.36664 -382.790889) (xy 167.374769 -382.842216)
			(xy 167.374769 -382.894184) (xy 167.36664 -382.945511) (xy 167.350582 -382.994935) (xy 167.32699 -383.041239)
			(xy 167.296445 -383.083282) (xy 167.2597 -383.12003) (xy 167.217659 -383.150577) (xy 167.171357 -383.174172)
			(xy 167.121935 -383.190234) (xy 167.070608 -383.198367) (xy 167.044624 -383.198878) (xy 167.02085 -383.198463)
			(xy 166.973792 -383.191662) (xy 166.928195 -383.178183) (xy 166.885002 -383.158305) (xy 166.845106 -383.132439)
			(xy 166.826946 -383.11709) (xy 166.819833 -383.111394) (xy 166.802777 -383.105018) (xy 166.793672 -383.104644)
			(xy 166.762176 -383.104644) (xy 166.753073 -383.105018) (xy 166.736023 -383.111406) (xy 166.728902 -383.11709)
			(xy 166.710744 -383.13244) (xy 166.670842 -383.158295) (xy 166.627648 -383.178169) (xy 166.582053 -383.191651)
			(xy 166.534997 -383.198464) (xy 166.511224 -383.198878) (xy 166.485231 -383.198457) (xy 166.433885 -383.190328)
			(xy 166.384443 -383.174266) (xy 166.338122 -383.150667) (xy 166.296064 -383.120113) (xy 166.259303 -383.083355)
			(xy 166.228745 -383.041298) (xy 166.205143 -382.994979) (xy 166.189078 -382.945538) (xy 166.180945 -382.894193)
			(xy 165.771949 -382.894193) (xy 165.766238 -382.930252) (xy 165.750177 -382.979682) (xy 165.726581 -383.025992)
			(xy 165.696031 -383.06804) (xy 165.65928 -383.104791) (xy 165.617232 -383.135341) (xy 165.570922 -383.158937)
			(xy 165.521492 -383.174998) (xy 165.470157 -383.183128) (xy 165.418183 -383.183128) (xy 165.366848 -383.174998)
			(xy 165.317418 -383.158937) (xy 165.271108 -383.135341) (xy 165.22906 -383.104791) (xy 165.192309 -383.06804)
			(xy 165.161759 -383.025992) (xy 165.138163 -382.979682) (xy 165.122102 -382.930252) (xy 165.113972 -382.878917)
			(xy 164.574472 -382.878917) (xy 164.566342 -382.930252) (xy 164.550281 -382.979682) (xy 164.526685 -383.025992)
			(xy 164.496135 -383.06804) (xy 164.459384 -383.104791) (xy 164.417336 -383.135341) (xy 164.371026 -383.158937)
			(xy 164.321596 -383.174998) (xy 164.270261 -383.183128) (xy 164.218287 -383.183128) (xy 164.166952 -383.174998)
			(xy 164.117522 -383.158937) (xy 164.071212 -383.135341) (xy 164.029164 -383.104791) (xy 163.992413 -383.06804)
			(xy 163.961863 -383.025992) (xy 163.938267 -382.979682) (xy 163.922206 -382.930252) (xy 163.914076 -382.878917)
			(xy 163.374322 -382.878917) (xy 163.366192 -382.930252) (xy 163.350131 -382.979682) (xy 163.326535 -383.025992)
			(xy 163.295985 -383.06804) (xy 163.259234 -383.104791) (xy 163.217186 -383.135341) (xy 163.170876 -383.158937)
			(xy 163.121446 -383.174998) (xy 163.070111 -383.183128) (xy 163.018137 -383.183128) (xy 162.966802 -383.174998)
			(xy 162.917372 -383.158937) (xy 162.871062 -383.135341) (xy 162.829014 -383.104791) (xy 162.792263 -383.06804)
			(xy 162.761713 -383.025992) (xy 162.738117 -382.979682) (xy 162.722056 -382.930252) (xy 162.713926 -382.878917)
			(xy 162.174426 -382.878917) (xy 162.166296 -382.930252) (xy 162.150235 -382.979682) (xy 162.126639 -383.025992)
			(xy 162.096089 -383.06804) (xy 162.059338 -383.104791) (xy 162.01729 -383.135341) (xy 161.97098 -383.158937)
			(xy 161.92155 -383.174998) (xy 161.870215 -383.183128) (xy 161.818241 -383.183128) (xy 161.766906 -383.174998)
			(xy 161.717476 -383.158937) (xy 161.671166 -383.135341) (xy 161.629118 -383.104791) (xy 161.592367 -383.06804)
			(xy 161.561817 -383.025992) (xy 161.538221 -382.979682) (xy 161.52216 -382.930252) (xy 161.51403 -382.878917)
			(xy 160.97453 -382.878917) (xy 160.9664 -382.930252) (xy 160.950339 -382.979682) (xy 160.926743 -383.025992)
			(xy 160.896193 -383.06804) (xy 160.859442 -383.104791) (xy 160.817394 -383.135341) (xy 160.771084 -383.158937)
			(xy 160.721654 -383.174998) (xy 160.670319 -383.183128) (xy 160.618345 -383.183128) (xy 160.56701 -383.174998)
			(xy 160.51758 -383.158937) (xy 160.47127 -383.135341) (xy 160.429222 -383.104791) (xy 160.392471 -383.06804)
			(xy 160.361921 -383.025992) (xy 160.338325 -382.979682) (xy 160.322264 -382.930252) (xy 160.314134 -382.878917)
			(xy 159.77438 -382.878917) (xy 159.76625 -382.930252) (xy 159.750189 -382.979682) (xy 159.726593 -383.025992)
			(xy 159.696043 -383.06804) (xy 159.659292 -383.104791) (xy 159.617244 -383.135341) (xy 159.570934 -383.158937)
			(xy 159.521504 -383.174998) (xy 159.470169 -383.183128) (xy 159.418195 -383.183128) (xy 159.36686 -383.174998)
			(xy 159.31743 -383.158937) (xy 159.27112 -383.135341) (xy 159.229072 -383.104791) (xy 159.192321 -383.06804)
			(xy 159.161771 -383.025992) (xy 159.138175 -382.979682) (xy 159.122114 -382.930252) (xy 159.113984 -382.878917)
			(xy 158.574484 -382.878917) (xy 158.566354 -382.930252) (xy 158.550293 -382.979682) (xy 158.526697 -383.025992)
			(xy 158.496147 -383.06804) (xy 158.459396 -383.104791) (xy 158.417348 -383.135341) (xy 158.371038 -383.158937)
			(xy 158.321608 -383.174998) (xy 158.270273 -383.183128) (xy 158.218299 -383.183128) (xy 158.166964 -383.174998)
			(xy 158.117534 -383.158937) (xy 158.071224 -383.135341) (xy 158.029176 -383.104791) (xy 157.992425 -383.06804)
			(xy 157.961875 -383.025992) (xy 157.938279 -382.979682) (xy 157.922218 -382.930252) (xy 157.914088 -382.878917)
			(xy 157.374334 -382.878917) (xy 157.366204 -382.930252) (xy 157.350143 -382.979682) (xy 157.326547 -383.025992)
			(xy 157.295997 -383.06804) (xy 157.259246 -383.104791) (xy 157.217198 -383.135341) (xy 157.170888 -383.158937)
			(xy 157.121458 -383.174998) (xy 157.070123 -383.183128) (xy 157.018149 -383.183128) (xy 156.966814 -383.174998)
			(xy 156.917384 -383.158937) (xy 156.871074 -383.135341) (xy 156.829026 -383.104791) (xy 156.792275 -383.06804)
			(xy 156.761725 -383.025992) (xy 156.738129 -382.979682) (xy 156.722068 -382.930252) (xy 156.713938 -382.878917)
			(xy 156.174438 -382.878917) (xy 156.166308 -382.930252) (xy 156.150247 -382.979682) (xy 156.126651 -383.025992)
			(xy 156.096101 -383.06804) (xy 156.05935 -383.104791) (xy 156.017302 -383.135341) (xy 155.970992 -383.158937)
			(xy 155.921562 -383.174998) (xy 155.870227 -383.183128) (xy 155.818253 -383.183128) (xy 155.766918 -383.174998)
			(xy 155.717488 -383.158937) (xy 155.671178 -383.135341) (xy 155.62913 -383.104791) (xy 155.592379 -383.06804)
			(xy 155.561829 -383.025992) (xy 155.538233 -382.979682) (xy 155.522172 -382.930252) (xy 155.514042 -382.878917)
			(xy 154.974542 -382.878917) (xy 154.966412 -382.930252) (xy 154.950351 -382.979682) (xy 154.926755 -383.025992)
			(xy 154.896205 -383.06804) (xy 154.859454 -383.104791) (xy 154.817406 -383.135341) (xy 154.771096 -383.158937)
			(xy 154.721666 -383.174998) (xy 154.670331 -383.183128) (xy 154.618357 -383.183128) (xy 154.567022 -383.174998)
			(xy 154.517592 -383.158937) (xy 154.471282 -383.135341) (xy 154.429234 -383.104791) (xy 154.392483 -383.06804)
			(xy 154.361933 -383.025992) (xy 154.338337 -382.979682) (xy 154.322276 -382.930252) (xy 154.314146 -382.878917)
			(xy 153.774392 -382.878917) (xy 153.766262 -382.930252) (xy 153.750201 -382.979682) (xy 153.726605 -383.025992)
			(xy 153.696055 -383.06804) (xy 153.659304 -383.104791) (xy 153.617256 -383.135341) (xy 153.570946 -383.158937)
			(xy 153.521516 -383.174998) (xy 153.470181 -383.183128) (xy 153.418207 -383.183128) (xy 153.366872 -383.174998)
			(xy 153.317442 -383.158937) (xy 153.271132 -383.135341) (xy 153.229084 -383.104791) (xy 153.192333 -383.06804)
			(xy 153.161783 -383.025992) (xy 153.138187 -382.979682) (xy 153.122126 -382.930252) (xy 153.113996 -382.878917)
			(xy 152.574496 -382.878917) (xy 152.566366 -382.930252) (xy 152.550305 -382.979682) (xy 152.526709 -383.025992)
			(xy 152.496159 -383.06804) (xy 152.459408 -383.104791) (xy 152.41736 -383.135341) (xy 152.37105 -383.158937)
			(xy 152.32162 -383.174998) (xy 152.270285 -383.183128) (xy 152.218311 -383.183128) (xy 152.166976 -383.174998)
			(xy 152.117546 -383.158937) (xy 152.071236 -383.135341) (xy 152.029188 -383.104791) (xy 151.992437 -383.06804)
			(xy 151.961887 -383.025992) (xy 151.938291 -382.979682) (xy 151.92223 -382.930252) (xy 151.9141 -382.878917)
			(xy 151.374346 -382.878917) (xy 151.366216 -382.930252) (xy 151.350155 -382.979682) (xy 151.326559 -383.025992)
			(xy 151.296009 -383.06804) (xy 151.259258 -383.104791) (xy 151.21721 -383.135341) (xy 151.1709 -383.158937)
			(xy 151.12147 -383.174998) (xy 151.070135 -383.183128) (xy 151.018161 -383.183128) (xy 150.966826 -383.174998)
			(xy 150.917396 -383.158937) (xy 150.871086 -383.135341) (xy 150.829038 -383.104791) (xy 150.792287 -383.06804)
			(xy 150.761737 -383.025992) (xy 150.738141 -382.979682) (xy 150.72208 -382.930252) (xy 150.71395 -382.878917)
			(xy 150.17445 -382.878917) (xy 150.16632 -382.930252) (xy 150.150259 -382.979682) (xy 150.126663 -383.025992)
			(xy 150.096113 -383.06804) (xy 150.059362 -383.104791) (xy 150.017314 -383.135341) (xy 149.971004 -383.158937)
			(xy 149.921574 -383.174998) (xy 149.870239 -383.183128) (xy 149.818265 -383.183128) (xy 149.76693 -383.174998)
			(xy 149.7175 -383.158937) (xy 149.67119 -383.135341) (xy 149.629142 -383.104791) (xy 149.592391 -383.06804)
			(xy 149.561841 -383.025992) (xy 149.538245 -382.979682) (xy 149.522184 -382.930252) (xy 149.514054 -382.878917)
			(xy 148.974554 -382.878917) (xy 148.966424 -382.930252) (xy 148.950363 -382.979682) (xy 148.926767 -383.025992)
			(xy 148.896217 -383.06804) (xy 148.859466 -383.104791) (xy 148.817418 -383.135341) (xy 148.771108 -383.158937)
			(xy 148.721678 -383.174998) (xy 148.670343 -383.183128) (xy 148.618369 -383.183128) (xy 148.567034 -383.174998)
			(xy 148.517604 -383.158937) (xy 148.471294 -383.135341) (xy 148.429246 -383.104791) (xy 148.392495 -383.06804)
			(xy 148.361945 -383.025992) (xy 148.338349 -382.979682) (xy 148.322288 -382.930252) (xy 148.314158 -382.878917)
			(xy 147.774404 -382.878917) (xy 147.766274 -382.930252) (xy 147.750213 -382.979682) (xy 147.726617 -383.025992)
			(xy 147.696067 -383.06804) (xy 147.659316 -383.104791) (xy 147.617268 -383.135341) (xy 147.570958 -383.158937)
			(xy 147.521528 -383.174998) (xy 147.470193 -383.183128) (xy 147.418219 -383.183128) (xy 147.366884 -383.174998)
			(xy 147.317454 -383.158937) (xy 147.271144 -383.135341) (xy 147.229096 -383.104791) (xy 147.192345 -383.06804)
			(xy 147.161795 -383.025992) (xy 147.138199 -382.979682) (xy 147.122138 -382.930252) (xy 147.114008 -382.878917)
			(xy 146.425768 -382.878917) (xy 146.426354 -382.882618) (xy 146.426354 -382.934582) (xy 146.418226 -382.985907)
			(xy 146.402168 -383.035329) (xy 146.378578 -383.08163) (xy 146.348036 -383.123671) (xy 146.311293 -383.160417)
			(xy 146.269254 -383.190964) (xy 146.222955 -383.214558) (xy 146.173534 -383.230619) (xy 146.12221 -383.238752)
			(xy 146.096228 -383.239264) (xy 146.071391 -383.238823) (xy 146.022273 -383.231403) (xy 145.974822 -383.21671)
			(xy 145.930105 -383.195076) (xy 145.889133 -383.16699) (xy 145.870676 -383.150364) (xy 145.863602 -383.144335)
			(xy 145.846419 -383.137294) (xy 145.837148 -383.136648) (xy 145.805906 -383.135886) (xy 145.79665 -383.136039)
			(xy 145.779197 -383.142166) (xy 145.77187 -383.147824) (xy 145.749305 -383.165988) (xy 145.699175 -383.195005)
			(xy 145.644762 -383.214858) (xy 145.587725 -383.224945) (xy 145.558764 -383.225548) (xy 145.535568 -383.225117)
			(xy 145.48963 -383.218636) (xy 145.445046 -383.205805) (xy 145.40269 -383.186877) (xy 145.363391 -383.162222)
			(xy 145.345404 -383.14757) (xy 145.338292 -383.141474) (xy 145.320766 -383.135378) (xy 145.235168 -383.137156)
			(xy 145.217896 -383.144268) (xy 145.211038 -383.150618) (xy 145.192595 -383.166936) (xy 145.151821 -383.194543)
			(xy 145.107404 -383.215801) (xy 145.060328 -383.23024) (xy 145.011631 -383.237541) (xy 144.98701 -383.237994)
			(xy 144.961019 -383.23754) (xy 144.909677 -383.229409) (xy 144.860239 -383.213347) (xy 144.813923 -383.189749)
			(xy 144.771868 -383.159196) (xy 144.735111 -383.12244) (xy 144.704556 -383.080386) (xy 144.680957 -383.03407)
			(xy 144.664893 -382.984633) (xy 144.656761 -382.933291) (xy 141.949581 -382.933291) (xy 141.605254 -383.277618)
			(xy 141.597857 -383.284466) (xy 141.579258 -383.292197) (xy 141.569186 -383.292604) (xy 141.355572 -383.292604)
			(xy 141.34594 -383.293073) (xy 141.328061 -383.300257) (xy 141.320774 -383.306574) (xy 141.299378 -383.326069)
			(xy 141.251802 -383.359035) (xy 141.199796 -383.384443) (xy 141.144551 -383.401712) (xy 141.087333 -383.410446)
			(xy 141.058392 -383.410968) (xy 141.02945 -383.410452) (xy 140.972226 -383.401741) (xy 140.916977 -383.384477)
			(xy 140.864975 -383.359055) (xy 140.817416 -383.326061) (xy 140.79601 -383.306574) (xy 140.788746 -383.300218)
			(xy 140.770854 -383.29302) (xy 140.761212 -383.292604) (xy 138.458194 -383.292604) (xy 138.448124 -383.29218)
			(xy 138.429521 -383.284464) (xy 138.422126 -383.277618) (xy 135.923274 -380.778766) (xy 135.915877 -380.771917)
			(xy 135.897278 -380.764181) (xy 135.887206 -380.76378) (xy 132.152644 -380.76378) (xy 132.142578 -380.764213)
			(xy 132.123986 -380.771939) (xy 132.116576 -380.778766) (xy 132.01523 -380.880112) (xy 132.007832 -380.886957)
			(xy 131.989233 -380.89468) (xy 131.979162 -380.895098) (xy 112.01908 -380.895098) (xy 112.009011 -380.894671)
			(xy 111.990413 -380.886951) (xy 111.983012 -380.880112) (xy 109.122718 -378.019818) (xy 109.115316 -378.012983)
			(xy 109.096717 -378.005275) (xy 109.08665 -378.004832) (xy 75.66025 -378.004832) (xy 75.650185 -378.005265)
			(xy 75.631596 -378.012996) (xy 75.624182 -378.019818) (xy 74.295147 -379.348853) (xy 102.764046 -379.348853)
			(xy 102.764046 -379.294347) (xy 102.771803 -379.240397) (xy 102.787158 -379.188099) (xy 102.8098 -379.138519)
			(xy 102.839267 -379.092665) (xy 102.874959 -379.051472) (xy 102.916151 -379.015778) (xy 102.962003 -378.986308)
			(xy 103.011582 -378.963664) (xy 103.063879 -378.948306) (xy 103.117829 -378.940547) (xy 103.145082 -378.94006)
			(xy 103.169153 -378.940435) (xy 103.216915 -378.946467) (xy 103.263542 -378.95845) (xy 103.286052 -378.966984)
			(xy 103.298498 -378.972064) (xy 103.324406 -378.968762) (xy 103.415084 -378.90196) (xy 103.426006 -378.878338)
			(xy 103.42499 -378.86513) (xy 103.423974 -378.836428) (xy 103.42446 -378.809177) (xy 103.432216 -378.755229)
			(xy 103.447571 -378.702934) (xy 103.470213 -378.653357) (xy 103.499679 -378.607507) (xy 103.53537 -378.566316)
			(xy 103.576561 -378.530625) (xy 103.622411 -378.501159) (xy 103.671988 -378.478517) (xy 103.724283 -378.463162)
			(xy 103.778231 -378.455406) (xy 103.832733 -378.455406) (xy 103.886681 -378.463162) (xy 103.938976 -378.478517)
			(xy 103.988553 -378.501159) (xy 104.034403 -378.530625) (xy 104.075594 -378.566316) (xy 104.111285 -378.607507)
			(xy 104.140751 -378.653357) (xy 104.163393 -378.702934) (xy 104.178748 -378.755229) (xy 104.186504 -378.809177)
			(xy 104.18699 -378.836428) (xy 104.185974 -378.86513) (xy 104.184958 -378.878338) (xy 104.19588 -378.90196)
			(xy 104.286558 -378.968762) (xy 104.312466 -378.972064) (xy 104.324912 -378.966984) (xy 104.347423 -378.958447)
			(xy 104.394046 -378.946443) (xy 104.44181 -378.940411) (xy 104.465882 -378.94006) (xy 104.493133 -378.940586)
			(xy 104.547082 -378.94834) (xy 104.599377 -378.963693) (xy 104.648956 -378.986333) (xy 104.694807 -379.015798)
			(xy 104.735999 -379.051489) (xy 104.771691 -379.092678) (xy 104.801158 -379.138529) (xy 104.8238 -379.188106)
			(xy 104.839156 -379.240401) (xy 104.846913 -379.294349) (xy 104.846913 -379.348851) (xy 104.839156 -379.402799)
			(xy 104.8238 -379.455094) (xy 104.801158 -379.504671) (xy 104.771691 -379.550522) (xy 104.735999 -379.591711)
			(xy 104.694807 -379.627402) (xy 104.648956 -379.656867) (xy 104.599377 -379.679507) (xy 104.547082 -379.69486)
			(xy 104.493133 -379.702614) (xy 104.465882 -379.703076) (xy 104.436446 -379.702508) (xy 104.378272 -379.693455)
			(xy 104.350058 -379.685042) (xy 104.341448 -379.682687) (xy 104.323626 -379.683456) (xy 104.31526 -379.686566)
			(xy 104.287066 -379.698504) (xy 104.278825 -379.702313) (xy 104.265556 -379.71469) (xy 104.261158 -379.722634)
			(xy 104.247998 -379.748332) (xy 104.216676 -379.796835) (xy 104.198674 -379.819408) (xy 104.193397 -379.826403)
			(xy 104.187555 -379.842909) (xy 104.187244 -379.851666) (xy 104.187244 -380.00559) (xy 104.187604 -380.014337)
			(xy 104.193442 -380.030829) (xy 104.198674 -380.037848) (xy 104.216655 -380.060436) (xy 104.247975 -380.108937)
			(xy 104.261158 -380.134622) (xy 104.265556 -380.142564) (xy 104.278832 -380.154928) (xy 104.287066 -380.158752)
			(xy 104.31526 -380.17069) (xy 104.323647 -380.173715) (xy 104.341443 -380.174504) (xy 104.350058 -380.172214)
			(xy 104.378268 -380.163783) (xy 104.436444 -380.154725) (xy 104.465882 -380.15418) (xy 104.493135 -380.154666)
			(xy 104.547086 -380.162421) (xy 104.599384 -380.177775) (xy 104.648965 -380.200415) (xy 104.694819 -380.229882)
			(xy 104.736013 -380.265575) (xy 104.771707 -380.306766) (xy 104.801176 -380.352619) (xy 104.823819 -380.402199)
			(xy 104.839175 -380.454496) (xy 104.846933 -380.508447) (xy 104.846933 -380.562953) (xy 104.839175 -380.616904)
			(xy 104.823819 -380.669201) (xy 104.801176 -380.718781) (xy 104.771707 -380.764634) (xy 104.736013 -380.805825)
			(xy 104.694819 -380.841518) (xy 104.648965 -380.870985) (xy 104.599384 -380.893625) (xy 104.547086 -380.908979)
			(xy 104.493135 -380.916734) (xy 104.465882 -380.917196) (xy 104.441811 -380.916829) (xy 104.394048 -380.910793)
			(xy 104.347422 -380.898807) (xy 104.324912 -380.890272) (xy 104.312466 -380.885192) (xy 104.286558 -380.888494)
			(xy 104.19588 -380.955296) (xy 104.184958 -380.978918) (xy 104.185974 -380.992126) (xy 104.18699 -381.020828)
			(xy 104.186504 -381.048079) (xy 104.178748 -381.102027) (xy 104.163393 -381.154322) (xy 104.140751 -381.203899)
			(xy 104.111285 -381.249749) (xy 104.075594 -381.29094) (xy 104.034403 -381.326631) (xy 103.988553 -381.356097)
			(xy 103.98558 -381.357455) (xy 107.489155 -381.357455) (xy 107.489155 -381.302945) (xy 107.496914 -381.24899)
			(xy 107.512272 -381.196689) (xy 107.534918 -381.147106) (xy 107.56439 -381.101251) (xy 107.600088 -381.060057)
			(xy 107.641286 -381.024363) (xy 107.687145 -380.994896) (xy 107.73673 -380.972256) (xy 107.789033 -380.956904)
			(xy 107.842989 -380.949152) (xy 107.870244 -380.948692) (xy 107.894181 -380.949055) (xy 107.941681 -380.955024)
			(xy 107.988058 -380.9669) (xy 108.010452 -380.975362) (xy 108.02239 -380.980188) (xy 108.047282 -380.97714)
			(xy 108.138214 -380.913894) (xy 108.14939 -380.891796) (xy 108.149136 -380.878588) (xy 108.149136 -380.87046)
			(xy 108.149622 -380.843209) (xy 108.157378 -380.789261) (xy 108.172733 -380.736966) (xy 108.195375 -380.687389)
			(xy 108.224841 -380.641539) (xy 108.260532 -380.600348) (xy 108.301723 -380.564657) (xy 108.347573 -380.535191)
			(xy 108.39715 -380.512549) (xy 108.449445 -380.497194) (xy 108.503393 -380.489438) (xy 108.557895 -380.489438)
			(xy 108.611843 -380.497194) (xy 108.664138 -380.512549) (xy 108.713715 -380.535191) (xy 108.759565 -380.564657)
			(xy 108.800756 -380.600348) (xy 108.836447 -380.641539) (xy 108.865913 -380.687389) (xy 108.888555 -380.736966)
			(xy 108.90391 -380.789261) (xy 108.909376 -380.82728) (xy 110.397542 -380.82728) (xy 110.401613 -380.771658)
			(xy 110.413739 -380.717221) (xy 110.433662 -380.66513) (xy 110.460958 -380.616495) (xy 110.495044 -380.572352)
			(xy 110.535193 -380.533643) (xy 110.580551 -380.501192) (xy 110.630151 -380.475691) (xy 110.682935 -380.457684)
			(xy 110.737778 -380.447554) (xy 110.793512 -380.445517) (xy 110.848949 -380.451617) (xy 110.902906 -380.465723)
			(xy 110.954235 -380.487535) (xy 111.001841 -380.516589) (xy 111.044709 -380.552264) (xy 111.081926 -380.593801)
			(xy 111.112699 -380.640314) (xy 111.136371 -380.690811) (xy 111.152439 -380.744218) (xy 111.160559 -380.799394)
			(xy 111.161068 -380.82728) (xy 111.160559 -380.855166) (xy 111.152439 -380.910342) (xy 111.136371 -380.963749)
			(xy 111.112699 -381.014246) (xy 111.081926 -381.060759) (xy 111.044709 -381.102296) (xy 111.001841 -381.137971)
			(xy 110.954235 -381.167025) (xy 110.902906 -381.188837) (xy 110.848949 -381.202943) (xy 110.793512 -381.209043)
			(xy 110.737778 -381.207006) (xy 110.682935 -381.196876) (xy 110.630151 -381.178869) (xy 110.580551 -381.153368)
			(xy 110.535193 -381.120917) (xy 110.495044 -381.082208) (xy 110.460958 -381.038065) (xy 110.433662 -380.98943)
			(xy 110.413739 -380.937339) (xy 110.401613 -380.882902) (xy 110.397542 -380.82728) (xy 108.909376 -380.82728)
			(xy 108.911666 -380.843209) (xy 108.912152 -380.87046) (xy 108.912152 -380.878588) (xy 108.911898 -380.891796)
			(xy 108.923074 -380.913894) (xy 109.014006 -380.97714) (xy 109.038898 -380.980188) (xy 109.050836 -380.975362)
			(xy 109.073237 -380.966921) (xy 109.119613 -380.955052) (xy 109.167109 -380.949067) (xy 109.191044 -380.948692)
			(xy 109.218293 -380.949181) (xy 109.272236 -380.956942) (xy 109.324526 -380.972301) (xy 109.374097 -380.994945)
			(xy 109.419942 -381.024412) (xy 109.461127 -381.060104) (xy 109.496814 -381.101293) (xy 109.526276 -381.147141)
			(xy 109.548914 -381.196716) (xy 109.564267 -381.249007) (xy 109.572022 -381.302951) (xy 109.572022 -381.357449)
			(xy 109.564267 -381.411393) (xy 109.548914 -381.463684) (xy 109.526276 -381.513259) (xy 109.496814 -381.559107)
			(xy 109.461127 -381.600296) (xy 109.419942 -381.635988) (xy 109.374097 -381.665455) (xy 109.324526 -381.688099)
			(xy 109.272236 -381.703458) (xy 109.218293 -381.711219) (xy 109.191044 -381.711708) (xy 109.161607 -381.711147)
			(xy 109.103434 -381.70209) (xy 109.07522 -381.693674) (xy 109.066614 -381.691298) (xy 109.048788 -381.69208)
			(xy 109.040422 -381.695198) (xy 109.012228 -381.707136) (xy 109.00401 -381.710988) (xy 108.990729 -381.723335)
			(xy 108.98632 -381.731266) (xy 108.973147 -381.756957) (xy 108.941833 -381.805465) (xy 108.923836 -381.82804)
			(xy 108.918517 -381.835024) (xy 108.912557 -381.851527) (xy 108.912152 -381.860298) (xy 108.912152 -382.014222)
			(xy 108.912512 -382.022999) (xy 108.9185 -382.039501) (xy 108.923836 -382.04648) (xy 108.941825 -382.069062)
			(xy 108.97314 -382.117567) (xy 108.98632 -382.143254) (xy 108.990722 -382.151193) (xy 109.003996 -382.163558)
			(xy 109.012228 -382.167384) (xy 109.040422 -382.179322) (xy 109.0488 -382.182377) (xy 109.066604 -382.183146)
			(xy 109.07522 -382.180846) (xy 109.103433 -382.172424) (xy 109.161606 -382.16336) (xy 109.191044 -382.162812)
			(xy 109.218295 -382.163261) (xy 109.27224 -382.171023) (xy 109.324533 -382.186383) (xy 109.374107 -382.209027)
			(xy 109.418386 -382.237488) (xy 136.192258 -382.237488) (xy 136.196329 -382.181866) (xy 136.208455 -382.127429)
			(xy 136.228378 -382.075338) (xy 136.255674 -382.026703) (xy 136.28976 -381.98256) (xy 136.329909 -381.943851)
			(xy 136.375267 -381.9114) (xy 136.424867 -381.885899) (xy 136.477651 -381.867892) (xy 136.532494 -381.857762)
			(xy 136.588228 -381.855725) (xy 136.643665 -381.861825) (xy 136.697622 -381.875931) (xy 136.748951 -381.897743)
			(xy 136.796557 -381.926797) (xy 136.839425 -381.962472) (xy 136.876642 -382.004009) (xy 136.907415 -382.050522)
			(xy 136.931087 -382.101019) (xy 136.947155 -382.154426) (xy 136.955275 -382.209602) (xy 136.955784 -382.237488)
			(xy 136.955275 -382.265374) (xy 136.947155 -382.32055) (xy 136.931087 -382.373957) (xy 136.907415 -382.424454)
			(xy 136.876642 -382.470967) (xy 136.839425 -382.512504) (xy 136.796557 -382.548179) (xy 136.748951 -382.577233)
			(xy 136.697622 -382.599045) (xy 136.643665 -382.613151) (xy 136.588228 -382.619251) (xy 136.532494 -382.617214)
			(xy 136.477651 -382.607084) (xy 136.424867 -382.589077) (xy 136.375267 -382.563576) (xy 136.329909 -382.531125)
			(xy 136.28976 -382.492416) (xy 136.255674 -382.448273) (xy 136.228378 -382.399638) (xy 136.208455 -382.347547)
			(xy 136.196329 -382.29311) (xy 136.192258 -382.237488) (xy 109.418386 -382.237488) (xy 109.419954 -382.238496)
			(xy 109.461141 -382.27419) (xy 109.49683 -382.315381) (xy 109.526294 -382.361232) (xy 109.548933 -382.410809)
			(xy 109.564287 -382.463103) (xy 109.572042 -382.517049) (xy 109.572042 -382.571551) (xy 109.564287 -382.625497)
			(xy 109.548933 -382.677791) (xy 109.526294 -382.727368) (xy 109.49683 -382.773219) (xy 109.461141 -382.81441)
			(xy 109.419954 -382.850104) (xy 109.374107 -382.879573) (xy 109.324533 -382.902217) (xy 109.27224 -382.917577)
			(xy 109.218295 -382.925339) (xy 109.191044 -382.925828) (xy 109.166972 -382.925477) (xy 109.119209 -382.919435)
			(xy 109.072584 -382.907442) (xy 109.050074 -382.898904) (xy 109.037628 -382.893824) (xy 109.01172 -382.897126)
			(xy 108.962636 -382.933286) (xy 112.129087 -382.933286) (xy 112.129087 -382.881314) (xy 112.137217 -382.829981)
			(xy 112.153277 -382.780551) (xy 112.17687 -382.734242) (xy 112.207417 -382.692194) (xy 112.244165 -382.655442)
			(xy 112.28621 -382.62489) (xy 112.332516 -382.601291) (xy 112.381944 -382.585226) (xy 112.433276 -382.57709)
			(xy 112.459262 -382.576578) (xy 112.482496 -382.576962) (xy 112.528508 -382.583464) (xy 112.573155 -382.596343)
			(xy 112.61556 -382.615348) (xy 112.654885 -382.640102) (xy 112.672876 -382.65481) (xy 112.679988 -382.660906)
			(xy 112.696498 -382.667002) (xy 112.780826 -382.667002) (xy 112.797336 -382.660906) (xy 112.804448 -382.65481)
			(xy 112.822446 -382.640113) (xy 112.861773 -382.615364) (xy 112.904176 -382.596363) (xy 112.948821 -382.583481)
			(xy 112.994829 -382.576974) (xy 113.018062 -382.576578) (xy 113.046657 -382.57717) (xy 113.102992 -382.587025)
			(xy 113.156795 -382.606414) (xy 113.206466 -382.634759) (xy 113.228882 -382.652524) (xy 113.23574 -382.658112)
			(xy 113.252504 -382.664208) (xy 113.3348 -382.664208) (xy 113.351564 -382.658366) (xy 113.358422 -382.652778)
			(xy 113.380786 -382.635141) (xy 113.430303 -382.607006) (xy 113.483902 -382.587756) (xy 113.540005 -382.57796)
			(xy 113.56848 -382.57734) (xy 113.594474 -382.577726) (xy 113.645822 -382.585856) (xy 113.695267 -382.601919)
			(xy 113.74159 -382.625519) (xy 113.78365 -382.656075) (xy 113.820412 -382.692835) (xy 113.850971 -382.734893)
			(xy 113.874574 -382.781215) (xy 113.89064 -382.830658) (xy 113.898284 -382.878917) (xy 114.58626 -382.878917)
			(xy 114.58626 -382.826943) (xy 114.59439 -382.775608) (xy 114.610451 -382.726178) (xy 114.634047 -382.679868)
			(xy 114.664597 -382.63782) (xy 114.701348 -382.601069) (xy 114.743396 -382.570519) (xy 114.789706 -382.546923)
			(xy 114.839136 -382.530862) (xy 114.890471 -382.522732) (xy 114.942445 -382.522732) (xy 114.99378 -382.530862)
			(xy 115.04321 -382.546923) (xy 115.08952 -382.570519) (xy 115.131568 -382.601069) (xy 115.168319 -382.63782)
			(xy 115.198869 -382.679868) (xy 115.222465 -382.726178) (xy 115.238526 -382.775608) (xy 115.246656 -382.826943)
			(xy 115.247166 -382.85293) (xy 115.246656 -382.878917) (xy 115.78641 -382.878917) (xy 115.78641 -382.826943)
			(xy 115.79454 -382.775608) (xy 115.810601 -382.726178) (xy 115.834197 -382.679868) (xy 115.864747 -382.63782)
			(xy 115.901498 -382.601069) (xy 115.943546 -382.570519) (xy 115.989856 -382.546923) (xy 116.039286 -382.530862)
			(xy 116.090621 -382.522732) (xy 116.142595 -382.522732) (xy 116.19393 -382.530862) (xy 116.24336 -382.546923)
			(xy 116.28967 -382.570519) (xy 116.331718 -382.601069) (xy 116.368469 -382.63782) (xy 116.399019 -382.679868)
			(xy 116.422615 -382.726178) (xy 116.438676 -382.775608) (xy 116.446806 -382.826943) (xy 116.447316 -382.85293)
			(xy 116.446806 -382.878917) (xy 116.986306 -382.878917) (xy 116.986306 -382.826943) (xy 116.994436 -382.775608)
			(xy 117.010497 -382.726178) (xy 117.034093 -382.679868) (xy 117.064643 -382.63782) (xy 117.101394 -382.601069)
			(xy 117.143442 -382.570519) (xy 117.189752 -382.546923) (xy 117.239182 -382.530862) (xy 117.290517 -382.522732)
			(xy 117.342491 -382.522732) (xy 117.393826 -382.530862) (xy 117.443256 -382.546923) (xy 117.489566 -382.570519)
			(xy 117.531614 -382.601069) (xy 117.568365 -382.63782) (xy 117.598915 -382.679868) (xy 117.622511 -382.726178)
			(xy 117.638572 -382.775608) (xy 117.646702 -382.826943) (xy 117.647212 -382.85293) (xy 117.646702 -382.878917)
			(xy 118.186202 -382.878917) (xy 118.186202 -382.826943) (xy 118.194332 -382.775608) (xy 118.210393 -382.726178)
			(xy 118.233989 -382.679868) (xy 118.264539 -382.63782) (xy 118.30129 -382.601069) (xy 118.343338 -382.570519)
			(xy 118.389648 -382.546923) (xy 118.439078 -382.530862) (xy 118.490413 -382.522732) (xy 118.542387 -382.522732)
			(xy 118.593722 -382.530862) (xy 118.643152 -382.546923) (xy 118.689462 -382.570519) (xy 118.73151 -382.601069)
			(xy 118.768261 -382.63782) (xy 118.798811 -382.679868) (xy 118.822407 -382.726178) (xy 118.838468 -382.775608)
			(xy 118.846598 -382.826943) (xy 118.847108 -382.85293) (xy 118.846598 -382.878917) (xy 119.386352 -382.878917)
			(xy 119.386352 -382.826943) (xy 119.394482 -382.775608) (xy 119.410543 -382.726178) (xy 119.434139 -382.679868)
			(xy 119.464689 -382.63782) (xy 119.50144 -382.601069) (xy 119.543488 -382.570519) (xy 119.589798 -382.546923)
			(xy 119.639228 -382.530862) (xy 119.690563 -382.522732) (xy 119.742537 -382.522732) (xy 119.793872 -382.530862)
			(xy 119.843302 -382.546923) (xy 119.889612 -382.570519) (xy 119.93166 -382.601069) (xy 119.968411 -382.63782)
			(xy 119.998961 -382.679868) (xy 120.022557 -382.726178) (xy 120.038618 -382.775608) (xy 120.046748 -382.826943)
			(xy 120.047258 -382.85293) (xy 120.046748 -382.878917) (xy 120.586248 -382.878917) (xy 120.586248 -382.826943)
			(xy 120.594378 -382.775608) (xy 120.610439 -382.726178) (xy 120.634035 -382.679868) (xy 120.664585 -382.63782)
			(xy 120.701336 -382.601069) (xy 120.743384 -382.570519) (xy 120.789694 -382.546923) (xy 120.839124 -382.530862)
			(xy 120.890459 -382.522732) (xy 120.942433 -382.522732) (xy 120.993768 -382.530862) (xy 121.043198 -382.546923)
			(xy 121.089508 -382.570519) (xy 121.131556 -382.601069) (xy 121.168307 -382.63782) (xy 121.198857 -382.679868)
			(xy 121.222453 -382.726178) (xy 121.238514 -382.775608) (xy 121.246644 -382.826943) (xy 121.247154 -382.85293)
			(xy 121.246644 -382.878917) (xy 121.786398 -382.878917) (xy 121.786398 -382.826943) (xy 121.794528 -382.775608)
			(xy 121.810589 -382.726178) (xy 121.834185 -382.679868) (xy 121.864735 -382.63782) (xy 121.901486 -382.601069)
			(xy 121.943534 -382.570519) (xy 121.989844 -382.546923) (xy 122.039274 -382.530862) (xy 122.090609 -382.522732)
			(xy 122.142583 -382.522732) (xy 122.193918 -382.530862) (xy 122.243348 -382.546923) (xy 122.289658 -382.570519)
			(xy 122.331706 -382.601069) (xy 122.368457 -382.63782) (xy 122.399007 -382.679868) (xy 122.422603 -382.726178)
			(xy 122.438664 -382.775608) (xy 122.446794 -382.826943) (xy 122.447304 -382.85293) (xy 122.446794 -382.878917)
			(xy 122.986294 -382.878917) (xy 122.986294 -382.826943) (xy 122.994424 -382.775608) (xy 123.010485 -382.726178)
			(xy 123.034081 -382.679868) (xy 123.064631 -382.63782) (xy 123.101382 -382.601069) (xy 123.14343 -382.570519)
			(xy 123.18974 -382.546923) (xy 123.23917 -382.530862) (xy 123.290505 -382.522732) (xy 123.342479 -382.522732)
			(xy 123.393814 -382.530862) (xy 123.443244 -382.546923) (xy 123.489554 -382.570519) (xy 123.531602 -382.601069)
			(xy 123.568353 -382.63782) (xy 123.598903 -382.679868) (xy 123.622499 -382.726178) (xy 123.63856 -382.775608)
			(xy 123.64669 -382.826943) (xy 123.6472 -382.85293) (xy 123.64669 -382.878917) (xy 124.18619 -382.878917)
			(xy 124.18619 -382.826943) (xy 124.19432 -382.775608) (xy 124.210381 -382.726178) (xy 124.233977 -382.679868)
			(xy 124.264527 -382.63782) (xy 124.301278 -382.601069) (xy 124.343326 -382.570519) (xy 124.389636 -382.546923)
			(xy 124.439066 -382.530862) (xy 124.490401 -382.522732) (xy 124.542375 -382.522732) (xy 124.59371 -382.530862)
			(xy 124.64314 -382.546923) (xy 124.68945 -382.570519) (xy 124.731498 -382.601069) (xy 124.768249 -382.63782)
			(xy 124.798799 -382.679868) (xy 124.822395 -382.726178) (xy 124.838456 -382.775608) (xy 124.846586 -382.826943)
			(xy 124.847096 -382.85293) (xy 124.846586 -382.878917) (xy 125.38634 -382.878917) (xy 125.38634 -382.826943)
			(xy 125.39447 -382.775608) (xy 125.410531 -382.726178) (xy 125.434127 -382.679868) (xy 125.464677 -382.63782)
			(xy 125.501428 -382.601069) (xy 125.543476 -382.570519) (xy 125.589786 -382.546923) (xy 125.639216 -382.530862)
			(xy 125.690551 -382.522732) (xy 125.742525 -382.522732) (xy 125.79386 -382.530862) (xy 125.84329 -382.546923)
			(xy 125.8896 -382.570519) (xy 125.931648 -382.601069) (xy 125.968399 -382.63782) (xy 125.998949 -382.679868)
			(xy 126.022545 -382.726178) (xy 126.038606 -382.775608) (xy 126.046736 -382.826943) (xy 126.047246 -382.85293)
			(xy 126.046736 -382.878917) (xy 126.586236 -382.878917) (xy 126.586236 -382.826943) (xy 126.594366 -382.775608)
			(xy 126.610427 -382.726178) (xy 126.634023 -382.679868) (xy 126.664573 -382.63782) (xy 126.701324 -382.601069)
			(xy 126.743372 -382.570519) (xy 126.789682 -382.546923) (xy 126.839112 -382.530862) (xy 126.890447 -382.522732)
			(xy 126.942421 -382.522732) (xy 126.993756 -382.530862) (xy 127.043186 -382.546923) (xy 127.089496 -382.570519)
			(xy 127.131544 -382.601069) (xy 127.168295 -382.63782) (xy 127.198845 -382.679868) (xy 127.222441 -382.726178)
			(xy 127.238502 -382.775608) (xy 127.246632 -382.826943) (xy 127.247142 -382.85293) (xy 127.246632 -382.878917)
			(xy 127.786386 -382.878917) (xy 127.786386 -382.826943) (xy 127.794516 -382.775608) (xy 127.810577 -382.726178)
			(xy 127.834173 -382.679868) (xy 127.864723 -382.63782) (xy 127.901474 -382.601069) (xy 127.943522 -382.570519)
			(xy 127.989832 -382.546923) (xy 128.039262 -382.530862) (xy 128.090597 -382.522732) (xy 128.142571 -382.522732)
			(xy 128.193906 -382.530862) (xy 128.243336 -382.546923) (xy 128.289646 -382.570519) (xy 128.331694 -382.601069)
			(xy 128.368445 -382.63782) (xy 128.398995 -382.679868) (xy 128.422591 -382.726178) (xy 128.438652 -382.775608)
			(xy 128.446782 -382.826943) (xy 128.447292 -382.85293) (xy 128.446782 -382.878917) (xy 128.986282 -382.878917)
			(xy 128.986282 -382.826943) (xy 128.994412 -382.775608) (xy 129.010473 -382.726178) (xy 129.034069 -382.679868)
			(xy 129.064619 -382.63782) (xy 129.10137 -382.601069) (xy 129.143418 -382.570519) (xy 129.189728 -382.546923)
			(xy 129.239158 -382.530862) (xy 129.290493 -382.522732) (xy 129.342467 -382.522732) (xy 129.393802 -382.530862)
			(xy 129.443232 -382.546923) (xy 129.489542 -382.570519) (xy 129.53159 -382.601069) (xy 129.568341 -382.63782)
			(xy 129.598891 -382.679868) (xy 129.622487 -382.726178) (xy 129.638548 -382.775608) (xy 129.646678 -382.826943)
			(xy 129.647188 -382.85293) (xy 129.646678 -382.878917) (xy 130.186178 -382.878917) (xy 130.186178 -382.826943)
			(xy 130.194308 -382.775608) (xy 130.210369 -382.726178) (xy 130.233965 -382.679868) (xy 130.264515 -382.63782)
			(xy 130.301266 -382.601069) (xy 130.343314 -382.570519) (xy 130.389624 -382.546923) (xy 130.439054 -382.530862)
			(xy 130.490389 -382.522732) (xy 130.542363 -382.522732) (xy 130.593698 -382.530862) (xy 130.643128 -382.546923)
			(xy 130.689438 -382.570519) (xy 130.731486 -382.601069) (xy 130.768237 -382.63782) (xy 130.798787 -382.679868)
			(xy 130.822383 -382.726178) (xy 130.838444 -382.775608) (xy 130.846574 -382.826943) (xy 130.847084 -382.85293)
			(xy 130.846574 -382.878917) (xy 131.386328 -382.878917) (xy 131.386328 -382.826943) (xy 131.394458 -382.775608)
			(xy 131.410519 -382.726178) (xy 131.434115 -382.679868) (xy 131.464665 -382.63782) (xy 131.501416 -382.601069)
			(xy 131.543464 -382.570519) (xy 131.589774 -382.546923) (xy 131.639204 -382.530862) (xy 131.690539 -382.522732)
			(xy 131.742513 -382.522732) (xy 131.793848 -382.530862) (xy 131.843278 -382.546923) (xy 131.889588 -382.570519)
			(xy 131.931636 -382.601069) (xy 131.968387 -382.63782) (xy 131.998937 -382.679868) (xy 132.022533 -382.726178)
			(xy 132.038594 -382.775608) (xy 132.046724 -382.826943) (xy 132.047234 -382.85293) (xy 132.046724 -382.878917)
			(xy 132.586224 -382.878917) (xy 132.586224 -382.826943) (xy 132.594354 -382.775608) (xy 132.610415 -382.726178)
			(xy 132.634011 -382.679868) (xy 132.664561 -382.63782) (xy 132.701312 -382.601069) (xy 132.74336 -382.570519)
			(xy 132.78967 -382.546923) (xy 132.8391 -382.530862) (xy 132.890435 -382.522732) (xy 132.942409 -382.522732)
			(xy 132.993744 -382.530862) (xy 133.043174 -382.546923) (xy 133.089484 -382.570519) (xy 133.131532 -382.601069)
			(xy 133.168283 -382.63782) (xy 133.198833 -382.679868) (xy 133.222429 -382.726178) (xy 133.23849 -382.775608)
			(xy 133.24662 -382.826943) (xy 133.24713 -382.85293) (xy 133.24662 -382.878917) (xy 133.244202 -382.894188)
			(xy 133.653272 -382.894188) (xy 133.653272 -382.842212) (xy 133.661402 -382.790875) (xy 133.677463 -382.741442)
			(xy 133.701059 -382.69513) (xy 133.731609 -382.653079) (xy 133.768361 -382.616324) (xy 133.810409 -382.585772)
			(xy 133.85672 -382.562172) (xy 133.906151 -382.546108) (xy 133.957488 -382.537973) (xy 133.983476 -382.537462)
			(xy 134.00725 -382.537867) (xy 134.05431 -382.544669) (xy 134.099907 -382.558149) (xy 134.1431 -382.57803)
			(xy 134.182995 -382.6039) (xy 134.201154 -382.61925) (xy 134.208272 -382.624938) (xy 134.225324 -382.631321)
			(xy 134.234428 -382.631696) (xy 134.265924 -382.631696) (xy 134.275026 -382.631313) (xy 134.292076 -382.624931)
			(xy 134.299198 -382.61925) (xy 134.317361 -382.603906) (xy 134.357261 -382.578049) (xy 134.400454 -382.558174)
			(xy 134.446048 -382.54469) (xy 134.493103 -382.537876) (xy 134.516876 -382.537462) (xy 134.542864 -382.538003)
			(xy 134.594201 -382.546131) (xy 134.643634 -382.562189) (xy 134.689947 -382.585784) (xy 134.731998 -382.616333)
			(xy 134.768752 -382.653084) (xy 134.799304 -382.695133) (xy 134.822901 -382.741444) (xy 134.838964 -382.790876)
			(xy 134.847095 -382.842212) (xy 134.847095 -382.894188) (xy 134.838964 -382.945524) (xy 134.822901 -382.994956)
			(xy 134.799304 -383.041267) (xy 134.768752 -383.083316) (xy 134.731998 -383.120067) (xy 134.689947 -383.150616)
			(xy 134.643634 -383.174211) (xy 134.594201 -383.190269) (xy 134.542864 -383.198397) (xy 134.516876 -383.198878)
			(xy 134.493101 -383.198492) (xy 134.446041 -383.191684) (xy 134.400444 -383.178199) (xy 134.357251 -383.158314)
			(xy 134.317357 -383.132442) (xy 134.299198 -383.11709) (xy 134.292099 -383.111374) (xy 134.275032 -383.10501)
			(xy 134.265924 -383.104644) (xy 134.234428 -383.104644) (xy 134.225328 -383.105043) (xy 134.208277 -383.111413)
			(xy 134.201154 -383.11709) (xy 134.182977 -383.132416) (xy 134.14308 -383.158274) (xy 134.099891 -383.178153)
			(xy 134.0543 -383.191641) (xy 134.007248 -383.198461) (xy 133.983476 -383.198878) (xy 133.957488 -383.198427)
			(xy 133.906151 -383.190292) (xy 133.85672 -383.174228) (xy 133.810409 -383.150628) (xy 133.768361 -383.120076)
			(xy 133.731609 -383.083321) (xy 133.701059 -383.04127) (xy 133.677463 -382.994958) (xy 133.661402 -382.945525)
			(xy 133.653272 -382.894188) (xy 133.244202 -382.894188) (xy 133.23849 -382.930252) (xy 133.222429 -382.979682)
			(xy 133.198833 -383.025992) (xy 133.168283 -383.06804) (xy 133.131532 -383.104791) (xy 133.089484 -383.135341)
			(xy 133.043174 -383.158937) (xy 132.993744 -383.174998) (xy 132.942409 -383.183128) (xy 132.890435 -383.183128)
			(xy 132.8391 -383.174998) (xy 132.78967 -383.158937) (xy 132.74336 -383.135341) (xy 132.701312 -383.104791)
			(xy 132.664561 -383.06804) (xy 132.634011 -383.025992) (xy 132.610415 -382.979682) (xy 132.594354 -382.930252)
			(xy 132.586224 -382.878917) (xy 132.046724 -382.878917) (xy 132.038594 -382.930252) (xy 132.022533 -382.979682)
			(xy 131.998937 -383.025992) (xy 131.968387 -383.06804) (xy 131.931636 -383.104791) (xy 131.889588 -383.135341)
			(xy 131.843278 -383.158937) (xy 131.793848 -383.174998) (xy 131.742513 -383.183128) (xy 131.690539 -383.183128)
			(xy 131.639204 -383.174998) (xy 131.589774 -383.158937) (xy 131.543464 -383.135341) (xy 131.501416 -383.104791)
			(xy 131.464665 -383.06804) (xy 131.434115 -383.025992) (xy 131.410519 -382.979682) (xy 131.394458 -382.930252)
			(xy 131.386328 -382.878917) (xy 130.846574 -382.878917) (xy 130.838444 -382.930252) (xy 130.822383 -382.979682)
			(xy 130.798787 -383.025992) (xy 130.768237 -383.06804) (xy 130.731486 -383.104791) (xy 130.689438 -383.135341)
			(xy 130.643128 -383.158937) (xy 130.593698 -383.174998) (xy 130.542363 -383.183128) (xy 130.490389 -383.183128)
			(xy 130.439054 -383.174998) (xy 130.389624 -383.158937) (xy 130.343314 -383.135341) (xy 130.301266 -383.104791)
			(xy 130.264515 -383.06804) (xy 130.233965 -383.025992) (xy 130.210369 -382.979682) (xy 130.194308 -382.930252)
			(xy 130.186178 -382.878917) (xy 129.646678 -382.878917) (xy 129.638548 -382.930252) (xy 129.622487 -382.979682)
			(xy 129.598891 -383.025992) (xy 129.568341 -383.06804) (xy 129.53159 -383.104791) (xy 129.489542 -383.135341)
			(xy 129.443232 -383.158937) (xy 129.393802 -383.174998) (xy 129.342467 -383.183128) (xy 129.290493 -383.183128)
			(xy 129.239158 -383.174998) (xy 129.189728 -383.158937) (xy 129.143418 -383.135341) (xy 129.10137 -383.104791)
			(xy 129.064619 -383.06804) (xy 129.034069 -383.025992) (xy 129.010473 -382.979682) (xy 128.994412 -382.930252)
			(xy 128.986282 -382.878917) (xy 128.446782 -382.878917) (xy 128.438652 -382.930252) (xy 128.422591 -382.979682)
			(xy 128.398995 -383.025992) (xy 128.368445 -383.06804) (xy 128.331694 -383.104791) (xy 128.289646 -383.135341)
			(xy 128.243336 -383.158937) (xy 128.193906 -383.174998) (xy 128.142571 -383.183128) (xy 128.090597 -383.183128)
			(xy 128.039262 -383.174998) (xy 127.989832 -383.158937) (xy 127.943522 -383.135341) (xy 127.901474 -383.104791)
			(xy 127.864723 -383.06804) (xy 127.834173 -383.025992) (xy 127.810577 -382.979682) (xy 127.794516 -382.930252)
			(xy 127.786386 -382.878917) (xy 127.246632 -382.878917) (xy 127.238502 -382.930252) (xy 127.222441 -382.979682)
			(xy 127.198845 -383.025992) (xy 127.168295 -383.06804) (xy 127.131544 -383.104791) (xy 127.089496 -383.135341)
			(xy 127.043186 -383.158937) (xy 126.993756 -383.174998) (xy 126.942421 -383.183128) (xy 126.890447 -383.183128)
			(xy 126.839112 -383.174998) (xy 126.789682 -383.158937) (xy 126.743372 -383.135341) (xy 126.701324 -383.104791)
			(xy 126.664573 -383.06804) (xy 126.634023 -383.025992) (xy 126.610427 -382.979682) (xy 126.594366 -382.930252)
			(xy 126.586236 -382.878917) (xy 126.046736 -382.878917) (xy 126.038606 -382.930252) (xy 126.022545 -382.979682)
			(xy 125.998949 -383.025992) (xy 125.968399 -383.06804) (xy 125.931648 -383.104791) (xy 125.8896 -383.135341)
			(xy 125.84329 -383.158937) (xy 125.79386 -383.174998) (xy 125.742525 -383.183128) (xy 125.690551 -383.183128)
			(xy 125.639216 -383.174998) (xy 125.589786 -383.158937) (xy 125.543476 -383.135341) (xy 125.501428 -383.104791)
			(xy 125.464677 -383.06804) (xy 125.434127 -383.025992) (xy 125.410531 -382.979682) (xy 125.39447 -382.930252)
			(xy 125.38634 -382.878917) (xy 124.846586 -382.878917) (xy 124.838456 -382.930252) (xy 124.822395 -382.979682)
			(xy 124.798799 -383.025992) (xy 124.768249 -383.06804) (xy 124.731498 -383.104791) (xy 124.68945 -383.135341)
			(xy 124.64314 -383.158937) (xy 124.59371 -383.174998) (xy 124.542375 -383.183128) (xy 124.490401 -383.183128)
			(xy 124.439066 -383.174998) (xy 124.389636 -383.158937) (xy 124.343326 -383.135341) (xy 124.301278 -383.104791)
			(xy 124.264527 -383.06804) (xy 124.233977 -383.025992) (xy 124.210381 -382.979682) (xy 124.19432 -382.930252)
			(xy 124.18619 -382.878917) (xy 123.64669 -382.878917) (xy 123.63856 -382.930252) (xy 123.622499 -382.979682)
			(xy 123.598903 -383.025992) (xy 123.568353 -383.06804) (xy 123.531602 -383.104791) (xy 123.489554 -383.135341)
			(xy 123.443244 -383.158937) (xy 123.393814 -383.174998) (xy 123.342479 -383.183128) (xy 123.290505 -383.183128)
			(xy 123.23917 -383.174998) (xy 123.18974 -383.158937) (xy 123.14343 -383.135341) (xy 123.101382 -383.104791)
			(xy 123.064631 -383.06804) (xy 123.034081 -383.025992) (xy 123.010485 -382.979682) (xy 122.994424 -382.930252)
			(xy 122.986294 -382.878917) (xy 122.446794 -382.878917) (xy 122.438664 -382.930252) (xy 122.422603 -382.979682)
			(xy 122.399007 -383.025992) (xy 122.368457 -383.06804) (xy 122.331706 -383.104791) (xy 122.289658 -383.135341)
			(xy 122.243348 -383.158937) (xy 122.193918 -383.174998) (xy 122.142583 -383.183128) (xy 122.090609 -383.183128)
			(xy 122.039274 -383.174998) (xy 121.989844 -383.158937) (xy 121.943534 -383.135341) (xy 121.901486 -383.104791)
			(xy 121.864735 -383.06804) (xy 121.834185 -383.025992) (xy 121.810589 -382.979682) (xy 121.794528 -382.930252)
			(xy 121.786398 -382.878917) (xy 121.246644 -382.878917) (xy 121.238514 -382.930252) (xy 121.222453 -382.979682)
			(xy 121.198857 -383.025992) (xy 121.168307 -383.06804) (xy 121.131556 -383.104791) (xy 121.089508 -383.135341)
			(xy 121.043198 -383.158937) (xy 120.993768 -383.174998) (xy 120.942433 -383.183128) (xy 120.890459 -383.183128)
			(xy 120.839124 -383.174998) (xy 120.789694 -383.158937) (xy 120.743384 -383.135341) (xy 120.701336 -383.104791)
			(xy 120.664585 -383.06804) (xy 120.634035 -383.025992) (xy 120.610439 -382.979682) (xy 120.594378 -382.930252)
			(xy 120.586248 -382.878917) (xy 120.046748 -382.878917) (xy 120.038618 -382.930252) (xy 120.022557 -382.979682)
			(xy 119.998961 -383.025992) (xy 119.968411 -383.06804) (xy 119.93166 -383.104791) (xy 119.889612 -383.135341)
			(xy 119.843302 -383.158937) (xy 119.793872 -383.174998) (xy 119.742537 -383.183128) (xy 119.690563 -383.183128)
			(xy 119.639228 -383.174998) (xy 119.589798 -383.158937) (xy 119.543488 -383.135341) (xy 119.50144 -383.104791)
			(xy 119.464689 -383.06804) (xy 119.434139 -383.025992) (xy 119.410543 -382.979682) (xy 119.394482 -382.930252)
			(xy 119.386352 -382.878917) (xy 118.846598 -382.878917) (xy 118.838468 -382.930252) (xy 118.822407 -382.979682)
			(xy 118.798811 -383.025992) (xy 118.768261 -383.06804) (xy 118.73151 -383.104791) (xy 118.689462 -383.135341)
			(xy 118.643152 -383.158937) (xy 118.593722 -383.174998) (xy 118.542387 -383.183128) (xy 118.490413 -383.183128)
			(xy 118.439078 -383.174998) (xy 118.389648 -383.158937) (xy 118.343338 -383.135341) (xy 118.30129 -383.104791)
			(xy 118.264539 -383.06804) (xy 118.233989 -383.025992) (xy 118.210393 -382.979682) (xy 118.194332 -382.930252)
			(xy 118.186202 -382.878917) (xy 117.646702 -382.878917) (xy 117.638572 -382.930252) (xy 117.622511 -382.979682)
			(xy 117.598915 -383.025992) (xy 117.568365 -383.06804) (xy 117.531614 -383.104791) (xy 117.489566 -383.135341)
			(xy 117.443256 -383.158937) (xy 117.393826 -383.174998) (xy 117.342491 -383.183128) (xy 117.290517 -383.183128)
			(xy 117.239182 -383.174998) (xy 117.189752 -383.158937) (xy 117.143442 -383.135341) (xy 117.101394 -383.104791)
			(xy 117.064643 -383.06804) (xy 117.034093 -383.025992) (xy 117.010497 -382.979682) (xy 116.994436 -382.930252)
			(xy 116.986306 -382.878917) (xy 116.446806 -382.878917) (xy 116.438676 -382.930252) (xy 116.422615 -382.979682)
			(xy 116.399019 -383.025992) (xy 116.368469 -383.06804) (xy 116.331718 -383.104791) (xy 116.28967 -383.135341)
			(xy 116.24336 -383.158937) (xy 116.19393 -383.174998) (xy 116.142595 -383.183128) (xy 116.090621 -383.183128)
			(xy 116.039286 -383.174998) (xy 115.989856 -383.158937) (xy 115.943546 -383.135341) (xy 115.901498 -383.104791)
			(xy 115.864747 -383.06804) (xy 115.834197 -383.025992) (xy 115.810601 -382.979682) (xy 115.79454 -382.930252)
			(xy 115.78641 -382.878917) (xy 115.246656 -382.878917) (xy 115.238526 -382.930252) (xy 115.222465 -382.979682)
			(xy 115.198869 -383.025992) (xy 115.168319 -383.06804) (xy 115.131568 -383.104791) (xy 115.08952 -383.135341)
			(xy 115.04321 -383.158937) (xy 114.99378 -383.174998) (xy 114.942445 -383.183128) (xy 114.890471 -383.183128)
			(xy 114.839136 -383.174998) (xy 114.789706 -383.158937) (xy 114.743396 -383.135341) (xy 114.701348 -383.104791)
			(xy 114.664597 -383.06804) (xy 114.634047 -383.025992) (xy 114.610451 -382.979682) (xy 114.59439 -382.930252)
			(xy 114.58626 -382.878917) (xy 113.898284 -382.878917) (xy 113.898773 -382.882006) (xy 113.898773 -382.933994)
			(xy 113.89064 -382.985342) (xy 113.874574 -383.034785) (xy 113.850971 -383.081107) (xy 113.820412 -383.123165)
			(xy 113.78365 -383.159925) (xy 113.74159 -383.190481) (xy 113.695267 -383.214081) (xy 113.645822 -383.230144)
			(xy 113.594474 -383.238274) (xy 113.56848 -383.238756) (xy 113.539887 -383.238133) (xy 113.483554 -383.228287)
			(xy 113.42975 -383.208907) (xy 113.380077 -383.18057) (xy 113.35766 -383.16281) (xy 113.350802 -383.157222)
			(xy 113.334038 -383.151126) (xy 113.251742 -383.151126) (xy 113.234978 -383.156968) (xy 113.22812 -383.162556)
			(xy 113.205768 -383.18021) (xy 113.156248 -383.208344) (xy 113.102645 -383.227589) (xy 113.046538 -383.237379)
			(xy 113.018062 -383.237994) (xy 112.994828 -383.237602) (xy 112.948817 -383.231103) (xy 112.904169 -383.218226)
			(xy 112.861764 -383.199223) (xy 112.822439 -383.174469) (xy 112.804448 -383.159762) (xy 112.797336 -383.153666)
			(xy 112.780826 -383.14757) (xy 112.696498 -383.14757) (xy 112.679988 -383.153666) (xy 112.672876 -383.159762)
			(xy 112.654866 -383.174444) (xy 112.615543 -383.199195) (xy 112.573143 -383.218201) (xy 112.5285 -383.231086)
			(xy 112.482494 -383.237596) (xy 112.459262 -383.237994) (xy 112.433276 -383.23751) (xy 112.381944 -383.229374)
			(xy 112.332516 -383.213309) (xy 112.28621 -383.18971) (xy 112.244165 -383.159158) (xy 112.207417 -383.122406)
			(xy 112.17687 -383.080358) (xy 112.153277 -383.034049) (xy 112.137217 -382.984619) (xy 112.129087 -382.933286)
			(xy 108.962636 -382.933286) (xy 108.921042 -382.963928) (xy 108.91012 -382.98755) (xy 108.911136 -383.000758)
			(xy 108.912152 -383.02946) (xy 108.911666 -383.056711) (xy 108.90391 -383.110659) (xy 108.888555 -383.162954)
			(xy 108.865913 -383.212531) (xy 108.836447 -383.258381) (xy 108.800756 -383.299572) (xy 108.759565 -383.335263)
			(xy 108.713715 -383.364729) (xy 108.664138 -383.387371) (xy 108.611843 -383.402726) (xy 108.557895 -383.410482)
			(xy 108.503393 -383.410482) (xy 108.449445 -383.402726) (xy 108.39715 -383.387371) (xy 108.347573 -383.364729)
			(xy 108.301723 -383.335263) (xy 108.260532 -383.299572) (xy 108.224841 -383.258381) (xy 108.195375 -383.212531)
			(xy 108.172733 -383.162954) (xy 108.157378 -383.110659) (xy 108.149622 -383.056711) (xy 108.149136 -383.02946)
			(xy 108.150152 -383.000758) (xy 108.151168 -382.98755) (xy 108.140246 -382.963928) (xy 108.049568 -382.897126)
			(xy 108.02366 -382.893824) (xy 108.011214 -382.898904) (xy 107.988711 -382.907462) (xy 107.942084 -382.919458)
			(xy 107.894317 -382.925482) (xy 107.870244 -382.925828) (xy 107.842991 -382.925328) (xy 107.789038 -382.917576)
			(xy 107.736737 -382.902225) (xy 107.687154 -382.879586) (xy 107.641298 -382.850121) (xy 107.600102 -382.814429)
			(xy 107.564406 -382.773237) (xy 107.534935 -382.727384) (xy 107.512291 -382.677804) (xy 107.496933 -382.625505)
			(xy 107.489175 -382.571553) (xy 107.489175 -382.517047) (xy 107.496933 -382.463095) (xy 107.512291 -382.410796)
			(xy 107.534935 -382.361216) (xy 107.564406 -382.315363) (xy 107.600102 -382.274171) (xy 107.641298 -382.238479)
			(xy 107.687154 -382.209014) (xy 107.736737 -382.186375) (xy 107.789038 -382.171024) (xy 107.842991 -382.163272)
			(xy 107.870244 -382.162812) (xy 107.899681 -382.163375) (xy 107.957854 -382.172431) (xy 107.986068 -382.180846)
			(xy 107.994676 -382.183215) (xy 108.0125 -382.182437) (xy 108.020866 -382.179322) (xy 108.04906 -382.167384)
			(xy 108.057291 -382.163555) (xy 108.070567 -382.151193) (xy 108.074968 -382.143254) (xy 108.088132 -382.117558)
			(xy 108.119452 -382.069054) (xy 108.137452 -382.04648) (xy 108.142761 -382.039489) (xy 108.148728 -382.022991)
			(xy 108.149136 -382.014222) (xy 108.149136 -381.860298) (xy 108.148769 -381.851521) (xy 108.142787 -381.835019)
			(xy 108.137452 -381.82804) (xy 108.119472 -381.805452) (xy 108.088151 -381.756951) (xy 108.074968 -381.731266)
			(xy 108.070565 -381.723328) (xy 108.057292 -381.710962) (xy 108.04906 -381.707136) (xy 108.020866 -381.695198)
			(xy 108.01249 -381.692137) (xy 107.994685 -381.691371) (xy 107.986068 -381.693674) (xy 107.957856 -381.702099)
			(xy 107.899682 -381.711161) (xy 107.870244 -381.711708) (xy 107.842989 -381.711248) (xy 107.789033 -381.703496)
			(xy 107.73673 -381.688144) (xy 107.687145 -381.665504) (xy 107.641286 -381.636037) (xy 107.600088 -381.600343)
			(xy 107.56439 -381.559149) (xy 107.534918 -381.513294) (xy 107.512272 -381.463711) (xy 107.496914 -381.41141)
			(xy 107.489155 -381.357455) (xy 103.98558 -381.357455) (xy 103.938976 -381.378739) (xy 103.886681 -381.394094)
			(xy 103.832733 -381.40185) (xy 103.778231 -381.40185) (xy 103.724283 -381.394094) (xy 103.671988 -381.378739)
			(xy 103.622411 -381.356097) (xy 103.576561 -381.326631) (xy 103.53537 -381.29094) (xy 103.499679 -381.249749)
			(xy 103.470213 -381.203899) (xy 103.447571 -381.154322) (xy 103.432216 -381.102027) (xy 103.42446 -381.048079)
			(xy 103.423974 -381.020828) (xy 103.42499 -380.992126) (xy 103.426006 -380.978918) (xy 103.415084 -380.955296)
			(xy 103.324406 -380.888494) (xy 103.298498 -380.885192) (xy 103.286052 -380.890272) (xy 103.263546 -380.898822)
			(xy 103.216921 -380.91082) (xy 103.169155 -380.916847) (xy 103.145082 -380.917196) (xy 103.117831 -380.916733)
			(xy 103.063883 -380.908974) (xy 103.011589 -380.893617) (xy 102.962013 -380.870974) (xy 102.916163 -380.841506)
			(xy 102.874974 -380.805814) (xy 102.839283 -380.764623) (xy 102.809817 -380.718772) (xy 102.787177 -380.669194)
			(xy 102.771822 -380.616899) (xy 102.764066 -380.562951) (xy 102.764066 -380.508449) (xy 102.771822 -380.454501)
			(xy 102.787177 -380.402206) (xy 102.809817 -380.352628) (xy 102.839283 -380.306777) (xy 102.874974 -380.265586)
			(xy 102.916163 -380.229894) (xy 102.962013 -380.200426) (xy 103.011589 -380.177783) (xy 103.063883 -380.162426)
			(xy 103.117831 -380.154667) (xy 103.145082 -380.15418) (xy 103.174519 -380.154735) (xy 103.232692 -380.163797)
			(xy 103.260906 -380.172214) (xy 103.269509 -380.174604) (xy 103.287338 -380.173813) (xy 103.295704 -380.17069)
			(xy 103.323898 -380.158752) (xy 103.332123 -380.154912) (xy 103.3454 -380.142557) (xy 103.349806 -380.134622)
			(xy 103.362976 -380.108929) (xy 103.394291 -380.060423) (xy 103.41229 -380.037848) (xy 103.417539 -380.030835)
			(xy 103.423399 -380.014343) (xy 103.42372 -380.00559) (xy 103.42372 -379.851666) (xy 103.423367 -379.842918)
			(xy 103.417523 -379.826427) (xy 103.41229 -379.819408) (xy 103.394302 -379.796826) (xy 103.362986 -379.748321)
			(xy 103.349806 -379.722634) (xy 103.345405 -379.714694) (xy 103.332132 -379.702327) (xy 103.323898 -379.698504)
			(xy 103.295704 -379.686566) (xy 103.287322 -379.683522) (xy 103.269522 -379.682743) (xy 103.260906 -379.685042)
			(xy 103.232697 -379.69348) (xy 103.174521 -379.702534) (xy 103.145082 -379.703076) (xy 103.117829 -379.702653)
			(xy 103.063879 -379.694894) (xy 103.011582 -379.679536) (xy 102.962003 -379.656892) (xy 102.916151 -379.627422)
			(xy 102.874959 -379.591728) (xy 102.839267 -379.550535) (xy 102.8098 -379.504681) (xy 102.787158 -379.455101)
			(xy 102.771803 -379.402803) (xy 102.764046 -379.348853) (xy 74.295147 -379.348853) (xy 72.286551 -381.357449)
			(xy 72.917078 -381.357449) (xy 72.917078 -381.302951) (xy 72.924833 -381.249008) (xy 72.940185 -381.196717)
			(xy 72.962823 -381.147143) (xy 72.992285 -381.101295) (xy 73.027971 -381.060106) (xy 73.069155 -381.024415)
			(xy 73.114999 -380.994947) (xy 73.16457 -380.972303) (xy 73.216859 -380.956943) (xy 73.270801 -380.949181)
			(xy 73.29805 -380.948692) (xy 73.321987 -380.949053) (xy 73.369487 -380.955023) (xy 73.415864 -380.966899)
			(xy 73.438258 -380.975362) (xy 73.450196 -380.980188) (xy 73.475088 -380.97714) (xy 73.56602 -380.913894)
			(xy 73.577196 -380.891796) (xy 73.576942 -380.878588) (xy 73.576942 -380.87046) (xy 73.577428 -380.843209)
			(xy 73.585184 -380.789261) (xy 73.600539 -380.736966) (xy 73.623181 -380.687389) (xy 73.652647 -380.641539)
			(xy 73.688338 -380.600348) (xy 73.729529 -380.564657) (xy 73.775379 -380.535191) (xy 73.824956 -380.512549)
			(xy 73.877251 -380.497194) (xy 73.931199 -380.489438) (xy 73.985701 -380.489438) (xy 74.039649 -380.497194)
			(xy 74.091944 -380.512549) (xy 74.141521 -380.535191) (xy 74.187371 -380.564657) (xy 74.228562 -380.600348)
			(xy 74.264253 -380.641539) (xy 74.293719 -380.687389) (xy 74.316361 -380.736966) (xy 74.331716 -380.789261)
			(xy 74.339472 -380.843209) (xy 74.339958 -380.87046) (xy 74.339958 -380.873) (xy 75.805282 -380.873)
			(xy 75.809353 -380.817378) (xy 75.821479 -380.762941) (xy 75.841402 -380.71085) (xy 75.868698 -380.662215)
			(xy 75.902784 -380.618072) (xy 75.942933 -380.579363) (xy 75.988291 -380.546912) (xy 76.037891 -380.521411)
			(xy 76.090675 -380.503404) (xy 76.145518 -380.493274) (xy 76.201252 -380.491237) (xy 76.256689 -380.497337)
			(xy 76.310646 -380.511443) (xy 76.361975 -380.533255) (xy 76.409581 -380.562309) (xy 76.452449 -380.597984)
			(xy 76.489666 -380.639521) (xy 76.520439 -380.686034) (xy 76.544111 -380.736531) (xy 76.560179 -380.789938)
			(xy 76.568299 -380.845114) (xy 76.568808 -380.873) (xy 76.568299 -380.900886) (xy 76.560179 -380.956062)
			(xy 76.544111 -381.009469) (xy 76.520439 -381.059966) (xy 76.489666 -381.106479) (xy 76.452449 -381.148016)
			(xy 76.409581 -381.183691) (xy 76.361975 -381.212745) (xy 76.310646 -381.234557) (xy 76.256689 -381.248663)
			(xy 76.201252 -381.254763) (xy 76.145518 -381.252726) (xy 76.090675 -381.242596) (xy 76.037891 -381.224589)
			(xy 75.988291 -381.199088) (xy 75.942933 -381.166637) (xy 75.902784 -381.127928) (xy 75.868698 -381.083785)
			(xy 75.841402 -381.03515) (xy 75.821479 -380.983059) (xy 75.809353 -380.928622) (xy 75.805282 -380.873)
			(xy 74.339958 -380.873) (xy 74.339958 -380.878588) (xy 74.339704 -380.891796) (xy 74.35088 -380.913894)
			(xy 74.441812 -380.97714) (xy 74.466704 -380.980188) (xy 74.478642 -380.975362) (xy 74.501042 -380.96692)
			(xy 74.547419 -380.955051) (xy 74.594914 -380.949067) (xy 74.61885 -380.948692) (xy 74.646105 -380.949152)
			(xy 74.700062 -380.956903) (xy 74.752365 -380.972255) (xy 74.801952 -380.994894) (xy 74.847811 -381.024361)
			(xy 74.88901 -381.060055) (xy 74.924709 -381.101249) (xy 74.954182 -381.147104) (xy 74.976828 -381.196688)
			(xy 74.992186 -381.24899) (xy 74.999945 -381.302945) (xy 74.999945 -381.357455) (xy 74.992186 -381.41141)
			(xy 74.976828 -381.463712) (xy 74.954182 -381.513296) (xy 74.924709 -381.559151) (xy 74.88901 -381.600345)
			(xy 74.847811 -381.636039) (xy 74.801952 -381.665506) (xy 74.752365 -381.688145) (xy 74.700062 -381.703497)
			(xy 74.646105 -381.711248) (xy 74.61885 -381.711708) (xy 74.589413 -381.711146) (xy 74.53124 -381.702089)
			(xy 74.503026 -381.693674) (xy 74.494419 -381.691301) (xy 74.476594 -381.692081) (xy 74.468228 -381.695198)
			(xy 74.440034 -381.707136) (xy 74.431817 -381.71099) (xy 74.418535 -381.723335) (xy 74.414126 -381.731266)
			(xy 74.400952 -381.756957) (xy 74.369639 -381.805465) (xy 74.351642 -381.82804) (xy 74.34639 -381.835051)
			(xy 74.340533 -381.851545) (xy 74.340212 -381.860298) (xy 74.340212 -382.014222) (xy 74.340564 -382.02297)
			(xy 74.346408 -382.039461) (xy 74.351642 -382.04648) (xy 74.369624 -382.069067) (xy 74.400943 -382.117569)
			(xy 74.414126 -382.143254) (xy 74.418526 -382.151195) (xy 74.431801 -382.163558) (xy 74.440034 -382.167384)
			(xy 74.468228 -382.179322) (xy 74.476605 -382.18238) (xy 74.494409 -382.183148) (xy 74.503026 -382.180846)
			(xy 74.531239 -382.172423) (xy 74.589412 -382.163359) (xy 74.61885 -382.162812) (xy 74.646107 -382.163231)
			(xy 74.700066 -382.170983) (xy 74.752373 -382.186336) (xy 74.801962 -382.208976) (xy 74.846334 -382.237488)
			(xy 101.620064 -382.237488) (xy 101.624135 -382.181866) (xy 101.636261 -382.127429) (xy 101.656184 -382.075338)
			(xy 101.68348 -382.026703) (xy 101.717566 -381.98256) (xy 101.757715 -381.943851) (xy 101.803073 -381.9114)
			(xy 101.852673 -381.885899) (xy 101.905457 -381.867892) (xy 101.9603 -381.857762) (xy 102.016034 -381.855725)
			(xy 102.071471 -381.861825) (xy 102.125428 -381.875931) (xy 102.176757 -381.897743) (xy 102.224363 -381.926797)
			(xy 102.244566 -381.94361) (xy 105.24693 -381.94361) (xy 105.251001 -381.887988) (xy 105.263127 -381.833551)
			(xy 105.28305 -381.78146) (xy 105.310346 -381.732825) (xy 105.344432 -381.688682) (xy 105.384581 -381.649973)
			(xy 105.429939 -381.617522) (xy 105.479539 -381.592021) (xy 105.532323 -381.574014) (xy 105.587166 -381.563884)
			(xy 105.6429 -381.561847) (xy 105.698337 -381.567947) (xy 105.752294 -381.582053) (xy 105.803623 -381.603865)
			(xy 105.851229 -381.632919) (xy 105.894097 -381.668594) (xy 105.931314 -381.710131) (xy 105.962087 -381.756644)
			(xy 105.985759 -381.807141) (xy 106.001827 -381.860548) (xy 106.009947 -381.915724) (xy 106.010456 -381.94361)
			(xy 106.009947 -381.971496) (xy 106.001827 -382.026672) (xy 105.985759 -382.080079) (xy 105.962087 -382.130576)
			(xy 105.931314 -382.177089) (xy 105.894097 -382.218626) (xy 105.851229 -382.254301) (xy 105.803623 -382.283355)
			(xy 105.752294 -382.305167) (xy 105.698337 -382.319273) (xy 105.6429 -382.325373) (xy 105.587166 -382.323336)
			(xy 105.532323 -382.313206) (xy 105.479539 -382.295199) (xy 105.429939 -382.269698) (xy 105.384581 -382.237247)
			(xy 105.344432 -382.198538) (xy 105.310346 -382.154395) (xy 105.28305 -382.10576) (xy 105.263127 -382.053669)
			(xy 105.251001 -381.999232) (xy 105.24693 -381.94361) (xy 102.244566 -381.94361) (xy 102.267231 -381.962472)
			(xy 102.304448 -382.004009) (xy 102.335221 -382.050522) (xy 102.358893 -382.101019) (xy 102.374961 -382.154426)
			(xy 102.383081 -382.209602) (xy 102.38359 -382.237488) (xy 102.383081 -382.265374) (xy 102.374961 -382.32055)
			(xy 102.358893 -382.373957) (xy 102.335221 -382.424454) (xy 102.304448 -382.470967) (xy 102.267231 -382.512504)
			(xy 102.224363 -382.548179) (xy 102.176757 -382.577233) (xy 102.125428 -382.599045) (xy 102.071471 -382.613151)
			(xy 102.016034 -382.619251) (xy 101.9603 -382.617214) (xy 101.905457 -382.607084) (xy 101.852673 -382.589077)
			(xy 101.803073 -382.563576) (xy 101.757715 -382.531125) (xy 101.717566 -382.492416) (xy 101.68348 -382.448273)
			(xy 101.656184 -382.399638) (xy 101.636261 -382.347547) (xy 101.624135 -382.29311) (xy 101.620064 -382.237488)
			(xy 74.846334 -382.237488) (xy 74.847823 -382.238445) (xy 74.889024 -382.27414) (xy 74.924725 -382.315336)
			(xy 74.9542 -382.361194) (xy 74.976847 -382.410781) (xy 74.992206 -382.463085) (xy 74.999965 -382.517043)
			(xy 74.999965 -382.571557) (xy 74.992206 -382.625515) (xy 74.976847 -382.677819) (xy 74.9542 -382.727406)
			(xy 74.924725 -382.773264) (xy 74.889024 -382.81446) (xy 74.847823 -382.850155) (xy 74.809331 -382.874889)
			(xy 77.570068 -382.874889) (xy 77.570068 -382.822911) (xy 77.578198 -382.771574) (xy 77.594259 -382.72214)
			(xy 77.617856 -382.675828) (xy 77.648406 -382.633776) (xy 77.685158 -382.597021) (xy 77.727207 -382.566468)
			(xy 77.773518 -382.542869) (xy 77.822951 -382.526804) (xy 77.874287 -382.518669) (xy 77.900276 -382.518158)
			(xy 77.926317 -382.518672) (xy 77.977757 -382.526826) (xy 78.02728 -382.542952) (xy 78.073658 -382.566649)
			(xy 78.115743 -382.597332) (xy 78.134464 -382.61544) (xy 78.141068 -382.622044) (xy 78.15707 -382.62941)
			(xy 78.241398 -382.636522) (xy 78.258416 -382.631696) (xy 78.265782 -382.626362) (xy 78.286989 -382.611691)
			(xy 78.333018 -382.588445) (xy 78.382098 -382.572628) (xy 78.433039 -382.564625) (xy 78.458822 -382.564132)
			(xy 78.483658 -382.564604) (xy 78.532774 -382.572017) (xy 78.580225 -382.586703) (xy 78.624942 -382.608329)
			(xy 78.665916 -382.636409) (xy 78.684374 -382.653032) (xy 78.691433 -382.659081) (xy 78.708627 -382.66611)
			(xy 78.717902 -382.666748) (xy 78.749144 -382.66751) (xy 78.758398 -382.667333) (xy 78.77585 -382.661222)
			(xy 78.78318 -382.655572) (xy 78.805727 -382.637384) (xy 78.855864 -382.608373) (xy 78.910282 -382.588526)
			(xy 78.967324 -382.578447) (xy 78.996286 -382.577848) (xy 79.022273 -382.578418) (xy 79.073606 -382.586546)
			(xy 79.123036 -382.602605) (xy 79.169345 -382.626199) (xy 79.211393 -382.656747) (xy 79.248144 -382.693497)
			(xy 79.278694 -382.735543) (xy 79.302289 -382.781851) (xy 79.31835 -382.83128) (xy 79.325896 -382.878917)
			(xy 80.014066 -382.878917) (xy 80.014066 -382.826943) (xy 80.022196 -382.775608) (xy 80.038257 -382.726178)
			(xy 80.061853 -382.679868) (xy 80.092403 -382.63782) (xy 80.129154 -382.601069) (xy 80.171202 -382.570519)
			(xy 80.217512 -382.546923) (xy 80.266942 -382.530862) (xy 80.318277 -382.522732) (xy 80.370251 -382.522732)
			(xy 80.421586 -382.530862) (xy 80.471016 -382.546923) (xy 80.517326 -382.570519) (xy 80.559374 -382.601069)
			(xy 80.596125 -382.63782) (xy 80.626675 -382.679868) (xy 80.650271 -382.726178) (xy 80.666332 -382.775608)
			(xy 80.674462 -382.826943) (xy 80.674972 -382.85293) (xy 80.674462 -382.878917) (xy 81.214216 -382.878917)
			(xy 81.214216 -382.826943) (xy 81.222346 -382.775608) (xy 81.238407 -382.726178) (xy 81.262003 -382.679868)
			(xy 81.292553 -382.63782) (xy 81.329304 -382.601069) (xy 81.371352 -382.570519) (xy 81.417662 -382.546923)
			(xy 81.467092 -382.530862) (xy 81.518427 -382.522732) (xy 81.570401 -382.522732) (xy 81.621736 -382.530862)
			(xy 81.671166 -382.546923) (xy 81.717476 -382.570519) (xy 81.759524 -382.601069) (xy 81.796275 -382.63782)
			(xy 81.826825 -382.679868) (xy 81.850421 -382.726178) (xy 81.866482 -382.775608) (xy 81.874612 -382.826943)
			(xy 81.875122 -382.85293) (xy 81.874612 -382.878917) (xy 82.414112 -382.878917) (xy 82.414112 -382.826943)
			(xy 82.422242 -382.775608) (xy 82.438303 -382.726178) (xy 82.461899 -382.679868) (xy 82.492449 -382.63782)
			(xy 82.5292 -382.601069) (xy 82.571248 -382.570519) (xy 82.617558 -382.546923) (xy 82.666988 -382.530862)
			(xy 82.718323 -382.522732) (xy 82.770297 -382.522732) (xy 82.821632 -382.530862) (xy 82.871062 -382.546923)
			(xy 82.917372 -382.570519) (xy 82.95942 -382.601069) (xy 82.996171 -382.63782) (xy 83.026721 -382.679868)
			(xy 83.050317 -382.726178) (xy 83.066378 -382.775608) (xy 83.074508 -382.826943) (xy 83.075018 -382.85293)
			(xy 83.074508 -382.878917) (xy 83.614008 -382.878917) (xy 83.614008 -382.826943) (xy 83.622138 -382.775608)
			(xy 83.638199 -382.726178) (xy 83.661795 -382.679868) (xy 83.692345 -382.63782) (xy 83.729096 -382.601069)
			(xy 83.771144 -382.570519) (xy 83.817454 -382.546923) (xy 83.866884 -382.530862) (xy 83.918219 -382.522732)
			(xy 83.970193 -382.522732) (xy 84.021528 -382.530862) (xy 84.070958 -382.546923) (xy 84.117268 -382.570519)
			(xy 84.159316 -382.601069) (xy 84.196067 -382.63782) (xy 84.226617 -382.679868) (xy 84.250213 -382.726178)
			(xy 84.266274 -382.775608) (xy 84.274404 -382.826943) (xy 84.274914 -382.85293) (xy 84.274404 -382.878917)
			(xy 84.814158 -382.878917) (xy 84.814158 -382.826943) (xy 84.822288 -382.775608) (xy 84.838349 -382.726178)
			(xy 84.861945 -382.679868) (xy 84.892495 -382.63782) (xy 84.929246 -382.601069) (xy 84.971294 -382.570519)
			(xy 85.017604 -382.546923) (xy 85.067034 -382.530862) (xy 85.118369 -382.522732) (xy 85.170343 -382.522732)
			(xy 85.221678 -382.530862) (xy 85.271108 -382.546923) (xy 85.317418 -382.570519) (xy 85.359466 -382.601069)
			(xy 85.396217 -382.63782) (xy 85.426767 -382.679868) (xy 85.450363 -382.726178) (xy 85.466424 -382.775608)
			(xy 85.474554 -382.826943) (xy 85.475064 -382.85293) (xy 85.474554 -382.878917) (xy 86.014054 -382.878917)
			(xy 86.014054 -382.826943) (xy 86.022184 -382.775608) (xy 86.038245 -382.726178) (xy 86.061841 -382.679868)
			(xy 86.092391 -382.63782) (xy 86.129142 -382.601069) (xy 86.17119 -382.570519) (xy 86.2175 -382.546923)
			(xy 86.26693 -382.530862) (xy 86.318265 -382.522732) (xy 86.370239 -382.522732) (xy 86.421574 -382.530862)
			(xy 86.471004 -382.546923) (xy 86.517314 -382.570519) (xy 86.559362 -382.601069) (xy 86.596113 -382.63782)
			(xy 86.626663 -382.679868) (xy 86.650259 -382.726178) (xy 86.66632 -382.775608) (xy 86.67445 -382.826943)
			(xy 86.67496 -382.85293) (xy 86.67445 -382.878917) (xy 87.214204 -382.878917) (xy 87.214204 -382.826943)
			(xy 87.222334 -382.775608) (xy 87.238395 -382.726178) (xy 87.261991 -382.679868) (xy 87.292541 -382.63782)
			(xy 87.329292 -382.601069) (xy 87.37134 -382.570519) (xy 87.41765 -382.546923) (xy 87.46708 -382.530862)
			(xy 87.518415 -382.522732) (xy 87.570389 -382.522732) (xy 87.621724 -382.530862) (xy 87.671154 -382.546923)
			(xy 87.717464 -382.570519) (xy 87.759512 -382.601069) (xy 87.796263 -382.63782) (xy 87.826813 -382.679868)
			(xy 87.850409 -382.726178) (xy 87.86647 -382.775608) (xy 87.8746 -382.826943) (xy 87.87511 -382.85293)
			(xy 87.8746 -382.878917) (xy 88.4141 -382.878917) (xy 88.4141 -382.826943) (xy 88.42223 -382.775608)
			(xy 88.438291 -382.726178) (xy 88.461887 -382.679868) (xy 88.492437 -382.63782) (xy 88.529188 -382.601069)
			(xy 88.571236 -382.570519) (xy 88.617546 -382.546923) (xy 88.666976 -382.530862) (xy 88.718311 -382.522732)
			(xy 88.770285 -382.522732) (xy 88.82162 -382.530862) (xy 88.87105 -382.546923) (xy 88.91736 -382.570519)
			(xy 88.959408 -382.601069) (xy 88.996159 -382.63782) (xy 89.026709 -382.679868) (xy 89.050305 -382.726178)
			(xy 89.066366 -382.775608) (xy 89.074496 -382.826943) (xy 89.075006 -382.85293) (xy 89.074496 -382.878917)
			(xy 89.613996 -382.878917) (xy 89.613996 -382.826943) (xy 89.622126 -382.775608) (xy 89.638187 -382.726178)
			(xy 89.661783 -382.679868) (xy 89.692333 -382.63782) (xy 89.729084 -382.601069) (xy 89.771132 -382.570519)
			(xy 89.817442 -382.546923) (xy 89.866872 -382.530862) (xy 89.918207 -382.522732) (xy 89.970181 -382.522732)
			(xy 90.021516 -382.530862) (xy 90.070946 -382.546923) (xy 90.117256 -382.570519) (xy 90.159304 -382.601069)
			(xy 90.196055 -382.63782) (xy 90.226605 -382.679868) (xy 90.250201 -382.726178) (xy 90.266262 -382.775608)
			(xy 90.274392 -382.826943) (xy 90.274902 -382.85293) (xy 90.274392 -382.878917) (xy 90.814146 -382.878917)
			(xy 90.814146 -382.826943) (xy 90.822276 -382.775608) (xy 90.838337 -382.726178) (xy 90.861933 -382.679868)
			(xy 90.892483 -382.63782) (xy 90.929234 -382.601069) (xy 90.971282 -382.570519) (xy 91.017592 -382.546923)
			(xy 91.067022 -382.530862) (xy 91.118357 -382.522732) (xy 91.170331 -382.522732) (xy 91.221666 -382.530862)
			(xy 91.271096 -382.546923) (xy 91.317406 -382.570519) (xy 91.359454 -382.601069) (xy 91.396205 -382.63782)
			(xy 91.426755 -382.679868) (xy 91.450351 -382.726178) (xy 91.466412 -382.775608) (xy 91.474542 -382.826943)
			(xy 91.475052 -382.85293) (xy 91.474542 -382.878917) (xy 92.014042 -382.878917) (xy 92.014042 -382.826943)
			(xy 92.022172 -382.775608) (xy 92.038233 -382.726178) (xy 92.061829 -382.679868) (xy 92.092379 -382.63782)
			(xy 92.12913 -382.601069) (xy 92.171178 -382.570519) (xy 92.217488 -382.546923) (xy 92.266918 -382.530862)
			(xy 92.318253 -382.522732) (xy 92.370227 -382.522732) (xy 92.421562 -382.530862) (xy 92.470992 -382.546923)
			(xy 92.517302 -382.570519) (xy 92.55935 -382.601069) (xy 92.596101 -382.63782) (xy 92.626651 -382.679868)
			(xy 92.650247 -382.726178) (xy 92.666308 -382.775608) (xy 92.674438 -382.826943) (xy 92.674948 -382.85293)
			(xy 92.674438 -382.878917) (xy 93.214192 -382.878917) (xy 93.214192 -382.826943) (xy 93.222322 -382.775608)
			(xy 93.238383 -382.726178) (xy 93.261979 -382.679868) (xy 93.292529 -382.63782) (xy 93.32928 -382.601069)
			(xy 93.371328 -382.570519) (xy 93.417638 -382.546923) (xy 93.467068 -382.530862) (xy 93.518403 -382.522732)
			(xy 93.570377 -382.522732) (xy 93.621712 -382.530862) (xy 93.671142 -382.546923) (xy 93.717452 -382.570519)
			(xy 93.7595 -382.601069) (xy 93.796251 -382.63782) (xy 93.826801 -382.679868) (xy 93.850397 -382.726178)
			(xy 93.866458 -382.775608) (xy 93.874588 -382.826943) (xy 93.875098 -382.85293) (xy 93.874588 -382.878917)
			(xy 94.414088 -382.878917) (xy 94.414088 -382.826943) (xy 94.422218 -382.775608) (xy 94.438279 -382.726178)
			(xy 94.461875 -382.679868) (xy 94.492425 -382.63782) (xy 94.529176 -382.601069) (xy 94.571224 -382.570519)
			(xy 94.617534 -382.546923) (xy 94.666964 -382.530862) (xy 94.718299 -382.522732) (xy 94.770273 -382.522732)
			(xy 94.821608 -382.530862) (xy 94.871038 -382.546923) (xy 94.917348 -382.570519) (xy 94.959396 -382.601069)
			(xy 94.996147 -382.63782) (xy 95.026697 -382.679868) (xy 95.050293 -382.726178) (xy 95.066354 -382.775608)
			(xy 95.074484 -382.826943) (xy 95.074994 -382.85293) (xy 95.074484 -382.878917) (xy 95.613984 -382.878917)
			(xy 95.613984 -382.826943) (xy 95.622114 -382.775608) (xy 95.638175 -382.726178) (xy 95.661771 -382.679868)
			(xy 95.692321 -382.63782) (xy 95.729072 -382.601069) (xy 95.77112 -382.570519) (xy 95.81743 -382.546923)
			(xy 95.86686 -382.530862) (xy 95.918195 -382.522732) (xy 95.970169 -382.522732) (xy 96.021504 -382.530862)
			(xy 96.070934 -382.546923) (xy 96.117244 -382.570519) (xy 96.159292 -382.601069) (xy 96.196043 -382.63782)
			(xy 96.226593 -382.679868) (xy 96.250189 -382.726178) (xy 96.26625 -382.775608) (xy 96.27438 -382.826943)
			(xy 96.27489 -382.85293) (xy 96.27438 -382.878917) (xy 96.814134 -382.878917) (xy 96.814134 -382.826943)
			(xy 96.822264 -382.775608) (xy 96.838325 -382.726178) (xy 96.861921 -382.679868) (xy 96.892471 -382.63782)
			(xy 96.929222 -382.601069) (xy 96.97127 -382.570519) (xy 97.01758 -382.546923) (xy 97.06701 -382.530862)
			(xy 97.118345 -382.522732) (xy 97.170319 -382.522732) (xy 97.221654 -382.530862) (xy 97.271084 -382.546923)
			(xy 97.317394 -382.570519) (xy 97.359442 -382.601069) (xy 97.396193 -382.63782) (xy 97.426743 -382.679868)
			(xy 97.450339 -382.726178) (xy 97.4664 -382.775608) (xy 97.47453 -382.826943) (xy 97.47504 -382.85293)
			(xy 97.47453 -382.878917) (xy 98.01403 -382.878917) (xy 98.01403 -382.826943) (xy 98.02216 -382.775608)
			(xy 98.038221 -382.726178) (xy 98.061817 -382.679868) (xy 98.092367 -382.63782) (xy 98.129118 -382.601069)
			(xy 98.171166 -382.570519) (xy 98.217476 -382.546923) (xy 98.266906 -382.530862) (xy 98.318241 -382.522732)
			(xy 98.370215 -382.522732) (xy 98.42155 -382.530862) (xy 98.47098 -382.546923) (xy 98.51729 -382.570519)
			(xy 98.559338 -382.601069) (xy 98.596089 -382.63782) (xy 98.626639 -382.679868) (xy 98.650235 -382.726178)
			(xy 98.666296 -382.775608) (xy 98.674426 -382.826943) (xy 98.674936 -382.85293) (xy 98.674426 -382.878917)
			(xy 98.672007 -382.894189) (xy 99.081072 -382.894189) (xy 99.081072 -382.842211) (xy 99.089202 -382.790874)
			(xy 99.105264 -382.74144) (xy 99.12886 -382.695128) (xy 99.159411 -382.653077) (xy 99.196163 -382.616322)
			(xy 99.238213 -382.585769) (xy 99.284524 -382.562171) (xy 99.333956 -382.546107) (xy 99.385293 -382.537973)
			(xy 99.411282 -382.537462) (xy 99.435056 -382.537864) (xy 99.482116 -382.544666) (xy 99.527714 -382.558148)
			(xy 99.570906 -382.578029) (xy 99.610801 -382.603899) (xy 99.62896 -382.61925) (xy 99.636076 -382.624941)
			(xy 99.65313 -382.631322) (xy 99.662234 -382.631696) (xy 99.69373 -382.631696) (xy 99.702832 -382.631316)
			(xy 99.719882 -382.624932) (xy 99.727004 -382.61925) (xy 99.745165 -382.603904) (xy 99.785066 -382.578047)
			(xy 99.828259 -382.558172) (xy 99.873853 -382.544689) (xy 99.920909 -382.537876) (xy 99.944682 -382.537462)
			(xy 99.97067 -382.538004) (xy 100.022006 -382.546132) (xy 100.071438 -382.562191) (xy 100.11775 -382.585786)
			(xy 100.1598 -382.616335) (xy 100.196553 -382.653086) (xy 100.227105 -382.695135) (xy 100.250702 -382.741445)
			(xy 100.266764 -382.790877) (xy 100.274895 -382.842212) (xy 100.274895 -382.894188) (xy 100.266764 -382.945523)
			(xy 100.250702 -382.994955) (xy 100.227105 -383.041265) (xy 100.196553 -383.083314) (xy 100.1598 -383.120065)
			(xy 100.11775 -383.150614) (xy 100.071438 -383.174209) (xy 100.022006 -383.190268) (xy 99.97067 -383.198396)
			(xy 99.944682 -383.198878) (xy 99.920907 -383.198488) (xy 99.873848 -383.191681) (xy 99.82825 -383.178196)
			(xy 99.785058 -383.158313) (xy 99.745163 -383.132441) (xy 99.727004 -383.11709) (xy 99.719903 -383.111377)
			(xy 99.702838 -383.105011) (xy 99.69373 -383.104644) (xy 99.662234 -383.104644) (xy 99.653134 -383.105046)
			(xy 99.636083 -383.111414) (xy 99.62896 -383.11709) (xy 99.61078 -383.132413) (xy 99.570884 -383.158272)
			(xy 99.527696 -383.178151) (xy 99.482106 -383.19164) (xy 99.435054 -383.19846) (xy 99.411282 -383.198878)
			(xy 99.385293 -383.198427) (xy 99.333956 -383.190293) (xy 99.284524 -383.174229) (xy 99.238213 -383.150631)
			(xy 99.196163 -383.120078) (xy 99.159411 -383.083323) (xy 99.12886 -383.041272) (xy 99.105264 -382.99496)
			(xy 99.089202 -382.945526) (xy 99.081072 -382.894189) (xy 98.672007 -382.894189) (xy 98.666296 -382.930252)
			(xy 98.650235 -382.979682) (xy 98.626639 -383.025992) (xy 98.596089 -383.06804) (xy 98.559338 -383.104791)
			(xy 98.51729 -383.135341) (xy 98.47098 -383.158937) (xy 98.42155 -383.174998) (xy 98.370215 -383.183128)
			(xy 98.318241 -383.183128) (xy 98.266906 -383.174998) (xy 98.217476 -383.158937) (xy 98.171166 -383.135341)
			(xy 98.129118 -383.104791) (xy 98.092367 -383.06804) (xy 98.061817 -383.025992) (xy 98.038221 -382.979682)
			(xy 98.02216 -382.930252) (xy 98.01403 -382.878917) (xy 97.47453 -382.878917) (xy 97.4664 -382.930252)
			(xy 97.450339 -382.979682) (xy 97.426743 -383.025992) (xy 97.396193 -383.06804) (xy 97.359442 -383.104791)
			(xy 97.317394 -383.135341) (xy 97.271084 -383.158937) (xy 97.221654 -383.174998) (xy 97.170319 -383.183128)
			(xy 97.118345 -383.183128) (xy 97.06701 -383.174998) (xy 97.01758 -383.158937) (xy 96.97127 -383.135341)
			(xy 96.929222 -383.104791) (xy 96.892471 -383.06804) (xy 96.861921 -383.025992) (xy 96.838325 -382.979682)
			(xy 96.822264 -382.930252) (xy 96.814134 -382.878917) (xy 96.27438 -382.878917) (xy 96.26625 -382.930252)
			(xy 96.250189 -382.979682) (xy 96.226593 -383.025992) (xy 96.196043 -383.06804) (xy 96.159292 -383.104791)
			(xy 96.117244 -383.135341) (xy 96.070934 -383.158937) (xy 96.021504 -383.174998) (xy 95.970169 -383.183128)
			(xy 95.918195 -383.183128) (xy 95.86686 -383.174998) (xy 95.81743 -383.158937) (xy 95.77112 -383.135341)
			(xy 95.729072 -383.104791) (xy 95.692321 -383.06804) (xy 95.661771 -383.025992) (xy 95.638175 -382.979682)
			(xy 95.622114 -382.930252) (xy 95.613984 -382.878917) (xy 95.074484 -382.878917) (xy 95.066354 -382.930252)
			(xy 95.050293 -382.979682) (xy 95.026697 -383.025992) (xy 94.996147 -383.06804) (xy 94.959396 -383.104791)
			(xy 94.917348 -383.135341) (xy 94.871038 -383.158937) (xy 94.821608 -383.174998) (xy 94.770273 -383.183128)
			(xy 94.718299 -383.183128) (xy 94.666964 -383.174998) (xy 94.617534 -383.158937) (xy 94.571224 -383.135341)
			(xy 94.529176 -383.104791) (xy 94.492425 -383.06804) (xy 94.461875 -383.025992) (xy 94.438279 -382.979682)
			(xy 94.422218 -382.930252) (xy 94.414088 -382.878917) (xy 93.874588 -382.878917) (xy 93.866458 -382.930252)
			(xy 93.850397 -382.979682) (xy 93.826801 -383.025992) (xy 93.796251 -383.06804) (xy 93.7595 -383.104791)
			(xy 93.717452 -383.135341) (xy 93.671142 -383.158937) (xy 93.621712 -383.174998) (xy 93.570377 -383.183128)
			(xy 93.518403 -383.183128) (xy 93.467068 -383.174998) (xy 93.417638 -383.158937) (xy 93.371328 -383.135341)
			(xy 93.32928 -383.104791) (xy 93.292529 -383.06804) (xy 93.261979 -383.025992) (xy 93.238383 -382.979682)
			(xy 93.222322 -382.930252) (xy 93.214192 -382.878917) (xy 92.674438 -382.878917) (xy 92.666308 -382.930252)
			(xy 92.650247 -382.979682) (xy 92.626651 -383.025992) (xy 92.596101 -383.06804) (xy 92.55935 -383.104791)
			(xy 92.517302 -383.135341) (xy 92.470992 -383.158937) (xy 92.421562 -383.174998) (xy 92.370227 -383.183128)
			(xy 92.318253 -383.183128) (xy 92.266918 -383.174998) (xy 92.217488 -383.158937) (xy 92.171178 -383.135341)
			(xy 92.12913 -383.104791) (xy 92.092379 -383.06804) (xy 92.061829 -383.025992) (xy 92.038233 -382.979682)
			(xy 92.022172 -382.930252) (xy 92.014042 -382.878917) (xy 91.474542 -382.878917) (xy 91.466412 -382.930252)
			(xy 91.450351 -382.979682) (xy 91.426755 -383.025992) (xy 91.396205 -383.06804) (xy 91.359454 -383.104791)
			(xy 91.317406 -383.135341) (xy 91.271096 -383.158937) (xy 91.221666 -383.174998) (xy 91.170331 -383.183128)
			(xy 91.118357 -383.183128) (xy 91.067022 -383.174998) (xy 91.017592 -383.158937) (xy 90.971282 -383.135341)
			(xy 90.929234 -383.104791) (xy 90.892483 -383.06804) (xy 90.861933 -383.025992) (xy 90.838337 -382.979682)
			(xy 90.822276 -382.930252) (xy 90.814146 -382.878917) (xy 90.274392 -382.878917) (xy 90.266262 -382.930252)
			(xy 90.250201 -382.979682) (xy 90.226605 -383.025992) (xy 90.196055 -383.06804) (xy 90.159304 -383.104791)
			(xy 90.117256 -383.135341) (xy 90.070946 -383.158937) (xy 90.021516 -383.174998) (xy 89.970181 -383.183128)
			(xy 89.918207 -383.183128) (xy 89.866872 -383.174998) (xy 89.817442 -383.158937) (xy 89.771132 -383.135341)
			(xy 89.729084 -383.104791) (xy 89.692333 -383.06804) (xy 89.661783 -383.025992) (xy 89.638187 -382.979682)
			(xy 89.622126 -382.930252) (xy 89.613996 -382.878917) (xy 89.074496 -382.878917) (xy 89.066366 -382.930252)
			(xy 89.050305 -382.979682) (xy 89.026709 -383.025992) (xy 88.996159 -383.06804) (xy 88.959408 -383.104791)
			(xy 88.91736 -383.135341) (xy 88.87105 -383.158937) (xy 88.82162 -383.174998) (xy 88.770285 -383.183128)
			(xy 88.718311 -383.183128) (xy 88.666976 -383.174998) (xy 88.617546 -383.158937) (xy 88.571236 -383.135341)
			(xy 88.529188 -383.104791) (xy 88.492437 -383.06804) (xy 88.461887 -383.025992) (xy 88.438291 -382.979682)
			(xy 88.42223 -382.930252) (xy 88.4141 -382.878917) (xy 87.8746 -382.878917) (xy 87.86647 -382.930252)
			(xy 87.850409 -382.979682) (xy 87.826813 -383.025992) (xy 87.796263 -383.06804) (xy 87.759512 -383.104791)
			(xy 87.717464 -383.135341) (xy 87.671154 -383.158937) (xy 87.621724 -383.174998) (xy 87.570389 -383.183128)
			(xy 87.518415 -383.183128) (xy 87.46708 -383.174998) (xy 87.41765 -383.158937) (xy 87.37134 -383.135341)
			(xy 87.329292 -383.104791) (xy 87.292541 -383.06804) (xy 87.261991 -383.025992) (xy 87.238395 -382.979682)
			(xy 87.222334 -382.930252) (xy 87.214204 -382.878917) (xy 86.67445 -382.878917) (xy 86.66632 -382.930252)
			(xy 86.650259 -382.979682) (xy 86.626663 -383.025992) (xy 86.596113 -383.06804) (xy 86.559362 -383.104791)
			(xy 86.517314 -383.135341) (xy 86.471004 -383.158937) (xy 86.421574 -383.174998) (xy 86.370239 -383.183128)
			(xy 86.318265 -383.183128) (xy 86.26693 -383.174998) (xy 86.2175 -383.158937) (xy 86.17119 -383.135341)
			(xy 86.129142 -383.104791) (xy 86.092391 -383.06804) (xy 86.061841 -383.025992) (xy 86.038245 -382.979682)
			(xy 86.022184 -382.930252) (xy 86.014054 -382.878917) (xy 85.474554 -382.878917) (xy 85.466424 -382.930252)
			(xy 85.450363 -382.979682) (xy 85.426767 -383.025992) (xy 85.396217 -383.06804) (xy 85.359466 -383.104791)
			(xy 85.317418 -383.135341) (xy 85.271108 -383.158937) (xy 85.221678 -383.174998) (xy 85.170343 -383.183128)
			(xy 85.118369 -383.183128) (xy 85.067034 -383.174998) (xy 85.017604 -383.158937) (xy 84.971294 -383.135341)
			(xy 84.929246 -383.104791) (xy 84.892495 -383.06804) (xy 84.861945 -383.025992) (xy 84.838349 -382.979682)
			(xy 84.822288 -382.930252) (xy 84.814158 -382.878917) (xy 84.274404 -382.878917) (xy 84.266274 -382.930252)
			(xy 84.250213 -382.979682) (xy 84.226617 -383.025992) (xy 84.196067 -383.06804) (xy 84.159316 -383.104791)
			(xy 84.117268 -383.135341) (xy 84.070958 -383.158937) (xy 84.021528 -383.174998) (xy 83.970193 -383.183128)
			(xy 83.918219 -383.183128) (xy 83.866884 -383.174998) (xy 83.817454 -383.158937) (xy 83.771144 -383.135341)
			(xy 83.729096 -383.104791) (xy 83.692345 -383.06804) (xy 83.661795 -383.025992) (xy 83.638199 -382.979682)
			(xy 83.622138 -382.930252) (xy 83.614008 -382.878917) (xy 83.074508 -382.878917) (xy 83.066378 -382.930252)
			(xy 83.050317 -382.979682) (xy 83.026721 -383.025992) (xy 82.996171 -383.06804) (xy 82.95942 -383.104791)
			(xy 82.917372 -383.135341) (xy 82.871062 -383.158937) (xy 82.821632 -383.174998) (xy 82.770297 -383.183128)
			(xy 82.718323 -383.183128) (xy 82.666988 -383.174998) (xy 82.617558 -383.158937) (xy 82.571248 -383.135341)
			(xy 82.5292 -383.104791) (xy 82.492449 -383.06804) (xy 82.461899 -383.025992) (xy 82.438303 -382.979682)
			(xy 82.422242 -382.930252) (xy 82.414112 -382.878917) (xy 81.874612 -382.878917) (xy 81.866482 -382.930252)
			(xy 81.850421 -382.979682) (xy 81.826825 -383.025992) (xy 81.796275 -383.06804) (xy 81.759524 -383.104791)
			(xy 81.717476 -383.135341) (xy 81.671166 -383.158937) (xy 81.621736 -383.174998) (xy 81.570401 -383.183128)
			(xy 81.518427 -383.183128) (xy 81.467092 -383.174998) (xy 81.417662 -383.158937) (xy 81.371352 -383.135341)
			(xy 81.329304 -383.104791) (xy 81.292553 -383.06804) (xy 81.262003 -383.025992) (xy 81.238407 -382.979682)
			(xy 81.222346 -382.930252) (xy 81.214216 -382.878917) (xy 80.674462 -382.878917) (xy 80.666332 -382.930252)
			(xy 80.650271 -382.979682) (xy 80.626675 -383.025992) (xy 80.596125 -383.06804) (xy 80.559374 -383.104791)
			(xy 80.517326 -383.135341) (xy 80.471016 -383.158937) (xy 80.421586 -383.174998) (xy 80.370251 -383.183128)
			(xy 80.318277 -383.183128) (xy 80.266942 -383.174998) (xy 80.217512 -383.158937) (xy 80.171202 -383.135341)
			(xy 80.129154 -383.104791) (xy 80.092403 -383.06804) (xy 80.061853 -383.025992) (xy 80.038257 -382.979682)
			(xy 80.022196 -382.930252) (xy 80.014066 -382.878917) (xy 79.325896 -382.878917) (xy 79.326481 -382.882613)
			(xy 79.326481 -382.934587) (xy 79.31835 -382.98592) (xy 79.302289 -383.035349) (xy 79.278694 -383.081657)
			(xy 79.248144 -383.123703) (xy 79.211393 -383.160453) (xy 79.169345 -383.191001) (xy 79.123036 -383.214595)
			(xy 79.073606 -383.230654) (xy 79.022273 -383.238782) (xy 78.996286 -383.239264) (xy 78.971448 -383.238849)
			(xy 78.922329 -383.231422) (xy 78.874877 -383.216723) (xy 78.830161 -383.195084) (xy 78.789191 -383.166992)
			(xy 78.770734 -383.150364) (xy 78.763673 -383.144317) (xy 78.74648 -383.137287) (xy 78.737206 -383.136648)
			(xy 78.705964 -383.135886) (xy 78.696711 -383.136068) (xy 78.679258 -383.142175) (xy 78.671928 -383.147824)
			(xy 78.649377 -383.166008) (xy 78.599242 -383.19502) (xy 78.544825 -383.214868) (xy 78.487784 -383.224948)
			(xy 78.458822 -383.225548) (xy 78.432781 -383.225034) (xy 78.381341 -383.216879) (xy 78.331818 -383.200754)
			(xy 78.28544 -383.177056) (xy 78.243355 -383.146374) (xy 78.224634 -383.128266) (xy 78.21803 -383.121662)
			(xy 78.202028 -383.114296) (xy 78.1177 -383.107184) (xy 78.100682 -383.11201) (xy 78.093316 -383.117344)
			(xy 78.07211 -383.132017) (xy 78.026081 -383.155262) (xy 77.977 -383.171078) (xy 77.926059 -383.179081)
			(xy 77.900276 -383.179574) (xy 77.874287 -383.179131) (xy 77.822951 -383.170996) (xy 77.773518 -383.154931)
			(xy 77.727207 -383.131332) (xy 77.685158 -383.100779) (xy 77.648406 -383.064024) (xy 77.617856 -383.021972)
			(xy 77.594259 -382.97566) (xy 77.578198 -382.926226) (xy 77.570068 -382.874889) (xy 74.809331 -382.874889)
			(xy 74.801962 -382.879624) (xy 74.752373 -382.902264) (xy 74.700066 -382.917617) (xy 74.646107 -382.925369)
			(xy 74.61885 -382.925828) (xy 74.594778 -382.925475) (xy 74.547015 -382.919434) (xy 74.50039 -382.907442)
			(xy 74.47788 -382.898904) (xy 74.465434 -382.893824) (xy 74.439526 -382.897126) (xy 74.348848 -382.963928)
			(xy 74.337926 -382.98755) (xy 74.338942 -383.000758) (xy 74.339958 -383.02946) (xy 74.339472 -383.056711)
			(xy 74.331716 -383.110659) (xy 74.316361 -383.162954) (xy 74.293719 -383.212531) (xy 74.264253 -383.258381)
			(xy 74.228562 -383.299572) (xy 74.187371 -383.335263) (xy 74.141521 -383.364729) (xy 74.091944 -383.387371)
			(xy 74.039649 -383.402726) (xy 73.985701 -383.410482) (xy 73.931199 -383.410482) (xy 73.877251 -383.402726)
			(xy 73.824956 -383.387371) (xy 73.775379 -383.364729) (xy 73.729529 -383.335263) (xy 73.688338 -383.299572)
			(xy 73.652647 -383.258381) (xy 73.623181 -383.212531) (xy 73.600539 -383.162954) (xy 73.585184 -383.110659)
			(xy 73.577428 -383.056711) (xy 73.576942 -383.02946) (xy 73.577958 -383.000758) (xy 73.578974 -382.98755)
			(xy 73.568052 -382.963928) (xy 73.477374 -382.897126) (xy 73.451466 -382.893824) (xy 73.43902 -382.898904)
			(xy 73.416516 -382.90746) (xy 73.36989 -382.919457) (xy 73.322123 -382.925481) (xy 73.29805 -382.925828)
			(xy 73.270803 -382.925298) (xy 73.216863 -382.917536) (xy 73.164577 -382.902178) (xy 73.115009 -382.879535)
			(xy 73.069167 -382.850069) (xy 73.027985 -382.814379) (xy 72.992301 -382.773193) (xy 72.962841 -382.727347)
			(xy 72.940205 -382.677776) (xy 72.924853 -382.625488) (xy 72.917098 -382.571548) (xy 72.917098 -382.517052)
			(xy 72.924853 -382.463112) (xy 72.940205 -382.410824) (xy 72.962841 -382.361253) (xy 72.992301 -382.315407)
			(xy 73.027985 -382.274221) (xy 73.069167 -382.238531) (xy 73.115009 -382.209065) (xy 73.164577 -382.186422)
			(xy 73.216863 -382.171064) (xy 73.270803 -382.163302) (xy 73.29805 -382.162812) (xy 73.327487 -382.163373)
			(xy 73.38566 -382.17243) (xy 73.413874 -382.180846) (xy 73.422481 -382.183218) (xy 73.440306 -382.182438)
			(xy 73.448672 -382.179322) (xy 73.476866 -382.167384) (xy 73.485098 -382.163557) (xy 73.498373 -382.151194)
			(xy 73.502774 -382.143254) (xy 73.515938 -382.117558) (xy 73.547258 -382.069054) (xy 73.565258 -382.04648)
			(xy 73.570543 -382.039491) (xy 73.57638 -382.02298) (xy 73.576688 -382.014222) (xy 73.576688 -381.860298)
			(xy 73.576327 -381.851551) (xy 73.570489 -381.835059) (xy 73.565258 -381.82804) (xy 73.547279 -381.805451)
			(xy 73.515958 -381.75695) (xy 73.502774 -381.731266) (xy 73.498368 -381.723329) (xy 73.485097 -381.710963)
			(xy 73.476866 -381.707136) (xy 73.448672 -381.695198) (xy 73.440295 -381.69214) (xy 73.42249 -381.691372)
			(xy 73.413874 -381.693674) (xy 73.385662 -381.702098) (xy 73.327488 -381.711161) (xy 73.29805 -381.711708)
			(xy 73.270801 -381.711219) (xy 73.216859 -381.703457) (xy 73.16457 -381.688097) (xy 73.114999 -381.665453)
			(xy 73.069155 -381.635985) (xy 73.027971 -381.600294) (xy 72.992285 -381.559105) (xy 72.962823 -381.513257)
			(xy 72.940185 -381.463683) (xy 72.924833 -381.411392) (xy 72.917078 -381.357449) (xy 72.286551 -381.357449)
			(xy 70.576186 -383.067814) (xy 70.569332 -383.075209) (xy 70.56159 -383.093808) (xy 70.5612 -383.103882)
			(xy 70.5612 -383.667254) (xy 70.561824 -383.678676) (xy 70.571712 -383.699268) (xy 70.58025 -383.706878)
			(xy 70.605339 -383.727622) (xy 70.620381 -383.7432) (xy 76.211682 -383.7432) (xy 76.215753 -383.687578)
			(xy 76.227879 -383.633141) (xy 76.247802 -383.58105) (xy 76.275098 -383.532415) (xy 76.309184 -383.488272)
			(xy 76.349333 -383.449563) (xy 76.394691 -383.417112) (xy 76.444291 -383.391611) (xy 76.497075 -383.373604)
			(xy 76.551918 -383.363474) (xy 76.607652 -383.361437) (xy 76.663089 -383.367537) (xy 76.717046 -383.381643)
			(xy 76.768375 -383.403455) (xy 76.815981 -383.432509) (xy 76.858849 -383.468184) (xy 76.896066 -383.509721)
			(xy 76.926839 -383.556234) (xy 76.950511 -383.606731) (xy 76.966579 -383.660138) (xy 76.974699 -383.715314)
			(xy 76.975208 -383.7432) (xy 76.974699 -383.771086) (xy 76.966579 -383.826262) (xy 76.950511 -383.879669)
			(xy 76.926839 -383.930166) (xy 76.896066 -383.976679) (xy 76.858849 -384.018216) (xy 76.815981 -384.053891)
			(xy 76.768375 -384.082945) (xy 76.717046 -384.104757) (xy 76.663089 -384.118863) (xy 76.607652 -384.124963)
			(xy 76.551918 -384.122926) (xy 76.497075 -384.112796) (xy 76.444291 -384.094789) (xy 76.394691 -384.069288)
			(xy 76.349333 -384.036837) (xy 76.309184 -383.998128) (xy 76.275098 -383.953985) (xy 76.247802 -383.90535)
			(xy 76.227879 -383.853259) (xy 76.215753 -383.798822) (xy 76.211682 -383.7432) (xy 70.620381 -383.7432)
			(xy 70.650559 -383.774454) (xy 70.689431 -383.826675) (xy 70.721321 -383.88343) (xy 70.745707 -383.94379)
			(xy 70.76219 -384.006769) (xy 70.7705 -384.071337) (xy 70.770501 -384.136438) (xy 70.762195 -384.201006)
			(xy 70.745715 -384.263986) (xy 70.721332 -384.324348) (xy 70.689445 -384.381104) (xy 70.650575 -384.433327)
			(xy 70.605358 -384.480161) (xy 70.58025 -384.500882) (xy 70.571734 -384.508512) (xy 70.561835 -384.52909)
			(xy 70.5612 -384.540506) (xy 70.5612 -384.657854) (xy 70.561464 -384.66268) (xy 76.211682 -384.66268)
			(xy 76.215753 -384.607058) (xy 76.227879 -384.552621) (xy 76.247802 -384.50053) (xy 76.275098 -384.451895)
			(xy 76.309184 -384.407752) (xy 76.349333 -384.369043) (xy 76.394691 -384.336592) (xy 76.444291 -384.311091)
			(xy 76.497075 -384.293084) (xy 76.551918 -384.282954) (xy 76.607652 -384.280917) (xy 76.663089 -384.287017)
			(xy 76.717046 -384.301123) (xy 76.768375 -384.322935) (xy 76.815981 -384.351989) (xy 76.85846 -384.38734)
			(xy 77.47176 -384.38734) (xy 77.47176 -384.327404) (xy 77.479583 -384.267982) (xy 77.495096 -384.210089)
			(xy 77.518032 -384.154716) (xy 77.547999 -384.10281) (xy 77.584486 -384.05526) (xy 77.626866 -384.01288)
			(xy 77.674416 -383.976393) (xy 77.726322 -383.946426) (xy 77.781695 -383.92349) (xy 77.839588 -383.907977)
			(xy 77.89901 -383.900154) (xy 77.958946 -383.900154) (xy 78.018368 -383.907977) (xy 78.076261 -383.92349)
			(xy 78.131634 -383.946426) (xy 78.18354 -383.976393) (xy 78.23109 -384.01288) (xy 78.27347 -384.05526)
			(xy 78.309957 -384.10281) (xy 78.339924 -384.154716) (xy 78.36286 -384.210089) (xy 78.378373 -384.267982)
			(xy 78.386196 -384.327404) (xy 78.386686 -384.357372) (xy 78.386196 -384.38734) (xy 78.378373 -384.446762)
			(xy 78.36286 -384.504655) (xy 78.339924 -384.560028) (xy 78.309957 -384.611934) (xy 78.27347 -384.659484)
			(xy 78.23109 -384.701864) (xy 78.18354 -384.738351) (xy 78.131634 -384.768318) (xy 78.076261 -384.791254)
			(xy 78.018368 -384.806767) (xy 77.958946 -384.81459) (xy 77.89901 -384.81459) (xy 77.839588 -384.806767)
			(xy 77.781695 -384.791254) (xy 77.726322 -384.768318) (xy 77.674416 -384.738351) (xy 77.626866 -384.701864)
			(xy 77.584486 -384.659484) (xy 77.547999 -384.611934) (xy 77.518032 -384.560028) (xy 77.495096 -384.504655)
			(xy 77.479583 -384.446762) (xy 77.47176 -384.38734) (xy 76.85846 -384.38734) (xy 76.858849 -384.387664)
			(xy 76.896066 -384.429201) (xy 76.926839 -384.475714) (xy 76.950511 -384.526211) (xy 76.966579 -384.579618)
			(xy 76.974699 -384.634794) (xy 76.975208 -384.66268) (xy 76.974699 -384.690566) (xy 76.966579 -384.745742)
			(xy 76.950511 -384.799149) (xy 76.926839 -384.849646) (xy 76.896066 -384.896159) (xy 76.858849 -384.937696)
			(xy 76.815981 -384.973371) (xy 76.768375 -385.002425) (xy 76.717046 -385.024237) (xy 76.663089 -385.038343)
			(xy 76.607652 -385.044443) (xy 76.551918 -385.042406) (xy 76.497075 -385.032276) (xy 76.444291 -385.014269)
			(xy 76.394691 -384.988768) (xy 76.349333 -384.956317) (xy 76.309184 -384.917608) (xy 76.275098 -384.873465)
			(xy 76.247802 -384.82483) (xy 76.227879 -384.772739) (xy 76.215753 -384.718302) (xy 76.211682 -384.66268)
			(xy 70.561464 -384.66268) (xy 70.561824 -384.669276) (xy 70.571712 -384.689868) (xy 70.58025 -384.697478)
			(xy 70.605339 -384.718222) (xy 70.650559 -384.765054) (xy 70.689431 -384.817275) (xy 70.721321 -384.87403)
			(xy 70.745707 -384.93439) (xy 70.76219 -384.997369) (xy 70.7705 -385.061937) (xy 70.770501 -385.127038)
			(xy 70.762195 -385.191606) (xy 70.745715 -385.254586) (xy 70.721332 -385.314948) (xy 70.689445 -385.371704)
			(xy 70.650575 -385.423927) (xy 70.605358 -385.470761) (xy 70.58025 -385.491482) (xy 70.571734 -385.499112)
			(xy 70.561835 -385.51969) (xy 70.5612 -385.531106) (xy 70.5612 -385.609454) (xy 76.212638 -385.609454)
			(xy 76.212638 -385.554946) (xy 76.220395 -385.500993) (xy 76.235752 -385.448692) (xy 76.258395 -385.39911)
			(xy 76.287865 -385.353255) (xy 76.32356 -385.31206) (xy 76.364755 -385.276365) (xy 76.41061 -385.246895)
			(xy 76.460192 -385.224252) (xy 76.512493 -385.208895) (xy 76.566446 -385.201138) (xy 76.5937 -385.200652)
			(xy 76.622333 -385.201201) (xy 76.678955 -385.20976) (xy 76.733663 -385.226685) (xy 76.785226 -385.251597)
			(xy 76.832487 -385.283936) (xy 76.874383 -385.322976) (xy 76.909974 -385.367838) (xy 76.924662 -385.392422)
			(xy 76.931774 -385.404614) (xy 76.95565 -385.41833) (xy 77.072744 -385.416044) (xy 77.096112 -385.40182)
			(xy 77.102716 -385.389374) (xy 77.117644 -385.362116) (xy 77.153776 -385.311551) (xy 77.196421 -385.266343)
			(xy 77.244793 -385.227325) (xy 77.298002 -385.195214) (xy 77.355068 -385.170602) (xy 77.414941 -385.153942)
			(xy 77.476518 -385.145541) (xy 77.507592 -385.145026) (xy 77.537562 -385.145469) (xy 77.59699 -385.153292)
			(xy 77.654888 -385.168805) (xy 77.710266 -385.191744) (xy 77.762175 -385.221715) (xy 77.809729 -385.258205)
			(xy 77.852112 -385.300591) (xy 77.8886 -385.348146) (xy 77.918567 -385.400058) (xy 77.941503 -385.455437)
			(xy 77.957013 -385.513336) (xy 77.964833 -385.572764) (xy 77.9653 -385.602734) (xy 77.964787 -385.633614)
			(xy 77.956473 -385.694811) (xy 77.939999 -385.754332) (xy 77.915666 -385.811096) (xy 77.883916 -385.864069)
			(xy 77.874744 -385.87553) (xy 79.361792 -385.87553) (xy 79.362303 -385.849542) (xy 79.37043 -385.798204)
			(xy 79.386488 -385.74877) (xy 79.410082 -385.702457) (xy 79.440631 -385.660405) (xy 79.477382 -385.62365)
			(xy 79.519431 -385.593097) (xy 79.565742 -385.569499) (xy 79.615175 -385.553437) (xy 79.666512 -385.545305)
			(xy 79.6925 -385.544822) (xy 79.708933 -385.545053) (xy 79.741633 -385.548357) (xy 79.757778 -385.551426)
			(xy 79.770732 -385.553966) (xy 79.795878 -385.546092) (xy 79.873094 -385.464304) (xy 79.879698 -385.438904)
			(xy 79.876396 -385.426204) (xy 79.86939 -385.397762) (xy 79.861872 -385.339669) (xy 79.86141 -385.31038)
			(xy 79.861934 -385.279492) (xy 79.87024 -385.218276) (xy 79.886697 -385.158733) (xy 79.911007 -385.101941)
			(xy 79.926434 -385.075176) (xy 79.932276 -385.06527) (xy 79.934562 -385.042918) (xy 79.901288 -384.947668)
			(xy 79.88554 -384.931666) (xy 79.874872 -384.927602) (xy 79.851485 -384.918431) (xy 79.807589 -384.894009)
			(xy 79.767893 -384.863226) (xy 79.733313 -384.826791) (xy 79.704644 -384.785542) (xy 79.682547 -384.740431)
			(xy 79.667531 -384.692495) (xy 79.659942 -384.642839) (xy 79.65948 -384.617722) (xy 79.65999 -384.591735)
			(xy 79.66812 -384.5404) (xy 79.684181 -384.49097) (xy 79.707777 -384.44466) (xy 79.738327 -384.402612)
			(xy 79.775078 -384.365861) (xy 79.817126 -384.335311) (xy 79.863436 -384.311715) (xy 79.912866 -384.295654)
			(xy 79.964201 -384.287524) (xy 80.016175 -384.287524) (xy 80.06751 -384.295654) (xy 80.11694 -384.311715)
			(xy 80.16325 -384.335311) (xy 80.205298 -384.365861) (xy 80.242049 -384.402612) (xy 80.272599 -384.44466)
			(xy 80.296195 -384.49097) (xy 80.312256 -384.5404) (xy 80.320386 -384.591735) (xy 80.320896 -384.617722)
			(xy 80.859376 -384.617722) (xy 80.859886 -384.591735) (xy 80.868016 -384.5404) (xy 80.884077 -384.49097)
			(xy 80.907673 -384.44466) (xy 80.938223 -384.402612) (xy 80.974974 -384.365861) (xy 81.017022 -384.335311)
			(xy 81.063332 -384.311715) (xy 81.112762 -384.295654) (xy 81.164097 -384.287524) (xy 81.216071 -384.287524)
			(xy 81.267406 -384.295654) (xy 81.316836 -384.311715) (xy 81.363146 -384.335311) (xy 81.405194 -384.365861)
			(xy 81.441945 -384.402612) (xy 81.472495 -384.44466) (xy 81.496091 -384.49097) (xy 81.512152 -384.5404)
			(xy 81.520282 -384.591735) (xy 81.520792 -384.617722) (xy 82.059526 -384.617722) (xy 82.060036 -384.591735)
			(xy 82.068166 -384.5404) (xy 82.084227 -384.49097) (xy 82.107823 -384.44466) (xy 82.138373 -384.402612)
			(xy 82.175124 -384.365861) (xy 82.217172 -384.335311) (xy 82.263482 -384.311715) (xy 82.312912 -384.295654)
			(xy 82.364247 -384.287524) (xy 82.416221 -384.287524) (xy 82.467556 -384.295654) (xy 82.516986 -384.311715)
			(xy 82.563296 -384.335311) (xy 82.605344 -384.365861) (xy 82.642095 -384.402612) (xy 82.672645 -384.44466)
			(xy 82.696241 -384.49097) (xy 82.712302 -384.5404) (xy 82.720432 -384.591735) (xy 82.720942 -384.617722)
			(xy 83.259422 -384.617722) (xy 83.259932 -384.591735) (xy 83.268062 -384.5404) (xy 83.284123 -384.49097)
			(xy 83.307719 -384.44466) (xy 83.338269 -384.402612) (xy 83.37502 -384.365861) (xy 83.417068 -384.335311)
			(xy 83.463378 -384.311715) (xy 83.512808 -384.295654) (xy 83.564143 -384.287524) (xy 83.616117 -384.287524)
			(xy 83.667452 -384.295654) (xy 83.716882 -384.311715) (xy 83.763192 -384.335311) (xy 83.80524 -384.365861)
			(xy 83.841991 -384.402612) (xy 83.872541 -384.44466) (xy 83.896137 -384.49097) (xy 83.912198 -384.5404)
			(xy 83.920328 -384.591735) (xy 83.920838 -384.617722) (xy 84.459572 -384.617722) (xy 84.460082 -384.591735)
			(xy 84.468212 -384.5404) (xy 84.484273 -384.49097) (xy 84.507869 -384.44466) (xy 84.538419 -384.402612)
			(xy 84.57517 -384.365861) (xy 84.617218 -384.335311) (xy 84.663528 -384.311715) (xy 84.712958 -384.295654)
			(xy 84.764293 -384.287524) (xy 84.816267 -384.287524) (xy 84.867602 -384.295654) (xy 84.917032 -384.311715)
			(xy 84.963342 -384.335311) (xy 85.00539 -384.365861) (xy 85.042141 -384.402612) (xy 85.072691 -384.44466)
			(xy 85.096287 -384.49097) (xy 85.112348 -384.5404) (xy 85.120478 -384.591735) (xy 85.120988 -384.617722)
			(xy 85.659468 -384.617722) (xy 85.659978 -384.591735) (xy 85.668108 -384.5404) (xy 85.684169 -384.49097)
			(xy 85.707765 -384.44466) (xy 85.738315 -384.402612) (xy 85.775066 -384.365861) (xy 85.817114 -384.335311)
			(xy 85.863424 -384.311715) (xy 85.912854 -384.295654) (xy 85.964189 -384.287524) (xy 86.016163 -384.287524)
			(xy 86.067498 -384.295654) (xy 86.116928 -384.311715) (xy 86.163238 -384.335311) (xy 86.205286 -384.365861)
			(xy 86.242037 -384.402612) (xy 86.272587 -384.44466) (xy 86.296183 -384.49097) (xy 86.312244 -384.5404)
			(xy 86.320374 -384.591735) (xy 86.320884 -384.617722) (xy 86.859364 -384.617722) (xy 86.859874 -384.591735)
			(xy 86.868004 -384.5404) (xy 86.884065 -384.49097) (xy 86.907661 -384.44466) (xy 86.938211 -384.402612)
			(xy 86.974962 -384.365861) (xy 87.01701 -384.335311) (xy 87.06332 -384.311715) (xy 87.11275 -384.295654)
			(xy 87.164085 -384.287524) (xy 87.216059 -384.287524) (xy 87.267394 -384.295654) (xy 87.316824 -384.311715)
			(xy 87.363134 -384.335311) (xy 87.405182 -384.365861) (xy 87.441933 -384.402612) (xy 87.472483 -384.44466)
			(xy 87.496079 -384.49097) (xy 87.51214 -384.5404) (xy 87.52027 -384.591735) (xy 87.52078 -384.617722)
			(xy 88.059514 -384.617722) (xy 88.060024 -384.591735) (xy 88.068154 -384.5404) (xy 88.084215 -384.49097)
			(xy 88.107811 -384.44466) (xy 88.138361 -384.402612) (xy 88.175112 -384.365861) (xy 88.21716 -384.335311)
			(xy 88.26347 -384.311715) (xy 88.3129 -384.295654) (xy 88.364235 -384.287524) (xy 88.416209 -384.287524)
			(xy 88.467544 -384.295654) (xy 88.516974 -384.311715) (xy 88.563284 -384.335311) (xy 88.605332 -384.365861)
			(xy 88.642083 -384.402612) (xy 88.672633 -384.44466) (xy 88.696229 -384.49097) (xy 88.71229 -384.5404)
			(xy 88.72042 -384.591735) (xy 88.72093 -384.617722) (xy 89.25941 -384.617722) (xy 89.25992 -384.591735)
			(xy 89.26805 -384.5404) (xy 89.284111 -384.49097) (xy 89.307707 -384.44466) (xy 89.338257 -384.402612)
			(xy 89.375008 -384.365861) (xy 89.417056 -384.335311) (xy 89.463366 -384.311715) (xy 89.512796 -384.295654)
			(xy 89.564131 -384.287524) (xy 89.616105 -384.287524) (xy 89.66744 -384.295654) (xy 89.71687 -384.311715)
			(xy 89.76318 -384.335311) (xy 89.805228 -384.365861) (xy 89.841979 -384.402612) (xy 89.872529 -384.44466)
			(xy 89.896125 -384.49097) (xy 89.912186 -384.5404) (xy 89.920316 -384.591735) (xy 89.920826 -384.617722)
			(xy 90.45956 -384.617722) (xy 90.46007 -384.591735) (xy 90.4682 -384.5404) (xy 90.484261 -384.49097)
			(xy 90.507857 -384.44466) (xy 90.538407 -384.402612) (xy 90.575158 -384.365861) (xy 90.617206 -384.335311)
			(xy 90.663516 -384.311715) (xy 90.712946 -384.295654) (xy 90.764281 -384.287524) (xy 90.816255 -384.287524)
			(xy 90.86759 -384.295654) (xy 90.91702 -384.311715) (xy 90.96333 -384.335311) (xy 91.005378 -384.365861)
			(xy 91.042129 -384.402612) (xy 91.072679 -384.44466) (xy 91.096275 -384.49097) (xy 91.112336 -384.5404)
			(xy 91.120466 -384.591735) (xy 91.120976 -384.617722) (xy 91.659456 -384.617722) (xy 91.659966 -384.591735)
			(xy 91.668096 -384.5404) (xy 91.684157 -384.49097) (xy 91.707753 -384.44466) (xy 91.738303 -384.402612)
			(xy 91.775054 -384.365861) (xy 91.817102 -384.335311) (xy 91.863412 -384.311715) (xy 91.912842 -384.295654)
			(xy 91.964177 -384.287524) (xy 92.016151 -384.287524) (xy 92.067486 -384.295654) (xy 92.116916 -384.311715)
			(xy 92.163226 -384.335311) (xy 92.205274 -384.365861) (xy 92.242025 -384.402612) (xy 92.272575 -384.44466)
			(xy 92.296171 -384.49097) (xy 92.312232 -384.5404) (xy 92.320362 -384.591735) (xy 92.320872 -384.617722)
			(xy 92.859352 -384.617722) (xy 92.859862 -384.591735) (xy 92.867992 -384.5404) (xy 92.884053 -384.49097)
			(xy 92.907649 -384.44466) (xy 92.938199 -384.402612) (xy 92.97495 -384.365861) (xy 93.016998 -384.335311)
			(xy 93.063308 -384.311715) (xy 93.112738 -384.295654) (xy 93.164073 -384.287524) (xy 93.216047 -384.287524)
			(xy 93.267382 -384.295654) (xy 93.316812 -384.311715) (xy 93.363122 -384.335311) (xy 93.40517 -384.365861)
			(xy 93.441921 -384.402612) (xy 93.472471 -384.44466) (xy 93.496067 -384.49097) (xy 93.512128 -384.5404)
			(xy 93.520258 -384.591735) (xy 93.520768 -384.617722) (xy 94.059502 -384.617722) (xy 94.060012 -384.591735)
			(xy 94.068142 -384.5404) (xy 94.084203 -384.49097) (xy 94.107799 -384.44466) (xy 94.138349 -384.402612)
			(xy 94.1751 -384.365861) (xy 94.217148 -384.335311) (xy 94.263458 -384.311715) (xy 94.312888 -384.295654)
			(xy 94.364223 -384.287524) (xy 94.416197 -384.287524) (xy 94.467532 -384.295654) (xy 94.516962 -384.311715)
			(xy 94.563272 -384.335311) (xy 94.60532 -384.365861) (xy 94.642071 -384.402612) (xy 94.672621 -384.44466)
			(xy 94.696217 -384.49097) (xy 94.712278 -384.5404) (xy 94.720408 -384.591735) (xy 94.720918 -384.617722)
			(xy 95.259398 -384.617722) (xy 95.259908 -384.591735) (xy 95.268038 -384.5404) (xy 95.284099 -384.49097)
			(xy 95.307695 -384.44466) (xy 95.338245 -384.402612) (xy 95.374996 -384.365861) (xy 95.417044 -384.335311)
			(xy 95.463354 -384.311715) (xy 95.512784 -384.295654) (xy 95.564119 -384.287524) (xy 95.616093 -384.287524)
			(xy 95.667428 -384.295654) (xy 95.716858 -384.311715) (xy 95.763168 -384.335311) (xy 95.805216 -384.365861)
			(xy 95.841967 -384.402612) (xy 95.872517 -384.44466) (xy 95.896113 -384.49097) (xy 95.912174 -384.5404)
			(xy 95.920304 -384.591735) (xy 95.920814 -384.617722) (xy 96.459548 -384.617722) (xy 96.460058 -384.591735)
			(xy 96.468188 -384.5404) (xy 96.484249 -384.49097) (xy 96.507845 -384.44466) (xy 96.538395 -384.402612)
			(xy 96.575146 -384.365861) (xy 96.617194 -384.335311) (xy 96.663504 -384.311715) (xy 96.712934 -384.295654)
			(xy 96.764269 -384.287524) (xy 96.816243 -384.287524) (xy 96.867578 -384.295654) (xy 96.917008 -384.311715)
			(xy 96.963318 -384.335311) (xy 97.005366 -384.365861) (xy 97.042117 -384.402612) (xy 97.072667 -384.44466)
			(xy 97.096263 -384.49097) (xy 97.112324 -384.5404) (xy 97.120454 -384.591735) (xy 97.120964 -384.617722)
			(xy 97.659444 -384.617722) (xy 97.659954 -384.591735) (xy 97.668084 -384.5404) (xy 97.684145 -384.49097)
			(xy 97.707741 -384.44466) (xy 97.738291 -384.402612) (xy 97.775042 -384.365861) (xy 97.81709 -384.335311)
			(xy 97.8634 -384.311715) (xy 97.91283 -384.295654) (xy 97.964165 -384.287524) (xy 98.016139 -384.287524)
			(xy 98.067474 -384.295654) (xy 98.116904 -384.311715) (xy 98.163214 -384.335311) (xy 98.205262 -384.365861)
			(xy 98.242013 -384.402612) (xy 98.272563 -384.44466) (xy 98.296159 -384.49097) (xy 98.31222 -384.5404)
			(xy 98.32035 -384.591735) (xy 98.32086 -384.617722) (xy 98.320329 -384.644824) (xy 98.31152 -384.698307)
			(xy 98.303334 -384.724148) (xy 98.299524 -384.73507) (xy 98.302064 -384.757422) (xy 98.354642 -384.843274)
			(xy 98.373692 -384.85572) (xy 98.384868 -384.857498) (xy 98.414191 -384.862176) (xy 98.471362 -384.878229)
			(xy 98.525976 -384.901543) (xy 98.577115 -384.931726) (xy 98.62392 -384.968271) (xy 98.665604 -385.010563)
			(xy 98.701467 -385.057892) (xy 98.730907 -385.109462) (xy 98.747254 -385.149344) (xy 99.830128 -385.149344)
			(xy 99.830552 -385.120708) (xy 99.837709 -385.063886) (xy 99.851891 -385.008398) (xy 99.872879 -384.95511)
			(xy 99.900343 -384.904854) (xy 99.916742 -384.881374) (xy 99.922418 -384.872857) (xy 99.927027 -384.85293)
			(xy 99.92346 -384.832791) (xy 99.918266 -384.82397) (xy 99.900779 -384.795992) (xy 99.87315 -384.73608)
			(xy 99.854404 -384.672823) (xy 99.844931 -384.60753) (xy 99.844352 -384.574542) (xy 99.844809 -384.545301)
			(xy 99.852241 -384.487293) (xy 99.867003 -384.430705) (xy 99.888854 -384.376458) (xy 99.917438 -384.325437)
			(xy 99.952288 -384.278474) (xy 99.992838 -384.236333) (xy 100.038426 -384.199701) (xy 100.088309 -384.169176)
			(xy 100.141675 -384.145254) (xy 100.197653 -384.128326) (xy 100.255332 -384.118667) (xy 100.284534 -384.117088)
			(xy 100.294186 -384.116834) (xy 100.311712 -384.109214) (xy 100.374196 -384.046222) (xy 100.381816 -384.02895)
			(xy 100.38207 -384.019044) (xy 100.383653 -383.986493) (xy 100.394143 -383.922172) (xy 100.412764 -383.859717)
			(xy 100.439211 -383.800153) (xy 100.473052 -383.744457) (xy 100.513731 -383.69354) (xy 100.560581 -383.648237)
			(xy 100.612836 -383.609292) (xy 100.669638 -383.577341) (xy 100.730056 -383.552909) (xy 100.793101 -383.536396)
			(xy 100.857738 -383.528073) (xy 100.890324 -383.527554) (xy 100.923907 -383.528118) (xy 100.990491 -383.536944)
			(xy 101.055331 -383.554466) (xy 101.117297 -383.580378) (xy 101.175309 -383.614227) (xy 101.228356 -383.655426)
			(xy 101.275513 -383.703253) (xy 101.315957 -383.756877) (xy 101.348983 -383.815362) (xy 101.362002 -383.846324)
			(xy 101.36759 -383.86004) (xy 101.391212 -383.877058) (xy 101.51237 -383.884678) (xy 101.538024 -383.870454)
			(xy 101.545136 -383.8575) (xy 101.562074 -383.828167) (xy 101.602482 -383.773805) (xy 101.649745 -383.725285)
			(xy 101.703028 -383.683465) (xy 101.761388 -383.649084) (xy 101.823794 -383.622749) (xy 101.889142 -383.604927)
			(xy 101.956277 -383.595933) (xy 101.990144 -383.595372) (xy 102.029396 -383.596137) (xy 102.106961 -383.608257)
			(xy 102.144576 -383.619502) (xy 102.157022 -383.623312) (xy 102.18293 -383.618232) (xy 102.268528 -383.545334)
			(xy 102.277926 -383.520696) (xy 102.275894 -383.507742) (xy 102.273995 -383.493914) (xy 102.27196 -383.466073)
			(xy 102.27183 -383.452116) (xy 102.272316 -383.424865) (xy 102.280072 -383.370917) (xy 102.295427 -383.318622)
			(xy 102.318069 -383.269045) (xy 102.347535 -383.223195) (xy 102.383226 -383.182004) (xy 102.424417 -383.146313)
			(xy 102.470267 -383.116847) (xy 102.519844 -383.094205) (xy 102.572139 -383.07885) (xy 102.626087 -383.071094)
			(xy 102.680589 -383.071094) (xy 102.734537 -383.07885) (xy 102.786832 -383.094205) (xy 102.836409 -383.116847)
			(xy 102.882259 -383.146313) (xy 102.92345 -383.182004) (xy 102.959141 -383.223195) (xy 102.988607 -383.269045)
			(xy 103.011249 -383.318622) (xy 103.026604 -383.370917) (xy 103.03436 -383.424865) (xy 103.034846 -383.452116)
			(xy 103.034176 -383.483763) (xy 103.0237 -383.546185) (xy 103.014018 -383.576322) (xy 103.011611 -383.58462)
			(xy 103.011866 -383.601884) (xy 103.014526 -383.610104) (xy 103.024686 -383.638298) (xy 103.027976 -383.646544)
			(xy 103.039289 -383.66021) (xy 103.046784 -383.664968) (xy 103.075106 -383.682148) (xy 103.127486 -383.722698)
			(xy 103.147839 -383.7432) (xy 110.783876 -383.7432) (xy 110.787947 -383.687578) (xy 110.800073 -383.633141)
			(xy 110.819996 -383.58105) (xy 110.847292 -383.532415) (xy 110.881378 -383.488272) (xy 110.921527 -383.449563)
			(xy 110.966885 -383.417112) (xy 111.016485 -383.391611) (xy 111.069269 -383.373604) (xy 111.124112 -383.363474)
			(xy 111.179846 -383.361437) (xy 111.235283 -383.367537) (xy 111.28924 -383.381643) (xy 111.340569 -383.403455)
			(xy 111.388175 -383.432509) (xy 111.431043 -383.468184) (xy 111.46826 -383.509721) (xy 111.499033 -383.556234)
			(xy 111.522705 -383.606731) (xy 111.538773 -383.660138) (xy 111.546893 -383.715314) (xy 111.547402 -383.7432)
			(xy 111.546893 -383.771086) (xy 111.538773 -383.826262) (xy 111.522705 -383.879669) (xy 111.499033 -383.930166)
			(xy 111.46826 -383.976679) (xy 111.431043 -384.018216) (xy 111.388175 -384.053891) (xy 111.340569 -384.082945)
			(xy 111.28924 -384.104757) (xy 111.235283 -384.118863) (xy 111.179846 -384.124963) (xy 111.124112 -384.122926)
			(xy 111.069269 -384.112796) (xy 111.016485 -384.094789) (xy 110.966885 -384.069288) (xy 110.921527 -384.036837)
			(xy 110.881378 -383.998128) (xy 110.847292 -383.953985) (xy 110.819996 -383.90535) (xy 110.800073 -383.853259)
			(xy 110.787947 -383.798822) (xy 110.783876 -383.7432) (xy 103.147839 -383.7432) (xy 103.174154 -383.769708)
			(xy 103.21432 -383.822383) (xy 103.247301 -383.87983) (xy 103.27254 -383.941075) (xy 103.289609 -384.00508)
			(xy 103.298217 -384.070759) (xy 103.298752 -384.10388) (xy 103.298332 -384.13399) (xy 103.2912 -384.193787)
			(xy 103.277058 -384.252324) (xy 103.256103 -384.308782) (xy 103.228628 -384.36237) (xy 103.195018 -384.412339)
			(xy 103.155744 -384.457991) (xy 103.111353 -384.498686) (xy 103.08717 -384.51663) (xy 103.077707 -384.524257)
			(xy 103.066705 -384.545892) (xy 103.066088 -384.558032) (xy 103.066088 -384.640328) (xy 103.066693 -384.652463)
			(xy 103.07191 -384.66268) (xy 110.783876 -384.66268) (xy 110.787947 -384.607058) (xy 110.800073 -384.552621)
			(xy 110.819996 -384.50053) (xy 110.847292 -384.451895) (xy 110.881378 -384.407752) (xy 110.921527 -384.369043)
			(xy 110.966885 -384.336592) (xy 111.016485 -384.311091) (xy 111.069269 -384.293084) (xy 111.124112 -384.282954)
			(xy 111.179846 -384.280917) (xy 111.235283 -384.287017) (xy 111.28924 -384.301123) (xy 111.340569 -384.322935)
			(xy 111.388175 -384.351989) (xy 111.430654 -384.38734) (xy 112.043954 -384.38734) (xy 112.043954 -384.327404)
			(xy 112.051777 -384.267982) (xy 112.06729 -384.210089) (xy 112.090226 -384.154716) (xy 112.120193 -384.10281)
			(xy 112.15668 -384.05526) (xy 112.19906 -384.01288) (xy 112.24661 -383.976393) (xy 112.298516 -383.946426)
			(xy 112.353889 -383.92349) (xy 112.411782 -383.907977) (xy 112.471204 -383.900154) (xy 112.53114 -383.900154)
			(xy 112.590562 -383.907977) (xy 112.648455 -383.92349) (xy 112.703828 -383.946426) (xy 112.755734 -383.976393)
			(xy 112.803284 -384.01288) (xy 112.845664 -384.05526) (xy 112.882151 -384.10281) (xy 112.912118 -384.154716)
			(xy 112.935054 -384.210089) (xy 112.950567 -384.267982) (xy 112.95839 -384.327404) (xy 112.95888 -384.357372)
			(xy 112.95839 -384.38734) (xy 112.950567 -384.446762) (xy 112.935054 -384.504655) (xy 112.912118 -384.560028)
			(xy 112.882151 -384.611934) (xy 112.845664 -384.659484) (xy 112.803284 -384.701864) (xy 112.755734 -384.738351)
			(xy 112.703828 -384.768318) (xy 112.648455 -384.791254) (xy 112.590562 -384.806767) (xy 112.53114 -384.81459)
			(xy 112.471204 -384.81459) (xy 112.411782 -384.806767) (xy 112.353889 -384.791254) (xy 112.298516 -384.768318)
			(xy 112.24661 -384.738351) (xy 112.19906 -384.701864) (xy 112.15668 -384.659484) (xy 112.120193 -384.611934)
			(xy 112.090226 -384.560028) (xy 112.06729 -384.504655) (xy 112.051777 -384.446762) (xy 112.043954 -384.38734)
			(xy 111.430654 -384.38734) (xy 111.431043 -384.387664) (xy 111.46826 -384.429201) (xy 111.499033 -384.475714)
			(xy 111.522705 -384.526211) (xy 111.538773 -384.579618) (xy 111.546893 -384.634794) (xy 111.547402 -384.66268)
			(xy 111.546893 -384.690566) (xy 111.538773 -384.745742) (xy 111.522705 -384.799149) (xy 111.499033 -384.849646)
			(xy 111.46826 -384.896159) (xy 111.431043 -384.937696) (xy 111.388175 -384.973371) (xy 111.340569 -385.002425)
			(xy 111.28924 -385.024237) (xy 111.235283 -385.038343) (xy 111.179846 -385.044443) (xy 111.124112 -385.042406)
			(xy 111.069269 -385.032276) (xy 111.016485 -385.014269) (xy 110.966885 -384.988768) (xy 110.921527 -384.956317)
			(xy 110.881378 -384.917608) (xy 110.847292 -384.873465) (xy 110.819996 -384.82483) (xy 110.800073 -384.772739)
			(xy 110.787947 -384.718302) (xy 110.783876 -384.66268) (xy 103.07191 -384.66268) (xy 103.077729 -384.674077)
			(xy 103.08717 -384.68173) (xy 103.111366 -384.69966) (xy 103.155767 -384.740346) (xy 103.19505 -384.785994)
			(xy 103.228662 -384.835965) (xy 103.256133 -384.889558) (xy 103.277079 -384.946022) (xy 103.291204 -385.004566)
			(xy 103.298312 -385.064368) (xy 103.298752 -385.09448) (xy 103.298225 -385.125209) (xy 103.29082 -385.186219)
			(xy 103.276115 -385.245891) (xy 103.254325 -385.303356) (xy 103.225767 -385.357776) (xy 103.190858 -385.408357)
			(xy 103.150106 -385.454361) (xy 103.104107 -385.495118) (xy 103.053531 -385.530034) (xy 102.999115 -385.558598)
			(xy 102.941653 -385.580396) (xy 102.881982 -385.595108) (xy 102.820973 -385.602521) (xy 102.790244 -385.602988)
			(xy 102.758119 -385.602513) (xy 102.694383 -385.594403) (xy 102.632176 -385.578332) (xy 102.572487 -385.554557)
			(xy 102.516267 -385.523454) (xy 102.464411 -385.48552) (xy 102.44074 -385.463796) (xy 102.433392 -385.457454)
			(xy 102.415383 -385.450262) (xy 102.405688 -385.449826) (xy 102.3747 -385.449826) (xy 102.364999 -385.450255)
			(xy 102.346973 -385.457423) (xy 102.339648 -385.463796) (xy 102.3239 -385.478274) (xy 102.31501 -385.485894)
			(xy 102.30612 -385.506468) (xy 102.309422 -385.608576) (xy 102.309867 -385.609454) (xy 110.784838 -385.609454)
			(xy 110.784838 -385.554946) (xy 110.792595 -385.500993) (xy 110.807951 -385.448694) (xy 110.830595 -385.399112)
			(xy 110.860063 -385.353257) (xy 110.895758 -385.312062) (xy 110.936952 -385.276367) (xy 110.982806 -385.246897)
			(xy 111.032388 -385.224254) (xy 111.084687 -385.208896) (xy 111.13864 -385.201138) (xy 111.165894 -385.200652)
			(xy 111.194527 -385.201205) (xy 111.251149 -385.209764) (xy 111.305856 -385.226688) (xy 111.357419 -385.2516)
			(xy 111.40468 -385.283938) (xy 111.446577 -385.322976) (xy 111.482168 -385.367838) (xy 111.496856 -385.392422)
			(xy 111.503968 -385.404614) (xy 111.527844 -385.41833) (xy 111.644938 -385.416044) (xy 111.668306 -385.40182)
			(xy 111.67491 -385.389374) (xy 111.689843 -385.362119) (xy 111.725974 -385.311554) (xy 111.768618 -385.266346)
			(xy 111.816989 -385.227327) (xy 111.870198 -385.195216) (xy 111.927263 -385.170603) (xy 111.987136 -385.153943)
			(xy 112.048712 -385.145541) (xy 112.079786 -385.145026) (xy 112.109756 -385.145474) (xy 112.169184 -385.153297)
			(xy 112.227082 -385.16881) (xy 112.282459 -385.191748) (xy 112.334369 -385.221718) (xy 112.381922 -385.258208)
			(xy 112.424305 -385.300593) (xy 112.460793 -385.348148) (xy 112.490761 -385.400059) (xy 112.513697 -385.455437)
			(xy 112.529207 -385.513336) (xy 112.537027 -385.572764) (xy 112.537494 -385.602734) (xy 112.536983 -385.633614)
			(xy 112.528668 -385.694811) (xy 112.512194 -385.754333) (xy 112.487861 -385.811096) (xy 112.456111 -385.864069)
			(xy 112.446939 -385.87553) (xy 113.933986 -385.87553) (xy 113.934503 -385.849542) (xy 113.942629 -385.798205)
			(xy 113.958687 -385.748771) (xy 113.982281 -385.702459) (xy 114.012829 -385.660407) (xy 114.04958 -385.623652)
			(xy 114.091628 -385.593099) (xy 114.137938 -385.569501) (xy 114.18737 -385.553438) (xy 114.238706 -385.545306)
			(xy 114.264694 -385.544822) (xy 114.281127 -385.545054) (xy 114.313827 -385.548358) (xy 114.329972 -385.551426)
			(xy 114.342926 -385.553966) (xy 114.368072 -385.546092) (xy 114.445288 -385.464304) (xy 114.451892 -385.438904)
			(xy 114.44859 -385.426204) (xy 114.441584 -385.397762) (xy 114.434066 -385.339669) (xy 114.433604 -385.31038)
			(xy 114.434129 -385.279492) (xy 114.442434 -385.218277) (xy 114.458891 -385.158733) (xy 114.483201 -385.101941)
			(xy 114.498628 -385.075176) (xy 114.50447 -385.06527) (xy 114.506756 -385.042918) (xy 114.473482 -384.947668)
			(xy 114.457734 -384.931666) (xy 114.447066 -384.927602) (xy 114.423678 -384.918434) (xy 114.379782 -384.894012)
			(xy 114.340086 -384.863228) (xy 114.305506 -384.826792) (xy 114.276838 -384.785543) (xy 114.254741 -384.740431)
			(xy 114.239725 -384.692495) (xy 114.232136 -384.642839) (xy 114.231674 -384.617722) (xy 114.232184 -384.591735)
			(xy 114.240314 -384.5404) (xy 114.256375 -384.49097) (xy 114.279971 -384.44466) (xy 114.310521 -384.402612)
			(xy 114.347272 -384.365861) (xy 114.38932 -384.335311) (xy 114.43563 -384.311715) (xy 114.48506 -384.295654)
			(xy 114.536395 -384.287524) (xy 114.588369 -384.287524) (xy 114.639704 -384.295654) (xy 114.689134 -384.311715)
			(xy 114.735444 -384.335311) (xy 114.777492 -384.365861) (xy 114.814243 -384.402612) (xy 114.844793 -384.44466)
			(xy 114.868389 -384.49097) (xy 114.88445 -384.5404) (xy 114.89258 -384.591735) (xy 114.89309 -384.617722)
			(xy 115.43157 -384.617722) (xy 115.43208 -384.591735) (xy 115.44021 -384.5404) (xy 115.456271 -384.49097)
			(xy 115.479867 -384.44466) (xy 115.510417 -384.402612) (xy 115.547168 -384.365861) (xy 115.589216 -384.335311)
			(xy 115.635526 -384.311715) (xy 115.684956 -384.295654) (xy 115.736291 -384.287524) (xy 115.788265 -384.287524)
			(xy 115.8396 -384.295654) (xy 115.88903 -384.311715) (xy 115.93534 -384.335311) (xy 115.977388 -384.365861)
			(xy 116.014139 -384.402612) (xy 116.044689 -384.44466) (xy 116.068285 -384.49097) (xy 116.084346 -384.5404)
			(xy 116.092476 -384.591735) (xy 116.092986 -384.617722) (xy 116.63172 -384.617722) (xy 116.63223 -384.591735)
			(xy 116.64036 -384.5404) (xy 116.656421 -384.49097) (xy 116.680017 -384.44466) (xy 116.710567 -384.402612)
			(xy 116.747318 -384.365861) (xy 116.789366 -384.335311) (xy 116.835676 -384.311715) (xy 116.885106 -384.295654)
			(xy 116.936441 -384.287524) (xy 116.988415 -384.287524) (xy 117.03975 -384.295654) (xy 117.08918 -384.311715)
			(xy 117.13549 -384.335311) (xy 117.177538 -384.365861) (xy 117.214289 -384.402612) (xy 117.244839 -384.44466)
			(xy 117.268435 -384.49097) (xy 117.284496 -384.5404) (xy 117.292626 -384.591735) (xy 117.293136 -384.617722)
			(xy 117.831616 -384.617722) (xy 117.832126 -384.591735) (xy 117.840256 -384.5404) (xy 117.856317 -384.49097)
			(xy 117.879913 -384.44466) (xy 117.910463 -384.402612) (xy 117.947214 -384.365861) (xy 117.989262 -384.335311)
			(xy 118.035572 -384.311715) (xy 118.085002 -384.295654) (xy 118.136337 -384.287524) (xy 118.188311 -384.287524)
			(xy 118.239646 -384.295654) (xy 118.289076 -384.311715) (xy 118.335386 -384.335311) (xy 118.377434 -384.365861)
			(xy 118.414185 -384.402612) (xy 118.444735 -384.44466) (xy 118.468331 -384.49097) (xy 118.484392 -384.5404)
			(xy 118.492522 -384.591735) (xy 118.493032 -384.617722) (xy 119.031766 -384.617722) (xy 119.032276 -384.591735)
			(xy 119.040406 -384.5404) (xy 119.056467 -384.49097) (xy 119.080063 -384.44466) (xy 119.110613 -384.402612)
			(xy 119.147364 -384.365861) (xy 119.189412 -384.335311) (xy 119.235722 -384.311715) (xy 119.285152 -384.295654)
			(xy 119.336487 -384.287524) (xy 119.388461 -384.287524) (xy 119.439796 -384.295654) (xy 119.489226 -384.311715)
			(xy 119.535536 -384.335311) (xy 119.577584 -384.365861) (xy 119.614335 -384.402612) (xy 119.644885 -384.44466)
			(xy 119.668481 -384.49097) (xy 119.684542 -384.5404) (xy 119.692672 -384.591735) (xy 119.693182 -384.617722)
			(xy 120.231662 -384.617722) (xy 120.232172 -384.591735) (xy 120.240302 -384.5404) (xy 120.256363 -384.49097)
			(xy 120.279959 -384.44466) (xy 120.310509 -384.402612) (xy 120.34726 -384.365861) (xy 120.389308 -384.335311)
			(xy 120.435618 -384.311715) (xy 120.485048 -384.295654) (xy 120.536383 -384.287524) (xy 120.588357 -384.287524)
			(xy 120.639692 -384.295654) (xy 120.689122 -384.311715) (xy 120.735432 -384.335311) (xy 120.77748 -384.365861)
			(xy 120.814231 -384.402612) (xy 120.844781 -384.44466) (xy 120.868377 -384.49097) (xy 120.884438 -384.5404)
			(xy 120.892568 -384.591735) (xy 120.893078 -384.617722) (xy 121.431558 -384.617722) (xy 121.432068 -384.591735)
			(xy 121.440198 -384.5404) (xy 121.456259 -384.49097) (xy 121.479855 -384.44466) (xy 121.510405 -384.402612)
			(xy 121.547156 -384.365861) (xy 121.589204 -384.335311) (xy 121.635514 -384.311715) (xy 121.684944 -384.295654)
			(xy 121.736279 -384.287524) (xy 121.788253 -384.287524) (xy 121.839588 -384.295654) (xy 121.889018 -384.311715)
			(xy 121.935328 -384.335311) (xy 121.977376 -384.365861) (xy 122.014127 -384.402612) (xy 122.044677 -384.44466)
			(xy 122.068273 -384.49097) (xy 122.084334 -384.5404) (xy 122.092464 -384.591735) (xy 122.092974 -384.617722)
			(xy 122.631708 -384.617722) (xy 122.632218 -384.591735) (xy 122.640348 -384.5404) (xy 122.656409 -384.49097)
			(xy 122.680005 -384.44466) (xy 122.710555 -384.402612) (xy 122.747306 -384.365861) (xy 122.789354 -384.335311)
			(xy 122.835664 -384.311715) (xy 122.885094 -384.295654) (xy 122.936429 -384.287524) (xy 122.988403 -384.287524)
			(xy 123.039738 -384.295654) (xy 123.089168 -384.311715) (xy 123.135478 -384.335311) (xy 123.177526 -384.365861)
			(xy 123.214277 -384.402612) (xy 123.244827 -384.44466) (xy 123.268423 -384.49097) (xy 123.284484 -384.5404)
			(xy 123.292614 -384.591735) (xy 123.293124 -384.617722) (xy 123.831604 -384.617722) (xy 123.832114 -384.591735)
			(xy 123.840244 -384.5404) (xy 123.856305 -384.49097) (xy 123.879901 -384.44466) (xy 123.910451 -384.402612)
			(xy 123.947202 -384.365861) (xy 123.98925 -384.335311) (xy 124.03556 -384.311715) (xy 124.08499 -384.295654)
			(xy 124.136325 -384.287524) (xy 124.188299 -384.287524) (xy 124.239634 -384.295654) (xy 124.289064 -384.311715)
			(xy 124.335374 -384.335311) (xy 124.377422 -384.365861) (xy 124.414173 -384.402612) (xy 124.444723 -384.44466)
			(xy 124.468319 -384.49097) (xy 124.48438 -384.5404) (xy 124.49251 -384.591735) (xy 124.49302 -384.617722)
			(xy 125.031754 -384.617722) (xy 125.032264 -384.591735) (xy 125.040394 -384.5404) (xy 125.056455 -384.49097)
			(xy 125.080051 -384.44466) (xy 125.110601 -384.402612) (xy 125.147352 -384.365861) (xy 125.1894 -384.335311)
			(xy 125.23571 -384.311715) (xy 125.28514 -384.295654) (xy 125.336475 -384.287524) (xy 125.388449 -384.287524)
			(xy 125.439784 -384.295654) (xy 125.489214 -384.311715) (xy 125.535524 -384.335311) (xy 125.577572 -384.365861)
			(xy 125.614323 -384.402612) (xy 125.644873 -384.44466) (xy 125.668469 -384.49097) (xy 125.68453 -384.5404)
			(xy 125.69266 -384.591735) (xy 125.69317 -384.617722) (xy 126.23165 -384.617722) (xy 126.23216 -384.591735)
			(xy 126.24029 -384.5404) (xy 126.256351 -384.49097) (xy 126.279947 -384.44466) (xy 126.310497 -384.402612)
			(xy 126.347248 -384.365861) (xy 126.389296 -384.335311) (xy 126.435606 -384.311715) (xy 126.485036 -384.295654)
			(xy 126.536371 -384.287524) (xy 126.588345 -384.287524) (xy 126.63968 -384.295654) (xy 126.68911 -384.311715)
			(xy 126.73542 -384.335311) (xy 126.777468 -384.365861) (xy 126.814219 -384.402612) (xy 126.844769 -384.44466)
			(xy 126.868365 -384.49097) (xy 126.884426 -384.5404) (xy 126.892556 -384.591735) (xy 126.893066 -384.617722)
			(xy 127.431546 -384.617722) (xy 127.432056 -384.591735) (xy 127.440186 -384.5404) (xy 127.456247 -384.49097)
			(xy 127.479843 -384.44466) (xy 127.510393 -384.402612) (xy 127.547144 -384.365861) (xy 127.589192 -384.335311)
			(xy 127.635502 -384.311715) (xy 127.684932 -384.295654) (xy 127.736267 -384.287524) (xy 127.788241 -384.287524)
			(xy 127.839576 -384.295654) (xy 127.889006 -384.311715) (xy 127.935316 -384.335311) (xy 127.977364 -384.365861)
			(xy 128.014115 -384.402612) (xy 128.044665 -384.44466) (xy 128.068261 -384.49097) (xy 128.084322 -384.5404)
			(xy 128.092452 -384.591735) (xy 128.092962 -384.617722) (xy 128.631696 -384.617722) (xy 128.632206 -384.591735)
			(xy 128.640336 -384.5404) (xy 128.656397 -384.49097) (xy 128.679993 -384.44466) (xy 128.710543 -384.402612)
			(xy 128.747294 -384.365861) (xy 128.789342 -384.335311) (xy 128.835652 -384.311715) (xy 128.885082 -384.295654)
			(xy 128.936417 -384.287524) (xy 128.988391 -384.287524) (xy 129.039726 -384.295654) (xy 129.089156 -384.311715)
			(xy 129.135466 -384.335311) (xy 129.177514 -384.365861) (xy 129.214265 -384.402612) (xy 129.244815 -384.44466)
			(xy 129.268411 -384.49097) (xy 129.284472 -384.5404) (xy 129.292602 -384.591735) (xy 129.293112 -384.617722)
			(xy 129.831592 -384.617722) (xy 129.832102 -384.591735) (xy 129.840232 -384.5404) (xy 129.856293 -384.49097)
			(xy 129.879889 -384.44466) (xy 129.910439 -384.402612) (xy 129.94719 -384.365861) (xy 129.989238 -384.335311)
			(xy 130.035548 -384.311715) (xy 130.084978 -384.295654) (xy 130.136313 -384.287524) (xy 130.188287 -384.287524)
			(xy 130.239622 -384.295654) (xy 130.289052 -384.311715) (xy 130.335362 -384.335311) (xy 130.37741 -384.365861)
			(xy 130.414161 -384.402612) (xy 130.444711 -384.44466) (xy 130.468307 -384.49097) (xy 130.484368 -384.5404)
			(xy 130.492498 -384.591735) (xy 130.493008 -384.617722) (xy 131.031742 -384.617722) (xy 131.032252 -384.591735)
			(xy 131.040382 -384.5404) (xy 131.056443 -384.49097) (xy 131.080039 -384.44466) (xy 131.110589 -384.402612)
			(xy 131.14734 -384.365861) (xy 131.189388 -384.335311) (xy 131.235698 -384.311715) (xy 131.285128 -384.295654)
			(xy 131.336463 -384.287524) (xy 131.388437 -384.287524) (xy 131.439772 -384.295654) (xy 131.489202 -384.311715)
			(xy 131.535512 -384.335311) (xy 131.57756 -384.365861) (xy 131.614311 -384.402612) (xy 131.644861 -384.44466)
			(xy 131.668457 -384.49097) (xy 131.684518 -384.5404) (xy 131.692648 -384.591735) (xy 131.693158 -384.617722)
			(xy 132.231638 -384.617722) (xy 132.232148 -384.591735) (xy 132.240278 -384.5404) (xy 132.256339 -384.49097)
			(xy 132.279935 -384.44466) (xy 132.310485 -384.402612) (xy 132.347236 -384.365861) (xy 132.389284 -384.335311)
			(xy 132.435594 -384.311715) (xy 132.485024 -384.295654) (xy 132.536359 -384.287524) (xy 132.588333 -384.287524)
			(xy 132.639668 -384.295654) (xy 132.689098 -384.311715) (xy 132.735408 -384.335311) (xy 132.777456 -384.365861)
			(xy 132.814207 -384.402612) (xy 132.844757 -384.44466) (xy 132.868353 -384.49097) (xy 132.884414 -384.5404)
			(xy 132.892544 -384.591735) (xy 132.893054 -384.617722) (xy 132.892524 -384.644824) (xy 132.883714 -384.698307)
			(xy 132.875528 -384.724148) (xy 132.871718 -384.73507) (xy 132.874258 -384.757422) (xy 132.926836 -384.843274)
			(xy 132.945886 -384.85572) (xy 132.957062 -384.857498) (xy 132.986384 -384.862181) (xy 133.043555 -384.878233)
			(xy 133.098169 -384.901547) (xy 133.149308 -384.931729) (xy 133.196113 -384.968273) (xy 133.237797 -385.010564)
			(xy 133.273661 -385.057893) (xy 133.3031 -385.109463) (xy 133.319447 -385.149344) (xy 134.402322 -385.149344)
			(xy 134.402747 -385.120708) (xy 134.409904 -385.063886) (xy 134.424086 -385.008398) (xy 134.445073 -384.95511)
			(xy 134.472538 -384.904854) (xy 134.488936 -384.881374) (xy 134.494612 -384.872857) (xy 134.499222 -384.85293)
			(xy 134.495655 -384.832791) (xy 134.49046 -384.82397) (xy 134.472973 -384.795993) (xy 134.445344 -384.73608)
			(xy 134.426598 -384.672823) (xy 134.417125 -384.60753) (xy 134.416546 -384.574542) (xy 134.417008 -384.545301)
			(xy 134.424441 -384.487294) (xy 134.439202 -384.430706) (xy 134.461053 -384.37646) (xy 134.489636 -384.325439)
			(xy 134.524486 -384.278476) (xy 134.565035 -384.236335) (xy 134.610623 -384.199703) (xy 134.660505 -384.169177)
			(xy 134.71387 -384.145255) (xy 134.769848 -384.128327) (xy 134.827526 -384.118667) (xy 134.856728 -384.117088)
			(xy 134.86638 -384.116834) (xy 134.883906 -384.109214) (xy 134.94639 -384.046222) (xy 134.95401 -384.02895)
			(xy 134.954264 -384.019044) (xy 134.955853 -383.986494) (xy 134.966343 -383.922172) (xy 134.984963 -383.859718)
			(xy 135.01141 -383.800155) (xy 135.045251 -383.744459) (xy 135.085929 -383.693542) (xy 135.132779 -383.64824)
			(xy 135.185033 -383.609294) (xy 135.241834 -383.577343) (xy 135.302251 -383.55291) (xy 135.365295 -383.536397)
			(xy 135.429933 -383.528073) (xy 135.462518 -383.527554) (xy 135.496101 -383.528123) (xy 135.562684 -383.536949)
			(xy 135.627524 -383.554469) (xy 135.68949 -383.58038) (xy 135.747503 -383.61423) (xy 135.80055 -383.655427)
			(xy 135.847706 -383.703255) (xy 135.88815 -383.756878) (xy 135.921177 -383.815363) (xy 135.934196 -383.846324)
			(xy 135.939784 -383.86004) (xy 135.963406 -383.877058) (xy 136.084564 -383.884678) (xy 136.110218 -383.870454)
			(xy 136.11733 -383.8575) (xy 136.134273 -383.828169) (xy 136.17468 -383.773808) (xy 136.221942 -383.725288)
			(xy 136.275224 -383.683467) (xy 136.333584 -383.649086) (xy 136.395989 -383.622751) (xy 136.461337 -383.604929)
			(xy 136.528471 -383.595934) (xy 136.562338 -383.595372) (xy 136.592652 -383.595827) (xy 136.652853 -383.603014)
			(xy 136.711773 -383.617306) (xy 136.768577 -383.6385) (xy 136.822458 -383.666296) (xy 136.872654 -383.700299)
			(xy 136.89584 -383.719832) (xy 136.902698 -383.726182) (xy 136.919716 -383.732278) (xy 137.00506 -383.732278)
			(xy 137.022078 -383.726182) (xy 137.028936 -383.719832) (xy 137.052105 -383.700275) (xy 137.102296 -383.666256)
			(xy 137.156179 -383.63845) (xy 137.212986 -383.617253) (xy 137.271913 -383.602966) (xy 137.332121 -383.595792)
			(xy 137.362438 -383.595372) (xy 137.393169 -383.59582) (xy 137.454183 -383.603232) (xy 137.513858 -383.617945)
			(xy 137.571325 -383.639742) (xy 137.625746 -383.668307) (xy 137.676327 -383.703223) (xy 137.72145 -383.7432)
			(xy 143.311624 -383.7432) (xy 143.315695 -383.687578) (xy 143.327821 -383.633141) (xy 143.347744 -383.58105)
			(xy 143.37504 -383.532415) (xy 143.409126 -383.488272) (xy 143.449275 -383.449563) (xy 143.494633 -383.417112)
			(xy 143.544233 -383.391611) (xy 143.597017 -383.373604) (xy 143.65186 -383.363474) (xy 143.707594 -383.361437)
			(xy 143.763031 -383.367537) (xy 143.816988 -383.381643) (xy 143.868317 -383.403455) (xy 143.915923 -383.432509)
			(xy 143.958791 -383.468184) (xy 143.996008 -383.509721) (xy 144.026781 -383.556234) (xy 144.050453 -383.606731)
			(xy 144.066521 -383.660138) (xy 144.074641 -383.715314) (xy 144.07515 -383.7432) (xy 144.074641 -383.771086)
			(xy 144.066521 -383.826262) (xy 144.050453 -383.879669) (xy 144.026781 -383.930166) (xy 143.996008 -383.976679)
			(xy 143.958791 -384.018216) (xy 143.915923 -384.053891) (xy 143.868317 -384.082945) (xy 143.816988 -384.104757)
			(xy 143.763031 -384.118863) (xy 143.707594 -384.124963) (xy 143.65186 -384.122926) (xy 143.597017 -384.112796)
			(xy 143.544233 -384.094789) (xy 143.494633 -384.069288) (xy 143.449275 -384.036837) (xy 143.409126 -383.998128)
			(xy 143.37504 -383.953985) (xy 143.347744 -383.90535) (xy 143.327821 -383.853259) (xy 143.315695 -383.798822)
			(xy 143.311624 -383.7432) (xy 137.72145 -383.7432) (xy 137.722332 -383.743981) (xy 137.763088 -383.789987)
			(xy 137.798002 -383.840569) (xy 137.826565 -383.894991) (xy 137.848361 -383.952459) (xy 137.863071 -384.012135)
			(xy 137.870481 -384.073149) (xy 137.870946 -384.10388) (xy 137.870528 -384.13399) (xy 137.863397 -384.193788)
			(xy 137.849254 -384.252325) (xy 137.828299 -384.308782) (xy 137.800824 -384.362371) (xy 137.767214 -384.41234)
			(xy 137.727938 -384.457991) (xy 137.683548 -384.498686) (xy 137.659364 -384.51663) (xy 137.6499 -384.524256)
			(xy 137.638899 -384.545892) (xy 137.638282 -384.558032) (xy 137.638282 -384.640328) (xy 137.638889 -384.652463)
			(xy 137.644106 -384.66268) (xy 143.311624 -384.66268) (xy 143.315695 -384.607058) (xy 143.327821 -384.552621)
			(xy 143.347744 -384.50053) (xy 143.37504 -384.451895) (xy 143.409126 -384.407752) (xy 143.449275 -384.369043)
			(xy 143.494633 -384.336592) (xy 143.544233 -384.311091) (xy 143.597017 -384.293084) (xy 143.65186 -384.282954)
			(xy 143.707594 -384.280917) (xy 143.763031 -384.287017) (xy 143.816988 -384.301123) (xy 143.868317 -384.322935)
			(xy 143.915923 -384.351989) (xy 143.958402 -384.38734) (xy 144.571702 -384.38734) (xy 144.571702 -384.327404)
			(xy 144.579525 -384.267982) (xy 144.595038 -384.210089) (xy 144.617974 -384.154716) (xy 144.647941 -384.10281)
			(xy 144.684428 -384.05526) (xy 144.726808 -384.01288) (xy 144.774358 -383.976393) (xy 144.826264 -383.946426)
			(xy 144.881637 -383.92349) (xy 144.93953 -383.907977) (xy 144.998952 -383.900154) (xy 145.058888 -383.900154)
			(xy 145.11831 -383.907977) (xy 145.176203 -383.92349) (xy 145.231576 -383.946426) (xy 145.283482 -383.976393)
			(xy 145.331032 -384.01288) (xy 145.373412 -384.05526) (xy 145.409899 -384.10281) (xy 145.439866 -384.154716)
			(xy 145.462802 -384.210089) (xy 145.478315 -384.267982) (xy 145.486138 -384.327404) (xy 145.486628 -384.357372)
			(xy 145.486138 -384.38734) (xy 145.478315 -384.446762) (xy 145.462802 -384.504655) (xy 145.439866 -384.560028)
			(xy 145.409899 -384.611934) (xy 145.373412 -384.659484) (xy 145.331032 -384.701864) (xy 145.283482 -384.738351)
			(xy 145.231576 -384.768318) (xy 145.176203 -384.791254) (xy 145.11831 -384.806767) (xy 145.058888 -384.81459)
			(xy 144.998952 -384.81459) (xy 144.93953 -384.806767) (xy 144.881637 -384.791254) (xy 144.826264 -384.768318)
			(xy 144.774358 -384.738351) (xy 144.726808 -384.701864) (xy 144.684428 -384.659484) (xy 144.647941 -384.611934)
			(xy 144.617974 -384.560028) (xy 144.595038 -384.504655) (xy 144.579525 -384.446762) (xy 144.571702 -384.38734)
			(xy 143.958402 -384.38734) (xy 143.958791 -384.387664) (xy 143.996008 -384.429201) (xy 144.026781 -384.475714)
			(xy 144.050453 -384.526211) (xy 144.066521 -384.579618) (xy 144.074641 -384.634794) (xy 144.07515 -384.66268)
			(xy 144.074641 -384.690566) (xy 144.066521 -384.745742) (xy 144.050453 -384.799149) (xy 144.026781 -384.849646)
			(xy 143.996008 -384.896159) (xy 143.958791 -384.937696) (xy 143.915923 -384.973371) (xy 143.868317 -385.002425)
			(xy 143.816988 -385.024237) (xy 143.763031 -385.038343) (xy 143.707594 -385.044443) (xy 143.65186 -385.042406)
			(xy 143.597017 -385.032276) (xy 143.544233 -385.014269) (xy 143.494633 -384.988768) (xy 143.449275 -384.956317)
			(xy 143.409126 -384.917608) (xy 143.37504 -384.873465) (xy 143.347744 -384.82483) (xy 143.327821 -384.772739)
			(xy 143.315695 -384.718302) (xy 143.311624 -384.66268) (xy 137.644106 -384.66268) (xy 137.649924 -384.674076)
			(xy 137.659364 -384.68173) (xy 137.683558 -384.699662) (xy 137.72796 -384.740347) (xy 137.767243 -384.785995)
			(xy 137.800856 -384.835966) (xy 137.828327 -384.889558) (xy 137.849272 -384.946022) (xy 137.863398 -385.004566)
			(xy 137.870506 -385.064368) (xy 137.870946 -385.09448) (xy 137.870425 -385.125209) (xy 137.86302 -385.18622)
			(xy 137.848315 -385.245893) (xy 137.826524 -385.303358) (xy 137.797966 -385.357778) (xy 137.763056 -385.408359)
			(xy 137.722304 -385.454363) (xy 137.676305 -385.49512) (xy 137.625728 -385.530036) (xy 137.571311 -385.5586)
			(xy 137.513848 -385.580397) (xy 137.454177 -385.595109) (xy 137.393167 -385.602522) (xy 137.362438 -385.602988)
			(xy 137.330313 -385.602517) (xy 137.266577 -385.594406) (xy 137.204369 -385.578335) (xy 137.144681 -385.554558)
			(xy 137.088461 -385.523455) (xy 137.036605 -385.485521) (xy 137.012934 -385.463796) (xy 137.005588 -385.457452)
			(xy 136.987578 -385.450261) (xy 136.977882 -385.449826) (xy 136.946894 -385.449826) (xy 136.937192 -385.450252)
			(xy 136.919166 -385.457422) (xy 136.911842 -385.463796) (xy 136.896094 -385.478274) (xy 136.887204 -385.485894)
			(xy 136.878314 -385.506468) (xy 136.881616 -385.608576) (xy 136.891776 -385.628642) (xy 136.901174 -385.635754)
			(xy 136.927495 -385.656434) (xy 136.975033 -385.703558) (xy 137.015974 -385.756514) (xy 137.04961 -385.814386)
			(xy 137.075359 -385.876172) (xy 137.092775 -385.940803) (xy 137.101557 -386.007162) (xy 137.102088 -386.04063)
			(xy 137.101672 -386.071362) (xy 137.09426 -386.132379) (xy 137.079547 -386.192057) (xy 137.057748 -386.249526)
			(xy 137.029181 -386.303949) (xy 136.994262 -386.354532) (xy 136.953501 -386.400537) (xy 136.907492 -386.441293)
			(xy 136.856906 -386.476207) (xy 136.80248 -386.504769) (xy 136.745009 -386.526562) (xy 136.685329 -386.541269)
			(xy 136.624312 -386.548675) (xy 136.59358 -386.549138) (xy 136.562078 -386.548652) (xy 136.499557 -386.540863)
			(xy 136.438478 -386.525407) (xy 136.379777 -386.502521) (xy 136.324354 -386.472557) (xy 136.298432 -386.45465)
			(xy 136.28751 -386.44703) (xy 136.261602 -386.444236) (xy 136.157208 -386.488178) (xy 136.141206 -386.508752)
			(xy 136.139174 -386.52196) (xy 136.133738 -386.554309) (xy 136.115508 -386.617323) (xy 136.089328 -386.677471)
			(xy 136.055632 -386.733754) (xy 136.014981 -386.785238) (xy 135.968048 -386.831069) (xy 135.915612 -386.870486)
			(xy 135.858544 -386.902834) (xy 135.797791 -386.927577) (xy 135.734361 -386.944305) (xy 135.669307 -386.95274)
			(xy 135.636508 -386.953252) (xy 135.605104 -386.952719) (xy 135.542775 -386.944985) (xy 135.481873 -386.929633)
			(xy 135.423326 -386.906897) (xy 135.368024 -386.877123) (xy 135.316811 -386.840766) (xy 135.270465 -386.798377)
			(xy 135.229692 -386.750603) (xy 135.195114 -386.698171) (xy 135.167257 -386.64188) (xy 135.146544 -386.582586)
			(xy 135.133292 -386.521193) (xy 135.130032 -386.489956) (xy 135.129016 -386.479796) (xy 135.12038 -386.462778)
			(xy 135.052308 -386.403342) (xy 135.03402 -386.396992) (xy 135.02386 -386.3975) (xy 134.99973 -386.398008)
			(xy 134.968999 -386.397534) (xy 134.907983 -386.390129) (xy 134.848306 -386.375423) (xy 134.790836 -386.35363)
			(xy 134.736412 -386.325069) (xy 134.685828 -386.290156) (xy 134.639821 -386.2494) (xy 134.599062 -386.203396)
			(xy 134.564146 -386.152814) (xy 134.535582 -386.098391) (xy 134.513786 -386.040923) (xy 134.499076 -385.981246)
			(xy 134.491668 -385.920231) (xy 134.491222 -385.8895) (xy 134.491646 -385.858719) (xy 134.499062 -385.797605)
			(xy 134.513798 -385.737833) (xy 134.535638 -385.680275) (xy 134.564264 -385.625773) (xy 134.581392 -385.600194)
			(xy 134.58647 -385.5922) (xy 134.590919 -385.573807) (xy 134.590028 -385.56438) (xy 134.58571 -385.533646)
			(xy 134.584048 -385.524382) (xy 134.574924 -385.507939) (xy 134.56793 -385.501642) (xy 134.546105 -385.482953)
			(xy 134.506799 -385.441039) (xy 134.473051 -385.394534) (xy 134.445391 -385.34417) (xy 134.424254 -385.290738)
			(xy 134.409974 -385.235081) (xy 134.402774 -385.178074) (xy 134.402322 -385.149344) (xy 133.319447 -385.149344)
			(xy 133.325622 -385.164408) (xy 133.340846 -385.221805) (xy 133.348517 -385.280689) (xy 133.348984 -385.31038)
			(xy 133.348457 -385.341443) (xy 133.340045 -385.402996) (xy 133.33222 -385.433062) (xy 133.329426 -385.443222)
			(xy 133.331966 -385.463034) (xy 133.379464 -385.54533) (xy 133.395466 -385.557522) (xy 133.405626 -385.560062)
			(xy 133.43473 -385.568079) (xy 133.490697 -385.59071) (xy 133.543203 -385.620502) (xy 133.591337 -385.656937)
			(xy 133.634264 -385.699384) (xy 133.671239 -385.747105) (xy 133.701619 -385.799272) (xy 133.724879 -385.85498)
			(xy 133.740614 -385.913263) (xy 133.74855 -385.973108) (xy 133.749034 -386.003292) (xy 133.748932 -386.017042)
			(xy 133.74728 -386.044493) (xy 133.745732 -386.058156) (xy 133.745013 -386.066844) (xy 133.748787 -386.083853)
			(xy 133.753098 -386.09143) (xy 133.7691 -386.11683) (xy 133.773869 -386.123867) (xy 133.787112 -386.134509)
			(xy 133.795008 -386.137658) (xy 133.818783 -386.146582) (xy 133.863432 -386.170775) (xy 133.903857 -386.201509)
			(xy 133.939108 -386.238063) (xy 133.968357 -386.279576) (xy 133.990914 -386.325073) (xy 134.00625 -386.373484)
			(xy 134.014005 -386.423671) (xy 134.014464 -386.449062) (xy 134.01399 -386.475052) (xy 134.005863 -386.526394)
			(xy 133.989803 -386.575832) (xy 133.966206 -386.622148) (xy 133.935653 -386.664202) (xy 133.898897 -386.700957)
			(xy 133.856843 -386.731509) (xy 133.810526 -386.755105) (xy 133.761088 -386.771164) (xy 133.709746 -386.77929)
			(xy 133.683756 -386.77977) (xy 133.658849 -386.779268) (xy 133.609595 -386.771818) (xy 133.562016 -386.757063)
			(xy 133.517189 -386.735336) (xy 133.47613 -386.70713) (xy 133.439766 -386.673084) (xy 133.408923 -386.633967)
			(xy 133.384296 -386.590666) (xy 133.366445 -386.54416) (xy 133.360668 -386.519928) (xy 133.358504 -386.511708)
			(xy 133.349694 -386.497188) (xy 133.343396 -386.49148) (xy 133.320028 -386.47243) (xy 133.313138 -386.467227)
			(xy 133.296904 -386.461382) (xy 133.288278 -386.461) (xy 133.258442 -386.460293) (xy 133.199319 -386.452145)
			(xy 133.141758 -386.436382) (xy 133.086734 -386.41327) (xy 133.03518 -386.383202) (xy 132.987973 -386.346688)
			(xy 132.945912 -386.304347) (xy 132.909711 -386.256899) (xy 132.879985 -386.205148) (xy 132.857238 -386.149972)
			(xy 132.841856 -386.092307) (xy 132.834099 -386.033133) (xy 132.833618 -386.003292) (xy 132.83414 -385.972229)
			(xy 132.842555 -385.910675) (xy 132.850382 -385.88061) (xy 132.853176 -385.87045) (xy 132.850636 -385.850638)
			(xy 132.803138 -385.768342) (xy 132.787136 -385.75615) (xy 132.776976 -385.75361) (xy 132.747864 -385.745617)
			(xy 132.691896 -385.722984) (xy 132.639389 -385.69319) (xy 132.591254 -385.656753) (xy 132.548327 -385.614304)
			(xy 132.511353 -385.56658) (xy 132.480974 -385.514409) (xy 132.457716 -385.458698) (xy 132.441984 -385.400413)
			(xy 132.43405 -385.340566) (xy 132.433568 -385.31038) (xy 132.434098 -385.279492) (xy 132.442403 -385.218277)
			(xy 132.458858 -385.158733) (xy 132.483167 -385.101941) (xy 132.498592 -385.075176) (xy 132.504434 -385.06527)
			(xy 132.50672 -385.042918) (xy 132.473446 -384.947668) (xy 132.457698 -384.931666) (xy 132.44703 -384.927602)
			(xy 132.423634 -384.918454) (xy 132.379739 -384.894027) (xy 132.340045 -384.863239) (xy 132.305466 -384.8268)
			(xy 132.276799 -384.785549) (xy 132.254704 -384.740435) (xy 132.239689 -384.692497) (xy 132.2321 -384.642839)
			(xy 132.231638 -384.617722) (xy 131.693158 -384.617722) (xy 131.692628 -384.644824) (xy 131.683818 -384.698307)
			(xy 131.675632 -384.724148) (xy 131.671822 -384.73507) (xy 131.674362 -384.757422) (xy 131.72694 -384.843274)
			(xy 131.74599 -384.85572) (xy 131.757166 -384.857498) (xy 131.786489 -384.862178) (xy 131.84366 -384.878231)
			(xy 131.898273 -384.901544) (xy 131.949412 -384.931727) (xy 131.996217 -384.968271) (xy 132.037902 -385.010563)
			(xy 132.073765 -385.057892) (xy 132.103205 -385.109462) (xy 132.125726 -385.164408) (xy 132.14095 -385.221805)
			(xy 132.148621 -385.280689) (xy 132.149088 -385.31038) (xy 132.148564 -385.341506) (xy 132.140159 -385.403188)
			(xy 132.132324 -385.433316) (xy 132.12953 -385.443476) (xy 132.13207 -385.463542) (xy 132.179314 -385.54533)
			(xy 132.195316 -385.557522) (xy 132.205476 -385.560062) (xy 132.23459 -385.568046) (xy 132.290556 -385.590683)
			(xy 132.343061 -385.62048) (xy 132.391194 -385.65692) (xy 132.434119 -385.69937) (xy 132.471093 -385.747094)
			(xy 132.501472 -385.799265) (xy 132.524731 -385.854975) (xy 132.540464 -385.91326) (xy 132.548401 -385.973107)
			(xy 132.548884 -386.003292) (xy 132.548759 -386.017427) (xy 132.546977 -386.045641) (xy 132.545328 -386.05968)
			(xy 132.544572 -386.068287) (xy 132.548209 -386.085166) (xy 132.55244 -386.0927) (xy 132.568188 -386.1181)
			(xy 132.572899 -386.125159) (xy 132.586004 -386.135929) (xy 132.593842 -386.139182) (xy 132.617226 -386.148359)
			(xy 132.661121 -386.172781) (xy 132.700816 -386.203564) (xy 132.735396 -386.239998) (xy 132.764065 -386.281246)
			(xy 132.786162 -386.326356) (xy 132.80118 -386.374291) (xy 132.808771 -386.423946) (xy 132.809234 -386.449062)
			(xy 132.80882 -386.473265) (xy 132.801745 -386.52115) (xy 132.787755 -386.56749) (xy 132.767151 -386.611291)
			(xy 132.754116 -386.631688) (xy 132.749324 -386.639642) (xy 132.745294 -386.657755) (xy 132.746242 -386.666994)
			(xy 132.75056 -386.697982) (xy 132.752254 -386.707275) (xy 132.761528 -386.723717) (xy 132.768594 -386.729986)
			(xy 132.790668 -386.748685) (xy 132.830443 -386.790692) (xy 132.864608 -386.837376) (xy 132.892618 -386.887993)
			(xy 132.914028 -386.941736) (xy 132.928495 -386.997748) (xy 132.935789 -387.055137) (xy 132.936234 -387.084062)
			(xy 136.983722 -387.084062) (xy 136.987793 -387.02844) (xy 136.999919 -386.974003) (xy 137.019842 -386.921912)
			(xy 137.047138 -386.873277) (xy 137.081224 -386.829134) (xy 137.121373 -386.790425) (xy 137.166731 -386.757974)
			(xy 137.216331 -386.732473) (xy 137.269115 -386.714466) (xy 137.323958 -386.704336) (xy 137.379692 -386.702299)
			(xy 137.435129 -386.708399) (xy 137.489086 -386.722505) (xy 137.540415 -386.744317) (xy 137.588021 -386.773371)
			(xy 137.630889 -386.809046) (xy 137.668106 -386.850583) (xy 137.698879 -386.897096) (xy 137.722551 -386.947593)
			(xy 137.738619 -387.001) (xy 137.746739 -387.056176) (xy 137.747248 -387.084062) (xy 137.746739 -387.111948)
			(xy 137.738619 -387.167124) (xy 137.722551 -387.220531) (xy 137.698879 -387.271028) (xy 137.668106 -387.317541)
			(xy 137.630889 -387.359078) (xy 137.588021 -387.394753) (xy 137.540415 -387.423807) (xy 137.489086 -387.445619)
			(xy 137.435129 -387.459725) (xy 137.379692 -387.465825) (xy 137.323958 -387.463788) (xy 137.269115 -387.453658)
			(xy 137.216331 -387.435651) (xy 137.166731 -387.41015) (xy 137.121373 -387.377699) (xy 137.081224 -387.33899)
			(xy 137.047138 -387.294847) (xy 137.019842 -387.246212) (xy 136.999919 -387.194121) (xy 136.987793 -387.139684)
			(xy 136.983722 -387.084062) (xy 132.936234 -387.084062) (xy 132.935645 -387.117383) (xy 132.925982 -387.183322)
			(xy 132.906856 -387.247161) (xy 132.893308 -387.27761) (xy 132.88905 -387.288072) (xy 132.889164 -387.310635)
			(xy 132.898904 -387.330987) (xy 132.907278 -387.33857) (xy 132.929504 -387.357268) (xy 132.969569 -387.399319)
			(xy 133.003992 -387.446101) (xy 133.03222 -387.496861) (xy 133.053799 -387.550786) (xy 133.068382 -387.607007)
			(xy 133.075735 -387.664621) (xy 133.076188 -387.693662) (xy 133.075698 -387.722666) (xy 133.068388 -387.780213)
			(xy 133.053867 -387.836374) (xy 133.032369 -387.890252) (xy 133.004237 -387.940982) (xy 132.969922 -387.987753)
			(xy 132.929974 -388.029814) (xy 132.907786 -388.0485) (xy 132.900674 -388.054088) (xy 132.89153 -388.069328)
			(xy 132.87629 -388.152132) (xy 132.879084 -388.169404) (xy 132.883656 -388.177532) (xy 132.896232 -388.200718)
			(xy 132.914106 -388.25034) (xy 132.920929 -388.289292) (xy 134.469124 -388.289292) (xy 134.469614 -388.259324)
			(xy 134.477437 -388.199902) (xy 134.49295 -388.142009) (xy 134.515886 -388.086636) (xy 134.545853 -388.03473)
			(xy 134.58234 -387.98718) (xy 134.62472 -387.9448) (xy 134.67227 -387.908313) (xy 134.724176 -387.878346)
			(xy 134.779549 -387.85541) (xy 134.837442 -387.839897) (xy 134.896864 -387.832074) (xy 134.9568 -387.832074)
			(xy 134.980089 -387.83514) (xy 139.455142 -387.83514) (xy 139.459213 -387.779518) (xy 139.471339 -387.725081)
			(xy 139.491262 -387.67299) (xy 139.518558 -387.624355) (xy 139.552644 -387.580212) (xy 139.592793 -387.541503)
			(xy 139.638151 -387.509052) (xy 139.687751 -387.483551) (xy 139.740535 -387.465544) (xy 139.795378 -387.455414)
			(xy 139.851112 -387.453377) (xy 139.906549 -387.459477) (xy 139.960506 -387.473583) (xy 140.011835 -387.495395)
			(xy 140.059441 -387.524449) (xy 140.102309 -387.560124) (xy 140.139526 -387.601661) (xy 140.170299 -387.648174)
			(xy 140.193971 -387.698671) (xy 140.210039 -387.752078) (xy 140.218159 -387.807254) (xy 140.218668 -387.83514)
			(xy 140.218159 -387.863026) (xy 140.210039 -387.918202) (xy 140.193971 -387.971609) (xy 140.170299 -388.022106)
			(xy 140.139526 -388.068619) (xy 140.102309 -388.110156) (xy 140.059441 -388.145831) (xy 140.011835 -388.174885)
			(xy 139.960506 -388.196697) (xy 139.906549 -388.210803) (xy 139.851112 -388.216903) (xy 139.795378 -388.214866)
			(xy 139.740535 -388.204736) (xy 139.687751 -388.186729) (xy 139.638151 -388.161228) (xy 139.592793 -388.128777)
			(xy 139.552644 -388.090068) (xy 139.518558 -388.045925) (xy 139.491262 -387.99729) (xy 139.471339 -387.945199)
			(xy 139.459213 -387.890762) (xy 139.455142 -387.83514) (xy 134.980089 -387.83514) (xy 135.016222 -387.839897)
			(xy 135.074115 -387.85541) (xy 135.129488 -387.878346) (xy 135.181394 -387.908313) (xy 135.228944 -387.9448)
			(xy 135.271324 -387.98718) (xy 135.307811 -388.03473) (xy 135.337778 -388.086636) (xy 135.360714 -388.142009)
			(xy 135.376227 -388.199902) (xy 135.38405 -388.259324) (xy 135.38454 -388.289292) (xy 135.384129 -388.317617)
			(xy 135.377128 -388.373834) (xy 135.363246 -388.428757) (xy 135.342694 -388.481548) (xy 135.315785 -388.5314)
			(xy 135.299704 -388.554722) (xy 135.29437 -388.562342) (xy 135.289544 -388.580376) (xy 135.29945 -388.666482)
			(xy 135.307832 -388.682992) (xy 135.314944 -388.689342) (xy 135.338498 -388.711032) (xy 135.37993 -388.759852)
			(xy 135.397494 -388.786624) (xy 135.405368 -388.79907) (xy 135.431276 -388.811516) (xy 135.551672 -388.798054)
			(xy 135.574278 -388.78002) (xy 135.579104 -388.76605) (xy 135.588173 -388.741528) (xy 135.612078 -388.695031)
			(xy 135.642109 -388.652233) (xy 135.677704 -388.613939) (xy 135.718195 -388.580864) (xy 135.762824 -388.553628)
			(xy 135.810754 -388.532743) (xy 135.861087 -388.518599) (xy 135.912881 -388.511462) (xy 135.939022 -388.511034)
			(xy 135.966393 -388.511479) (xy 136.020573 -388.519301) (xy 136.073077 -388.534794) (xy 136.122824 -388.557641)
			(xy 136.168789 -388.58737) (xy 136.18972 -388.605014) (xy 136.196832 -388.61111) (xy 136.21385 -388.61746)
			(xy 136.299194 -388.61746) (xy 136.316212 -388.61111) (xy 136.323324 -388.605014) (xy 136.344257 -388.587373)
			(xy 136.390225 -388.557649) (xy 136.439971 -388.534803) (xy 136.492473 -388.519307) (xy 136.546651 -388.511478)
			(xy 136.601393 -388.511478) (xy 136.655571 -388.519307) (xy 136.708073 -388.534803) (xy 136.757819 -388.557649)
			(xy 136.803787 -388.587373) (xy 136.82472 -388.605014) (xy 136.831832 -388.61111) (xy 136.84885 -388.61746)
			(xy 136.934194 -388.61746) (xy 136.951212 -388.61111) (xy 136.958324 -388.605014) (xy 136.979276 -388.587399)
			(xy 137.025243 -388.557683) (xy 137.074985 -388.534842) (xy 137.127482 -388.519346) (xy 137.181654 -388.511511)
			(xy 137.209022 -388.511034) (xy 137.236275 -388.511437) (xy 137.290227 -388.519197) (xy 137.342524 -388.534556)
			(xy 137.392104 -388.557201) (xy 137.437957 -388.586671) (xy 137.479149 -388.622366) (xy 137.514842 -388.663561)
			(xy 137.54431 -388.709415) (xy 137.566952 -388.758996) (xy 137.578507 -388.798352) (xy 138.841185 -388.798352)
			(xy 138.841185 -388.743848) (xy 138.848942 -388.689899) (xy 138.864299 -388.637603) (xy 138.886941 -388.588025)
			(xy 138.916409 -388.542175) (xy 138.952103 -388.500984) (xy 138.993295 -388.465294) (xy 139.039148 -388.435829)
			(xy 139.088728 -388.413189) (xy 139.141025 -388.397837) (xy 139.194974 -388.390083) (xy 139.222226 -388.389622)
			(xy 139.249597 -388.390067) (xy 139.303777 -388.397889) (xy 139.356281 -388.413383) (xy 139.406027 -388.436229)
			(xy 139.451993 -388.465959) (xy 139.472924 -388.483602) (xy 139.480036 -388.489698) (xy 139.497054 -388.496048)
			(xy 139.582398 -388.496048) (xy 139.599416 -388.489698) (xy 139.606528 -388.483602) (xy 139.627477 -388.465984)
			(xy 139.673445 -388.436269) (xy 139.723188 -388.413429) (xy 139.775685 -388.397933) (xy 139.829858 -388.390099)
			(xy 139.857226 -388.389622) (xy 139.884478 -388.39005) (xy 139.938427 -388.39781) (xy 139.990723 -388.413168)
			(xy 140.040301 -388.435813) (xy 140.086152 -388.465282) (xy 140.127342 -388.500976) (xy 140.163034 -388.542169)
			(xy 140.1925 -388.588022) (xy 140.215141 -388.637601) (xy 140.230496 -388.689898) (xy 140.238252 -388.743848)
			(xy 140.238252 -388.798352) (xy 140.230496 -388.852302) (xy 140.215141 -388.904599) (xy 140.1925 -388.954178)
			(xy 140.163034 -389.000031) (xy 140.127342 -389.041224) (xy 140.086152 -389.076918) (xy 140.040301 -389.106387)
			(xy 139.990723 -389.129032) (xy 139.938427 -389.14439) (xy 139.884478 -389.15215) (xy 139.857226 -389.152638)
			(xy 139.829856 -389.152172) (xy 139.775676 -389.144356) (xy 139.723172 -389.128868) (xy 139.673425 -389.106026)
			(xy 139.627459 -389.0763) (xy 139.606528 -389.058658) (xy 139.599416 -389.052562) (xy 139.582398 -389.046212)
			(xy 139.497054 -389.046212) (xy 139.480036 -389.052562) (xy 139.472924 -389.058658) (xy 139.451988 -389.076293)
			(xy 139.406017 -389.106007) (xy 139.356271 -389.128844) (xy 139.303771 -389.144336) (xy 139.249595 -389.152164)
			(xy 139.222226 -389.152638) (xy 139.194974 -389.152117) (xy 139.141025 -389.144363) (xy 139.088728 -389.129011)
			(xy 139.039148 -389.106371) (xy 138.993295 -389.076906) (xy 138.952103 -389.041216) (xy 138.916409 -389.000025)
			(xy 138.886941 -388.954175) (xy 138.864299 -388.904597) (xy 138.848942 -388.852301) (xy 138.841185 -388.798352)
			(xy 137.578507 -388.798352) (xy 137.582307 -388.811295) (xy 137.590064 -388.865247) (xy 137.590064 -388.919753)
			(xy 137.582307 -388.973705) (xy 137.566952 -389.026004) (xy 137.54431 -389.075585) (xy 137.514842 -389.121439)
			(xy 137.479149 -389.162634) (xy 137.437957 -389.198329) (xy 137.392104 -389.227799) (xy 137.342524 -389.250444)
			(xy 137.290227 -389.265803) (xy 137.236275 -389.273563) (xy 137.209022 -389.27405) (xy 137.181652 -389.273583)
			(xy 137.127472 -389.265767) (xy 137.074969 -389.250279) (xy 137.025222 -389.227437) (xy 136.979255 -389.197712)
			(xy 136.958324 -389.18007) (xy 136.951212 -389.173974) (xy 136.934194 -389.167624) (xy 136.84885 -389.167624)
			(xy 136.831832 -389.173974) (xy 136.82472 -389.18007) (xy 136.803787 -389.197711) (xy 136.757819 -389.227435)
			(xy 136.708073 -389.250281) (xy 136.655571 -389.265777) (xy 136.601393 -389.273606) (xy 136.546651 -389.273606)
			(xy 136.492473 -389.265777) (xy 136.439971 -389.250281) (xy 136.390225 -389.227435) (xy 136.344257 -389.197711)
			(xy 136.323324 -389.18007) (xy 136.316212 -389.173974) (xy 136.299194 -389.167624) (xy 136.21385 -389.167624)
			(xy 136.196832 -389.173974) (xy 136.18972 -389.18007) (xy 136.168787 -389.197709) (xy 136.122815 -389.227421)
			(xy 136.073068 -389.250258) (xy 136.020567 -389.265749) (xy 135.966391 -389.273577) (xy 135.939022 -389.27405)
			(xy 135.909227 -389.273501) (xy 135.850362 -389.264238) (xy 135.793652 -389.245935) (xy 135.740479 -389.219037)
			(xy 135.692135 -389.184198) (xy 135.649796 -389.142265) (xy 135.631682 -389.118602) (xy 135.622792 -389.106664)
			(xy 135.596122 -389.095996) (xy 135.476996 -389.118094) (xy 135.45566 -389.137652) (xy 135.45185 -389.151876)
			(xy 135.444795 -389.176349) (xy 135.425957 -389.223672) (xy 135.401971 -389.268606) (xy 135.387842 -389.289798)
			(xy 135.382508 -389.297672) (xy 135.37819 -389.315706) (xy 135.38962 -389.402066) (xy 135.39851 -389.418322)
			(xy 135.405876 -389.424672) (xy 135.427173 -389.443325) (xy 135.465435 -389.485053) (xy 135.498255 -389.531184)
			(xy 135.525133 -389.581013) (xy 135.545657 -389.633776) (xy 135.559514 -389.688669) (xy 135.566493 -389.744852)
			(xy 135.566912 -389.77316) (xy 135.566433 -389.80228) (xy 135.559014 -389.860046) (xy 135.544328 -389.916404)
			(xy 135.533892 -389.943594) (xy 135.530706 -389.952633) (xy 135.530634 -389.971786) (xy 135.537588 -389.989633)
			(xy 135.543798 -389.996934) (xy 135.562682 -390.018084) (xy 135.595593 -390.064255) (xy 135.622546 -390.114139)
			(xy 135.64313 -390.166972) (xy 135.657027 -390.221943) (xy 135.664026 -390.27821) (xy 135.664448 -390.30656)
			(xy 135.664001 -390.335718) (xy 135.656574 -390.39356) (xy 135.656134 -390.395249) (xy 137.098806 -390.395249)
			(xy 137.098806 -390.340751) (xy 137.106562 -390.286809) (xy 137.121915 -390.234519) (xy 137.144553 -390.184947)
			(xy 137.174016 -390.1391) (xy 137.209704 -390.097914) (xy 137.250889 -390.062225) (xy 137.296734 -390.03276)
			(xy 137.346306 -390.01012) (xy 137.398595 -389.994765) (xy 137.452537 -389.987007) (xy 137.479786 -389.98652)
			(xy 137.507156 -389.986989) (xy 137.561335 -389.994806) (xy 137.613839 -390.010294) (xy 137.663586 -390.033135)
			(xy 137.709552 -390.062859) (xy 137.730484 -390.0805) (xy 137.737596 -390.086596) (xy 137.754614 -390.092946)
			(xy 137.839958 -390.092946) (xy 137.856976 -390.086596) (xy 137.864088 -390.0805) (xy 137.885014 -390.062853)
			(xy 137.930988 -390.033142) (xy 137.980737 -390.010308) (xy 138.033239 -389.994819) (xy 138.087416 -389.986993)
			(xy 138.114786 -389.98652) (xy 138.142042 -389.986926) (xy 138.195998 -389.994682) (xy 138.248301 -390.010038)
			(xy 138.297887 -390.032681) (xy 138.343745 -390.062151) (xy 138.384943 -390.097847) (xy 138.420641 -390.139043)
			(xy 138.450112 -390.184901) (xy 138.472757 -390.234485) (xy 138.488115 -390.286788) (xy 138.495873 -390.340744)
			(xy 138.495873 -390.395256) (xy 138.488115 -390.449212) (xy 138.472757 -390.501515) (xy 138.450112 -390.551099)
			(xy 138.420641 -390.596957) (xy 138.384943 -390.638153) (xy 138.343745 -390.673849) (xy 138.297887 -390.703319)
			(xy 138.248301 -390.725962) (xy 138.195998 -390.741318) (xy 138.142042 -390.749074) (xy 138.114786 -390.749536)
			(xy 138.087415 -390.749094) (xy 138.033234 -390.741273) (xy 137.98073 -390.725779) (xy 137.930983 -390.702931)
			(xy 137.885018 -390.6732) (xy 137.864088 -390.655556) (xy 137.856976 -390.64946) (xy 137.839958 -390.64311)
			(xy 137.754614 -390.64311) (xy 137.737596 -390.64946) (xy 137.730484 -390.655556) (xy 137.709525 -390.673162)
			(xy 137.663561 -390.702881) (xy 137.61382 -390.725724) (xy 137.561325 -390.741222) (xy 137.507153 -390.749058)
			(xy 137.479786 -390.749536) (xy 137.452537 -390.748993) (xy 137.398595 -390.741235) (xy 137.346306 -390.72588)
			(xy 137.296734 -390.70324) (xy 137.250889 -390.673775) (xy 137.209704 -390.638087) (xy 137.174016 -390.5969)
			(xy 137.144553 -390.551053) (xy 137.121915 -390.501481) (xy 137.106562 -390.449191) (xy 137.098806 -390.395249)
			(xy 135.656134 -390.395249) (xy 135.641862 -390.44999) (xy 135.620101 -390.504095) (xy 135.591646 -390.554997)
			(xy 135.556956 -390.601874) (xy 135.516593 -390.643965) (xy 135.471211 -390.680589) (xy 135.421546 -390.711153)
			(xy 135.368401 -390.735162) (xy 135.312637 -390.752226) (xy 135.255157 -390.762071) (xy 135.226044 -390.76376)
			(xy 135.2169 -390.764268) (xy 135.200136 -390.77138) (xy 135.138414 -390.829038) (xy 135.130286 -390.845294)
			(xy 135.129524 -390.854438) (xy 135.126112 -390.881139) (xy 135.111748 -390.933013) (xy 135.089178 -390.981879)
			(xy 135.058998 -391.026447) (xy 135.022002 -391.065545) (xy 134.979168 -391.09814) (xy 134.931623 -391.123373)
			(xy 134.880621 -391.140579) (xy 134.827507 -391.149305) (xy 134.800594 -391.14984) (xy 134.774608 -391.149304)
			(xy 134.723277 -391.141174) (xy 134.673849 -391.125114) (xy 134.627541 -391.10152) (xy 134.585495 -391.070973)
			(xy 134.548744 -391.034225) (xy 134.518194 -390.992181) (xy 134.494596 -390.945875) (xy 134.478532 -390.896449)
			(xy 134.470398 -390.845118) (xy 134.469886 -390.819132) (xy 134.470332 -390.79363) (xy 134.478165 -390.74323)
			(xy 134.493649 -390.694632) (xy 134.516416 -390.648991) (xy 134.545926 -390.60739) (xy 134.581478 -390.570817)
			(xy 134.622227 -390.540142) (xy 134.667206 -390.516093) (xy 134.69112 -390.50722) (xy 134.699756 -390.504172)
			(xy 134.713472 -390.492488) (xy 134.75589 -390.419082) (xy 134.758938 -390.401302) (xy 134.75716 -390.392158)
			(xy 134.753366 -390.370962) (xy 134.749292 -390.328092) (xy 134.749032 -390.30656) (xy 134.749515 -390.27744)
			(xy 134.756932 -390.219674) (xy 134.771617 -390.163316) (xy 134.782052 -390.136126) (xy 134.785234 -390.127085)
			(xy 134.785313 -390.107932) (xy 134.778358 -390.090086) (xy 134.772146 -390.082786) (xy 134.753279 -390.061622)
			(xy 134.720365 -390.015454) (xy 134.693408 -389.965573) (xy 134.672821 -389.912743) (xy 134.658921 -389.857775)
			(xy 134.651919 -389.80151) (xy 134.651496 -389.77316) (xy 134.651895 -389.74564) (xy 134.658504 -389.690998)
			(xy 134.67162 -389.637543) (xy 134.691054 -389.586048) (xy 134.716527 -389.537257) (xy 134.73176 -389.514334)
			(xy 134.737094 -389.50646) (xy 134.741412 -389.488426) (xy 134.729982 -389.402066) (xy 134.721092 -389.38581)
			(xy 134.713726 -389.37946) (xy 134.692445 -389.36079) (xy 134.654182 -389.319064) (xy 134.62136 -389.272936)
			(xy 134.59448 -389.223111) (xy 134.573953 -389.17035) (xy 134.560093 -389.11546) (xy 134.553111 -389.059279)
			(xy 134.55269 -389.030972) (xy 134.553129 -389.002648) (xy 134.560122 -388.946432) (xy 134.573998 -388.891509)
			(xy 134.594544 -388.838717) (xy 134.621447 -388.788864) (xy 134.637526 -388.765542) (xy 134.64286 -388.757922)
			(xy 134.647686 -388.739888) (xy 134.63778 -388.653782) (xy 134.629398 -388.637272) (xy 134.622286 -388.630922)
			(xy 134.598658 -388.609102) (xy 134.5571 -388.56002) (xy 134.522826 -388.505601) (xy 134.496512 -388.446918)
			(xy 134.478675 -388.385128) (xy 134.469669 -388.321448) (xy 134.469124 -388.289292) (xy 132.920929 -388.289292)
			(xy 132.923206 -388.302291) (xy 132.923788 -388.328662) (xy 132.92372 -388.338021) (xy 132.922576 -388.356703)
			(xy 132.921502 -388.366) (xy 132.920486 -388.37489) (xy 132.924296 -388.391654) (xy 132.968238 -388.461504)
			(xy 132.981954 -388.471918) (xy 132.990336 -388.474712) (xy 133.014364 -388.483182) (xy 133.059536 -388.506734)
			(xy 133.100341 -388.537233) (xy 133.13572 -388.573888) (xy 133.164756 -388.615747) (xy 133.186695 -388.661725)
			(xy 133.194298 -388.68604) (xy 133.195822 -388.691882) (xy 133.516116 -389.245602) (xy 133.52018 -389.24992)
			(xy 133.536368 -389.267642) (xy 133.563796 -389.307028) (xy 133.584942 -389.350114) (xy 133.599319 -389.395906)
			(xy 133.606596 -389.443346) (xy 133.607048 -389.467344) (xy 133.606647 -389.49215) (xy 133.598875 -389.541151)
			(xy 133.58353 -389.588332) (xy 133.560991 -389.632529) (xy 133.531811 -389.672654) (xy 133.496712 -389.707718)
			(xy 133.456557 -389.736857) (xy 133.412337 -389.759352) (xy 133.365141 -389.774649) (xy 133.316133 -389.782371)
			(xy 133.291326 -389.782812) (xy 133.265932 -389.782289) (xy 133.2158 -389.774162) (xy 133.167615 -389.758114)
			(xy 133.12262 -389.73456) (xy 133.081977 -389.704105) (xy 133.046734 -389.667537) (xy 133.0178 -389.625798)
			(xy 132.995921 -389.579966) (xy 132.988304 -389.555736) (xy 132.98678 -389.549894) (xy 132.666486 -388.996174)
			(xy 132.662422 -388.991856) (xy 132.646257 -388.974127) (xy 132.618891 -388.934723) (xy 132.597802 -388.891632)
			(xy 132.583476 -388.845846) (xy 132.576242 -388.79842) (xy 132.575808 -388.774432) (xy 132.575889 -388.762384)
			(xy 132.577672 -388.738355) (xy 132.579364 -388.726426) (xy 132.580634 -388.717536) (xy 132.577586 -388.700518)
			(xy 132.535422 -388.629652) (xy 132.522214 -388.618476) (xy 132.513832 -388.615428) (xy 132.492076 -388.607054)
			(xy 132.451219 -388.584608) (xy 132.414249 -388.55621) (xy 132.382028 -388.522522) (xy 132.355304 -388.484325)
			(xy 132.3347 -388.442509) (xy 132.320693 -388.398046) (xy 132.31361 -388.351971) (xy 132.313172 -388.328662)
			(xy 132.313741 -388.302289) (xy 132.322823 -388.250331) (xy 132.34071 -388.200711) (xy 132.353304 -388.177532)
			(xy 132.357876 -388.169404) (xy 132.36067 -388.152132) (xy 132.34543 -388.069328) (xy 132.336286 -388.054088)
			(xy 132.329174 -388.0485) (xy 132.306998 -388.0298) (xy 132.267052 -387.987737) (xy 132.232736 -387.940968)
			(xy 132.204598 -387.890241) (xy 132.183089 -387.836367) (xy 132.168553 -387.78021) (xy 132.161223 -387.722666)
			(xy 132.160772 -387.693662) (xy 132.161369 -387.660341) (xy 132.171028 -387.594403) (xy 132.190152 -387.530563)
			(xy 132.203698 -387.500114) (xy 132.207931 -387.489644) (xy 132.207826 -387.467088) (xy 132.198097 -387.446738)
			(xy 132.189728 -387.439154) (xy 132.167467 -387.420496) (xy 132.127403 -387.378439) (xy 132.092983 -387.33165)
			(xy 132.06476 -387.280882) (xy 132.043187 -387.226951) (xy 132.028611 -387.170724) (xy 132.021266 -387.113105)
			(xy 132.020818 -387.084062) (xy 132.021282 -387.055136) (xy 132.028565 -386.997745) (xy 132.043023 -386.941729)
			(xy 132.064425 -386.887982) (xy 132.09243 -386.83736) (xy 132.126591 -386.790672) (xy 132.166364 -386.748661)
			(xy 132.188458 -386.729986) (xy 132.19543 -386.723638) (xy 132.204688 -386.707235) (xy 132.206492 -386.697982)
			(xy 132.21081 -386.666994) (xy 132.21172 -386.657758) (xy 132.207693 -386.639657) (xy 132.202936 -386.631688)
			(xy 132.186631 -386.605841) (xy 132.162726 -386.549606) (xy 132.155438 -386.519928) (xy 132.153369 -386.511769)
			(xy 132.144674 -386.497367) (xy 132.13842 -386.491734) (xy 132.115306 -386.472684) (xy 132.108419 -386.467448)
			(xy 132.092194 -386.461476) (xy 132.083556 -386.461) (xy 132.053919 -386.459996) (xy 131.995254 -386.451346)
			(xy 131.938197 -386.435195) (xy 131.883703 -386.411811) (xy 131.832684 -386.381588) (xy 131.785994 -386.345031)
			(xy 131.744415 -386.302751) (xy 131.708643 -386.255456) (xy 131.679276 -386.203939) (xy 131.656807 -386.149062)
			(xy 131.641611 -386.091743) (xy 131.633943 -386.032942) (xy 131.633468 -386.003292) (xy 131.633989 -385.972229)
			(xy 131.642405 -385.910675) (xy 131.650232 -385.88061) (xy 131.653026 -385.87045) (xy 131.650486 -385.850638)
			(xy 131.602988 -385.768342) (xy 131.586986 -385.75615) (xy 131.576826 -385.75361) (xy 131.547737 -385.745583)
			(xy 131.49181 -385.722915) (xy 131.439344 -385.693099) (xy 131.39125 -385.656649) (xy 131.34836 -385.614198)
			(xy 131.311418 -385.566482) (xy 131.281063 -385.514326) (xy 131.257821 -385.458635) (xy 131.242096 -385.400375)
			(xy 131.234159 -385.340553) (xy 131.233672 -385.31038) (xy 131.234202 -385.279492) (xy 131.242506 -385.218277)
			(xy 131.258962 -385.158733) (xy 131.28327 -385.101941) (xy 131.298696 -385.075176) (xy 131.304538 -385.06527)
			(xy 131.306824 -385.042918) (xy 131.27355 -384.947668) (xy 131.257802 -384.931666) (xy 131.247134 -384.927602)
			(xy 131.223739 -384.918452) (xy 131.179844 -384.894025) (xy 131.14015 -384.863238) (xy 131.105571 -384.826799)
			(xy 131.076904 -384.785548) (xy 131.054808 -384.740434) (xy 131.039793 -384.692497) (xy 131.032204 -384.642839)
			(xy 131.031742 -384.617722) (xy 130.493008 -384.617722) (xy 130.492475 -384.644824) (xy 130.483667 -384.698306)
			(xy 130.475482 -384.724148) (xy 130.471672 -384.73507) (xy 130.474212 -384.757422) (xy 130.52679 -384.843274)
			(xy 130.54584 -384.85572) (xy 130.557016 -384.857498) (xy 130.586332 -384.862217) (xy 130.643503 -384.878264)
			(xy 130.698117 -384.901572) (xy 130.749256 -384.931749) (xy 130.796062 -384.968289) (xy 130.837748 -385.010577)
			(xy 130.873612 -385.057903) (xy 130.903053 -385.10947) (xy 130.925575 -385.164413) (xy 130.940799 -385.221808)
			(xy 130.948471 -385.28069) (xy 130.948938 -385.31038) (xy 130.948412 -385.341443) (xy 130.939999 -385.402996)
			(xy 130.932174 -385.433062) (xy 130.92938 -385.443222) (xy 130.93192 -385.463034) (xy 130.979418 -385.54533)
			(xy 130.99542 -385.557522) (xy 131.00558 -385.560062) (xy 131.034695 -385.568043) (xy 131.090661 -385.590681)
			(xy 131.143166 -385.620478) (xy 131.191298 -385.656918) (xy 131.234224 -385.699369) (xy 131.271197 -385.747094)
			(xy 131.301576 -385.799264) (xy 131.324835 -385.854975) (xy 131.340569 -385.91326) (xy 131.348505 -385.973107)
			(xy 131.348988 -386.003292) (xy 131.348863 -386.017427) (xy 131.347081 -386.045641) (xy 131.345432 -386.05968)
			(xy 131.344675 -386.068287) (xy 131.348313 -386.085167) (xy 131.352544 -386.0927) (xy 131.368292 -386.1181)
			(xy 131.373001 -386.12516) (xy 131.386107 -386.135929) (xy 131.393946 -386.139182) (xy 131.417331 -386.148357)
			(xy 131.461226 -386.172779) (xy 131.500921 -386.203562) (xy 131.5355 -386.239997) (xy 131.564169 -386.281245)
			(xy 131.586266 -386.326356) (xy 131.601284 -386.374291) (xy 131.608875 -386.423946) (xy 131.609338 -386.449062)
			(xy 131.608923 -386.473265) (xy 131.601848 -386.52115) (xy 131.587859 -386.56749) (xy 131.567255 -386.611291)
			(xy 131.55422 -386.631688) (xy 131.549429 -386.639643) (xy 131.545398 -386.657755) (xy 131.546346 -386.666994)
			(xy 131.550664 -386.697982) (xy 131.552357 -386.707275) (xy 131.561631 -386.723717) (xy 131.568698 -386.729986)
			(xy 131.590772 -386.748684) (xy 131.630547 -386.790691) (xy 131.664712 -386.837376) (xy 131.692723 -386.887993)
			(xy 131.714132 -386.941736) (xy 131.728599 -386.997748) (xy 131.735893 -387.055137) (xy 131.736338 -387.084062)
			(xy 131.735748 -387.117383) (xy 131.726086 -387.183322) (xy 131.70696 -387.247161) (xy 131.693412 -387.27761)
			(xy 131.689153 -387.288072) (xy 131.689266 -387.310635) (xy 131.699007 -387.330988) (xy 131.707382 -387.33857)
			(xy 131.729609 -387.357267) (xy 131.769674 -387.399318) (xy 131.804097 -387.4461) (xy 131.832324 -387.496861)
			(xy 131.853903 -387.550786) (xy 131.868486 -387.607007) (xy 131.875839 -387.664621) (xy 131.876292 -387.693662)
			(xy 131.875801 -387.722666) (xy 131.86849 -387.780212) (xy 131.85397 -387.836374) (xy 131.832472 -387.890252)
			(xy 131.80434 -387.940982) (xy 131.770025 -387.987753) (xy 131.730078 -388.029814) (xy 131.70789 -388.0485)
			(xy 131.700778 -388.054088) (xy 131.691634 -388.069328) (xy 131.676394 -388.152132) (xy 131.679188 -388.169404)
			(xy 131.68376 -388.177532) (xy 131.696337 -388.200718) (xy 131.71421 -388.25034) (xy 131.72331 -388.302291)
			(xy 131.723892 -388.328662) (xy 131.723824 -388.338021) (xy 131.72268 -388.356703) (xy 131.721606 -388.366)
			(xy 131.72059 -388.37489) (xy 131.7244 -388.391654) (xy 131.768342 -388.461504) (xy 131.782058 -388.471918)
			(xy 131.79044 -388.474712) (xy 131.814546 -388.48317) (xy 131.859836 -388.506802) (xy 131.900729 -388.537417)
			(xy 131.936159 -388.574219) (xy 131.9652 -388.616245) (xy 131.987095 -388.6624) (xy 131.994656 -388.686802)
			(xy 131.99618 -388.692644) (xy 132.315966 -389.245602) (xy 132.32003 -389.24992) (xy 132.336223 -389.267625)
			(xy 132.363587 -389.307034) (xy 132.384672 -389.350132) (xy 132.398991 -389.395923) (xy 132.406215 -389.443354)
			(xy 132.406644 -389.467344) (xy 132.406222 -389.492136) (xy 132.398459 -389.541109) (xy 132.383131 -389.588264)
			(xy 132.360615 -389.632441) (xy 132.331466 -389.672552) (xy 132.2964 -389.70761) (xy 132.256283 -389.736751)
			(xy 132.212101 -389.759257) (xy 132.164942 -389.774575) (xy 132.115968 -389.782328) (xy 132.091176 -389.782812)
			(xy 132.065781 -389.782333) (xy 132.015646 -389.774198) (xy 131.96746 -389.758143) (xy 131.922466 -389.734582)
			(xy 131.881823 -389.704121) (xy 131.846581 -389.667548) (xy 131.817648 -389.625804) (xy 131.79577 -389.579967)
			(xy 131.788154 -389.555736) (xy 131.78663 -389.549894) (xy 131.466082 -388.995412) (xy 131.462018 -388.991094)
			(xy 131.445913 -388.973438) (xy 131.418727 -388.934137) (xy 131.397777 -388.891187) (xy 131.383542 -388.845569)
			(xy 131.376347 -388.798326) (xy 131.375912 -388.774432) (xy 131.375993 -388.762384) (xy 131.377776 -388.738355)
			(xy 131.379468 -388.726426) (xy 131.380738 -388.717536) (xy 131.37769 -388.700518) (xy 131.335526 -388.629652)
			(xy 131.322318 -388.618476) (xy 131.313936 -388.615428) (xy 131.292181 -388.607051) (xy 131.251323 -388.584606)
			(xy 131.214354 -388.556209) (xy 131.182133 -388.522521) (xy 131.155409 -388.484324) (xy 131.134804 -388.442509)
			(xy 131.120797 -388.398046) (xy 131.113714 -388.35197) (xy 131.113276 -388.328662) (xy 131.113845 -388.302289)
			(xy 131.122927 -388.250331) (xy 131.140814 -388.20071) (xy 131.153408 -388.177532) (xy 131.15798 -388.169404)
			(xy 131.160774 -388.152132) (xy 131.145534 -388.069328) (xy 131.13639 -388.054088) (xy 131.129278 -388.0485)
			(xy 131.107103 -388.029799) (xy 131.067157 -387.987736) (xy 131.03284 -387.940967) (xy 131.004702 -387.89024)
			(xy 130.983193 -387.836367) (xy 130.968657 -387.780209) (xy 130.961327 -387.722666) (xy 130.960876 -387.693662)
			(xy 130.961473 -387.660341) (xy 130.971132 -387.594402) (xy 130.990256 -387.530563) (xy 131.003802 -387.500114)
			(xy 131.008034 -387.489643) (xy 131.007928 -387.467088) (xy 130.9982 -387.446738) (xy 130.989832 -387.439154)
			(xy 130.967572 -387.420495) (xy 130.927508 -387.378438) (xy 130.893088 -387.331649) (xy 130.864864 -387.280882)
			(xy 130.843291 -387.226951) (xy 130.828715 -387.170724) (xy 130.82137 -387.113105) (xy 130.820922 -387.084062)
			(xy 130.821384 -387.055136) (xy 130.828667 -386.997745) (xy 130.843125 -386.941729) (xy 130.864528 -386.887981)
			(xy 130.892533 -386.83736) (xy 130.926694 -386.790671) (xy 130.966468 -386.74866) (xy 130.988562 -386.729986)
			(xy 130.995534 -386.723639) (xy 131.004792 -386.707235) (xy 131.006596 -386.697982) (xy 131.010914 -386.666994)
			(xy 131.011823 -386.657758) (xy 131.007796 -386.639657) (xy 131.00304 -386.631688) (xy 130.986735 -386.60584)
			(xy 130.96283 -386.549606) (xy 130.955542 -386.519928) (xy 130.953472 -386.51177) (xy 130.944778 -386.497367)
			(xy 130.938524 -386.491734) (xy 130.91541 -386.472684) (xy 130.908522 -386.46745) (xy 130.892298 -386.461477)
			(xy 130.88366 -386.461) (xy 130.854023 -386.459992) (xy 130.795358 -386.451343) (xy 130.738301 -386.435192)
			(xy 130.683807 -386.411809) (xy 130.632788 -386.381586) (xy 130.586098 -386.345029) (xy 130.544519 -386.30275)
			(xy 130.508747 -386.255456) (xy 130.47938 -386.203939) (xy 130.456911 -386.149062) (xy 130.441715 -386.091743)
			(xy 130.434047 -386.032941) (xy 130.433572 -386.003292) (xy 130.434092 -385.972229) (xy 130.442509 -385.910675)
			(xy 130.450336 -385.88061) (xy 130.45313 -385.87045) (xy 130.45059 -385.850638) (xy 130.403092 -385.768342)
			(xy 130.38709 -385.75615) (xy 130.37693 -385.75361) (xy 130.347809 -385.745648) (xy 130.291842 -385.72301)
			(xy 130.239336 -385.693211) (xy 130.191202 -385.656769) (xy 130.148276 -385.614316) (xy 130.111303 -385.566589)
			(xy 130.080925 -385.514416) (xy 130.057668 -385.458703) (xy 130.041937 -385.400416) (xy 130.034003 -385.340566)
			(xy 130.033522 -385.31038) (xy 130.034045 -385.279492) (xy 130.04235 -385.218276) (xy 130.058808 -385.158732)
			(xy 130.083119 -385.101941) (xy 130.098546 -385.075176) (xy 130.104388 -385.06527) (xy 130.106674 -385.042918)
			(xy 130.0734 -384.947668) (xy 130.057652 -384.931666) (xy 130.046984 -384.927602) (xy 130.0236 -384.918425)
			(xy 129.979703 -384.894004) (xy 129.940007 -384.863222) (xy 129.905426 -384.826788) (xy 129.876757 -384.78554)
			(xy 129.85466 -384.740429) (xy 129.839644 -384.692494) (xy 129.832054 -384.642838) (xy 129.831592 -384.617722)
			(xy 129.293112 -384.617722) (xy 129.292579 -384.644824) (xy 129.283771 -384.698306) (xy 129.275586 -384.724148)
			(xy 129.271776 -384.73507) (xy 129.274316 -384.757422) (xy 129.326894 -384.843274) (xy 129.345944 -384.85572)
			(xy 129.35712 -384.857498) (xy 129.386437 -384.862214) (xy 129.443607 -384.878261) (xy 129.498221 -384.90157)
			(xy 129.549361 -384.931747) (xy 129.596167 -384.968288) (xy 129.637852 -385.010576) (xy 129.673716 -385.057902)
			(xy 129.703157 -385.10947) (xy 129.725679 -385.164413) (xy 129.740903 -385.221808) (xy 129.748575 -385.28069)
			(xy 129.749042 -385.31038) (xy 129.748519 -385.341506) (xy 129.740113 -385.403188) (xy 129.732278 -385.433316)
			(xy 129.729484 -385.443476) (xy 129.732024 -385.463542) (xy 129.779268 -385.54533) (xy 129.79527 -385.557522)
			(xy 129.80543 -385.560062) (xy 129.834535 -385.568077) (xy 129.890502 -385.590708) (xy 129.943008 -385.6205)
			(xy 129.991142 -385.656936) (xy 130.034068 -385.699383) (xy 130.071043 -385.747104) (xy 130.101423 -385.799271)
			(xy 130.124683 -385.85498) (xy 130.140418 -385.913262) (xy 130.148354 -385.973107) (xy 130.148838 -386.003292)
			(xy 130.148713 -386.017427) (xy 130.146931 -386.045641) (xy 130.145282 -386.05968) (xy 130.144518 -386.068287)
			(xy 130.148159 -386.085168) (xy 130.152394 -386.0927) (xy 130.168142 -386.1181) (xy 130.172835 -386.125173)
			(xy 130.185952 -386.135935) (xy 130.193796 -386.139182) (xy 130.21717 -386.148384) (xy 130.261067 -386.1728)
			(xy 130.300763 -386.203578) (xy 130.335345 -386.240009) (xy 130.364016 -386.281253) (xy 130.386115 -386.326361)
			(xy 130.401133 -386.374293) (xy 130.408725 -386.423947) (xy 130.409188 -386.449062) (xy 130.408765 -386.473264)
			(xy 130.401691 -386.521149) (xy 130.387704 -386.567489) (xy 130.367104 -386.611291) (xy 130.35407 -386.631688)
			(xy 130.349282 -386.639645) (xy 130.345248 -386.657756) (xy 130.346196 -386.666994) (xy 130.350514 -386.697982)
			(xy 130.352192 -386.707279) (xy 130.361475 -386.723721) (xy 130.368548 -386.729986) (xy 130.390633 -386.748672)
			(xy 130.430406 -386.790682) (xy 130.464568 -386.83737) (xy 130.492576 -386.887989) (xy 130.513984 -386.941733)
			(xy 130.52845 -386.997747) (xy 130.535743 -387.055136) (xy 130.536188 -387.084062) (xy 130.535594 -387.117383)
			(xy 130.525932 -387.183321) (xy 130.506808 -387.247161) (xy 130.493262 -387.27761) (xy 130.488986 -387.288068)
			(xy 130.489099 -387.310637) (xy 130.49885 -387.330991) (xy 130.507232 -387.33857) (xy 130.529469 -387.357255)
			(xy 130.569532 -387.399309) (xy 130.603952 -387.446094) (xy 130.632178 -387.496857) (xy 130.653755 -387.550783)
			(xy 130.668337 -387.607005) (xy 130.675689 -387.664621) (xy 130.676142 -387.693662) (xy 130.675669 -387.722667)
			(xy 130.668358 -387.780215) (xy 130.653836 -387.836377) (xy 130.632335 -387.890256) (xy 130.6042 -387.940986)
			(xy 130.569881 -387.987756) (xy 130.52993 -388.029816) (xy 130.50774 -388.0485) (xy 130.500628 -388.054088)
			(xy 130.491484 -388.069328) (xy 130.476244 -388.152132) (xy 130.479038 -388.169404) (xy 130.48361 -388.177532)
			(xy 130.496183 -388.20072) (xy 130.514058 -388.250341) (xy 130.52316 -388.302292) (xy 130.523742 -388.328662)
			(xy 130.523673 -388.338021) (xy 130.52253 -388.356703) (xy 130.521456 -388.366) (xy 130.52044 -388.37489)
			(xy 130.52425 -388.391654) (xy 130.568192 -388.461504) (xy 130.581908 -388.471918) (xy 130.59029 -388.474712)
			(xy 130.614308 -388.483207) (xy 130.659482 -388.506752) (xy 130.700289 -388.537246) (xy 130.73567 -388.573896)
			(xy 130.764708 -388.615751) (xy 130.786648 -388.661726) (xy 130.794252 -388.68604) (xy 130.795776 -388.691882)
			(xy 131.11607 -389.245602) (xy 131.120134 -389.24992) (xy 131.136328 -389.267624) (xy 131.163691 -389.307034)
			(xy 131.184776 -389.350131) (xy 131.199095 -389.395923) (xy 131.206319 -389.443354) (xy 131.206748 -389.467344)
			(xy 131.206323 -389.492136) (xy 131.198559 -389.541108) (xy 131.183231 -389.588263) (xy 131.160716 -389.63244)
			(xy 131.131567 -389.672551) (xy 131.096502 -389.707608) (xy 131.056385 -389.736749) (xy 131.012204 -389.759256)
			(xy 130.965046 -389.774574) (xy 130.916072 -389.782328) (xy 130.89128 -389.782812) (xy 130.865885 -389.782329)
			(xy 130.815751 -389.774195) (xy 130.767565 -389.758141) (xy 130.72257 -389.73458) (xy 130.681928 -389.70412)
			(xy 130.646685 -389.667547) (xy 130.617752 -389.625804) (xy 130.595874 -389.579967) (xy 130.588258 -389.555736)
			(xy 130.586734 -389.549894) (xy 130.26644 -388.996174) (xy 130.262376 -388.991856) (xy 130.246169 -388.974151)
			(xy 130.218746 -388.934759) (xy 130.197604 -388.891669) (xy 130.183231 -388.845874) (xy 130.175958 -388.798431)
			(xy 130.175508 -388.774432) (xy 130.17565 -388.76238) (xy 130.177556 -388.73835) (xy 130.179318 -388.726426)
			(xy 130.180588 -388.717536) (xy 130.17754 -388.700518) (xy 130.135376 -388.629652) (xy 130.122168 -388.618476)
			(xy 130.113786 -388.615428) (xy 130.092042 -388.607024) (xy 130.051183 -388.584585) (xy 130.014211 -388.556194)
			(xy 129.981988 -388.522509) (xy 129.955262 -388.484317) (xy 129.934656 -388.442504) (xy 129.920648 -388.398043)
			(xy 129.913564 -388.35197) (xy 129.913126 -388.328662) (xy 129.913688 -388.302289) (xy 129.922772 -388.25033)
			(xy 129.940662 -388.20071) (xy 129.953258 -388.177532) (xy 129.95783 -388.169404) (xy 129.960624 -388.152132)
			(xy 129.945384 -388.069328) (xy 129.93624 -388.054088) (xy 129.929128 -388.0485) (xy 129.906963 -388.029787)
			(xy 129.867015 -387.987728) (xy 129.832696 -387.940961) (xy 129.804556 -387.890236) (xy 129.783045 -387.836365)
			(xy 129.768508 -387.780208) (xy 129.761177 -387.722666) (xy 129.760726 -387.693662) (xy 129.761327 -387.660341)
			(xy 129.770986 -387.594403) (xy 129.790107 -387.530563) (xy 129.803652 -387.500114) (xy 129.8079 -387.489648)
			(xy 129.807796 -387.467086) (xy 129.798057 -387.446735) (xy 129.789682 -387.439154) (xy 129.767411 -387.420508)
			(xy 129.72735 -387.378447) (xy 129.692932 -387.331655) (xy 129.664711 -387.280886) (xy 129.643139 -387.226953)
			(xy 129.628564 -387.170725) (xy 129.62122 -387.113105) (xy 129.620772 -387.084062) (xy 129.621216 -387.055135)
			(xy 129.6285 -386.997742) (xy 129.64296 -386.941725) (xy 129.664365 -386.887977) (xy 129.692373 -386.837356)
			(xy 129.726538 -386.790668) (xy 129.766315 -386.748659) (xy 129.788412 -386.729986) (xy 129.795376 -386.723631)
			(xy 129.80464 -386.707233) (xy 129.806446 -386.697982) (xy 129.810764 -386.666994) (xy 129.811665 -386.657757)
			(xy 129.807642 -386.639658) (xy 129.80289 -386.631688) (xy 129.786581 -386.605843) (xy 129.762678 -386.549607)
			(xy 129.755392 -386.519928) (xy 129.753335 -386.511765) (xy 129.744633 -386.497364) (xy 129.738374 -386.491734)
			(xy 129.71526 -386.472684) (xy 129.708385 -386.46743) (xy 129.692151 -386.461469) (xy 129.68351 -386.461)
			(xy 129.653875 -386.459946) (xy 129.595212 -386.451303) (xy 129.538155 -386.435158) (xy 129.483661 -386.411781)
			(xy 129.432642 -386.381563) (xy 129.385952 -386.34501) (xy 129.344372 -386.302734) (xy 129.308599 -386.255444)
			(xy 129.279232 -386.20393) (xy 129.256762 -386.149055) (xy 129.241565 -386.091739) (xy 129.233897 -386.03294)
			(xy 129.233422 -386.003292) (xy 129.233944 -385.972229) (xy 129.242359 -385.910675) (xy 129.250186 -385.88061)
			(xy 129.25298 -385.87045) (xy 129.25044 -385.850638) (xy 129.202942 -385.768342) (xy 129.18694 -385.75615)
			(xy 129.17678 -385.75361) (xy 129.147701 -385.745547) (xy 129.091773 -385.722886) (xy 129.039307 -385.693075)
			(xy 128.991211 -385.656631) (xy 128.94832 -385.614184) (xy 128.911376 -385.566471) (xy 128.881019 -385.514319)
			(xy 128.857776 -385.45863) (xy 128.84205 -385.400372) (xy 128.834113 -385.340552) (xy 128.833626 -385.31038)
			(xy 128.834148 -385.279492) (xy 128.842454 -385.218276) (xy 128.858911 -385.158732) (xy 128.883223 -385.101941)
			(xy 128.89865 -385.075176) (xy 128.904492 -385.06527) (xy 128.906778 -385.042918) (xy 128.873504 -384.947668)
			(xy 128.857756 -384.931666) (xy 128.847088 -384.927602) (xy 128.823705 -384.918422) (xy 128.779808 -384.894003)
			(xy 128.740112 -384.863221) (xy 128.705531 -384.826787) (xy 128.676861 -384.78554) (xy 128.654764 -384.740429)
			(xy 128.639748 -384.692494) (xy 128.632158 -384.642838) (xy 128.631696 -384.617722) (xy 128.092962 -384.617722)
			(xy 128.092431 -384.644824) (xy 128.083622 -384.698307) (xy 128.075436 -384.724148) (xy 128.071626 -384.73507)
			(xy 128.074166 -384.757422) (xy 128.126744 -384.843274) (xy 128.145794 -384.85572) (xy 128.15697 -384.857498)
			(xy 128.186293 -384.862175) (xy 128.243464 -384.878228) (xy 128.298078 -384.901542) (xy 128.349217 -384.931725)
			(xy 128.396022 -384.96827) (xy 128.437706 -385.010562) (xy 128.473569 -385.057891) (xy 128.503009 -385.109462)
			(xy 128.52553 -385.164407) (xy 128.540754 -385.221805) (xy 128.548425 -385.280689) (xy 128.548892 -385.31038)
			(xy 128.548364 -385.341443) (xy 128.539953 -385.402996) (xy 128.532128 -385.433062) (xy 128.529334 -385.443222)
			(xy 128.531874 -385.463034) (xy 128.579372 -385.54533) (xy 128.595374 -385.557522) (xy 128.605534 -385.560062)
			(xy 128.63464 -385.568074) (xy 128.690606 -385.590706) (xy 128.743112 -385.620499) (xy 128.791246 -385.656934)
			(xy 128.834173 -385.699382) (xy 128.871147 -385.747103) (xy 128.901528 -385.799271) (xy 128.924787 -385.854979)
			(xy 128.940522 -385.913262) (xy 128.948458 -385.973107) (xy 128.948942 -386.003292) (xy 128.948817 -386.017427)
			(xy 128.947035 -386.045641) (xy 128.945386 -386.05968) (xy 128.944621 -386.068287) (xy 128.948263 -386.085168)
			(xy 128.952498 -386.0927) (xy 128.968246 -386.1181) (xy 128.972938 -386.125174) (xy 128.986056 -386.135935)
			(xy 128.9939 -386.139182) (xy 129.017275 -386.148381) (xy 129.061172 -386.172798) (xy 129.100868 -386.203577)
			(xy 129.135449 -386.240008) (xy 129.16412 -386.281252) (xy 129.186219 -386.32636) (xy 129.201237 -386.374293)
			(xy 129.208829 -386.423947) (xy 129.209292 -386.449062) (xy 129.208868 -386.473264) (xy 129.201794 -386.521149)
			(xy 129.187808 -386.567489) (xy 129.167207 -386.611291) (xy 129.154174 -386.631688) (xy 129.149386 -386.639645)
			(xy 129.145352 -386.657756) (xy 129.1463 -386.666994) (xy 129.150618 -386.697982) (xy 129.152294 -386.70728)
			(xy 129.161579 -386.723721) (xy 129.168652 -386.729986) (xy 129.190738 -386.748671) (xy 129.23051 -386.790682)
			(xy 129.264673 -386.837369) (xy 129.292681 -386.887988) (xy 129.314088 -386.941733) (xy 129.328554 -386.997747)
			(xy 129.335847 -387.055136) (xy 129.336292 -387.084062) (xy 129.335697 -387.117383) (xy 129.326036 -387.183321)
			(xy 129.306912 -387.247161) (xy 129.293366 -387.27761) (xy 129.289122 -387.288076) (xy 129.289236 -387.310633)
			(xy 129.298968 -387.330984) (xy 129.307336 -387.33857) (xy 129.329574 -387.357254) (xy 129.369636 -387.399309)
			(xy 129.404057 -387.446094) (xy 129.432282 -387.496857) (xy 129.453859 -387.550783) (xy 129.468441 -387.607005)
			(xy 129.475793 -387.664621) (xy 129.476246 -387.693662) (xy 129.475771 -387.722667) (xy 129.46846 -387.780214)
			(xy 129.453938 -387.836377) (xy 129.432438 -387.890255) (xy 129.404303 -387.940986) (xy 129.369985 -387.987756)
			(xy 129.330034 -388.029815) (xy 129.307844 -388.0485) (xy 129.300732 -388.054088) (xy 129.291588 -388.069328)
			(xy 129.276348 -388.152132) (xy 129.279142 -388.169404) (xy 129.283714 -388.177532) (xy 129.296287 -388.20072)
			(xy 129.314162 -388.25034) (xy 129.323264 -388.302291) (xy 129.323846 -388.328662) (xy 129.323777 -388.338021)
			(xy 129.322634 -388.356703) (xy 129.32156 -388.366) (xy 129.320544 -388.37489) (xy 129.324354 -388.391654)
			(xy 129.368296 -388.461504) (xy 129.382012 -388.471918) (xy 129.390394 -388.474712) (xy 129.41449 -388.483195)
			(xy 129.459781 -388.50682) (xy 129.500677 -388.53743) (xy 129.536108 -388.574227) (xy 129.565152 -388.61625)
			(xy 129.587048 -388.662401) (xy 129.59461 -388.686802) (xy 129.596134 -388.692644) (xy 129.91592 -389.245602)
			(xy 129.919984 -389.24992) (xy 129.936173 -389.267641) (xy 129.9636 -389.307028) (xy 129.984746 -389.350114)
			(xy 129.999123 -389.395906) (xy 130.0064 -389.443346) (xy 130.006852 -389.467344) (xy 130.006447 -389.49215)
			(xy 129.998675 -389.54115) (xy 129.983331 -389.588331) (xy 129.960791 -389.632528) (xy 129.931613 -389.672653)
			(xy 129.896514 -389.707717) (xy 129.85636 -389.736856) (xy 129.81214 -389.759351) (xy 129.764945 -389.774648)
			(xy 129.715937 -389.782371) (xy 129.69113 -389.782812) (xy 129.665737 -389.782285) (xy 129.615604 -389.774159)
			(xy 129.567419 -389.758112) (xy 129.522425 -389.734558) (xy 129.481782 -389.704104) (xy 129.446538 -389.667536)
			(xy 129.417604 -389.625798) (xy 129.395725 -389.579965) (xy 129.388108 -389.555736) (xy 129.386584 -389.549894)
			(xy 129.066036 -388.995412) (xy 129.061972 -388.991094) (xy 129.045872 -388.973421) (xy 129.018623 -388.934143)
			(xy 128.997611 -388.891204) (xy 128.983318 -388.845586) (xy 128.976071 -388.798334) (xy 128.975612 -388.774432)
			(xy 128.975754 -388.76238) (xy 128.97766 -388.73835) (xy 128.979422 -388.726426) (xy 128.980692 -388.717536)
			(xy 128.977644 -388.700518) (xy 128.93548 -388.629652) (xy 128.922272 -388.618476) (xy 128.91389 -388.615428)
			(xy 128.892147 -388.607022) (xy 128.851287 -388.584584) (xy 128.814316 -388.556192) (xy 128.782093 -388.522509)
			(xy 128.755367 -388.484316) (xy 128.73476 -388.442503) (xy 128.720752 -388.398043) (xy 128.713668 -388.351969)
			(xy 128.71323 -388.328662) (xy 128.713792 -388.302289) (xy 128.722876 -388.25033) (xy 128.740766 -388.20071)
			(xy 128.753362 -388.177532) (xy 128.757934 -388.169404) (xy 128.760728 -388.152132) (xy 128.745488 -388.069328)
			(xy 128.736344 -388.054088) (xy 128.729232 -388.0485) (xy 128.707068 -388.029786) (xy 128.667119 -387.987727)
			(xy 128.6328 -387.940961) (xy 128.60466 -387.890236) (xy 128.583149 -387.836364) (xy 128.568612 -387.780208)
			(xy 128.561281 -387.722666) (xy 128.56083 -387.693662) (xy 128.561431 -387.660341) (xy 128.571089 -387.594403)
			(xy 128.590211 -387.530563) (xy 128.603756 -387.500114) (xy 128.608003 -387.489647) (xy 128.607898 -387.467086)
			(xy 128.598161 -387.446735) (xy 128.589786 -387.439154) (xy 128.567516 -387.420507) (xy 128.527455 -387.378446)
			(xy 128.493037 -387.331655) (xy 128.464815 -387.280885) (xy 128.443243 -387.226953) (xy 128.428668 -387.170725)
			(xy 128.421324 -387.113105) (xy 128.420876 -387.084062) (xy 128.421319 -387.055135) (xy 128.428603 -386.997742)
			(xy 128.443063 -386.941725) (xy 128.464467 -386.887977) (xy 128.492476 -386.837356) (xy 128.526642 -386.790668)
			(xy 128.566419 -386.748659) (xy 128.588516 -386.729986) (xy 128.595481 -386.723631) (xy 128.604744 -386.707233)
			(xy 128.60655 -386.697982) (xy 128.610868 -386.666994) (xy 128.611769 -386.657757) (xy 128.607746 -386.639658)
			(xy 128.602994 -386.631688) (xy 128.586685 -386.605843) (xy 128.562782 -386.549607) (xy 128.555496 -386.519928)
			(xy 128.553438 -386.511766) (xy 128.544736 -386.497365) (xy 128.538478 -386.491734) (xy 128.515364 -386.472684)
			(xy 128.508488 -386.467431) (xy 128.492255 -386.46147) (xy 128.483614 -386.461) (xy 128.453979 -386.459943)
			(xy 128.395316 -386.4513) (xy 128.33826 -386.435155) (xy 128.283766 -386.411778) (xy 128.232746 -386.381561)
			(xy 128.186056 -386.345008) (xy 128.144476 -386.302733) (xy 128.108703 -386.255443) (xy 128.079336 -386.203929)
			(xy 128.056866 -386.149055) (xy 128.041669 -386.091739) (xy 128.034001 -386.03294) (xy 128.033526 -386.003292)
			(xy 128.034048 -385.972229) (xy 128.042463 -385.910675) (xy 128.05029 -385.88061) (xy 128.053084 -385.87045)
			(xy 128.050544 -385.850638) (xy 128.003046 -385.768342) (xy 127.987044 -385.75615) (xy 127.976884 -385.75361)
			(xy 127.947774 -385.745612) (xy 127.891806 -385.72298) (xy 127.839298 -385.693187) (xy 127.791163 -385.65675)
			(xy 127.748236 -385.614301) (xy 127.711262 -385.566578) (xy 127.680882 -385.514408) (xy 127.657624 -385.458697)
			(xy 127.641892 -385.400413) (xy 127.633958 -385.340565) (xy 127.633476 -385.31038) (xy 127.634005 -385.279492)
			(xy 127.64231 -385.218277) (xy 127.658766 -385.158733) (xy 127.683074 -385.101941) (xy 127.6985 -385.075176)
			(xy 127.704342 -385.06527) (xy 127.706628 -385.042918) (xy 127.673354 -384.947668) (xy 127.657606 -384.931666)
			(xy 127.646938 -384.927602) (xy 127.623544 -384.918449) (xy 127.579649 -384.894023) (xy 127.539954 -384.863237)
			(xy 127.505375 -384.826798) (xy 127.476708 -384.785547) (xy 127.454612 -384.740434) (xy 127.439597 -384.692497)
			(xy 127.432008 -384.642839) (xy 127.431546 -384.617722) (xy 126.893066 -384.617722) (xy 126.892535 -384.644824)
			(xy 126.883726 -384.698307) (xy 126.87554 -384.724148) (xy 126.87173 -384.73507) (xy 126.87427 -384.757422)
			(xy 126.926848 -384.843274) (xy 126.945898 -384.85572) (xy 126.957074 -384.857498) (xy 126.986398 -384.862172)
			(xy 127.043569 -384.878225) (xy 127.098182 -384.90154) (xy 127.149321 -384.931723) (xy 127.196126 -384.968268)
			(xy 127.23781 -385.010561) (xy 127.273674 -385.05789) (xy 127.303113 -385.109461) (xy 127.325634 -385.164407)
			(xy 127.340858 -385.221804) (xy 127.348529 -385.280689) (xy 127.348996 -385.31038) (xy 127.348471 -385.341443)
			(xy 127.340058 -385.402997) (xy 127.332232 -385.433062) (xy 127.329438 -385.443222) (xy 127.331978 -385.463034)
			(xy 127.379476 -385.54533) (xy 127.395478 -385.557522) (xy 127.405638 -385.560062) (xy 127.434745 -385.568071)
			(xy 127.490711 -385.590704) (xy 127.543217 -385.620497) (xy 127.591351 -385.656933) (xy 127.634277 -385.69938)
			(xy 127.671251 -385.747102) (xy 127.701632 -385.79927) (xy 127.724891 -385.854979) (xy 127.740626 -385.913262)
			(xy 127.748562 -385.973107) (xy 127.749046 -386.003292) (xy 127.748921 -386.017427) (xy 127.747139 -386.045641)
			(xy 127.74549 -386.05968) (xy 127.744724 -386.068287) (xy 127.748367 -386.085168) (xy 127.752602 -386.0927)
			(xy 127.76835 -386.1181) (xy 127.77306 -386.125162) (xy 127.786159 -386.135942) (xy 127.794004 -386.139182)
			(xy 127.817347 -386.148424) (xy 127.861191 -386.172876) (xy 127.900836 -386.203672) (xy 127.935371 -386.240107)
			(xy 127.964004 -386.281342) (xy 127.986076 -386.326431) (xy 128.001081 -386.374337) (xy 128.008673 -386.423961)
			(xy 128.009142 -386.449062) (xy 128.008726 -386.473265) (xy 128.001652 -386.52115) (xy 127.987663 -386.56749)
			(xy 127.967059 -386.611291) (xy 127.954024 -386.631688) (xy 127.949233 -386.639643) (xy 127.945202 -386.657755)
			(xy 127.94615 -386.666994) (xy 127.950468 -386.697982) (xy 127.95216 -386.707275) (xy 127.961435 -386.723717)
			(xy 127.968502 -386.729986) (xy 127.990577 -386.748683) (xy 128.030352 -386.790691) (xy 128.064517 -386.837375)
			(xy 128.092527 -386.887993) (xy 128.113936 -386.941736) (xy 128.128403 -386.997748) (xy 128.135697 -387.055137)
			(xy 128.136142 -387.084062) (xy 128.135552 -387.117383) (xy 128.12589 -387.183322) (xy 128.106764 -387.247161)
			(xy 128.093216 -387.27761) (xy 128.088955 -387.288071) (xy 128.089069 -387.310635) (xy 128.098811 -387.330988)
			(xy 128.107186 -387.33857) (xy 128.129413 -387.357266) (xy 128.169478 -387.399317) (xy 128.203901 -387.4461)
			(xy 128.232129 -387.496861) (xy 128.253707 -387.550785) (xy 128.26829 -387.607007) (xy 128.275643 -387.664621)
			(xy 128.276096 -387.693662) (xy 128.275603 -387.722666) (xy 128.268293 -387.780212) (xy 128.253773 -387.836374)
			(xy 128.232274 -387.890251) (xy 128.204143 -387.940982) (xy 128.169829 -387.987753) (xy 128.129881 -388.029814)
			(xy 128.107694 -388.0485) (xy 128.100582 -388.054088) (xy 128.091438 -388.069328) (xy 128.076198 -388.152132)
			(xy 128.078992 -388.169404) (xy 128.083564 -388.177532) (xy 128.096141 -388.200718) (xy 128.114014 -388.25034)
			(xy 128.123114 -388.302291) (xy 128.123696 -388.328662) (xy 128.123628 -388.338021) (xy 128.122484 -388.356703)
			(xy 128.12141 -388.366) (xy 128.120394 -388.37489) (xy 128.124204 -388.391654) (xy 128.168146 -388.461504)
			(xy 128.181862 -388.471918) (xy 128.190244 -388.474712) (xy 128.214273 -388.483178) (xy 128.259445 -388.506731)
			(xy 128.30025 -388.537231) (xy 128.335629 -388.573886) (xy 128.364665 -388.615746) (xy 128.386603 -388.661724)
			(xy 128.394206 -388.68604) (xy 128.39573 -388.691882) (xy 128.716024 -389.245602) (xy 128.720088 -389.24992)
			(xy 128.736278 -389.26764) (xy 128.763704 -389.307028) (xy 128.78485 -389.350114) (xy 128.799227 -389.395906)
			(xy 128.806504 -389.443346) (xy 128.806956 -389.467344) (xy 128.806547 -389.49215) (xy 128.798775 -389.54115)
			(xy 128.783431 -389.58833) (xy 128.760892 -389.632527) (xy 128.731714 -389.672651) (xy 128.696615 -389.707715)
			(xy 128.656462 -389.736854) (xy 128.612243 -389.75935) (xy 128.565048 -389.774648) (xy 128.516041 -389.782371)
			(xy 128.491234 -389.782812) (xy 128.465841 -389.782282) (xy 128.415708 -389.774156) (xy 128.367524 -389.75811)
			(xy 128.322529 -389.734556) (xy 128.281886 -389.704103) (xy 128.246643 -389.667535) (xy 128.217708 -389.625797)
			(xy 128.195829 -389.579965) (xy 128.188212 -389.555736) (xy 128.186688 -389.549894) (xy 127.866394 -388.996174)
			(xy 127.86233 -388.991856) (xy 127.846167 -388.974126) (xy 127.8188 -388.934722) (xy 127.79771 -388.891631)
			(xy 127.783384 -388.845846) (xy 127.77615 -388.79842) (xy 127.775716 -388.774432) (xy 127.775797 -388.762384)
			(xy 127.777579 -388.738355) (xy 127.779272 -388.726426) (xy 127.780542 -388.717536) (xy 127.777494 -388.700518)
			(xy 127.73533 -388.629652) (xy 127.722122 -388.618476) (xy 127.71374 -388.615428) (xy 127.691986 -388.607049)
			(xy 127.651128 -388.584604) (xy 127.614159 -388.556208) (xy 127.581937 -388.52252) (xy 127.555213 -388.484324)
			(xy 127.534608 -388.442508) (xy 127.520601 -388.398046) (xy 127.513518 -388.35197) (xy 127.51308 -388.328662)
			(xy 127.513648 -388.302289) (xy 127.522731 -388.250331) (xy 127.540618 -388.20071) (xy 127.553212 -388.177532)
			(xy 127.557784 -388.169404) (xy 127.560578 -388.152132) (xy 127.545338 -388.069328) (xy 127.536194 -388.054088)
			(xy 127.529082 -388.0485) (xy 127.506908 -388.029798) (xy 127.466961 -387.987736) (xy 127.432645 -387.940967)
			(xy 127.404507 -387.89024) (xy 127.382998 -387.836367) (xy 127.368461 -387.780209) (xy 127.361131 -387.722666)
			(xy 127.36068 -387.693662) (xy 127.361276 -387.660341) (xy 127.370936 -387.594402) (xy 127.390059 -387.530563)
			(xy 127.403606 -387.500114) (xy 127.407836 -387.489643) (xy 127.407731 -387.467088) (xy 127.398003 -387.446738)
			(xy 127.389636 -387.439154) (xy 127.367376 -387.420494) (xy 127.327313 -387.378437) (xy 127.292892 -387.331649)
			(xy 127.264668 -387.280881) (xy 127.243095 -387.226951) (xy 127.228519 -387.170724) (xy 127.221174 -387.113105)
			(xy 127.220726 -387.084062) (xy 127.221187 -387.055136) (xy 127.22847 -386.997744) (xy 127.242928 -386.941728)
			(xy 127.264331 -386.887981) (xy 127.292336 -386.83736) (xy 127.326498 -386.790671) (xy 127.366271 -386.74866)
			(xy 127.388366 -386.729986) (xy 127.395339 -386.72364) (xy 127.404596 -386.707235) (xy 127.4064 -386.697982)
			(xy 127.410718 -386.666994) (xy 127.411627 -386.657757) (xy 127.4076 -386.639657) (xy 127.402844 -386.631688)
			(xy 127.38654 -386.60584) (xy 127.362634 -386.549606) (xy 127.355346 -386.519928) (xy 127.353275 -386.51177)
			(xy 127.344582 -386.497367) (xy 127.338328 -386.491734) (xy 127.315214 -386.472684) (xy 127.308383 -386.467479)
			(xy 127.292291 -386.461508) (xy 127.283718 -386.461) (xy 127.254083 -386.459939) (xy 127.19542 -386.451297)
			(xy 127.138364 -386.435153) (xy 127.08387 -386.411776) (xy 127.032851 -386.381559) (xy 126.98616 -386.345007)
			(xy 126.94458 -386.302732) (xy 126.908807 -386.255442) (xy 126.87944 -386.203929) (xy 126.85697 -386.149055)
			(xy 126.841773 -386.091739) (xy 126.834105 -386.03294) (xy 126.83363 -386.003292) (xy 126.834151 -385.972229)
			(xy 126.842567 -385.910675) (xy 126.850394 -385.88061) (xy 126.853188 -385.87045) (xy 126.850648 -385.850638)
			(xy 126.80315 -385.768342) (xy 126.787148 -385.75615) (xy 126.776988 -385.75361) (xy 126.747878 -385.745609)
			(xy 126.69191 -385.722978) (xy 126.639403 -385.693185) (xy 126.591268 -385.656749) (xy 126.548341 -385.6143)
			(xy 126.511366 -385.566577) (xy 126.480986 -385.514408) (xy 126.457728 -385.458697) (xy 126.441996 -385.400412)
			(xy 126.434062 -385.340565) (xy 126.43358 -385.31038) (xy 126.434109 -385.279492) (xy 126.442413 -385.218277)
			(xy 126.458869 -385.158733) (xy 126.483178 -385.101941) (xy 126.498604 -385.075176) (xy 126.504446 -385.06527)
			(xy 126.506732 -385.042918) (xy 126.473458 -384.947668) (xy 126.45771 -384.931666) (xy 126.447042 -384.927602)
			(xy 126.423649 -384.918447) (xy 126.379753 -384.894022) (xy 126.340059 -384.863235) (xy 126.30548 -384.826797)
			(xy 126.276812 -384.785547) (xy 126.254716 -384.740434) (xy 126.239701 -384.692496) (xy 126.232112 -384.642839)
			(xy 126.23165 -384.617722) (xy 125.69317 -384.617722) (xy 125.692639 -384.644824) (xy 125.68383 -384.698307)
			(xy 125.675644 -384.724148) (xy 125.671834 -384.73507) (xy 125.674374 -384.757422) (xy 125.726952 -384.843528)
			(xy 125.745748 -384.85572) (xy 125.757178 -384.857498) (xy 125.786472 -384.862279) (xy 125.843606 -384.878356)
			(xy 125.898182 -384.901685) (xy 125.949285 -384.931874) (xy 125.996055 -384.968417) (xy 126.037709 -385.010699)
			(xy 126.073547 -385.058011) (xy 126.102968 -385.10956) (xy 126.125477 -385.16448) (xy 126.140698 -385.221848)
			(xy 126.148374 -385.280703) (xy 126.148846 -385.31038) (xy 126.148319 -385.341443) (xy 126.139907 -385.402996)
			(xy 126.132082 -385.433062) (xy 126.129288 -385.443222) (xy 126.131828 -385.463034) (xy 126.179326 -385.54533)
			(xy 126.195328 -385.557522) (xy 126.205488 -385.560062) (xy 126.234604 -385.568038) (xy 126.29057 -385.590676)
			(xy 126.343075 -385.620475) (xy 126.391207 -385.656916) (xy 126.434133 -385.699367) (xy 126.471106 -385.747092)
			(xy 126.501485 -385.799263) (xy 126.524743 -385.854974) (xy 126.540477 -385.913259) (xy 126.548413 -385.973106)
			(xy 126.548896 -386.003292) (xy 126.548771 -386.017427) (xy 126.546989 -386.045641) (xy 126.54534 -386.05968)
			(xy 126.544582 -386.068287) (xy 126.54822 -386.085167) (xy 126.552452 -386.0927) (xy 126.5682 -386.1181)
			(xy 126.572907 -386.125162) (xy 126.586014 -386.13593) (xy 126.593854 -386.139182) (xy 126.617241 -386.148352)
			(xy 126.661136 -386.172776) (xy 126.70083 -386.20356) (xy 126.735409 -386.239996) (xy 126.764078 -386.281244)
			(xy 126.786175 -386.326355) (xy 126.801192 -386.37429) (xy 126.808783 -386.423946) (xy 126.809246 -386.449062)
			(xy 126.80883 -386.473265) (xy 126.801755 -386.52115) (xy 126.787766 -386.56749) (xy 126.767163 -386.611291)
			(xy 126.754128 -386.631688) (xy 126.749337 -386.639643) (xy 126.745306 -386.657756) (xy 126.746254 -386.666994)
			(xy 126.750572 -386.697982) (xy 126.752262 -386.707276) (xy 126.761538 -386.723718) (xy 126.768606 -386.729986)
			(xy 126.790682 -386.748682) (xy 126.830457 -386.79069) (xy 126.864621 -386.837375) (xy 126.892631 -386.887992)
			(xy 126.91404 -386.941735) (xy 126.928507 -386.997748) (xy 126.935801 -387.055137) (xy 126.936246 -387.084062)
			(xy 126.935656 -387.117383) (xy 126.925993 -387.183322) (xy 126.906867 -387.247161) (xy 126.89332 -387.27761)
			(xy 126.889058 -387.288071) (xy 126.889172 -387.310635) (xy 126.898914 -387.330988) (xy 126.90729 -387.33857)
			(xy 126.929518 -387.357265) (xy 126.969583 -387.399317) (xy 127.004005 -387.446099) (xy 127.032233 -387.49686)
			(xy 127.053811 -387.550785) (xy 127.068394 -387.607007) (xy 127.075747 -387.664621) (xy 127.0762 -387.693662)
			(xy 127.075742 -387.722668) (xy 127.06843 -387.780216) (xy 127.053906 -387.83638) (xy 127.032403 -387.890259)
			(xy 127.004266 -387.940989) (xy 126.969944 -387.987758) (xy 126.929989 -388.029816) (xy 126.907798 -388.0485)
			(xy 126.900686 -388.054088) (xy 126.891542 -388.069328) (xy 126.876302 -388.152132) (xy 126.879096 -388.169404)
			(xy 126.883668 -388.177532) (xy 126.896237 -388.200722) (xy 126.914115 -388.250341) (xy 126.923218 -388.302292)
			(xy 126.9238 -388.328662) (xy 126.923732 -388.338021) (xy 126.922588 -388.356703) (xy 126.921514 -388.366)
			(xy 126.920498 -388.37489) (xy 126.924308 -388.391654) (xy 126.96825 -388.461504) (xy 126.981966 -388.471918)
			(xy 126.990348 -388.474712) (xy 127.014378 -388.483175) (xy 127.05955 -388.506729) (xy 127.100355 -388.53723)
			(xy 127.135734 -388.573886) (xy 127.164769 -388.615746) (xy 127.186707 -388.661724) (xy 127.19431 -388.68604)
			(xy 127.195834 -388.691882) (xy 127.516128 -389.245602) (xy 127.520192 -389.24992) (xy 127.536382 -389.26764)
			(xy 127.563809 -389.307027) (xy 127.584954 -389.350114) (xy 127.599331 -389.395906) (xy 127.606608 -389.443346)
			(xy 127.60706 -389.467344) (xy 127.606647 -389.49215) (xy 127.598875 -389.541149) (xy 127.583531 -389.588329)
			(xy 127.560993 -389.632525) (xy 127.531815 -389.67265) (xy 127.496717 -389.707714) (xy 127.456564 -389.736853)
			(xy 127.412346 -389.759349) (xy 127.365151 -389.774647) (xy 127.316144 -389.782371) (xy 127.291338 -389.782812)
			(xy 127.265945 -389.782278) (xy 127.215813 -389.774153) (xy 127.167628 -389.758107) (xy 127.122634 -389.734554)
			(xy 127.08199 -389.704101) (xy 127.046747 -389.667534) (xy 127.017812 -389.625797) (xy 126.995933 -389.579965)
			(xy 126.988316 -389.555736) (xy 126.986792 -389.549894) (xy 126.666498 -388.996174) (xy 126.662434 -388.991856)
			(xy 126.646271 -388.974125) (xy 126.618904 -388.934722) (xy 126.597815 -388.891631) (xy 126.583488 -388.845846)
			(xy 126.576254 -388.79842) (xy 126.57582 -388.774432) (xy 126.575901 -388.762384) (xy 126.577683 -388.738355)
			(xy 126.579376 -388.726426) (xy 126.580646 -388.717536) (xy 126.577598 -388.700518) (xy 126.535434 -388.629652)
			(xy 126.522226 -388.618476) (xy 126.513844 -388.615428) (xy 126.492091 -388.607047) (xy 126.451233 -388.584603)
			(xy 126.414263 -388.556207) (xy 126.382042 -388.522519) (xy 126.355317 -388.484323) (xy 126.334712 -388.442508)
			(xy 126.320705 -388.398046) (xy 126.313622 -388.35197) (xy 126.313184 -388.328662) (xy 126.313752 -388.302289)
			(xy 126.322834 -388.250331) (xy 126.340722 -388.20071) (xy 126.353316 -388.177532) (xy 126.357888 -388.169404)
			(xy 126.360682 -388.152132) (xy 126.345442 -388.069328) (xy 126.336298 -388.054088) (xy 126.329186 -388.0485)
			(xy 126.307012 -388.029797) (xy 126.267066 -387.987735) (xy 126.232749 -387.940966) (xy 126.204611 -387.89024)
			(xy 126.183102 -387.836367) (xy 126.168565 -387.780209) (xy 126.161235 -387.722666) (xy 126.160784 -387.693662)
			(xy 126.16138 -387.660341) (xy 126.17104 -387.594402) (xy 126.190163 -387.530563) (xy 126.20371 -387.500114)
			(xy 126.207939 -387.489643) (xy 126.207834 -387.467088) (xy 126.198107 -387.446739) (xy 126.18974 -387.439154)
			(xy 126.167481 -387.420493) (xy 126.127417 -387.378437) (xy 126.092997 -387.331648) (xy 126.064773 -387.280881)
			(xy 126.043199 -387.226951) (xy 126.028623 -387.170724) (xy 126.021278 -387.113105) (xy 126.02083 -387.084062)
			(xy 126.021289 -387.055136) (xy 126.028573 -386.997744) (xy 126.043031 -386.941728) (xy 126.064433 -386.887981)
			(xy 126.092439 -386.837359) (xy 126.126601 -386.790671) (xy 126.166375 -386.74866) (xy 126.18847 -386.729986)
			(xy 126.195443 -386.72364) (xy 126.2047 -386.707235) (xy 126.206504 -386.697982) (xy 126.210822 -386.666994)
			(xy 126.21173 -386.657757) (xy 126.207704 -386.639657) (xy 126.202948 -386.631688) (xy 126.186635 -386.605845)
			(xy 126.162735 -386.549608) (xy 126.15545 -386.519928) (xy 126.153378 -386.51177) (xy 126.144685 -386.497368)
			(xy 126.138432 -386.491734) (xy 126.115318 -386.472684) (xy 126.108428 -386.467453) (xy 126.092205 -386.461478)
			(xy 126.083568 -386.461) (xy 126.053932 -386.459985) (xy 125.995267 -386.451337) (xy 125.93821 -386.435187)
			(xy 125.883716 -386.411805) (xy 125.832697 -386.381582) (xy 125.786007 -386.345026) (xy 125.744427 -386.302747)
			(xy 125.708655 -386.255454) (xy 125.679288 -386.203937) (xy 125.656819 -386.149061) (xy 125.641623 -386.091742)
			(xy 125.633955 -386.032941) (xy 125.63348 -386.003292) (xy 125.634 -385.972229) (xy 125.642417 -385.910675)
			(xy 125.650244 -385.88061) (xy 125.653038 -385.87045) (xy 125.650498 -385.850638) (xy 125.603 -385.768342)
			(xy 125.586998 -385.75615) (xy 125.576838 -385.75361) (xy 125.547719 -385.745643) (xy 125.491751 -385.723005)
			(xy 125.439245 -385.693207) (xy 125.391111 -385.656766) (xy 125.348185 -385.614314) (xy 125.311212 -385.566587)
			(xy 125.280833 -385.514415) (xy 125.257576 -385.458702) (xy 125.241845 -385.400415) (xy 125.233911 -385.340566)
			(xy 125.23343 -385.31038) (xy 125.233905 -385.279458) (xy 125.242187 -385.218171) (xy 125.258652 -385.158559)
			(xy 125.282999 -385.10171) (xy 125.298454 -385.074922) (xy 125.30455 -385.06527) (xy 125.306836 -385.042918)
			(xy 125.273308 -384.947668) (xy 125.25756 -384.931666) (xy 125.246892 -384.927602) (xy 125.223543 -384.918376)
			(xy 125.179698 -384.893922) (xy 125.140053 -384.863123) (xy 125.105518 -384.826686) (xy 125.076886 -384.785449)
			(xy 125.054815 -384.740358) (xy 125.039812 -384.692449) (xy 125.032222 -384.642823) (xy 125.031754 -384.617722)
			(xy 124.49302 -384.617722) (xy 124.492487 -384.644824) (xy 124.483679 -384.698306) (xy 124.475494 -384.724148)
			(xy 124.471684 -384.73507) (xy 124.474224 -384.757422) (xy 124.526802 -384.843274) (xy 124.545852 -384.85572)
			(xy 124.557028 -384.857498) (xy 124.586346 -384.862208) (xy 124.643516 -384.878256) (xy 124.69813 -384.901565)
			(xy 124.74927 -384.931744) (xy 124.796076 -384.968285) (xy 124.837761 -385.010574) (xy 124.873625 -385.0579)
			(xy 124.903065 -385.109468) (xy 124.925587 -385.164412) (xy 124.940811 -385.221807) (xy 124.948483 -385.28069)
			(xy 124.94895 -385.31038) (xy 124.948423 -385.341443) (xy 124.940011 -385.402996) (xy 124.932186 -385.433062)
			(xy 124.929392 -385.443222) (xy 124.931932 -385.463034) (xy 124.97943 -385.54533) (xy 124.995432 -385.557522)
			(xy 125.005592 -385.560062) (xy 125.034709 -385.568035) (xy 125.090675 -385.590674) (xy 125.14318 -385.620473)
			(xy 125.191312 -385.656914) (xy 125.234237 -385.699366) (xy 125.27121 -385.747091) (xy 125.301589 -385.799262)
			(xy 125.324847 -385.854974) (xy 125.340581 -385.913259) (xy 125.348517 -385.973106) (xy 125.349 -386.003292)
			(xy 125.348875 -386.017427) (xy 125.347093 -386.045641) (xy 125.345444 -386.05968) (xy 125.344685 -386.068287)
			(xy 125.348324 -386.085167) (xy 125.352556 -386.0927) (xy 125.368304 -386.1181) (xy 125.372997 -386.125176)
			(xy 125.386107 -386.135948) (xy 125.393958 -386.139182) (xy 125.417312 -386.148395) (xy 125.461155 -386.172853)
			(xy 125.500798 -386.203656) (xy 125.535331 -386.240095) (xy 125.563962 -386.281334) (xy 125.586032 -386.326426)
			(xy 125.601036 -386.374335) (xy 125.608627 -386.42396) (xy 125.609096 -386.449062) (xy 125.608671 -386.473264)
			(xy 125.601598 -386.521149) (xy 125.587611 -386.567488) (xy 125.567011 -386.61129) (xy 125.553978 -386.631688)
			(xy 125.549191 -386.639645) (xy 125.545156 -386.657756) (xy 125.546104 -386.666994) (xy 125.550422 -386.697982)
			(xy 125.552097 -386.70728) (xy 125.561382 -386.723721) (xy 125.568456 -386.729986) (xy 125.590543 -386.74867)
			(xy 125.630315 -386.790681) (xy 125.664477 -386.837369) (xy 125.692485 -386.887988) (xy 125.713892 -386.941733)
			(xy 125.728358 -386.997747) (xy 125.735651 -387.055136) (xy 125.736096 -387.084062) (xy 125.735501 -387.117383)
			(xy 125.72584 -387.183321) (xy 125.706716 -387.247161) (xy 125.69317 -387.27761) (xy 125.688925 -387.288075)
			(xy 125.689039 -387.310634) (xy 125.698771 -387.330985) (xy 125.70714 -387.33857) (xy 125.729358 -387.357278)
			(xy 125.769425 -387.399326) (xy 125.80385 -387.446105) (xy 125.832079 -387.496864) (xy 125.85366 -387.550788)
			(xy 125.868244 -387.607008) (xy 125.875597 -387.664622) (xy 125.87605 -387.693662) (xy 125.875574 -387.722667)
			(xy 125.868263 -387.780214) (xy 125.853741 -387.836377) (xy 125.832241 -387.890255) (xy 125.804106 -387.940985)
			(xy 125.769788 -387.987755) (xy 125.729837 -388.029815) (xy 125.707648 -388.0485) (xy 125.700536 -388.054088)
			(xy 125.691392 -388.069328) (xy 125.676152 -388.152132) (xy 125.678946 -388.169404) (xy 125.683518 -388.177532)
			(xy 125.696091 -388.20072) (xy 125.713966 -388.25034) (xy 125.723068 -388.302291) (xy 125.72365 -388.328662)
			(xy 125.723581 -388.338021) (xy 125.722438 -388.356703) (xy 125.721364 -388.366) (xy 125.720348 -388.37489)
			(xy 125.724158 -388.391654) (xy 125.7681 -388.461504) (xy 125.781816 -388.471918) (xy 125.790198 -388.474712)
			(xy 125.814218 -388.483202) (xy 125.859391 -388.506749) (xy 125.900198 -388.537244) (xy 125.935579 -388.573894)
			(xy 125.964616 -388.61575) (xy 125.986556 -388.661726) (xy 125.99416 -388.68604) (xy 125.995684 -388.691882)
			(xy 126.315978 -389.245602) (xy 126.320042 -389.24992) (xy 126.336237 -389.267623) (xy 126.3636 -389.307033)
			(xy 126.384684 -389.350131) (xy 126.399003 -389.395923) (xy 126.406228 -389.443354) (xy 126.406656 -389.467344)
			(xy 126.406223 -389.492135) (xy 126.39846 -389.541107) (xy 126.383132 -389.588261) (xy 126.360617 -389.632438)
			(xy 126.331469 -389.672548) (xy 126.296405 -389.707605) (xy 126.25629 -389.736746) (xy 126.212109 -389.759254)
			(xy 126.164952 -389.774573) (xy 126.115979 -389.782327) (xy 126.091188 -389.782812) (xy 126.065793 -389.782322)
			(xy 126.015659 -389.77419) (xy 125.967473 -389.758136) (xy 125.922479 -389.734576) (xy 125.881836 -389.704118)
			(xy 125.846594 -389.667545) (xy 125.81766 -389.625803) (xy 125.795782 -389.579967) (xy 125.788166 -389.555736)
			(xy 125.786642 -389.549894) (xy 125.466348 -388.996174) (xy 125.462284 -388.991856) (xy 125.446078 -388.97415)
			(xy 125.418655 -388.934758) (xy 125.397513 -388.891668) (xy 125.383139 -388.845874) (xy 125.375866 -388.798431)
			(xy 125.375416 -388.774432) (xy 125.375558 -388.76238) (xy 125.377464 -388.73835) (xy 125.379226 -388.726426)
			(xy 125.380496 -388.717536) (xy 125.377448 -388.700518) (xy 125.335284 -388.629652) (xy 125.322076 -388.618476)
			(xy 125.313694 -388.615428) (xy 125.291951 -388.60702) (xy 125.251092 -388.584582) (xy 125.214121 -388.556191)
			(xy 125.181897 -388.522508) (xy 125.155171 -388.484315) (xy 125.134564 -388.442503) (xy 125.120556 -388.398043)
			(xy 125.113472 -388.351969) (xy 125.113034 -388.328662) (xy 125.113595 -388.302289) (xy 125.122679 -388.25033)
			(xy 125.14057 -388.20071) (xy 125.153166 -388.177532) (xy 125.157738 -388.169404) (xy 125.160532 -388.152132)
			(xy 125.145292 -388.069328) (xy 125.136148 -388.054088) (xy 125.129036 -388.0485) (xy 125.106873 -388.029785)
			(xy 125.066924 -387.987726) (xy 125.032605 -387.94096) (xy 125.004464 -387.890236) (xy 124.982953 -387.836364)
			(xy 124.968416 -387.780208) (xy 124.961085 -387.722666) (xy 124.960634 -387.693662) (xy 124.961235 -387.660341)
			(xy 124.970893 -387.594403) (xy 124.990015 -387.530563) (xy 125.00356 -387.500114) (xy 125.007806 -387.489647)
			(xy 125.007701 -387.467087) (xy 124.997964 -387.446735) (xy 124.98959 -387.439154) (xy 124.967321 -387.420506)
			(xy 124.927259 -387.378445) (xy 124.892841 -387.331654) (xy 124.864619 -387.280885) (xy 124.843047 -387.226953)
			(xy 124.828472 -387.170725) (xy 124.821128 -387.113105) (xy 124.82068 -387.084062) (xy 124.821121 -387.055135)
			(xy 124.828405 -386.997742) (xy 124.842865 -386.941725) (xy 124.86427 -386.887977) (xy 124.892279 -386.837355)
			(xy 124.926445 -386.790668) (xy 124.966223 -386.748659) (xy 124.98832 -386.729986) (xy 124.995285 -386.723632)
			(xy 125.004548 -386.707234) (xy 125.006354 -386.697982) (xy 125.010672 -386.666994) (xy 125.011572 -386.657757)
			(xy 125.00755 -386.639658) (xy 125.002798 -386.631688) (xy 124.986489 -386.605843) (xy 124.962586 -386.549607)
			(xy 124.9553 -386.519928) (xy 124.953241 -386.511766) (xy 124.94454 -386.497365) (xy 124.938282 -386.491734)
			(xy 124.915168 -386.472684) (xy 124.908349 -386.46746) (xy 124.892248 -386.461501) (xy 124.883672 -386.461)
			(xy 124.854036 -386.459981) (xy 124.795371 -386.451334) (xy 124.738314 -386.435184) (xy 124.68382 -386.411802)
			(xy 124.632801 -386.381581) (xy 124.586111 -386.345024) (xy 124.544532 -386.302746) (xy 124.508759 -386.255453)
			(xy 124.479393 -386.203937) (xy 124.456923 -386.14906) (xy 124.441727 -386.091742) (xy 124.434059 -386.032941)
			(xy 124.433584 -386.003292) (xy 124.434104 -385.972229) (xy 124.442521 -385.910675) (xy 124.450348 -385.88061)
			(xy 124.453142 -385.87045) (xy 124.450602 -385.850638) (xy 124.403104 -385.768342) (xy 124.387102 -385.75615)
			(xy 124.376942 -385.75361) (xy 124.347824 -385.74564) (xy 124.291856 -385.723003) (xy 124.23935 -385.693206)
			(xy 124.191216 -385.656765) (xy 124.14829 -385.614313) (xy 124.111316 -385.566587) (xy 124.080938 -385.514414)
			(xy 124.057681 -385.458701) (xy 124.041949 -385.400415) (xy 124.034015 -385.340566) (xy 124.033534 -385.31038)
			(xy 124.034055 -385.279492) (xy 124.042361 -385.218276) (xy 124.058819 -385.158732) (xy 124.08313 -385.10194)
			(xy 124.098558 -385.075176) (xy 124.1044 -385.06527) (xy 124.106686 -385.042918) (xy 124.073412 -384.947668)
			(xy 124.057664 -384.931666) (xy 124.046996 -384.927602) (xy 124.023615 -384.918418) (xy 123.979717 -384.893999)
			(xy 123.940021 -384.863219) (xy 123.90544 -384.826785) (xy 123.87677 -384.785539) (xy 123.854672 -384.740428)
			(xy 123.839656 -384.692493) (xy 123.832066 -384.642838) (xy 123.831604 -384.617722) (xy 123.293124 -384.617722)
			(xy 123.292595 -384.644824) (xy 123.283785 -384.698307) (xy 123.275598 -384.724148) (xy 123.271788 -384.73507)
			(xy 123.274328 -384.757422) (xy 123.326906 -384.843274) (xy 123.345956 -384.85572) (xy 123.357132 -384.857498)
			(xy 123.38645 -384.862204) (xy 123.443621 -384.878253) (xy 123.498235 -384.901563) (xy 123.549374 -384.931742)
			(xy 123.59618 -384.968283) (xy 123.637865 -385.010573) (xy 123.673729 -385.057899) (xy 123.703169 -385.109468)
			(xy 123.725691 -385.164411) (xy 123.740915 -385.221807) (xy 123.748587 -385.28069) (xy 123.749054 -385.31038)
			(xy 123.748531 -385.341506) (xy 123.740125 -385.403188) (xy 123.73229 -385.433316) (xy 123.729496 -385.443476)
			(xy 123.732036 -385.463542) (xy 123.77928 -385.54533) (xy 123.795282 -385.557522) (xy 123.805442 -385.560062)
			(xy 123.834549 -385.568069) (xy 123.890516 -385.590702) (xy 123.943021 -385.620495) (xy 123.991155 -385.656932)
			(xy 124.034082 -385.699379) (xy 124.071056 -385.747101) (xy 124.101436 -385.79927) (xy 124.124695 -385.854979)
			(xy 124.14043 -385.913262) (xy 124.148366 -385.973107) (xy 124.14885 -386.003292) (xy 124.148725 -386.017427)
			(xy 124.146943 -386.045641) (xy 124.145294 -386.05968) (xy 124.144528 -386.068287) (xy 124.14817 -386.085168)
			(xy 124.152406 -386.0927) (xy 124.168154 -386.1181) (xy 124.172875 -386.125151) (xy 124.185973 -386.135925)
			(xy 124.193808 -386.139182) (xy 124.217185 -386.148377) (xy 124.261081 -386.172795) (xy 124.300777 -386.203574)
			(xy 124.335358 -386.240006) (xy 124.364028 -386.281251) (xy 124.386127 -386.32636) (xy 124.401145 -386.374293)
			(xy 124.408737 -386.423947) (xy 124.4092 -386.449062) (xy 124.408775 -386.473264) (xy 124.401701 -386.521149)
			(xy 124.387715 -386.567488) (xy 124.367115 -386.61129) (xy 124.354082 -386.631688) (xy 124.349295 -386.639645)
			(xy 124.34526 -386.657756) (xy 124.346208 -386.666994) (xy 124.350526 -386.697982) (xy 124.3522 -386.70728)
			(xy 124.361486 -386.723721) (xy 124.36856 -386.729986) (xy 124.390648 -386.748669) (xy 124.430419 -386.79068)
			(xy 124.464581 -386.837368) (xy 124.492589 -386.887988) (xy 124.513997 -386.941733) (xy 124.528462 -386.997746)
			(xy 124.535755 -387.055136) (xy 124.5362 -387.084062) (xy 124.535614 -387.117384) (xy 124.525951 -387.183322)
			(xy 124.506823 -387.247161) (xy 124.493274 -387.27761) (xy 124.489027 -387.288075) (xy 124.489141 -387.310634)
			(xy 124.498875 -387.330985) (xy 124.507244 -387.33857) (xy 124.529463 -387.357277) (xy 124.56953 -387.399325)
			(xy 124.603954 -387.446105) (xy 124.632184 -387.496864) (xy 124.653764 -387.550787) (xy 124.668348 -387.607008)
			(xy 124.675701 -387.664621) (xy 124.676154 -387.693662) (xy 124.675676 -387.722667) (xy 124.668366 -387.780214)
			(xy 124.653844 -387.836377) (xy 124.632344 -387.890255) (xy 124.604209 -387.940985) (xy 124.569892 -387.987755)
			(xy 124.529941 -388.029815) (xy 124.507752 -388.0485) (xy 124.50064 -388.054088) (xy 124.491496 -388.069328)
			(xy 124.476256 -388.152132) (xy 124.47905 -388.169404) (xy 124.483622 -388.177532) (xy 124.496196 -388.200719)
			(xy 124.514071 -388.25034) (xy 124.523172 -388.302291) (xy 124.523754 -388.328662) (xy 124.523685 -388.338021)
			(xy 124.522542 -388.356703) (xy 124.521468 -388.366) (xy 124.520452 -388.37489) (xy 124.524262 -388.391654)
			(xy 124.568204 -388.461504) (xy 124.58192 -388.471918) (xy 124.590302 -388.474712) (xy 124.614323 -388.4832)
			(xy 124.659496 -388.506748) (xy 124.700302 -388.537243) (xy 124.735683 -388.573894) (xy 124.76472 -388.61575)
			(xy 124.78666 -388.661725) (xy 124.794264 -388.68604) (xy 124.795788 -388.691882) (xy 125.116082 -389.245602)
			(xy 125.120146 -389.24992) (xy 125.136342 -389.267622) (xy 125.163705 -389.307033) (xy 125.184789 -389.350131)
			(xy 125.199107 -389.395923) (xy 125.206332 -389.443354) (xy 125.20676 -389.467344) (xy 125.206323 -389.492135)
			(xy 125.19856 -389.541106) (xy 125.183233 -389.58826) (xy 125.160718 -389.632436) (xy 125.13157 -389.672547)
			(xy 125.096507 -389.707604) (xy 125.056392 -389.736745) (xy 125.012212 -389.759252) (xy 124.965056 -389.774572)
			(xy 124.916083 -389.782327) (xy 124.891292 -389.782812) (xy 124.865897 -389.782319) (xy 124.815763 -389.774187)
			(xy 124.767578 -389.758134) (xy 124.722583 -389.734575) (xy 124.681941 -389.704116) (xy 124.646698 -389.667544)
			(xy 124.617765 -389.625802) (xy 124.595887 -389.579967) (xy 124.58827 -389.555736) (xy 124.586746 -389.549894)
			(xy 124.266452 -388.996174) (xy 124.262388 -388.991856) (xy 124.246183 -388.974149) (xy 124.218759 -388.934758)
			(xy 124.197617 -388.891668) (xy 124.183243 -388.845874) (xy 124.17597 -388.798431) (xy 124.17552 -388.774432)
			(xy 124.175662 -388.76238) (xy 124.177568 -388.73835) (xy 124.17933 -388.726426) (xy 124.1806 -388.717536)
			(xy 124.177552 -388.700518) (xy 124.135388 -388.629652) (xy 124.12218 -388.618476) (xy 124.113798 -388.615428)
			(xy 124.092056 -388.607017) (xy 124.051197 -388.58458) (xy 124.014225 -388.55619) (xy 123.982001 -388.522507)
			(xy 123.955275 -388.484315) (xy 123.934668 -388.442503) (xy 123.92066 -388.398043) (xy 123.913576 -388.351969)
			(xy 123.913138 -388.328662) (xy 123.913699 -388.302289) (xy 123.922783 -388.25033) (xy 123.940674 -388.20071)
			(xy 123.95327 -388.177532) (xy 123.957842 -388.169404) (xy 123.960636 -388.152132) (xy 123.945396 -388.069328)
			(xy 123.936252 -388.054088) (xy 123.92914 -388.0485) (xy 123.906978 -388.029784) (xy 123.867029 -387.987726)
			(xy 123.832709 -387.94096) (xy 123.804569 -387.890235) (xy 123.783058 -387.836364) (xy 123.76852 -387.780208)
			(xy 123.761189 -387.722666) (xy 123.760738 -387.693662) (xy 123.761338 -387.660341) (xy 123.770997 -387.594403)
			(xy 123.790119 -387.530563) (xy 123.803664 -387.500114) (xy 123.807908 -387.489647) (xy 123.807804 -387.467087)
			(xy 123.798067 -387.446736) (xy 123.789694 -387.439154) (xy 123.767426 -387.420505) (xy 123.727364 -387.378445)
			(xy 123.692945 -387.331654) (xy 123.664723 -387.280885) (xy 123.643151 -387.226953) (xy 123.628576 -387.170725)
			(xy 123.621232 -387.113105) (xy 123.620784 -387.084062) (xy 123.621224 -387.055135) (xy 123.628508 -386.997742)
			(xy 123.642968 -386.941725) (xy 123.664373 -386.887976) (xy 123.692382 -386.837355) (xy 123.726549 -386.790668)
			(xy 123.766327 -386.748659) (xy 123.788424 -386.729986) (xy 123.79539 -386.723633) (xy 123.804652 -386.707234)
			(xy 123.806458 -386.697982) (xy 123.810776 -386.666994) (xy 123.811676 -386.657757) (xy 123.807654 -386.639658)
			(xy 123.802902 -386.631688) (xy 123.786594 -386.605843) (xy 123.76269 -386.549607) (xy 123.755404 -386.519928)
			(xy 123.753344 -386.511766) (xy 123.744644 -386.497365) (xy 123.738386 -386.491734) (xy 123.715272 -386.472684)
			(xy 123.708394 -386.467435) (xy 123.692162 -386.461471) (xy 123.683522 -386.461) (xy 123.653884 -386.460027)
			(xy 123.595218 -386.451373) (xy 123.53816 -386.435218) (xy 123.483666 -386.411831) (xy 123.432647 -386.381604)
			(xy 123.385957 -386.345044) (xy 123.344379 -386.302761) (xy 123.308607 -386.255465) (xy 123.279241 -386.203945)
			(xy 123.256772 -386.149066) (xy 123.241577 -386.091745) (xy 123.233909 -386.032942) (xy 123.233434 -386.003292)
			(xy 123.233955 -385.972229) (xy 123.242371 -385.910675) (xy 123.250198 -385.88061) (xy 123.252992 -385.87045)
			(xy 123.250452 -385.850638) (xy 123.202954 -385.768342) (xy 123.186952 -385.75615) (xy 123.176792 -385.75361)
			(xy 123.147696 -385.745605) (xy 123.09177 -385.722934) (xy 123.039305 -385.693113) (xy 122.991212 -385.656661)
			(xy 122.948323 -385.614207) (xy 122.911381 -385.566488) (xy 122.881027 -385.514331) (xy 122.857786 -385.458639)
			(xy 122.842061 -385.400376) (xy 122.834125 -385.340553) (xy 122.833638 -385.31038) (xy 122.834158 -385.279492)
			(xy 122.842464 -385.218276) (xy 122.858922 -385.158732) (xy 122.883234 -385.10194) (xy 122.898662 -385.075176)
			(xy 122.904504 -385.06527) (xy 122.90679 -385.042918) (xy 122.873516 -384.947668) (xy 122.857768 -384.931666)
			(xy 122.8471 -384.927602) (xy 122.82372 -384.918416) (xy 122.779822 -384.893998) (xy 122.740126 -384.863217)
			(xy 122.705544 -384.826785) (xy 122.676874 -384.785538) (xy 122.654777 -384.740428) (xy 122.63976 -384.692493)
			(xy 122.63217 -384.642838) (xy 122.631708 -384.617722) (xy 122.092974 -384.617722) (xy 122.092443 -384.644824)
			(xy 122.083634 -384.698307) (xy 122.075448 -384.724148) (xy 122.071638 -384.73507) (xy 122.074178 -384.757422)
			(xy 122.126756 -384.843274) (xy 122.145806 -384.85572) (xy 122.156982 -384.857498) (xy 122.186307 -384.862165)
			(xy 122.243478 -384.87822) (xy 122.298092 -384.901536) (xy 122.34923 -384.93172) (xy 122.396035 -384.968266)
			(xy 122.437719 -385.010559) (xy 122.473582 -385.057889) (xy 122.503021 -385.10946) (xy 122.525542 -385.164406)
			(xy 122.540766 -385.221804) (xy 122.548437 -385.280689) (xy 122.548904 -385.31038) (xy 122.548379 -385.341443)
			(xy 122.539966 -385.402997) (xy 122.53214 -385.433062) (xy 122.529346 -385.443222) (xy 122.531886 -385.463034)
			(xy 122.579384 -385.54533) (xy 122.595386 -385.557522) (xy 122.605546 -385.560062) (xy 122.634654 -385.568066)
			(xy 122.690621 -385.590699) (xy 122.743126 -385.620493) (xy 122.79126 -385.65693) (xy 122.834186 -385.699378)
			(xy 122.87116 -385.7471) (xy 122.901541 -385.799269) (xy 122.9248 -385.854978) (xy 122.940534 -385.913261)
			(xy 122.948471 -385.973107) (xy 122.948954 -386.003292) (xy 122.948829 -386.017427) (xy 122.947047 -386.045641)
			(xy 122.945398 -386.05968) (xy 122.944632 -386.068287) (xy 122.948274 -386.085168) (xy 122.95251 -386.0927)
			(xy 122.968258 -386.1181) (xy 122.972978 -386.125152) (xy 122.986076 -386.135926) (xy 122.993912 -386.139182)
			(xy 123.017289 -386.148375) (xy 123.061186 -386.172793) (xy 123.100882 -386.203573) (xy 123.135463 -386.240005)
			(xy 123.164133 -386.28125) (xy 123.186231 -386.326359) (xy 123.201249 -386.374293) (xy 123.208841 -386.423946)
			(xy 123.209304 -386.449062) (xy 123.208878 -386.473264) (xy 123.201805 -386.521149) (xy 123.187818 -386.567488)
			(xy 123.167219 -386.61129) (xy 123.154186 -386.631688) (xy 123.149399 -386.639645) (xy 123.145364 -386.657756)
			(xy 123.146312 -386.666994) (xy 123.15063 -386.697982) (xy 123.152303 -386.707281) (xy 123.161589 -386.723722)
			(xy 123.168664 -386.729986) (xy 123.190752 -386.748668) (xy 123.230524 -386.79068) (xy 123.264686 -386.837368)
			(xy 123.292694 -386.887987) (xy 123.314101 -386.941733) (xy 123.328566 -386.997746) (xy 123.335859 -387.055136)
			(xy 123.336304 -387.084062) (xy 123.335718 -387.117384) (xy 123.326054 -387.183322) (xy 123.306927 -387.247161)
			(xy 123.293378 -387.27761) (xy 123.28913 -387.288075) (xy 123.289244 -387.310634) (xy 123.298978 -387.330985)
			(xy 123.307348 -387.33857) (xy 123.329567 -387.357276) (xy 123.369634 -387.399324) (xy 123.404059 -387.446104)
			(xy 123.432288 -387.496864) (xy 123.453868 -387.550787) (xy 123.468452 -387.607008) (xy 123.475805 -387.664621)
			(xy 123.476258 -387.693662) (xy 123.475779 -387.722667) (xy 123.468468 -387.780214) (xy 123.453947 -387.836376)
			(xy 123.432446 -387.890254) (xy 123.404313 -387.940985) (xy 123.369995 -387.987755) (xy 123.330045 -388.029815)
			(xy 123.307856 -388.0485) (xy 123.300744 -388.054088) (xy 123.2916 -388.069328) (xy 123.27636 -388.152132)
			(xy 123.279154 -388.169404) (xy 123.283726 -388.177532) (xy 123.2963 -388.200719) (xy 123.314175 -388.25034)
			(xy 123.323276 -388.302291) (xy 123.323858 -388.328662) (xy 123.323789 -388.338021) (xy 123.322646 -388.356703)
			(xy 123.321572 -388.366) (xy 123.320556 -388.37489) (xy 123.324366 -388.391654) (xy 123.368308 -388.461504)
			(xy 123.382024 -388.471918) (xy 123.390406 -388.474712) (xy 123.414505 -388.483189) (xy 123.459796 -388.506815)
			(xy 123.50069 -388.537427) (xy 123.536122 -388.574225) (xy 123.565164 -388.616248) (xy 123.58706 -388.662401)
			(xy 123.594622 -388.686802) (xy 123.596146 -388.692644) (xy 123.915932 -389.245602) (xy 123.919996 -389.24992)
			(xy 123.936187 -389.267639) (xy 123.963613 -389.307027) (xy 123.984759 -389.350114) (xy 123.999135 -389.395905)
			(xy 124.006412 -389.443346) (xy 124.006864 -389.467344) (xy 124.006447 -389.49215) (xy 123.998676 -389.541149)
			(xy 123.983332 -389.588328) (xy 123.960793 -389.632524) (xy 123.931616 -389.672649) (xy 123.896519 -389.707713)
			(xy 123.856366 -389.736851) (xy 123.812148 -389.759347) (xy 123.764955 -389.774646) (xy 123.715948 -389.78237)
			(xy 123.691142 -389.782812) (xy 123.665749 -389.782275) (xy 123.615617 -389.77415) (xy 123.567432 -389.758105)
			(xy 123.522438 -389.734552) (xy 123.481795 -389.7041) (xy 123.446551 -389.667534) (xy 123.417617 -389.625796)
			(xy 123.395737 -389.579965) (xy 123.38812 -389.555736) (xy 123.386596 -389.549894) (xy 123.066048 -388.995412)
			(xy 123.061984 -388.991094) (xy 123.045886 -388.973419) (xy 123.018636 -388.934142) (xy 122.997624 -388.891203)
			(xy 122.98333 -388.845586) (xy 122.976083 -388.798334) (xy 122.975624 -388.774432) (xy 122.975766 -388.76238)
			(xy 122.977672 -388.73835) (xy 122.979434 -388.726426) (xy 122.980704 -388.717536) (xy 122.977656 -388.700518)
			(xy 122.935492 -388.629652) (xy 122.922284 -388.618476) (xy 122.913902 -388.615428) (xy 122.892161 -388.607015)
			(xy 122.851302 -388.584578) (xy 122.81433 -388.556189) (xy 122.782106 -388.522506) (xy 122.755379 -388.484314)
			(xy 122.734772 -388.442502) (xy 122.720764 -388.398042) (xy 122.71368 -388.351969) (xy 122.713242 -388.328662)
			(xy 122.713802 -388.302289) (xy 122.722887 -388.25033) (xy 122.740778 -388.20071) (xy 122.753374 -388.177532)
			(xy 122.757946 -388.169404) (xy 122.76074 -388.152132) (xy 122.7455 -388.069328) (xy 122.736356 -388.054088)
			(xy 122.729244 -388.0485) (xy 122.707083 -388.029783) (xy 122.667133 -387.987725) (xy 122.632814 -387.940959)
			(xy 122.604673 -387.890235) (xy 122.583162 -387.836364) (xy 122.568624 -387.780208) (xy 122.561293 -387.722666)
			(xy 122.560842 -387.693662) (xy 122.561442 -387.660341) (xy 122.5711 -387.594403) (xy 122.590222 -387.530563)
			(xy 122.603768 -387.500114) (xy 122.608011 -387.489646) (xy 122.607906 -387.467087) (xy 122.598171 -387.446736)
			(xy 122.589798 -387.439154) (xy 122.567531 -387.420504) (xy 122.527469 -387.378444) (xy 122.49305 -387.331654)
			(xy 122.464828 -387.280884) (xy 122.443256 -387.226953) (xy 122.42868 -387.170725) (xy 122.421336 -387.113105)
			(xy 122.420888 -387.084062) (xy 122.421326 -387.055135) (xy 122.428611 -386.997742) (xy 122.443071 -386.941724)
			(xy 122.464476 -386.887976) (xy 122.492486 -386.837355) (xy 122.526652 -386.790667) (xy 122.566431 -386.748659)
			(xy 122.588528 -386.729986) (xy 122.595494 -386.723633) (xy 122.604756 -386.707234) (xy 122.606562 -386.697982)
			(xy 122.61088 -386.666994) (xy 122.611779 -386.657757) (xy 122.607757 -386.639658) (xy 122.603006 -386.631688)
			(xy 122.586698 -386.605842) (xy 122.562795 -386.549607) (xy 122.555508 -386.519928) (xy 122.553447 -386.511767)
			(xy 122.544747 -386.497365) (xy 122.53849 -386.491734) (xy 122.515376 -386.472684) (xy 122.508497 -386.467436)
			(xy 122.492266 -386.461472) (xy 122.483626 -386.461) (xy 122.453988 -386.460024) (xy 122.395322 -386.45137)
			(xy 122.338265 -386.435215) (xy 122.28377 -386.411829) (xy 122.232751 -386.381602) (xy 122.186062 -386.345042)
			(xy 122.144483 -386.30276) (xy 122.108711 -386.255464) (xy 122.079345 -386.203945) (xy 122.056876 -386.149066)
			(xy 122.041681 -386.091745) (xy 122.034013 -386.032942) (xy 122.033538 -386.003292) (xy 122.034059 -385.972229)
			(xy 122.042475 -385.910675) (xy 122.050302 -385.88061) (xy 122.053096 -385.87045) (xy 122.050556 -385.850638)
			(xy 122.003058 -385.768342) (xy 121.987056 -385.75615) (xy 121.976896 -385.75361) (xy 121.947788 -385.745604)
			(xy 121.89182 -385.722973) (xy 121.839312 -385.693182) (xy 121.791177 -385.656746) (xy 121.748249 -385.614298)
			(xy 121.711275 -385.566576) (xy 121.680895 -385.514406) (xy 121.657636 -385.458696) (xy 121.641904 -385.400412)
			(xy 121.63397 -385.340565) (xy 121.633488 -385.31038) (xy 121.634015 -385.279492) (xy 121.64232 -385.218277)
			(xy 121.658777 -385.158733) (xy 121.683086 -385.101941) (xy 121.698512 -385.075176) (xy 121.704354 -385.06527)
			(xy 121.70664 -385.042918) (xy 121.673366 -384.947668) (xy 121.657618 -384.931666) (xy 121.64695 -384.927602)
			(xy 121.623559 -384.918443) (xy 121.579663 -384.894018) (xy 121.539968 -384.863233) (xy 121.505389 -384.826796)
			(xy 121.476721 -384.785546) (xy 121.454625 -384.740433) (xy 121.439609 -384.692496) (xy 121.43202 -384.642839)
			(xy 121.431558 -384.617722) (xy 120.893078 -384.617722) (xy 120.892547 -384.644824) (xy 120.883738 -384.698307)
			(xy 120.875552 -384.724148) (xy 120.871742 -384.73507) (xy 120.874282 -384.757422) (xy 120.92686 -384.843274)
			(xy 120.94591 -384.85572) (xy 120.957086 -384.857498) (xy 120.986411 -384.862162) (xy 121.043582 -384.878218)
			(xy 121.098196 -384.901533) (xy 121.149335 -384.931718) (xy 121.196139 -384.968264) (xy 121.237823 -385.010558)
			(xy 121.273686 -385.057888) (xy 121.303125 -385.109459) (xy 121.325646 -385.164406) (xy 121.34087 -385.221804)
			(xy 121.348541 -385.280689) (xy 121.349008 -385.31038) (xy 121.348483 -385.341443) (xy 121.34007 -385.402997)
			(xy 121.332244 -385.433062) (xy 121.32945 -385.443222) (xy 121.33199 -385.463034) (xy 121.379488 -385.54533)
			(xy 121.39549 -385.557522) (xy 121.40565 -385.560062) (xy 121.434759 -385.568063) (xy 121.490725 -385.590697)
			(xy 121.543231 -385.620491) (xy 121.591364 -385.656929) (xy 121.634291 -385.699377) (xy 121.671265 -385.7471)
			(xy 121.701645 -385.799268) (xy 121.724904 -385.854978) (xy 121.740638 -385.913261) (xy 121.748575 -385.973107)
			(xy 121.749058 -386.003292) (xy 121.748933 -386.017427) (xy 121.747151 -386.045641) (xy 121.745502 -386.05968)
			(xy 121.744735 -386.068287) (xy 121.748378 -386.085168) (xy 121.752614 -386.0927) (xy 121.768362 -386.1181)
			(xy 121.773068 -386.125165) (xy 121.78617 -386.135943) (xy 121.794016 -386.139182) (xy 121.817361 -386.148417)
			(xy 121.861205 -386.172871) (xy 121.900849 -386.203669) (xy 121.935385 -386.240104) (xy 121.964017 -386.28134)
			(xy 121.986089 -386.32643) (xy 122.001093 -386.374337) (xy 122.008685 -386.423961) (xy 122.009154 -386.449062)
			(xy 122.008736 -386.473264) (xy 122.001662 -386.52115) (xy 121.987673 -386.567489) (xy 121.967071 -386.611291)
			(xy 121.954036 -386.631688) (xy 121.949246 -386.639643) (xy 121.945214 -386.657756) (xy 121.946162 -386.666994)
			(xy 121.95048 -386.697982) (xy 121.952168 -386.707276) (xy 121.961445 -386.723718) (xy 121.968514 -386.729986)
			(xy 121.990592 -386.74868) (xy 122.030366 -386.790689) (xy 122.06453 -386.837374) (xy 122.09254 -386.887992)
			(xy 122.113948 -386.941735) (xy 122.128415 -386.997748) (xy 122.135709 -387.055137) (xy 122.136154 -387.084062)
			(xy 122.135563 -387.117383) (xy 122.125901 -387.183322) (xy 122.106775 -387.247161) (xy 122.093228 -387.27761)
			(xy 122.088964 -387.288071) (xy 122.089077 -387.310635) (xy 122.098821 -387.330988) (xy 122.107198 -387.33857)
			(xy 122.129428 -387.357263) (xy 122.169492 -387.399315) (xy 122.203914 -387.446098) (xy 122.232141 -387.49686)
			(xy 122.25372 -387.550785) (xy 122.268302 -387.607006) (xy 122.275655 -387.664621) (xy 122.276108 -387.693662)
			(xy 122.275647 -387.722668) (xy 122.268336 -387.780216) (xy 122.253812 -387.83638) (xy 122.23231 -387.890258)
			(xy 122.204172 -387.940989) (xy 122.169852 -387.987758) (xy 122.129897 -388.029816) (xy 122.107706 -388.0485)
			(xy 122.100594 -388.054088) (xy 122.09145 -388.069328) (xy 122.07621 -388.152132) (xy 122.079004 -388.169404)
			(xy 122.083576 -388.177532) (xy 122.096146 -388.200721) (xy 122.114023 -388.250341) (xy 122.123126 -388.302292)
			(xy 122.123708 -388.328662) (xy 122.123639 -388.338021) (xy 122.122496 -388.356703) (xy 122.121422 -388.366)
			(xy 122.120406 -388.37489) (xy 122.124216 -388.391654) (xy 122.168158 -388.461504) (xy 122.181874 -388.471918)
			(xy 122.190256 -388.474712) (xy 122.214287 -388.483171) (xy 122.259459 -388.506726) (xy 122.300264 -388.537228)
			(xy 122.335642 -388.573884) (xy 122.364677 -388.615745) (xy 122.386615 -388.661724) (xy 122.394218 -388.68604)
			(xy 122.395742 -388.691882) (xy 122.716036 -389.245602) (xy 122.7201 -389.24992) (xy 122.736292 -389.267639)
			(xy 122.763718 -389.307027) (xy 122.784863 -389.350113) (xy 122.799239 -389.395905) (xy 122.806516 -389.443346)
			(xy 122.806968 -389.467344) (xy 122.806547 -389.492149) (xy 122.798776 -389.541148) (xy 122.783432 -389.588327)
			(xy 122.760894 -389.632523) (xy 122.731717 -389.672647) (xy 122.69662 -389.707711) (xy 122.656468 -389.73685)
			(xy 122.612251 -389.759346) (xy 122.565058 -389.774645) (xy 122.516052 -389.78237) (xy 122.491246 -389.782812)
			(xy 122.465853 -389.782271) (xy 122.415721 -389.774148) (xy 122.367537 -389.758103) (xy 122.322542 -389.734551)
			(xy 122.281899 -389.704099) (xy 122.246656 -389.667533) (xy 122.217721 -389.625796) (xy 122.195841 -389.579965)
			(xy 122.188224 -389.555736) (xy 122.1867 -389.549894) (xy 121.866406 -388.996174) (xy 121.862342 -388.991856)
			(xy 121.846181 -388.974124) (xy 121.818813 -388.934721) (xy 121.797723 -388.891631) (xy 121.783396 -388.845846)
			(xy 121.776162 -388.79842) (xy 121.775728 -388.774432) (xy 121.775809 -388.762384) (xy 121.777591 -388.738355)
			(xy 121.779284 -388.726426) (xy 121.780554 -388.717536) (xy 121.777506 -388.700518) (xy 121.735342 -388.629652)
			(xy 121.722134 -388.618476) (xy 121.713752 -388.615428) (xy 121.692 -388.607043) (xy 121.651142 -388.584599)
			(xy 121.614172 -388.556204) (xy 121.58195 -388.522517) (xy 121.555226 -388.484322) (xy 121.53462 -388.442507)
			(xy 121.520613 -388.398045) (xy 121.51353 -388.35197) (xy 121.513092 -388.328662) (xy 121.513659 -388.302289)
			(xy 121.522742 -388.250331) (xy 121.54063 -388.20071) (xy 121.553224 -388.177532) (xy 121.557796 -388.169404)
			(xy 121.56059 -388.152132) (xy 121.54535 -388.069328) (xy 121.536206 -388.054088) (xy 121.529094 -388.0485)
			(xy 121.506922 -388.029795) (xy 121.466975 -387.987734) (xy 121.432658 -387.940965) (xy 121.40452 -387.890239)
			(xy 121.38301 -387.836366) (xy 121.368473 -387.780209) (xy 121.361143 -387.722666) (xy 121.360692 -387.693662)
			(xy 121.361287 -387.660341) (xy 121.370947 -387.594402) (xy 121.390071 -387.530563) (xy 121.403618 -387.500114)
			(xy 121.407845 -387.489642) (xy 121.407739 -387.467088) (xy 121.398014 -387.446739) (xy 121.389648 -387.439154)
			(xy 121.367391 -387.420491) (xy 121.327326 -387.378435) (xy 121.292905 -387.331647) (xy 121.264681 -387.28088)
			(xy 121.243107 -387.22695) (xy 121.228531 -387.170724) (xy 121.221186 -387.113105) (xy 121.220738 -387.084062)
			(xy 121.221195 -387.055136) (xy 121.228478 -386.997744) (xy 121.242936 -386.941728) (xy 121.264339 -386.88798)
			(xy 121.292346 -386.837359) (xy 121.326508 -386.79067) (xy 121.366283 -386.74866) (xy 121.388378 -386.729986)
			(xy 121.395353 -386.723641) (xy 121.404608 -386.707236) (xy 121.406412 -386.697982) (xy 121.41073 -386.666994)
			(xy 121.411637 -386.657757) (xy 121.407611 -386.639657) (xy 121.402856 -386.631688) (xy 121.386544 -386.605845)
			(xy 121.362643 -386.549607) (xy 121.355358 -386.519928) (xy 121.35331 -386.511762) (xy 121.344602 -386.497362)
			(xy 121.33834 -386.491734) (xy 121.315226 -386.472684) (xy 121.308392 -386.467483) (xy 121.292302 -386.46151)
			(xy 121.28373 -386.461) (xy 121.254092 -386.46002) (xy 121.195426 -386.451367) (xy 121.138369 -386.435212)
			(xy 121.083875 -386.411826) (xy 121.032856 -386.3816) (xy 120.986166 -386.345041) (xy 120.944587 -386.302759)
			(xy 120.908816 -386.255463) (xy 120.879449 -386.203944) (xy 120.856981 -386.149065) (xy 120.841785 -386.091745)
			(xy 120.834117 -386.032942) (xy 120.833642 -386.003292) (xy 120.834163 -385.972229) (xy 120.842579 -385.910675)
			(xy 120.850406 -385.88061) (xy 120.8532 -385.87045) (xy 120.85066 -385.850638) (xy 120.803162 -385.768342)
			(xy 120.78716 -385.75615) (xy 120.777 -385.75361) (xy 120.747874 -385.745668) (xy 120.691907 -385.723026)
			(xy 120.639401 -385.693224) (xy 120.591268 -385.656779) (xy 120.548343 -385.614324) (xy 120.511371 -385.566595)
			(xy 120.480994 -385.51442) (xy 120.457737 -385.458705) (xy 120.442006 -385.400417) (xy 120.434073 -385.340567)
			(xy 120.433592 -385.31038) (xy 120.434119 -385.279492) (xy 120.442424 -385.218277) (xy 120.45888 -385.158733)
			(xy 120.48319 -385.101941) (xy 120.498616 -385.075176) (xy 120.504458 -385.06527) (xy 120.506744 -385.042918)
			(xy 120.47347 -384.947668) (xy 120.457722 -384.931666) (xy 120.447054 -384.927602) (xy 120.423664 -384.918441)
			(xy 120.379768 -384.894017) (xy 120.340073 -384.863232) (xy 120.305493 -384.826795) (xy 120.276825 -384.785545)
			(xy 120.254729 -384.740432) (xy 120.239713 -384.692496) (xy 120.232124 -384.642839) (xy 120.231662 -384.617722)
			(xy 119.693182 -384.617722) (xy 119.69265 -384.644824) (xy 119.683842 -384.698307) (xy 119.675656 -384.724148)
			(xy 119.671846 -384.73507) (xy 119.674386 -384.757422) (xy 119.726964 -384.843528) (xy 119.74576 -384.85572)
			(xy 119.75719 -384.857498) (xy 119.786485 -384.862269) (xy 119.84362 -384.878348) (xy 119.898196 -384.901679)
			(xy 119.949298 -384.931869) (xy 119.996069 -384.968412) (xy 120.037722 -385.010695) (xy 120.07356 -385.058009)
			(xy 120.10298 -385.109558) (xy 120.125489 -385.164478) (xy 120.14071 -385.221848) (xy 120.148386 -385.280703)
			(xy 120.148858 -385.31038) (xy 120.148331 -385.341443) (xy 120.139919 -385.402996) (xy 120.132094 -385.433062)
			(xy 120.1293 -385.443222) (xy 120.13184 -385.463034) (xy 120.179338 -385.54533) (xy 120.19534 -385.557522)
			(xy 120.2055 -385.560062) (xy 120.234619 -385.56803) (xy 120.290584 -385.59067) (xy 120.343089 -385.620469)
			(xy 120.391221 -385.656911) (xy 120.434146 -385.699364) (xy 120.471118 -385.74709) (xy 120.501497 -385.799261)
			(xy 120.524755 -385.854973) (xy 120.540489 -385.913258) (xy 120.548425 -385.973106) (xy 120.548908 -386.003292)
			(xy 120.548783 -386.017427) (xy 120.547001 -386.045641) (xy 120.545352 -386.05968) (xy 120.544592 -386.068287)
			(xy 120.548231 -386.085167) (xy 120.552464 -386.0927) (xy 120.568212 -386.1181) (xy 120.572915 -386.125165)
			(xy 120.586025 -386.135931) (xy 120.593866 -386.139182) (xy 120.617255 -386.148346) (xy 120.66115 -386.172771)
			(xy 120.700844 -386.203556) (xy 120.735423 -386.239993) (xy 120.764091 -386.281242) (xy 120.786187 -386.326354)
			(xy 120.801204 -386.37429) (xy 120.808795 -386.423946) (xy 120.809258 -386.449062) (xy 120.80884 -386.473264)
			(xy 120.801765 -386.52115) (xy 120.787777 -386.567489) (xy 120.767175 -386.611291) (xy 120.75414 -386.631688)
			(xy 120.74935 -386.639643) (xy 120.745318 -386.657756) (xy 120.746266 -386.666994) (xy 120.750584 -386.697982)
			(xy 120.752271 -386.707277) (xy 120.761549 -386.723719) (xy 120.768618 -386.729986) (xy 120.790697 -386.748679)
			(xy 120.83047 -386.790688) (xy 120.864634 -386.837373) (xy 120.892644 -386.887991) (xy 120.914053 -386.941735)
			(xy 120.928519 -386.997748) (xy 120.935813 -387.055137) (xy 120.936258 -387.084062) (xy 120.935667 -387.117383)
			(xy 120.926004 -387.183322) (xy 120.906879 -387.247161) (xy 120.893332 -387.27761) (xy 120.889066 -387.28807)
			(xy 120.88918 -387.310636) (xy 120.898925 -387.330989) (xy 120.907302 -387.33857) (xy 120.929533 -387.357262)
			(xy 120.969597 -387.399315) (xy 121.004019 -387.446098) (xy 121.032246 -387.49686) (xy 121.053824 -387.550785)
			(xy 121.068406 -387.607006) (xy 121.075759 -387.664621) (xy 121.076212 -387.693662) (xy 121.07575 -387.722668)
			(xy 121.068438 -387.780216) (xy 121.053915 -387.836379) (xy 121.032413 -387.890258) (xy 121.004276 -387.940988)
			(xy 120.969955 -387.987758) (xy 120.930001 -388.029816) (xy 120.90781 -388.0485) (xy 120.900698 -388.054088)
			(xy 120.891554 -388.069328) (xy 120.876314 -388.152132) (xy 120.879108 -388.169404) (xy 120.88368 -388.177532)
			(xy 120.89625 -388.200721) (xy 120.914127 -388.250341) (xy 120.92323 -388.302292) (xy 120.923812 -388.328662)
			(xy 120.923743 -388.338021) (xy 120.9226 -388.356703) (xy 120.921526 -388.366) (xy 120.92051 -388.37489)
			(xy 120.92432 -388.391654) (xy 120.968262 -388.461504) (xy 120.981978 -388.471918) (xy 120.99036 -388.474712)
			(xy 121.014392 -388.483169) (xy 121.059564 -388.506725) (xy 121.100368 -388.537227) (xy 121.135747 -388.573884)
			(xy 121.164781 -388.615745) (xy 121.186719 -388.661724) (xy 121.194322 -388.68604) (xy 121.195846 -388.691882)
			(xy 121.51614 -389.245602) (xy 121.520204 -389.24992) (xy 121.536396 -389.267638) (xy 121.563822 -389.307026)
			(xy 121.584967 -389.350113) (xy 121.599343 -389.395905) (xy 121.60662 -389.443346) (xy 121.607072 -389.467344)
			(xy 121.606647 -389.492149) (xy 121.598876 -389.541148) (xy 121.583533 -389.588326) (xy 121.560995 -389.632522)
			(xy 121.531818 -389.672646) (xy 121.496722 -389.70771) (xy 121.456571 -389.736849) (xy 121.412354 -389.759345)
			(xy 121.365161 -389.774644) (xy 121.316156 -389.78237) (xy 121.29135 -389.782812) (xy 121.265957 -389.782268)
			(xy 121.215826 -389.774145) (xy 121.167641 -389.7581) (xy 121.122647 -389.734549) (xy 121.082003 -389.704097)
			(xy 121.04676 -389.667532) (xy 121.017825 -389.625795) (xy 120.995945 -389.579965) (xy 120.988328 -389.555736)
			(xy 120.986804 -389.549894) (xy 120.66651 -388.996174) (xy 120.662446 -388.991856) (xy 120.646285 -388.974123)
			(xy 120.618918 -388.934721) (xy 120.597827 -388.891631) (xy 120.5835 -388.845845) (xy 120.576266 -388.798419)
			(xy 120.575832 -388.774432) (xy 120.575913 -388.762384) (xy 120.577695 -388.738355) (xy 120.579388 -388.726426)
			(xy 120.580658 -388.717536) (xy 120.57761 -388.700518) (xy 120.535446 -388.629652) (xy 120.522238 -388.618476)
			(xy 120.513856 -388.615428) (xy 120.492105 -388.60704) (xy 120.451247 -388.584598) (xy 120.414277 -388.556203)
			(xy 120.382055 -388.522516) (xy 120.35533 -388.484321) (xy 120.334724 -388.442507) (xy 120.320717 -388.398045)
			(xy 120.313634 -388.35197) (xy 120.313196 -388.328662) (xy 120.313762 -388.302289) (xy 120.322845 -388.250331)
			(xy 120.340733 -388.20071) (xy 120.353328 -388.177532) (xy 120.3579 -388.169404) (xy 120.360694 -388.152132)
			(xy 120.345454 -388.069328) (xy 120.33631 -388.054088) (xy 120.329198 -388.0485) (xy 120.307027 -388.029794)
			(xy 120.26708 -387.987733) (xy 120.232763 -387.940965) (xy 120.204624 -387.890239) (xy 120.183114 -387.836366)
			(xy 120.168577 -387.780209) (xy 120.161247 -387.722666) (xy 120.160796 -387.693662) (xy 120.161391 -387.660341)
			(xy 120.171051 -387.594402) (xy 120.190175 -387.530563) (xy 120.203722 -387.500114) (xy 120.207947 -387.489642)
			(xy 120.207842 -387.467089) (xy 120.198118 -387.446739) (xy 120.189752 -387.439154) (xy 120.167496 -387.420491)
			(xy 120.127431 -387.378434) (xy 120.09301 -387.331647) (xy 120.064785 -387.28088) (xy 120.043212 -387.22695)
			(xy 120.028635 -387.170724) (xy 120.02129 -387.113105) (xy 120.020842 -387.084062) (xy 120.021297 -387.055136)
			(xy 120.028581 -386.997744) (xy 120.043039 -386.941727) (xy 120.064442 -386.88798) (xy 120.092449 -386.837358)
			(xy 120.126612 -386.79067) (xy 120.166387 -386.74866) (xy 120.188482 -386.729986) (xy 120.195457 -386.723642)
			(xy 120.204713 -386.707236) (xy 120.206516 -386.697982) (xy 120.210834 -386.666994) (xy 120.21174 -386.657757)
			(xy 120.207715 -386.639657) (xy 120.20296 -386.631688) (xy 120.186648 -386.605845) (xy 120.162748 -386.549607)
			(xy 120.155462 -386.519928) (xy 120.153413 -386.511762) (xy 120.144706 -386.497362) (xy 120.138444 -386.491734)
			(xy 120.11533 -386.472684) (xy 120.108437 -386.467458) (xy 120.092216 -386.46148) (xy 120.08358 -386.461)
			(xy 120.053944 -386.459974) (xy 119.99528 -386.451327) (xy 119.938223 -386.435178) (xy 119.883729 -386.411798)
			(xy 119.83271 -386.381577) (xy 119.78602 -386.345021) (xy 119.74444 -386.302743) (xy 119.708668 -386.255451)
			(xy 119.679301 -386.203935) (xy 119.656831 -386.149059) (xy 119.641635 -386.091741) (xy 119.633967 -386.032941)
			(xy 119.633492 -386.003292) (xy 119.634012 -385.972229) (xy 119.642428 -385.910675) (xy 119.650256 -385.88061)
			(xy 119.65305 -385.87045) (xy 119.65051 -385.850638) (xy 119.603012 -385.768342) (xy 119.58701 -385.75615)
			(xy 119.57685 -385.75361) (xy 119.547733 -385.745635) (xy 119.491765 -385.722999) (xy 119.439259 -385.693202)
			(xy 119.391125 -385.656762) (xy 119.348198 -385.614311) (xy 119.311225 -385.566585) (xy 119.280846 -385.514413)
			(xy 119.257589 -385.458701) (xy 119.241857 -385.400414) (xy 119.233923 -385.340566) (xy 119.233442 -385.31038)
			(xy 119.233915 -385.279458) (xy 119.242197 -385.218171) (xy 119.258663 -385.158559) (xy 119.283011 -385.10171)
			(xy 119.298466 -385.074922) (xy 119.304562 -385.06527) (xy 119.306848 -385.042918) (xy 119.27332 -384.947668)
			(xy 119.257572 -384.931666) (xy 119.246904 -384.927602) (xy 119.223557 -384.918369) (xy 119.179713 -384.893917)
			(xy 119.140067 -384.863119) (xy 119.105531 -384.826683) (xy 119.076899 -384.785447) (xy 119.054827 -384.740356)
			(xy 119.039824 -384.692448) (xy 119.032234 -384.642823) (xy 119.031766 -384.617722) (xy 118.493032 -384.617722)
			(xy 118.492503 -384.644824) (xy 118.483693 -384.698307) (xy 118.475506 -384.724148) (xy 118.471696 -384.73507)
			(xy 118.474236 -384.757422) (xy 118.526814 -384.843274) (xy 118.545864 -384.85572) (xy 118.55704 -384.857498)
			(xy 118.586359 -384.862198) (xy 118.64353 -384.878248) (xy 118.698144 -384.901559) (xy 118.749283 -384.931739)
			(xy 118.796089 -384.968281) (xy 118.837774 -385.01057) (xy 118.873638 -385.057898) (xy 118.903078 -385.109466)
			(xy 118.925599 -385.164411) (xy 118.940823 -385.221806) (xy 118.948495 -385.28069) (xy 118.948962 -385.31038)
			(xy 118.948435 -385.341443) (xy 118.940023 -385.402996) (xy 118.932198 -385.433062) (xy 118.929404 -385.443222)
			(xy 118.931944 -385.463034) (xy 118.979442 -385.54533) (xy 118.995444 -385.557522) (xy 119.005604 -385.560062)
			(xy 119.034704 -385.568094) (xy 119.090671 -385.590722) (xy 119.143177 -385.620512) (xy 119.191312 -385.656945)
			(xy 119.23424 -385.699389) (xy 119.271215 -385.747109) (xy 119.301596 -385.799275) (xy 119.324856 -385.854982)
			(xy 119.340591 -385.913264) (xy 119.348528 -385.973108) (xy 119.349012 -386.003292) (xy 119.348887 -386.017427)
			(xy 119.347105 -386.045641) (xy 119.345456 -386.05968) (xy 119.344695 -386.068287) (xy 119.348335 -386.085167)
			(xy 119.352568 -386.0927) (xy 119.368316 -386.1181) (xy 119.373037 -386.125154) (xy 119.386128 -386.135938)
			(xy 119.39397 -386.139182) (xy 119.417327 -386.148388) (xy 119.461169 -386.172848) (xy 119.500812 -386.203652)
			(xy 119.535345 -386.240092) (xy 119.563975 -386.281332) (xy 119.586045 -386.326424) (xy 119.601048 -386.374334)
			(xy 119.60864 -386.42396) (xy 119.609108 -386.449062) (xy 119.608681 -386.473264) (xy 119.601608 -386.521149)
			(xy 119.587622 -386.567488) (xy 119.567023 -386.61129) (xy 119.55399 -386.631688) (xy 119.549203 -386.639646)
			(xy 119.545168 -386.657756) (xy 119.546116 -386.666994) (xy 119.550434 -386.697982) (xy 119.552106 -386.707281)
			(xy 119.561393 -386.723722) (xy 119.568468 -386.729986) (xy 119.590557 -386.748667) (xy 119.630329 -386.790679)
			(xy 119.66449 -386.837367) (xy 119.692498 -386.887987) (xy 119.713905 -386.941732) (xy 119.72837 -386.997746)
			(xy 119.735663 -387.055136) (xy 119.736108 -387.084062) (xy 119.735521 -387.117384) (xy 119.725858 -387.183322)
			(xy 119.706731 -387.247161) (xy 119.693182 -387.27761) (xy 119.688933 -387.288074) (xy 119.689047 -387.310634)
			(xy 119.698781 -387.330985) (xy 119.707152 -387.33857) (xy 119.729372 -387.357275) (xy 119.769439 -387.399323)
			(xy 119.803863 -387.446104) (xy 119.832092 -387.496863) (xy 119.853672 -387.550787) (xy 119.868256 -387.607008)
			(xy 119.875609 -387.664621) (xy 119.876062 -387.693662) (xy 119.875581 -387.722667) (xy 119.868271 -387.780214)
			(xy 119.853749 -387.836376) (xy 119.832249 -387.890254) (xy 119.804116 -387.940985) (xy 119.769799 -387.987755)
			(xy 119.729849 -388.029815) (xy 119.70766 -388.0485) (xy 119.700548 -388.054088) (xy 119.691404 -388.069328)
			(xy 119.676164 -388.152132) (xy 119.678958 -388.169404) (xy 119.68353 -388.177532) (xy 119.696104 -388.200719)
			(xy 119.713979 -388.25034) (xy 119.72308 -388.302291) (xy 119.723662 -388.328662) (xy 119.723593 -388.338021)
			(xy 119.72245 -388.356703) (xy 119.721376 -388.366) (xy 119.72036 -388.37489) (xy 119.72417 -388.391654)
			(xy 119.768112 -388.461504) (xy 119.781828 -388.471918) (xy 119.79021 -388.474712) (xy 119.814232 -388.483196)
			(xy 119.859405 -388.506744) (xy 119.900211 -388.53724) (xy 119.935592 -388.573892) (xy 119.964629 -388.615749)
			(xy 119.986568 -388.661725) (xy 119.994172 -388.68604) (xy 119.995696 -388.691882) (xy 120.31599 -389.245602)
			(xy 120.320054 -389.24992) (xy 120.336251 -389.267621) (xy 120.363614 -389.307032) (xy 120.384697 -389.35013)
			(xy 120.399016 -389.395923) (xy 120.40624 -389.443354) (xy 120.406668 -389.467344) (xy 120.406223 -389.492135)
			(xy 120.39846 -389.541105) (xy 120.383133 -389.588259) (xy 120.360619 -389.632434) (xy 120.331473 -389.672544)
			(xy 120.296411 -389.707601) (xy 120.256296 -389.736742) (xy 120.212118 -389.75925) (xy 120.164962 -389.77457)
			(xy 120.115991 -389.782326) (xy 120.0912 -389.782812) (xy 120.065806 -389.782312) (xy 120.015672 -389.774181)
			(xy 119.967486 -389.758129) (xy 119.922492 -389.734571) (xy 119.881849 -389.704114) (xy 119.846607 -389.667543)
			(xy 119.817673 -389.625801) (xy 119.795795 -389.579967) (xy 119.788178 -389.555736) (xy 119.786654 -389.549894)
			(xy 119.46636 -388.996174) (xy 119.462296 -388.991856) (xy 119.446092 -388.974148) (xy 119.418668 -388.934757)
			(xy 119.397525 -388.891668) (xy 119.383152 -388.845873) (xy 119.375878 -388.79843) (xy 119.375428 -388.774432)
			(xy 119.37557 -388.76238) (xy 119.377476 -388.73835) (xy 119.379238 -388.726426) (xy 119.380508 -388.717536)
			(xy 119.37746 -388.700518) (xy 119.335296 -388.629652) (xy 119.322088 -388.618476) (xy 119.313706 -388.615428)
			(xy 119.291966 -388.607013) (xy 119.251106 -388.584577) (xy 119.214134 -388.556187) (xy 119.18191 -388.522505)
			(xy 119.155184 -388.484314) (xy 119.134576 -388.442502) (xy 119.120568 -388.398042) (xy 119.113484 -388.351969)
			(xy 119.113046 -388.328662) (xy 119.113606 -388.302289) (xy 119.12269 -388.25033) (xy 119.140581 -388.20071)
			(xy 119.153178 -388.177532) (xy 119.15775 -388.169404) (xy 119.160544 -388.152132) (xy 119.145304 -388.069328)
			(xy 119.13616 -388.054088) (xy 119.129048 -388.0485) (xy 119.106867 -388.029807) (xy 119.066922 -387.987742)
			(xy 119.032607 -387.940971) (xy 119.00447 -387.890243) (xy 118.982962 -387.836368) (xy 118.968427 -387.78021)
			(xy 118.961096 -387.722666) (xy 118.960646 -387.693662) (xy 118.961245 -387.660341) (xy 118.970904 -387.594403)
			(xy 118.990026 -387.530563) (xy 119.003572 -387.500114) (xy 119.007814 -387.489646) (xy 119.007709 -387.467087)
			(xy 118.997974 -387.446736) (xy 118.989602 -387.439154) (xy 118.967335 -387.420503) (xy 118.927273 -387.378443)
			(xy 118.892854 -387.331653) (xy 118.864632 -387.280884) (xy 118.84306 -387.226952) (xy 118.828484 -387.170725)
			(xy 118.82114 -387.113105) (xy 118.820692 -387.084062) (xy 118.821129 -387.055135) (xy 118.828413 -386.997742)
			(xy 118.842874 -386.941724) (xy 118.864279 -386.887976) (xy 118.892289 -386.837354) (xy 118.926456 -386.790667)
			(xy 118.966235 -386.748659) (xy 118.988332 -386.729986) (xy 118.995299 -386.723634) (xy 119.00456 -386.707234)
			(xy 119.006366 -386.697982) (xy 119.010684 -386.666994) (xy 119.011582 -386.657757) (xy 119.007561 -386.639658)
			(xy 119.00281 -386.631688) (xy 118.986502 -386.605842) (xy 118.962599 -386.549607) (xy 118.955312 -386.519928)
			(xy 118.95325 -386.511767) (xy 118.944551 -386.497366) (xy 118.938294 -386.491734) (xy 118.91518 -386.472684)
			(xy 118.908358 -386.467465) (xy 118.892259 -386.461503) (xy 118.883684 -386.461) (xy 118.854048 -386.45997)
			(xy 118.795384 -386.451324) (xy 118.738327 -386.435176) (xy 118.683833 -386.411796) (xy 118.632814 -386.381575)
			(xy 118.586124 -386.34502) (xy 118.544544 -386.302742) (xy 118.508772 -386.25545) (xy 118.479405 -386.203935)
			(xy 118.456935 -386.149059) (xy 118.441739 -386.091741) (xy 118.434071 -386.032941) (xy 118.433596 -386.003292)
			(xy 118.434116 -385.972229) (xy 118.442532 -385.910675) (xy 118.45036 -385.88061) (xy 118.453154 -385.87045)
			(xy 118.450614 -385.850638) (xy 118.403116 -385.768342) (xy 118.387114 -385.75615) (xy 118.376954 -385.75361)
			(xy 118.347838 -385.745632) (xy 118.29187 -385.722997) (xy 118.239363 -385.6932) (xy 118.191229 -385.656761)
			(xy 118.148303 -385.61431) (xy 118.111329 -385.566584) (xy 118.08095 -385.514413) (xy 118.057693 -385.4587)
			(xy 118.041961 -385.400414) (xy 118.034027 -385.340566) (xy 118.033546 -385.31038) (xy 118.034065 -385.279492)
			(xy 118.042371 -385.218276) (xy 118.05883 -385.158732) (xy 118.083142 -385.10194) (xy 118.09857 -385.075176)
			(xy 118.104412 -385.06527) (xy 118.106698 -385.042918) (xy 118.073424 -384.947668) (xy 118.057676 -384.931666)
			(xy 118.047008 -384.927602) (xy 118.023629 -384.918412) (xy 117.979732 -384.893994) (xy 117.940035 -384.863215)
			(xy 117.905453 -384.826783) (xy 117.876783 -384.785537) (xy 117.854685 -384.740427) (xy 117.839668 -384.692493)
			(xy 117.832078 -384.642838) (xy 117.831616 -384.617722) (xy 117.293136 -384.617722) (xy 117.292607 -384.644824)
			(xy 117.283797 -384.698307) (xy 117.27561 -384.724148) (xy 117.2718 -384.73507) (xy 117.27434 -384.757422)
			(xy 117.326918 -384.843274) (xy 117.345968 -384.85572) (xy 117.357144 -384.857498) (xy 117.386464 -384.862195)
			(xy 117.443634 -384.878245) (xy 117.498248 -384.901556) (xy 117.549388 -384.931737) (xy 117.596193 -384.968279)
			(xy 117.637878 -385.010569) (xy 117.673742 -385.057897) (xy 117.703182 -385.109466) (xy 117.725703 -385.16441)
			(xy 117.740927 -385.221806) (xy 117.748599 -385.280689) (xy 117.749066 -385.31038) (xy 117.748542 -385.341506)
			(xy 117.740137 -385.403188) (xy 117.732302 -385.433316) (xy 117.729508 -385.443476) (xy 117.732048 -385.463542)
			(xy 117.779292 -385.54533) (xy 117.795294 -385.557522) (xy 117.805454 -385.560062) (xy 117.834564 -385.56806)
			(xy 117.89053 -385.590695) (xy 117.943036 -385.620489) (xy 117.991169 -385.656927) (xy 118.034095 -385.699376)
			(xy 118.071069 -385.747099) (xy 118.101449 -385.799268) (xy 118.124708 -385.854977) (xy 118.140442 -385.913261)
			(xy 118.148379 -385.973107) (xy 118.148862 -386.003292) (xy 118.148737 -386.017427) (xy 118.146955 -386.045641)
			(xy 118.145306 -386.05968) (xy 118.144539 -386.068287) (xy 118.148182 -386.085168) (xy 118.152418 -386.0927)
			(xy 118.168166 -386.1181) (xy 118.172884 -386.125154) (xy 118.185984 -386.135926) (xy 118.19382 -386.139182)
			(xy 118.217199 -386.148371) (xy 118.261095 -386.17279) (xy 118.300791 -386.20357) (xy 118.335372 -386.240003)
			(xy 118.364041 -386.281249) (xy 118.386139 -386.326358) (xy 118.401157 -386.374292) (xy 118.408749 -386.423946)
			(xy 118.409212 -386.449062) (xy 118.408785 -386.473264) (xy 118.401712 -386.521148) (xy 118.387726 -386.567488)
			(xy 118.367127 -386.61129) (xy 118.354094 -386.631688) (xy 118.349308 -386.639646) (xy 118.345272 -386.657756)
			(xy 118.34622 -386.666994) (xy 118.350538 -386.697982) (xy 118.352209 -386.707281) (xy 118.361497 -386.723722)
			(xy 118.368572 -386.729986) (xy 118.390662 -386.748666) (xy 118.430433 -386.790678) (xy 118.464595 -386.837367)
			(xy 118.492602 -386.887987) (xy 118.514009 -386.941732) (xy 118.528474 -386.997746) (xy 118.535767 -387.055136)
			(xy 118.536212 -387.084062) (xy 118.535625 -387.117384) (xy 118.525962 -387.183322) (xy 118.506834 -387.247161)
			(xy 118.493286 -387.27761) (xy 118.489035 -387.288074) (xy 118.489149 -387.310634) (xy 118.498885 -387.330986)
			(xy 118.507256 -387.33857) (xy 118.529477 -387.357274) (xy 118.569543 -387.399323) (xy 118.603968 -387.446103)
			(xy 118.632196 -387.496863) (xy 118.653776 -387.550787) (xy 118.66836 -387.607007) (xy 118.675713 -387.664621)
			(xy 118.676166 -387.693662) (xy 118.675684 -387.722667) (xy 118.668373 -387.780214) (xy 118.653852 -387.836376)
			(xy 118.632352 -387.890254) (xy 118.604219 -387.940984) (xy 118.569902 -387.987754) (xy 118.529953 -388.029815)
			(xy 118.507764 -388.0485) (xy 118.500652 -388.054088) (xy 118.491508 -388.069328) (xy 118.476268 -388.152132)
			(xy 118.479062 -388.169404) (xy 118.483634 -388.177532) (xy 118.496209 -388.200719) (xy 118.514083 -388.25034)
			(xy 118.523184 -388.302291) (xy 118.523766 -388.328662) (xy 118.523697 -388.338021) (xy 118.522554 -388.356703)
			(xy 118.52148 -388.366) (xy 118.520464 -388.37489) (xy 118.524274 -388.391654) (xy 118.568216 -388.461504)
			(xy 118.581932 -388.471918) (xy 118.590314 -388.474712) (xy 118.614337 -388.483194) (xy 118.65951 -388.506743)
			(xy 118.700316 -388.537239) (xy 118.735696 -388.573892) (xy 118.764733 -388.615749) (xy 118.786672 -388.661725)
			(xy 118.794276 -388.68604) (xy 118.7958 -388.691882) (xy 119.116094 -389.245602) (xy 119.120158 -389.24992)
			(xy 119.136356 -389.267621) (xy 119.163718 -389.307032) (xy 119.184801 -389.35013) (xy 119.19912 -389.395923)
			(xy 119.206344 -389.443354) (xy 119.206772 -389.467344) (xy 119.206323 -389.492135) (xy 119.19856 -389.541105)
			(xy 119.183234 -389.588258) (xy 119.16072 -389.632433) (xy 119.131574 -389.672543) (xy 119.096512 -389.7076)
			(xy 119.056399 -389.736741) (xy 119.012221 -389.759249) (xy 118.965066 -389.77457) (xy 118.916095 -389.782326)
			(xy 118.891304 -389.782812) (xy 118.86591 -389.782308) (xy 118.815776 -389.774178) (xy 118.767591 -389.758127)
			(xy 118.722596 -389.734569) (xy 118.681954 -389.704112) (xy 118.646711 -389.667542) (xy 118.617777 -389.625801)
			(xy 118.595899 -389.579966) (xy 118.588282 -389.555736) (xy 118.586758 -389.549894) (xy 118.266464 -388.996174)
			(xy 118.2624 -388.991856) (xy 118.246197 -388.974147) (xy 118.218772 -388.934757) (xy 118.19763 -388.891667)
			(xy 118.183256 -388.845873) (xy 118.175982 -388.79843) (xy 118.175532 -388.774432) (xy 118.175674 -388.76238)
			(xy 118.17758 -388.73835) (xy 118.179342 -388.726426) (xy 118.180612 -388.717536) (xy 118.177564 -388.700518)
			(xy 118.1354 -388.629652) (xy 118.122192 -388.618476) (xy 118.11381 -388.615428) (xy 118.092071 -388.607011)
			(xy 118.051211 -388.584575) (xy 118.014239 -388.556186) (xy 117.982015 -388.522504) (xy 117.955288 -388.484313)
			(xy 117.934681 -388.442501) (xy 117.920672 -388.398042) (xy 117.913588 -388.351969) (xy 117.91315 -388.328662)
			(xy 117.913722 -388.302289) (xy 117.922804 -388.250331) (xy 117.940689 -388.200711) (xy 117.953282 -388.177532)
			(xy 117.957854 -388.169404) (xy 117.960648 -388.152132) (xy 117.945408 -388.069328) (xy 117.936264 -388.054088)
			(xy 117.929152 -388.0485) (xy 117.906971 -388.029806) (xy 117.867027 -387.987741) (xy 117.832711 -387.94097)
			(xy 117.804575 -387.890242) (xy 117.783066 -387.836368) (xy 117.768531 -387.78021) (xy 117.7612 -387.722666)
			(xy 117.76075 -387.693662) (xy 117.761349 -387.660341) (xy 117.771008 -387.594403) (xy 117.79013 -387.530563)
			(xy 117.803676 -387.500114) (xy 117.807916 -387.489646) (xy 117.807811 -387.467087) (xy 117.798078 -387.446736)
			(xy 117.789706 -387.439154) (xy 117.76744 -387.420502) (xy 117.727378 -387.378443) (xy 117.692959 -387.331653)
			(xy 117.664736 -387.280884) (xy 117.643164 -387.226952) (xy 117.628588 -387.170725) (xy 117.621244 -387.113105)
			(xy 117.620796 -387.084062) (xy 117.621231 -387.055135) (xy 117.628516 -386.997741) (xy 117.642976 -386.941724)
			(xy 117.664382 -386.887975) (xy 117.692392 -386.837354) (xy 117.726559 -386.790667) (xy 117.766338 -386.748659)
			(xy 117.788436 -386.729986) (xy 117.795404 -386.723634) (xy 117.804665 -386.707234) (xy 117.80647 -386.697982)
			(xy 117.810788 -386.666994) (xy 117.811686 -386.657757) (xy 117.807665 -386.639658) (xy 117.802914 -386.631688)
			(xy 117.786607 -386.605842) (xy 117.762703 -386.549607) (xy 117.755416 -386.519928) (xy 117.753353 -386.511767)
			(xy 117.744655 -386.497366) (xy 117.738398 -386.491734) (xy 117.715284 -386.472684) (xy 117.708403 -386.467439)
			(xy 117.692173 -386.461473) (xy 117.683534 -386.461) (xy 117.653896 -386.460016) (xy 117.595231 -386.451364)
			(xy 117.538173 -386.43521) (xy 117.483679 -386.411824) (xy 117.43266 -386.381599) (xy 117.38597 -386.345039)
			(xy 117.344392 -386.302757) (xy 117.30862 -386.255462) (xy 117.279254 -386.203943) (xy 117.256785 -386.149065)
			(xy 117.241589 -386.091744) (xy 117.233921 -386.032942) (xy 117.233446 -386.003292) (xy 117.233967 -385.972229)
			(xy 117.242383 -385.910675) (xy 117.25021 -385.88061) (xy 117.253004 -385.87045) (xy 117.250464 -385.850638)
			(xy 117.202966 -385.768342) (xy 117.186964 -385.75615) (xy 117.176804 -385.75361) (xy 117.14771 -385.745597)
			(xy 117.091784 -385.722927) (xy 117.039319 -385.693108) (xy 116.991225 -385.656657) (xy 116.948336 -385.614204)
			(xy 116.911394 -385.566486) (xy 116.88104 -385.514329) (xy 116.857798 -385.458638) (xy 116.842073 -385.400376)
			(xy 116.834137 -385.340553) (xy 116.83365 -385.31038) (xy 116.834169 -385.279492) (xy 116.842475 -385.218276)
			(xy 116.858933 -385.158732) (xy 116.883246 -385.10194) (xy 116.898674 -385.075176) (xy 116.904516 -385.06527)
			(xy 116.906802 -385.042918) (xy 116.873528 -384.947668) (xy 116.85778 -384.931666) (xy 116.847112 -384.927602)
			(xy 116.823734 -384.918409) (xy 116.779836 -384.893993) (xy 116.740139 -384.863214) (xy 116.705557 -384.826782)
			(xy 116.676887 -384.785536) (xy 116.654789 -384.740427) (xy 116.639772 -384.692492) (xy 116.632182 -384.642838)
			(xy 116.63172 -384.617722) (xy 116.092986 -384.617722) (xy 116.092454 -384.644824) (xy 116.083646 -384.698307)
			(xy 116.07546 -384.724148) (xy 116.07165 -384.73507) (xy 116.07419 -384.757422) (xy 116.126768 -384.843274)
			(xy 116.145818 -384.85572) (xy 116.156994 -384.857498) (xy 116.186307 -384.862234) (xy 116.243478 -384.878278)
			(xy 116.298092 -384.901584) (xy 116.349232 -384.931759) (xy 116.396038 -384.968297) (xy 116.437724 -385.010583)
			(xy 116.473589 -385.057907) (xy 116.50303 -385.109474) (xy 116.525552 -385.164415) (xy 116.540777 -385.221809)
			(xy 116.548449 -385.28069) (xy 116.548916 -385.31038) (xy 116.54839 -385.341443) (xy 116.539978 -385.402996)
			(xy 116.532152 -385.433062) (xy 116.529358 -385.443222) (xy 116.531898 -385.463034) (xy 116.579396 -385.54533)
			(xy 116.595398 -385.557522) (xy 116.605558 -385.560062) (xy 116.634669 -385.568058) (xy 116.690635 -385.590693)
			(xy 116.74314 -385.620488) (xy 116.791274 -385.656926) (xy 116.8342 -385.699375) (xy 116.871173 -385.747098)
			(xy 116.901553 -385.799267) (xy 116.924812 -385.854977) (xy 116.940546 -385.913261) (xy 116.948483 -385.973107)
			(xy 116.948966 -386.003292) (xy 116.948841 -386.017427) (xy 116.947059 -386.045641) (xy 116.94541 -386.05968)
			(xy 116.944656 -386.068287) (xy 116.948292 -386.085166) (xy 116.952522 -386.0927) (xy 116.96827 -386.1181)
			(xy 116.972986 -386.125155) (xy 116.986087 -386.135927) (xy 116.993924 -386.139182) (xy 117.017304 -386.148368)
			(xy 117.0612 -386.172788) (xy 117.100895 -386.203569) (xy 117.135476 -386.240002) (xy 117.164146 -386.281249)
			(xy 117.186244 -386.326358) (xy 117.201261 -386.374292) (xy 117.208853 -386.423946) (xy 117.209316 -386.449062)
			(xy 117.208888 -386.473264) (xy 117.201815 -386.521148) (xy 117.187829 -386.567488) (xy 117.167231 -386.61129)
			(xy 117.154198 -386.631688) (xy 117.149412 -386.639646) (xy 117.145376 -386.657756) (xy 117.146324 -386.666994)
			(xy 117.150642 -386.697982) (xy 117.152312 -386.707281) (xy 117.1616 -386.723722) (xy 117.168676 -386.729986)
			(xy 117.190767 -386.748665) (xy 117.230538 -386.790678) (xy 117.264699 -386.837366) (xy 117.292706 -386.887987)
			(xy 117.314113 -386.941732) (xy 117.328578 -386.997746) (xy 117.335871 -387.055136) (xy 117.336316 -387.084062)
			(xy 117.335728 -387.117384) (xy 117.326065 -387.183322) (xy 117.306938 -387.247161) (xy 117.29339 -387.27761)
			(xy 117.289138 -387.288074) (xy 117.289252 -387.310634) (xy 117.298988 -387.330986) (xy 117.30736 -387.33857)
			(xy 117.329582 -387.357273) (xy 117.369648 -387.399322) (xy 117.404072 -387.446103) (xy 117.432301 -387.496863)
			(xy 117.45388 -387.550787) (xy 117.468464 -387.607007) (xy 117.475817 -387.664621) (xy 117.47627 -387.693662)
			(xy 117.475787 -387.722667) (xy 117.468476 -387.780213) (xy 117.453955 -387.836376) (xy 117.432455 -387.890253)
			(xy 117.404322 -387.940984) (xy 117.370006 -387.987754) (xy 117.330057 -388.029815) (xy 117.307868 -388.0485)
			(xy 117.300756 -388.054088) (xy 117.291612 -388.069328) (xy 117.276372 -388.152132) (xy 117.279166 -388.169404)
			(xy 117.283738 -388.177532) (xy 117.296313 -388.200719) (xy 117.314187 -388.25034) (xy 117.323288 -388.302291)
			(xy 117.32387 -388.328662) (xy 117.323801 -388.338021) (xy 117.322658 -388.356703) (xy 117.321584 -388.366)
			(xy 117.320568 -388.37489) (xy 117.324378 -388.391654) (xy 117.36832 -388.461504) (xy 117.382036 -388.471918)
			(xy 117.390418 -388.474712) (xy 117.414519 -388.483182) (xy 117.45981 -388.50681) (xy 117.500704 -388.537423)
			(xy 117.536135 -388.574223) (xy 117.565177 -388.616247) (xy 117.587072 -388.6624) (xy 117.594634 -388.686802)
			(xy 117.596158 -388.692644) (xy 117.915944 -389.245602) (xy 117.920008 -389.24992) (xy 117.936201 -389.267637)
			(xy 117.963627 -389.307026) (xy 117.984771 -389.350113) (xy 117.999147 -389.395905) (xy 118.006424 -389.443346)
			(xy 118.006876 -389.467344) (xy 118.006447 -389.492149) (xy 117.998676 -389.541147) (xy 117.983333 -389.588325)
			(xy 117.960796 -389.632521) (xy 117.93162 -389.672645) (xy 117.896524 -389.707708) (xy 117.856373 -389.736847)
			(xy 117.812157 -389.759344) (xy 117.764964 -389.774644) (xy 117.715959 -389.782369) (xy 117.691154 -389.782812)
			(xy 117.665758 -389.782352) (xy 117.615623 -389.774214) (xy 117.567436 -389.758156) (xy 117.522442 -389.734592)
			(xy 117.4818 -389.704129) (xy 117.446558 -389.667553) (xy 117.417625 -389.625807) (xy 117.395748 -389.579968)
			(xy 117.388132 -389.555736) (xy 117.386608 -389.549894) (xy 117.06606 -388.995412) (xy 117.061996 -388.991094)
			(xy 117.0459 -388.973418) (xy 117.018649 -388.934141) (xy 116.997636 -388.891203) (xy 116.983343 -388.845586)
			(xy 116.976095 -388.798334) (xy 116.975636 -388.774432) (xy 116.975778 -388.76238) (xy 116.977684 -388.73835)
			(xy 116.979446 -388.726426) (xy 116.980716 -388.717536) (xy 116.977668 -388.700518) (xy 116.935504 -388.629652)
			(xy 116.922296 -388.618476) (xy 116.913914 -388.615428) (xy 116.892176 -388.607009) (xy 116.851316 -388.584573)
			(xy 116.814344 -388.556185) (xy 116.782119 -388.522503) (xy 116.755392 -388.484312) (xy 116.734785 -388.442501)
			(xy 116.720776 -388.398042) (xy 116.713692 -388.351969) (xy 116.713254 -388.328662) (xy 116.713826 -388.302289)
			(xy 116.722907 -388.250331) (xy 116.740793 -388.200711) (xy 116.753386 -388.177532) (xy 116.757958 -388.169404)
			(xy 116.760752 -388.152132) (xy 116.745512 -388.069328) (xy 116.736368 -388.054088) (xy 116.729256 -388.0485)
			(xy 116.707076 -388.029805) (xy 116.667131 -387.98774) (xy 116.632816 -387.94097) (xy 116.604679 -387.890242)
			(xy 116.583171 -387.836368) (xy 116.568635 -387.78021) (xy 116.561305 -387.722666) (xy 116.560854 -387.693662)
			(xy 116.561453 -387.660341) (xy 116.571112 -387.594403) (xy 116.590234 -387.530563) (xy 116.60378 -387.500114)
			(xy 116.608019 -387.489645) (xy 116.607914 -387.467087) (xy 116.598181 -387.446737) (xy 116.58981 -387.439154)
			(xy 116.567545 -387.420501) (xy 116.527482 -387.378442) (xy 116.493063 -387.331652) (xy 116.46484 -387.280883)
			(xy 116.443268 -387.226952) (xy 116.428692 -387.170725) (xy 116.421348 -387.113105) (xy 116.4209 -387.084062)
			(xy 116.421334 -387.055135) (xy 116.428618 -386.997741) (xy 116.443079 -386.941723) (xy 116.464485 -386.887975)
			(xy 116.492495 -386.837354) (xy 116.526663 -386.790667) (xy 116.566442 -386.748658) (xy 116.58854 -386.729986)
			(xy 116.595508 -386.723635) (xy 116.604769 -386.707234) (xy 116.606574 -386.697982) (xy 116.610892 -386.666994)
			(xy 116.611789 -386.657757) (xy 116.607768 -386.639658) (xy 116.603018 -386.631688) (xy 116.586711 -386.605842)
			(xy 116.562807 -386.549607) (xy 116.55552 -386.519928) (xy 116.553456 -386.511768) (xy 116.544758 -386.497366)
			(xy 116.538502 -386.491734) (xy 116.515388 -386.472684) (xy 116.508506 -386.467441) (xy 116.492277 -386.461474)
			(xy 116.483638 -386.461) (xy 116.454 -386.460013) (xy 116.395335 -386.451361) (xy 116.338278 -386.435207)
			(xy 116.283783 -386.411822) (xy 116.232764 -386.381597) (xy 116.186075 -386.345037) (xy 116.144496 -386.302756)
			(xy 116.108724 -386.255461) (xy 116.079358 -386.203943) (xy 116.056889 -386.149064) (xy 116.041693 -386.091744)
			(xy 116.034025 -386.032942) (xy 116.03355 -386.003292) (xy 116.034071 -385.972229) (xy 116.042487 -385.910675)
			(xy 116.050314 -385.88061) (xy 116.053108 -385.87045) (xy 116.050568 -385.850638) (xy 116.00307 -385.768342)
			(xy 115.987068 -385.75615) (xy 115.976908 -385.75361) (xy 115.947783 -385.745662) (xy 115.891816 -385.723021)
			(xy 115.83931 -385.69322) (xy 115.791177 -385.656776) (xy 115.748252 -385.614322) (xy 115.71128 -385.566593)
			(xy 115.680902 -385.514419) (xy 115.657646 -385.458705) (xy 115.641914 -385.400417) (xy 115.633981 -385.340567)
			(xy 115.6335 -385.31038) (xy 115.634026 -385.279492) (xy 115.642331 -385.218277) (xy 115.658788 -385.158733)
			(xy 115.683098 -385.101941) (xy 115.698524 -385.075176) (xy 115.704366 -385.06527) (xy 115.706652 -385.042918)
			(xy 115.673378 -384.947668) (xy 115.65763 -384.931666) (xy 115.646962 -384.927602) (xy 115.623573 -384.918436)
			(xy 115.579677 -384.894013) (xy 115.539982 -384.863229) (xy 115.505402 -384.826793) (xy 115.476734 -384.785544)
			(xy 115.454637 -384.740432) (xy 115.439621 -384.692495) (xy 115.432032 -384.642839) (xy 115.43157 -384.617722)
			(xy 114.89309 -384.617722) (xy 114.892558 -384.644824) (xy 114.88375 -384.698306) (xy 114.875564 -384.724148)
			(xy 114.871754 -384.73507) (xy 114.874294 -384.757422) (xy 114.926872 -384.843274) (xy 114.945922 -384.85572)
			(xy 114.957098 -384.857498) (xy 114.986412 -384.862231) (xy 115.043582 -384.878276) (xy 115.098196 -384.901582)
			(xy 115.149336 -384.931757) (xy 115.196142 -384.968296) (xy 115.237828 -385.010582) (xy 115.273693 -385.057906)
			(xy 115.303134 -385.109473) (xy 115.325656 -385.164415) (xy 115.340881 -385.221809) (xy 115.348553 -385.28069)
			(xy 115.34902 -385.31038) (xy 115.348494 -385.341443) (xy 115.340082 -385.402996) (xy 115.332256 -385.433062)
			(xy 115.329462 -385.443222) (xy 115.332002 -385.463034) (xy 115.3795 -385.54533) (xy 115.395502 -385.557522)
			(xy 115.405662 -385.560062) (xy 115.434773 -385.568055) (xy 115.49074 -385.59069) (xy 115.543245 -385.620486)
			(xy 115.591378 -385.656924) (xy 115.634304 -385.699374) (xy 115.671278 -385.747097) (xy 115.701657 -385.799267)
			(xy 115.724916 -385.854977) (xy 115.74065 -385.91326) (xy 115.748587 -385.973107) (xy 115.74907 -386.003292)
			(xy 115.748944 -386.017427) (xy 115.747163 -386.045641) (xy 115.745514 -386.05968) (xy 115.744759 -386.068287)
			(xy 115.748396 -386.085166) (xy 115.752626 -386.0927) (xy 115.768374 -386.1181) (xy 115.773076 -386.125168)
			(xy 115.78618 -386.135945) (xy 115.794028 -386.139182) (xy 115.817376 -386.148411) (xy 115.861219 -386.172866)
			(xy 115.900863 -386.203665) (xy 115.935398 -386.240102) (xy 115.96403 -386.281339) (xy 115.986101 -386.326429)
			(xy 116.001105 -386.374336) (xy 116.008697 -386.423961) (xy 116.009166 -386.449062) (xy 116.008746 -386.473264)
			(xy 116.001672 -386.521149) (xy 115.987684 -386.567489) (xy 115.967082 -386.611291) (xy 115.954048 -386.631688)
			(xy 115.949258 -386.639644) (xy 115.945226 -386.657756) (xy 115.946174 -386.666994) (xy 115.950492 -386.697982)
			(xy 115.952176 -386.707277) (xy 115.961456 -386.723719) (xy 115.968526 -386.729986) (xy 115.990606 -386.748677)
			(xy 116.03038 -386.790687) (xy 116.064543 -386.837372) (xy 116.092552 -386.887991) (xy 116.113961 -386.941735)
			(xy 116.128427 -386.997747) (xy 116.135721 -387.055137) (xy 116.136166 -387.084062) (xy 116.135574 -387.117383)
			(xy 116.125912 -387.183322) (xy 116.106787 -387.247161) (xy 116.09324 -387.27761) (xy 116.088972 -387.28807)
			(xy 116.089085 -387.310636) (xy 116.098832 -387.330989) (xy 116.10721 -387.33857) (xy 116.129442 -387.35726)
			(xy 116.169506 -387.399313) (xy 116.203928 -387.446097) (xy 116.232154 -387.496859) (xy 116.253732 -387.550784)
			(xy 116.268315 -387.607006) (xy 116.275667 -387.664621) (xy 116.27612 -387.693662) (xy 116.275655 -387.722667)
			(xy 116.268343 -387.780216) (xy 116.25382 -387.836379) (xy 116.232318 -387.890257) (xy 116.204182 -387.940988)
			(xy 116.169862 -387.987757) (xy 116.129909 -388.029816) (xy 116.107718 -388.0485) (xy 116.100606 -388.054088)
			(xy 116.091462 -388.069328) (xy 116.076222 -388.152132) (xy 116.079016 -388.169404) (xy 116.083588 -388.177532)
			(xy 116.096159 -388.200721) (xy 116.114036 -388.250341) (xy 116.123138 -388.302292) (xy 116.12372 -388.328662)
			(xy 116.123651 -388.338021) (xy 116.122508 -388.356703) (xy 116.121434 -388.366) (xy 116.120418 -388.37489)
			(xy 116.124228 -388.391654) (xy 116.16817 -388.461504) (xy 116.181886 -388.471918) (xy 116.190268 -388.474712)
			(xy 116.214282 -388.483218) (xy 116.259456 -388.506761) (xy 116.300264 -388.537252) (xy 116.335646 -388.5739)
			(xy 116.364684 -388.615753) (xy 116.386626 -388.661726) (xy 116.39423 -388.68604) (xy 116.395754 -388.691882)
			(xy 116.716048 -389.245602) (xy 116.720112 -389.24992) (xy 116.736306 -389.267637) (xy 116.763731 -389.307025)
			(xy 116.784875 -389.350113) (xy 116.799252 -389.395905) (xy 116.806528 -389.443346) (xy 116.80698 -389.467344)
			(xy 116.806547 -389.492149) (xy 116.798776 -389.541146) (xy 116.783433 -389.588324) (xy 116.760896 -389.632519)
			(xy 116.731721 -389.672643) (xy 116.696625 -389.707707) (xy 116.656475 -389.736846) (xy 116.612259 -389.759343)
			(xy 116.565068 -389.774643) (xy 116.516063 -389.782369) (xy 116.491258 -389.782812) (xy 116.465862 -389.782348)
			(xy 116.415727 -389.774211) (xy 116.367541 -389.758154) (xy 116.322546 -389.73459) (xy 116.281904 -389.704127)
			(xy 116.246662 -389.667552) (xy 116.217729 -389.625806) (xy 116.195852 -389.579968) (xy 116.188236 -389.555736)
			(xy 116.186712 -389.549894) (xy 115.866418 -388.996174) (xy 115.862354 -388.991856) (xy 115.846195 -388.974122)
			(xy 115.818826 -388.93472) (xy 115.797736 -388.89163) (xy 115.783408 -388.845845) (xy 115.776174 -388.798419)
			(xy 115.77574 -388.774432) (xy 115.775821 -388.762384) (xy 115.777603 -388.738355) (xy 115.779296 -388.726426)
			(xy 115.780566 -388.717536) (xy 115.777518 -388.700518) (xy 115.735354 -388.629652) (xy 115.722146 -388.618476)
			(xy 115.713764 -388.615428) (xy 115.692015 -388.607036) (xy 115.651157 -388.584594) (xy 115.614186 -388.5562)
			(xy 115.581964 -388.522514) (xy 115.555239 -388.48432) (xy 115.534633 -388.442506) (xy 115.520625 -388.398044)
			(xy 115.513542 -388.35197) (xy 115.513104 -388.328662) (xy 115.513669 -388.302289) (xy 115.522752 -388.25033)
			(xy 115.540641 -388.20071) (xy 115.553236 -388.177532) (xy 115.557808 -388.169404) (xy 115.560602 -388.152132)
			(xy 115.545362 -388.069328) (xy 115.536218 -388.054088) (xy 115.529106 -388.0485) (xy 115.506937 -388.029792)
			(xy 115.466989 -387.987731) (xy 115.432671 -387.940964) (xy 115.404532 -387.890238) (xy 115.383022 -387.836366)
			(xy 115.368486 -387.780209) (xy 115.361155 -387.722666) (xy 115.360704 -387.693662) (xy 115.361307 -387.660341)
			(xy 115.370965 -387.594403) (xy 115.390086 -387.530564) (xy 115.40363 -387.500114) (xy 115.407853 -387.489641)
			(xy 115.407747 -387.467089) (xy 115.398024 -387.44674) (xy 115.38966 -387.439154) (xy 115.367405 -387.420489)
			(xy 115.32734 -387.378433) (xy 115.292919 -387.331646) (xy 115.264694 -387.28088) (xy 115.24312 -387.22695)
			(xy 115.228543 -387.170723) (xy 115.221198 -387.113105) (xy 115.22075 -387.084062) (xy 115.221202 -387.055136)
			(xy 115.228486 -386.997743) (xy 115.242945 -386.941727) (xy 115.264348 -386.887979) (xy 115.292355 -386.837358)
			(xy 115.326519 -386.79067) (xy 115.366294 -386.74866) (xy 115.38839 -386.729986) (xy 115.395367 -386.723643)
			(xy 115.404621 -386.707236) (xy 115.406424 -386.697982) (xy 115.410742 -386.666994) (xy 115.411647 -386.657757)
			(xy 115.407622 -386.639657) (xy 115.402868 -386.631688) (xy 115.386557 -386.605844) (xy 115.362656 -386.549607)
			(xy 115.35537 -386.519928) (xy 115.353319 -386.511763) (xy 115.344613 -386.497363) (xy 115.338352 -386.491734)
			(xy 115.315238 -386.472684) (xy 115.308401 -386.467488) (xy 115.292314 -386.461512) (xy 115.283742 -386.461)
			(xy 115.254105 -386.460009) (xy 115.195439 -386.451357) (xy 115.138382 -386.435204) (xy 115.083888 -386.411819)
			(xy 115.032869 -386.381595) (xy 114.986179 -386.345036) (xy 114.9446 -386.302755) (xy 114.908828 -386.25546)
			(xy 114.879462 -386.203942) (xy 114.856993 -386.149064) (xy 114.841797 -386.091744) (xy 114.834129 -386.032942)
			(xy 114.833654 -386.003292) (xy 114.834175 -385.972229) (xy 114.842591 -385.910675) (xy 114.850418 -385.88061)
			(xy 114.853212 -385.87045) (xy 114.850672 -385.850638) (xy 114.803174 -385.768342) (xy 114.787172 -385.75615)
			(xy 114.777012 -385.75361) (xy 114.765291 -385.750463) (xy 114.742165 -385.743093) (xy 114.730784 -385.738878)
			(xy 114.718338 -385.734306) (xy 114.69243 -385.738116) (xy 114.603022 -385.806696) (xy 114.592608 -385.830826)
			(xy 114.593878 -385.84378) (xy 114.595402 -385.87553) (xy 114.595014 -385.899206) (xy 114.588283 -385.946077)
			(xy 114.574919 -385.991503) (xy 114.56543 -386.013198) (xy 114.561112 -386.022596) (xy 114.56035 -386.042662)
			(xy 114.592608 -386.129022) (xy 114.606324 -386.143754) (xy 114.615722 -386.148072) (xy 114.640084 -386.159776)
			(xy 114.684956 -386.189899) (xy 114.724335 -386.226914) (xy 114.757175 -386.269837) (xy 114.782602 -386.317526)
			(xy 114.799941 -386.368714) (xy 114.80873 -386.42204) (xy 114.80927 -386.449062) (xy 114.80885 -386.473264)
			(xy 114.801776 -386.521149) (xy 114.787788 -386.567489) (xy 114.767186 -386.611291) (xy 114.754152 -386.631688)
			(xy 114.749363 -386.639644) (xy 114.74533 -386.657756) (xy 114.746278 -386.666994) (xy 114.750596 -386.697982)
			(xy 114.752279 -386.707278) (xy 114.761559 -386.723719) (xy 114.76863 -386.729986) (xy 114.790711 -386.748676)
			(xy 114.830484 -386.790686) (xy 114.864648 -386.837372) (xy 114.892657 -386.88799) (xy 114.914065 -386.941734)
			(xy 114.928531 -386.997747) (xy 114.935825 -387.055137) (xy 114.93627 -387.084062) (xy 114.935678 -387.117383)
			(xy 114.926016 -387.183322) (xy 114.906891 -387.247161) (xy 114.893344 -387.27761) (xy 114.889074 -387.288069)
			(xy 114.889188 -387.310636) (xy 114.898935 -387.330989) (xy 114.907314 -387.33857) (xy 114.929547 -387.357259)
			(xy 114.969611 -387.399313) (xy 115.004032 -387.446096) (xy 115.032259 -387.496859) (xy 115.053836 -387.550784)
			(xy 115.068419 -387.607006) (xy 115.075771 -387.664621) (xy 115.076224 -387.693662) (xy 115.075757 -387.722667)
			(xy 115.068446 -387.780215) (xy 115.053923 -387.836379) (xy 115.032421 -387.890257) (xy 115.004285 -387.940988)
			(xy 114.969966 -387.987757) (xy 114.930012 -388.029816) (xy 114.907822 -388.0485) (xy 114.90071 -388.054088)
			(xy 114.891566 -388.069328) (xy 114.876326 -388.152132) (xy 114.87912 -388.169404) (xy 114.883692 -388.177532)
			(xy 114.896263 -388.200721) (xy 114.91414 -388.250341) (xy 114.923242 -388.302292) (xy 114.923824 -388.328662)
			(xy 114.923755 -388.338021) (xy 114.922612 -388.356703) (xy 114.921538 -388.366) (xy 114.920522 -388.37489)
			(xy 114.924332 -388.391654) (xy 114.968274 -388.461504) (xy 114.98199 -388.471918) (xy 114.990372 -388.474712)
			(xy 115.014387 -388.483216) (xy 115.059561 -388.50676) (xy 115.100368 -388.537251) (xy 115.13575 -388.573899)
			(xy 115.164789 -388.615753) (xy 115.18673 -388.661726) (xy 115.194334 -388.68604) (xy 115.195858 -388.691882)
			(xy 115.516152 -389.245602) (xy 115.520216 -389.24992) (xy 115.53641 -389.267636) (xy 115.563835 -389.307025)
			(xy 115.58498 -389.350113) (xy 115.599356 -389.395905) (xy 115.606632 -389.443346) (xy 115.607084 -389.467344)
			(xy 115.606647 -389.492149) (xy 115.598876 -389.541146) (xy 115.583534 -389.588323) (xy 115.560997 -389.632518)
			(xy 115.531822 -389.672642) (xy 115.496727 -389.707705) (xy 115.456577 -389.736845) (xy 115.412362 -389.759342)
			(xy 115.365171 -389.774642) (xy 115.316167 -389.782369) (xy 115.291362 -389.782812) (xy 115.265966 -389.782345)
			(xy 115.215831 -389.774208) (xy 115.167645 -389.758151) (xy 115.122651 -389.734588) (xy 115.082008 -389.704126)
			(xy 115.046766 -389.667551) (xy 115.017833 -389.625806) (xy 114.995956 -389.579968) (xy 114.98834 -389.555736)
			(xy 114.986816 -389.549894) (xy 114.666522 -388.996174) (xy 114.662458 -388.991856) (xy 114.646299 -388.974121)
			(xy 114.618931 -388.93472) (xy 114.59784 -388.89163) (xy 114.583512 -388.845845) (xy 114.576278 -388.798419)
			(xy 114.575844 -388.774432) (xy 114.575925 -388.762384) (xy 114.577707 -388.738355) (xy 114.5794 -388.726426)
			(xy 114.58067 -388.717536) (xy 114.577622 -388.700518) (xy 114.535458 -388.629652) (xy 114.52225 -388.618476)
			(xy 114.513868 -388.615428) (xy 114.49212 -388.607034) (xy 114.451261 -388.584593) (xy 114.414291 -388.556199)
			(xy 114.382068 -388.522514) (xy 114.355343 -388.484319) (xy 114.334737 -388.442506) (xy 114.320729 -388.398044)
			(xy 114.313646 -388.35197) (xy 114.313208 -388.328662) (xy 114.313773 -388.302289) (xy 114.322856 -388.25033)
			(xy 114.340745 -388.20071) (xy 114.35334 -388.177532) (xy 114.357912 -388.169404) (xy 114.360706 -388.152132)
			(xy 114.345466 -388.069328) (xy 114.336322 -388.054088) (xy 114.32921 -388.0485) (xy 114.307041 -388.029791)
			(xy 114.267094 -387.987731) (xy 114.232776 -387.940963) (xy 114.204637 -387.890238) (xy 114.183127 -387.836365)
			(xy 114.16859 -387.780209) (xy 114.161259 -387.722666) (xy 114.160808 -387.693662) (xy 114.161411 -387.660341)
			(xy 114.171069 -387.594403) (xy 114.190189 -387.530564) (xy 114.203734 -387.500114) (xy 114.207955 -387.489641)
			(xy 114.20785 -387.467089) (xy 114.198128 -387.44674) (xy 114.189764 -387.439154) (xy 114.167489 -387.420512)
			(xy 114.127429 -387.37845) (xy 114.093012 -387.331658) (xy 114.064791 -387.280887) (xy 114.04322 -387.226954)
			(xy 114.028646 -387.170726) (xy 114.021302 -387.113105) (xy 114.020854 -387.084062) (xy 114.021305 -387.055136)
			(xy 114.028588 -386.997743) (xy 114.043047 -386.941726) (xy 114.064451 -386.887979) (xy 114.092458 -386.837357)
			(xy 114.126622 -386.790669) (xy 114.166398 -386.74866) (xy 114.188494 -386.729986) (xy 114.195471 -386.723644)
			(xy 114.204725 -386.707236) (xy 114.206528 -386.697982) (xy 114.210846 -386.666994) (xy 114.21175 -386.657757)
			(xy 114.207726 -386.639658) (xy 114.202972 -386.631688) (xy 114.189981 -386.611267) (xy 114.169402 -386.567464)
			(xy 114.155416 -386.521133) (xy 114.148321 -386.47326) (xy 114.147854 -386.449062) (xy 114.148234 -386.425386)
			(xy 114.154968 -386.378515) (xy 114.168335 -386.333088) (xy 114.177826 -386.311394) (xy 114.182144 -386.301996)
			(xy 114.182906 -386.28193) (xy 114.150648 -386.19557) (xy 114.136932 -386.180838) (xy 114.127534 -386.17652)
			(xy 114.103158 -386.164843) (xy 114.058289 -386.134713) (xy 114.018912 -386.097693) (xy 113.986074 -386.054765)
			(xy 113.960649 -386.007072) (xy 113.943312 -385.955881) (xy 113.934525 -385.902553) (xy 113.933986 -385.87553)
			(xy 112.446939 -385.87553) (xy 112.417521 -385.912288) (xy 112.395508 -385.93395) (xy 112.386872 -385.942332)
			(xy 112.378744 -385.964684) (xy 112.390682 -386.069078) (xy 112.403636 -386.08889) (xy 112.41405 -386.09524)
			(xy 112.439386 -386.110753) (xy 112.48624 -386.147278) (xy 112.527972 -386.189559) (xy 112.563881 -386.236886)
			(xy 112.593362 -386.288463) (xy 112.615921 -386.343421) (xy 112.631176 -386.400837) (xy 112.638871 -386.459744)
			(xy 112.639348 -386.489448) (xy 112.638876 -386.520107) (xy 112.630684 -386.580875) (xy 112.614453 -386.640006)
			(xy 112.590474 -386.696441) (xy 112.559177 -386.749169) (xy 112.52112 -386.797248) (xy 112.499394 -386.818886)
			(xy 112.491657 -386.827199) (xy 112.48366 -386.84842) (xy 112.485567 -386.871017) (xy 112.490758 -386.881116)
			(xy 112.504893 -386.906586) (xy 112.524964 -386.961264) (xy 112.535128 -387.018617) (xy 112.535716 -387.04774)
			(xy 112.535206 -387.073727) (xy 112.527076 -387.125062) (xy 112.511015 -387.174492) (xy 112.487419 -387.220802)
			(xy 112.456869 -387.26285) (xy 112.420118 -387.299601) (xy 112.37807 -387.330151) (xy 112.33176 -387.353747)
			(xy 112.28233 -387.369808) (xy 112.230995 -387.377938) (xy 112.179021 -387.377938) (xy 112.127686 -387.369808)
			(xy 112.078256 -387.353747) (xy 112.031946 -387.330151) (xy 111.989898 -387.299601) (xy 111.953147 -387.26285)
			(xy 111.922597 -387.220802) (xy 111.899001 -387.174492) (xy 111.88294 -387.125062) (xy 111.87481 -387.073727)
			(xy 111.8743 -387.04774) (xy 111.87472 -387.023227) (xy 111.881905 -386.97473) (xy 111.896181 -386.927829)
			(xy 111.906304 -386.9055) (xy 111.910681 -386.895032) (xy 111.910727 -386.872371) (xy 111.901 -386.851903)
			(xy 111.892588 -386.844286) (xy 111.870375 -386.825612) (xy 111.830364 -386.783578) (xy 111.795991 -386.736822)
			(xy 111.767807 -386.686093) (xy 111.746265 -386.632208) (xy 111.731711 -386.576031) (xy 111.724378 -386.518464)
			(xy 111.723932 -386.489448) (xy 111.724423 -386.458568) (xy 111.732741 -386.397369) (xy 111.749218 -386.337847)
			(xy 111.773555 -386.281083) (xy 111.805309 -386.228111) (xy 111.843903 -386.179893) (xy 111.865918 -386.158232)
			(xy 111.874554 -386.14985) (xy 111.882682 -386.127498) (xy 111.870744 -386.023104) (xy 111.85779 -386.003292)
			(xy 111.847376 -385.996942) (xy 111.823986 -385.982728) (xy 111.780477 -385.949521) (xy 111.741244 -385.911354)
			(xy 111.70685 -385.868776) (xy 111.677787 -385.822395) (xy 111.665766 -385.797806) (xy 111.65967 -385.785106)
			(xy 111.63681 -385.769612) (xy 111.51997 -385.762246) (xy 111.495586 -385.774692) (xy 111.487966 -385.78663)
			(xy 111.47288 -385.809512) (xy 111.437189 -385.851104) (xy 111.395913 -385.887161) (xy 111.349902 -385.91694)
			(xy 111.300102 -385.939827) (xy 111.24754 -385.955352) (xy 111.193297 -385.963194) (xy 111.165894 -385.963668)
			(xy 111.13864 -385.963262) (xy 111.084687 -385.955504) (xy 111.032388 -385.940146) (xy 110.982806 -385.917503)
			(xy 110.936952 -385.888033) (xy 110.895758 -385.852338) (xy 110.860063 -385.811143) (xy 110.830595 -385.765288)
			(xy 110.807951 -385.715706) (xy 110.792595 -385.663407) (xy 110.784838 -385.609454) (xy 102.309867 -385.609454)
			(xy 102.319582 -385.628642) (xy 102.32898 -385.635754) (xy 102.355302 -385.656433) (xy 102.40284 -385.703557)
			(xy 102.44378 -385.756513) (xy 102.477416 -385.814385) (xy 102.503165 -385.876172) (xy 102.520581 -385.940803)
			(xy 102.529363 -386.007162) (xy 102.529894 -386.04063) (xy 102.529472 -386.071362) (xy 102.52206 -386.132378)
			(xy 102.507347 -386.192056) (xy 102.485549 -386.249525) (xy 102.456982 -386.303947) (xy 102.422064 -386.35453)
			(xy 102.381304 -386.400535) (xy 102.335295 -386.441291) (xy 102.28471 -386.476205) (xy 102.230284 -386.504767)
			(xy 102.172813 -386.52656) (xy 102.113135 -386.541268) (xy 102.052118 -386.548675) (xy 102.021386 -386.549138)
			(xy 101.989884 -386.548649) (xy 101.927363 -386.540861) (xy 101.866284 -386.525406) (xy 101.807583 -386.502521)
			(xy 101.75216 -386.472556) (xy 101.726238 -386.45465) (xy 101.715316 -386.44703) (xy 101.689408 -386.444236)
			(xy 101.585014 -386.488178) (xy 101.569012 -386.508752) (xy 101.56698 -386.52196) (xy 101.561539 -386.554308)
			(xy 101.543309 -386.617322) (xy 101.517129 -386.677469) (xy 101.483434 -386.733752) (xy 101.442783 -386.785236)
			(xy 101.39585 -386.831067) (xy 101.343415 -386.870483) (xy 101.286348 -386.902832) (xy 101.225596 -386.927576)
			(xy 101.162166 -386.944304) (xy 101.097113 -386.952739) (xy 101.064314 -386.953252) (xy 101.032911 -386.952714)
			(xy 100.970582 -386.94498) (xy 100.90968 -386.929629) (xy 100.851132 -386.906893) (xy 100.795831 -386.87712)
			(xy 100.744617 -386.840763) (xy 100.698271 -386.798375) (xy 100.657499 -386.750602) (xy 100.62292 -386.69817)
			(xy 100.595063 -386.641879) (xy 100.57435 -386.582586) (xy 100.561098 -386.521193) (xy 100.557838 -386.489956)
			(xy 100.556822 -386.479796) (xy 100.548186 -386.462778) (xy 100.480114 -386.403342) (xy 100.461826 -386.396992)
			(xy 100.451666 -386.3975) (xy 100.427536 -386.398008) (xy 100.396805 -386.397529) (xy 100.33579 -386.390124)
			(xy 100.276112 -386.375419) (xy 100.218642 -386.353627) (xy 100.164218 -386.325066) (xy 100.113634 -386.290154)
			(xy 100.067627 -386.249398) (xy 100.026868 -386.203394) (xy 99.991952 -386.152812) (xy 99.963388 -386.09839)
			(xy 99.941592 -386.040922) (xy 99.926882 -385.981246) (xy 99.919474 -385.920231) (xy 99.919028 -385.8895)
			(xy 99.919451 -385.858719) (xy 99.926867 -385.797605) (xy 99.941603 -385.737833) (xy 99.963444 -385.680275)
			(xy 99.99207 -385.625773) (xy 100.009198 -385.600194) (xy 100.014276 -385.5922) (xy 100.018725 -385.573807)
			(xy 100.017834 -385.56438) (xy 100.013516 -385.533646) (xy 100.011852 -385.524383) (xy 100.002729 -385.507939)
			(xy 99.995736 -385.501642) (xy 99.973912 -385.482952) (xy 99.934606 -385.441038) (xy 99.900858 -385.394534)
			(xy 99.873197 -385.344169) (xy 99.852061 -385.290738) (xy 99.83778 -385.235081) (xy 99.83058 -385.178074)
			(xy 99.830128 -385.149344) (xy 98.747254 -385.149344) (xy 98.753428 -385.164408) (xy 98.768652 -385.221805)
			(xy 98.776323 -385.280689) (xy 98.77679 -385.31038) (xy 98.776262 -385.341443) (xy 98.767851 -385.402996)
			(xy 98.760026 -385.433062) (xy 98.757232 -385.443222) (xy 98.759772 -385.463034) (xy 98.80727 -385.54533)
			(xy 98.823272 -385.557522) (xy 98.833432 -385.560062) (xy 98.862538 -385.568075) (xy 98.918504 -385.590707)
			(xy 98.97101 -385.620499) (xy 99.019144 -385.656935) (xy 99.062071 -385.699382) (xy 99.099045 -385.747103)
			(xy 99.129426 -385.799271) (xy 99.152685 -385.85498) (xy 99.16842 -385.913262) (xy 99.176356 -385.973107)
			(xy 99.17684 -386.003292) (xy 99.176738 -386.017042) (xy 99.175086 -386.044493) (xy 99.173538 -386.058156)
			(xy 99.172818 -386.066844) (xy 99.176592 -386.083853) (xy 99.180904 -386.09143) (xy 99.196906 -386.11683)
			(xy 99.201673 -386.123868) (xy 99.214917 -386.134509) (xy 99.222814 -386.137658) (xy 99.24659 -386.146579)
			(xy 99.291239 -386.170772) (xy 99.331664 -386.201507) (xy 99.366915 -386.238061) (xy 99.396163 -386.279575)
			(xy 99.41872 -386.325073) (xy 99.434056 -386.373484) (xy 99.441811 -386.423671) (xy 99.44227 -386.449062)
			(xy 99.44179 -386.475052) (xy 99.433663 -386.526393) (xy 99.417604 -386.57583) (xy 99.394007 -386.622146)
			(xy 99.363455 -386.664199) (xy 99.326699 -386.700955) (xy 99.284646 -386.731507) (xy 99.23833 -386.755104)
			(xy 99.188893 -386.771163) (xy 99.137552 -386.77929) (xy 99.111562 -386.77977) (xy 99.086655 -386.779263)
			(xy 99.037401 -386.771813) (xy 98.989822 -386.757059) (xy 98.944996 -386.735333) (xy 98.903936 -386.707128)
			(xy 98.867573 -386.673082) (xy 98.836729 -386.633966) (xy 98.812102 -386.590665) (xy 98.794251 -386.54416)
			(xy 98.788474 -386.519928) (xy 98.786308 -386.511709) (xy 98.777499 -386.497188) (xy 98.771202 -386.49148)
			(xy 98.747834 -386.47243) (xy 98.740942 -386.467229) (xy 98.724709 -386.461383) (xy 98.716084 -386.461)
			(xy 98.686248 -386.460288) (xy 98.627126 -386.45214) (xy 98.569564 -386.436377) (xy 98.51454 -386.413266)
			(xy 98.462987 -386.383199) (xy 98.415779 -386.346685) (xy 98.373718 -386.304346) (xy 98.337517 -386.256898)
			(xy 98.307791 -386.205147) (xy 98.285044 -386.149971) (xy 98.269662 -386.092307) (xy 98.261905 -386.033132)
			(xy 98.261424 -386.003292) (xy 98.261946 -385.972229) (xy 98.270361 -385.910675) (xy 98.278188 -385.88061)
			(xy 98.280982 -385.87045) (xy 98.278442 -385.850638) (xy 98.230944 -385.768342) (xy 98.214942 -385.75615)
			(xy 98.204782 -385.75361) (xy 98.175671 -385.745613) (xy 98.119703 -385.722981) (xy 98.067196 -385.693188)
			(xy 98.019061 -385.656751) (xy 97.976134 -385.614302) (xy 97.93916 -385.566578) (xy 97.90878 -385.514408)
			(xy 97.885522 -385.458698) (xy 97.86979 -385.400413) (xy 97.861856 -385.340565) (xy 97.861374 -385.31038)
			(xy 97.861903 -385.279492) (xy 97.870208 -385.218277) (xy 97.886664 -385.158733) (xy 97.910972 -385.101941)
			(xy 97.926398 -385.075176) (xy 97.93224 -385.06527) (xy 97.934526 -385.042918) (xy 97.901252 -384.947668)
			(xy 97.885504 -384.931666) (xy 97.874836 -384.927602) (xy 97.851442 -384.91845) (xy 97.807546 -384.894024)
			(xy 97.767852 -384.863237) (xy 97.733273 -384.826799) (xy 97.704606 -384.785548) (xy 97.68251 -384.740434)
			(xy 97.667495 -384.692497) (xy 97.659906 -384.642839) (xy 97.659444 -384.617722) (xy 97.120964 -384.617722)
			(xy 97.120433 -384.644824) (xy 97.111624 -384.698307) (xy 97.103438 -384.724148) (xy 97.099628 -384.73507)
			(xy 97.102168 -384.757422) (xy 97.154746 -384.843274) (xy 97.173796 -384.85572) (xy 97.184972 -384.857498)
			(xy 97.214296 -384.862173) (xy 97.271466 -384.878227) (xy 97.32608 -384.901541) (xy 97.377219 -384.931724)
			(xy 97.424024 -384.968269) (xy 97.465708 -385.010561) (xy 97.501571 -385.057891) (xy 97.531011 -385.109462)
			(xy 97.553532 -385.164407) (xy 97.568756 -385.221805) (xy 97.576427 -385.280689) (xy 97.576894 -385.31038)
			(xy 97.57637 -385.341506) (xy 97.567965 -385.403188) (xy 97.56013 -385.433316) (xy 97.557336 -385.443476)
			(xy 97.559876 -385.463542) (xy 97.60712 -385.54533) (xy 97.623122 -385.557522) (xy 97.633282 -385.560062)
			(xy 97.662397 -385.568042) (xy 97.718363 -385.59068) (xy 97.770868 -385.620477) (xy 97.819001 -385.656918)
			(xy 97.861926 -385.699369) (xy 97.898899 -385.747093) (xy 97.929278 -385.799264) (xy 97.952537 -385.854975)
			(xy 97.968271 -385.913259) (xy 97.976207 -385.973106) (xy 97.97669 -386.003292) (xy 97.976565 -386.017427)
			(xy 97.974783 -386.045641) (xy 97.973134 -386.05968) (xy 97.972377 -386.068287) (xy 97.976015 -386.085167)
			(xy 97.980246 -386.0927) (xy 97.995994 -386.1181) (xy 98.000703 -386.125161) (xy 98.013809 -386.135929)
			(xy 98.021648 -386.139182) (xy 98.045033 -386.148356) (xy 98.088929 -386.172778) (xy 98.128623 -386.203562)
			(xy 98.163203 -386.239997) (xy 98.191871 -386.281245) (xy 98.213969 -386.326356) (xy 98.228986 -386.374291)
			(xy 98.236577 -386.423946) (xy 98.23704 -386.449062) (xy 98.236625 -386.473265) (xy 98.22955 -386.52115)
			(xy 98.215561 -386.56749) (xy 98.194957 -386.611291) (xy 98.181922 -386.631688) (xy 98.177131 -386.639643)
			(xy 98.1731 -386.657755) (xy 98.174048 -386.666994) (xy 98.178366 -386.697982) (xy 98.180058 -386.707275)
			(xy 98.189333 -386.723717) (xy 98.1964 -386.729986) (xy 98.218475 -386.748684) (xy 98.25825 -386.790691)
			(xy 98.292414 -386.837376) (xy 98.320425 -386.887993) (xy 98.341834 -386.941736) (xy 98.356301 -386.997748)
			(xy 98.363595 -387.055137) (xy 98.36404 -387.084062) (xy 102.411528 -387.084062) (xy 102.415599 -387.02844)
			(xy 102.427725 -386.974003) (xy 102.447648 -386.921912) (xy 102.474944 -386.873277) (xy 102.50903 -386.829134)
			(xy 102.549179 -386.790425) (xy 102.594537 -386.757974) (xy 102.644137 -386.732473) (xy 102.696921 -386.714466)
			(xy 102.751764 -386.704336) (xy 102.807498 -386.702299) (xy 102.862935 -386.708399) (xy 102.916892 -386.722505)
			(xy 102.968221 -386.744317) (xy 103.015827 -386.773371) (xy 103.058695 -386.809046) (xy 103.095912 -386.850583)
			(xy 103.126685 -386.897096) (xy 103.150357 -386.947593) (xy 103.166425 -387.001) (xy 103.174545 -387.056176)
			(xy 103.175054 -387.084062) (xy 103.174545 -387.111948) (xy 103.166425 -387.167124) (xy 103.150357 -387.220531)
			(xy 103.126685 -387.271028) (xy 103.095912 -387.317541) (xy 103.058695 -387.359078) (xy 103.015827 -387.394753)
			(xy 102.968221 -387.423807) (xy 102.916892 -387.445619) (xy 102.862935 -387.459725) (xy 102.807498 -387.465825)
			(xy 102.751764 -387.463788) (xy 102.696921 -387.453658) (xy 102.644137 -387.435651) (xy 102.594537 -387.41015)
			(xy 102.549179 -387.377699) (xy 102.50903 -387.33899) (xy 102.474944 -387.294847) (xy 102.447648 -387.246212)
			(xy 102.427725 -387.194121) (xy 102.415599 -387.139684) (xy 102.411528 -387.084062) (xy 98.36404 -387.084062)
			(xy 98.36345 -387.117383) (xy 98.353788 -387.183322) (xy 98.334662 -387.247161) (xy 98.321114 -387.27761)
			(xy 98.316854 -387.288072) (xy 98.316968 -387.310635) (xy 98.326709 -387.330988) (xy 98.335084 -387.33857)
			(xy 98.357311 -387.357267) (xy 98.397376 -387.399318) (xy 98.431799 -387.4461) (xy 98.460026 -387.496861)
			(xy 98.481605 -387.550785) (xy 98.496188 -387.607007) (xy 98.503541 -387.664621) (xy 98.503994 -387.693662)
			(xy 98.503502 -387.722666) (xy 98.496192 -387.780212) (xy 98.492498 -387.7945) (xy 104.48493 -387.7945)
			(xy 104.489001 -387.738878) (xy 104.501127 -387.684441) (xy 104.52105 -387.63235) (xy 104.548346 -387.583715)
			(xy 104.582432 -387.539572) (xy 104.622581 -387.500863) (xy 104.667939 -387.468412) (xy 104.717539 -387.442911)
			(xy 104.770323 -387.424904) (xy 104.825166 -387.414774) (xy 104.8809 -387.412737) (xy 104.936337 -387.418837)
			(xy 104.990294 -387.432943) (xy 105.041623 -387.454755) (xy 105.089229 -387.483809) (xy 105.132097 -387.519484)
			(xy 105.169314 -387.561021) (xy 105.200087 -387.607534) (xy 105.223759 -387.658031) (xy 105.239827 -387.711438)
			(xy 105.247947 -387.766614) (xy 105.248368 -387.789674) (xy 107.874308 -387.789674) (xy 107.874873 -387.754718)
			(xy 107.884438 -387.685464) (xy 107.903399 -387.618173) (xy 107.931398 -387.554113) (xy 107.967907 -387.494491)
			(xy 107.989624 -387.467094) (xy 107.994924 -387.460097) (xy 108.000897 -387.443604) (xy 108.001308 -387.434836)
			(xy 108.001308 -387.280912) (xy 108.00094 -387.272135) (xy 107.994959 -387.255633) (xy 107.989624 -387.248654)
			(xy 107.967939 -387.221233) (xy 107.931437 -387.161614) (xy 107.903438 -387.097559) (xy 107.884471 -387.030275)
			(xy 107.874892 -386.961027) (xy 107.874308 -386.926074) (xy 107.874732 -386.895342) (xy 107.882143 -386.834326)
			(xy 107.896856 -386.774648) (xy 107.918654 -386.717179) (xy 107.94722 -386.662757) (xy 107.982138 -386.612174)
			(xy 108.022899 -386.566169) (xy 108.068907 -386.525412) (xy 108.119492 -386.490499) (xy 108.173918 -386.461937)
			(xy 108.231389 -386.440143) (xy 108.291067 -386.425436) (xy 108.352084 -386.418029) (xy 108.382816 -386.417566)
			(xy 108.403551 -386.417797) (xy 108.444878 -386.421229) (xy 108.465366 -386.424424) (xy 108.474022 -386.425479)
			(xy 108.491166 -386.422366) (xy 108.498894 -386.418328) (xy 108.524802 -386.403342) (xy 108.532111 -386.398792)
			(xy 108.543406 -386.385811) (xy 108.5469 -386.377942) (xy 108.557909 -386.351693) (xy 108.586524 -386.302493)
			(xy 108.622131 -386.25809) (xy 108.663941 -386.219471) (xy 108.711025 -386.187493) (xy 108.762338 -386.162866)
			(xy 108.816741 -386.146137) (xy 108.873026 -386.137678) (xy 108.901484 -386.13715) (xy 108.928733 -386.137693)
			(xy 108.982676 -386.145446) (xy 109.034967 -386.160797) (xy 109.084542 -386.183433) (xy 109.13039 -386.212894)
			(xy 109.171579 -386.24858) (xy 109.207271 -386.289763) (xy 109.236739 -386.335607) (xy 109.259382 -386.385178)
			(xy 109.274741 -386.437467) (xy 109.282503 -386.491409) (xy 109.282992 -386.518658) (xy 109.282575 -386.546005)
			(xy 109.274783 -386.60014) (xy 109.259339 -386.652608) (xy 109.23656 -386.702331) (xy 109.206912 -386.748292)
			(xy 109.171004 -386.789546) (xy 109.129571 -386.825249) (xy 109.083464 -386.854668) (xy 109.033628 -386.8772)
			(xy 108.981084 -386.892383) (xy 108.954062 -386.89661) (xy 108.945648 -386.898089) (xy 108.930459 -386.905885)
			(xy 108.924344 -386.91185) (xy 108.90377 -386.93344) (xy 108.897954 -386.939992) (xy 108.890815 -386.955979)
			(xy 108.8898 -386.964682) (xy 108.886969 -386.99564) (xy 108.874755 -387.056594) (xy 108.855202 -387.115605)
			(xy 108.828602 -387.171792) (xy 108.79535 -387.224318) (xy 108.776008 -387.248654) (xy 108.770721 -387.255659)
			(xy 108.764742 -387.272146) (xy 108.764324 -387.280912) (xy 108.764324 -387.434836) (xy 108.764684 -387.443613)
			(xy 108.770672 -387.460115) (xy 108.776008 -387.467094) (xy 108.797719 -387.494494) (xy 108.834217 -387.55412)
			(xy 108.86221 -387.61818) (xy 108.881171 -387.685469) (xy 108.890743 -387.754719) (xy 108.891324 -387.789674)
			(xy 108.890874 -387.820891) (xy 108.883258 -387.88286) (xy 108.868113 -387.943429) (xy 108.845666 -388.001689)
			(xy 108.83138 -388.02945) (xy 108.826808 -388.037578) (xy 108.824522 -388.055612) (xy 108.843572 -388.138924)
			(xy 108.853478 -388.15391) (xy 108.861098 -388.159498) (xy 108.881623 -388.174953) (xy 108.91876 -388.210458)
			(xy 108.950795 -388.250627) (xy 108.977147 -388.294733) (xy 108.978404 -388.297674) (xy 110.908844 -388.297674)
			(xy 110.912915 -388.242052) (xy 110.925041 -388.187615) (xy 110.944964 -388.135524) (xy 110.97226 -388.086889)
			(xy 111.006346 -388.042746) (xy 111.046495 -388.004037) (xy 111.091853 -387.971586) (xy 111.141453 -387.946085)
			(xy 111.194237 -387.928078) (xy 111.24908 -387.917948) (xy 111.304814 -387.915911) (xy 111.360251 -387.922011)
			(xy 111.414208 -387.936117) (xy 111.465537 -387.957929) (xy 111.513143 -387.986983) (xy 111.556011 -388.022658)
			(xy 111.593228 -388.064195) (xy 111.624001 -388.110708) (xy 111.647673 -388.161205) (xy 111.663741 -388.214612)
			(xy 111.671861 -388.269788) (xy 111.67237 -388.297674) (xy 111.671923 -388.322137) (xy 111.87481 -388.322137)
			(xy 111.87481 -388.270163) (xy 111.88294 -388.218828) (xy 111.899001 -388.169398) (xy 111.922597 -388.123088)
			(xy 111.953147 -388.08104) (xy 111.989898 -388.044289) (xy 112.031946 -388.013739) (xy 112.078256 -387.990143)
			(xy 112.127686 -387.974082) (xy 112.179021 -387.965952) (xy 112.230995 -387.965952) (xy 112.28233 -387.974082)
			(xy 112.33176 -387.990143) (xy 112.37807 -388.013739) (xy 112.420118 -388.044289) (xy 112.456869 -388.08104)
			(xy 112.487419 -388.123088) (xy 112.511015 -388.169398) (xy 112.527076 -388.218828) (xy 112.535206 -388.270163)
			(xy 112.535716 -388.29615) (xy 112.535206 -388.322137) (xy 112.527076 -388.373472) (xy 112.511015 -388.422902)
			(xy 112.487419 -388.469212) (xy 112.456869 -388.51126) (xy 112.420118 -388.548011) (xy 112.37807 -388.578561)
			(xy 112.33176 -388.602157) (xy 112.28233 -388.618218) (xy 112.230995 -388.626348) (xy 112.179021 -388.626348)
			(xy 112.127686 -388.618218) (xy 112.078256 -388.602157) (xy 112.031946 -388.578561) (xy 111.989898 -388.548011)
			(xy 111.953147 -388.51126) (xy 111.922597 -388.469212) (xy 111.899001 -388.422902) (xy 111.88294 -388.373472)
			(xy 111.87481 -388.322137) (xy 111.671923 -388.322137) (xy 111.671861 -388.32556) (xy 111.663741 -388.380736)
			(xy 111.647673 -388.434143) (xy 111.624001 -388.48464) (xy 111.593228 -388.531153) (xy 111.556011 -388.57269)
			(xy 111.513143 -388.608365) (xy 111.465537 -388.637419) (xy 111.414208 -388.659231) (xy 111.360251 -388.673337)
			(xy 111.304814 -388.679437) (xy 111.24908 -388.6774) (xy 111.194237 -388.66727) (xy 111.141453 -388.649263)
			(xy 111.091853 -388.623762) (xy 111.046495 -388.591311) (xy 111.006346 -388.552602) (xy 110.97226 -388.508459)
			(xy 110.944964 -388.459824) (xy 110.925041 -388.407733) (xy 110.912915 -388.353296) (xy 110.908844 -388.297674)
			(xy 108.978404 -388.297674) (xy 108.997341 -388.341977) (xy 109.011009 -388.391505) (xy 109.017905 -388.442419)
			(xy 109.018324 -388.468108) (xy 109.017881 -388.495479) (xy 109.010061 -388.54966) (xy 108.994567 -388.602164)
			(xy 108.97172 -388.651911) (xy 108.941989 -388.697876) (xy 108.924344 -388.718806) (xy 108.918248 -388.725918)
			(xy 108.911898 -388.742936) (xy 108.911898 -388.82828) (xy 108.918248 -388.845298) (xy 108.924344 -388.85241)
			(xy 108.942008 -388.873322) (xy 108.971715 -388.919301) (xy 108.994546 -388.969053) (xy 109.010031 -389.021558)
			(xy 109.017853 -389.075738) (xy 109.018324 -389.103108) (xy 109.017838 -389.130359) (xy 109.010082 -389.184307)
			(xy 108.994727 -389.236602) (xy 108.974724 -389.2804) (xy 111.234982 -389.2804) (xy 111.235484 -389.248439)
			(xy 111.243495 -389.185021) (xy 111.259392 -389.123107) (xy 111.282924 -389.063674) (xy 111.313718 -389.007659)
			(xy 111.351291 -388.955944) (xy 111.395048 -388.909347) (xy 111.444301 -388.868602) (xy 111.498272 -388.834351)
			(xy 111.556111 -388.807134) (xy 111.616904 -388.787381) (xy 111.679694 -388.775403) (xy 111.74349 -388.77139)
			(xy 111.807286 -388.775403) (xy 111.870076 -388.787381) (xy 111.930869 -388.807134) (xy 111.988708 -388.834351)
			(xy 112.042679 -388.868602) (xy 112.091932 -388.909347) (xy 112.135689 -388.955944) (xy 112.173262 -389.007659)
			(xy 112.204056 -389.063674) (xy 112.227588 -389.123107) (xy 112.243485 -389.185021) (xy 112.251496 -389.248439)
			(xy 112.251998 -389.2804) (xy 112.251432 -389.314517) (xy 112.242305 -389.382137) (xy 112.224215 -389.44793)
			(xy 112.211358 -389.479536) (xy 112.206786 -389.490204) (xy 112.207802 -389.512556) (xy 112.2553 -389.60298)
			(xy 112.273334 -389.616442) (xy 112.28451 -389.618728) (xy 112.315147 -389.625504) (xy 112.37435 -389.646287)
			(xy 112.430159 -389.674963) (xy 112.481528 -389.710992) (xy 112.527495 -389.753701) (xy 112.567197 -389.802287)
			(xy 112.599891 -389.855841) (xy 112.624963 -389.913359) (xy 112.641944 -389.973763) (xy 112.650515 -390.03592)
			(xy 112.651032 -390.067292) (xy 112.650461 -390.100584) (xy 112.641788 -390.160002) (xy 114.185204 -390.160002)
			(xy 114.189164 -390.110948) (xy 114.200941 -390.063164) (xy 114.220232 -390.017888) (xy 114.246535 -389.976292)
			(xy 114.27917 -389.939455) (xy 114.317291 -389.90833) (xy 114.359912 -389.883723) (xy 114.405928 -389.866271)
			(xy 114.454147 -389.856427) (xy 114.503322 -389.854446) (xy 114.552177 -389.860378) (xy 114.599448 -389.87407)
			(xy 114.64391 -389.895168) (xy 114.684413 -389.923124) (xy 114.719906 -389.957216) (xy 114.749471 -389.99656)
			(xy 114.772342 -390.040137) (xy 114.787926 -390.086818) (xy 114.795821 -390.135395) (xy 114.796316 -390.160002)
			(xy 115.385354 -390.160002) (xy 115.389314 -390.110948) (xy 115.401091 -390.063164) (xy 115.420382 -390.017888)
			(xy 115.446685 -389.976292) (xy 115.47932 -389.939455) (xy 115.517441 -389.90833) (xy 115.560062 -389.883723)
			(xy 115.606078 -389.866271) (xy 115.654297 -389.856427) (xy 115.703472 -389.854446) (xy 115.752327 -389.860378)
			(xy 115.799598 -389.87407) (xy 115.84406 -389.895168) (xy 115.884563 -389.923124) (xy 115.920056 -389.957216)
			(xy 115.949621 -389.99656) (xy 115.972492 -390.040137) (xy 115.988076 -390.086818) (xy 115.995971 -390.135395)
			(xy 115.996466 -390.160002) (xy 116.585504 -390.160002) (xy 116.589464 -390.110948) (xy 116.601241 -390.063164)
			(xy 116.620532 -390.017888) (xy 116.646835 -389.976292) (xy 116.67947 -389.939455) (xy 116.717591 -389.90833)
			(xy 116.760212 -389.883723) (xy 116.806228 -389.866271) (xy 116.854447 -389.856427) (xy 116.903622 -389.854446)
			(xy 116.952477 -389.860378) (xy 116.999748 -389.87407) (xy 117.04421 -389.895168) (xy 117.084713 -389.923124)
			(xy 117.120206 -389.957216) (xy 117.149771 -389.99656) (xy 117.172642 -390.040137) (xy 117.188226 -390.086818)
			(xy 117.196121 -390.135395) (xy 117.196616 -390.160002) (xy 117.7854 -390.160002) (xy 117.78936 -390.110948)
			(xy 117.801137 -390.063164) (xy 117.820428 -390.017888) (xy 117.846731 -389.976292) (xy 117.879366 -389.939455)
			(xy 117.917487 -389.90833) (xy 117.960108 -389.883723) (xy 118.006124 -389.866271) (xy 118.054343 -389.856427)
			(xy 118.103518 -389.854446) (xy 118.152373 -389.860378) (xy 118.199644 -389.87407) (xy 118.244106 -389.895168)
			(xy 118.284609 -389.923124) (xy 118.320102 -389.957216) (xy 118.349667 -389.99656) (xy 118.372538 -390.040137)
			(xy 118.388122 -390.086818) (xy 118.396017 -390.135395) (xy 118.396512 -390.160002) (xy 118.98555 -390.160002)
			(xy 118.98951 -390.110948) (xy 119.001287 -390.063164) (xy 119.020578 -390.017888) (xy 119.046881 -389.976292)
			(xy 119.079516 -389.939455) (xy 119.117637 -389.90833) (xy 119.160258 -389.883723) (xy 119.206274 -389.866271)
			(xy 119.254493 -389.856427) (xy 119.303668 -389.854446) (xy 119.352523 -389.860378) (xy 119.399794 -389.87407)
			(xy 119.444256 -389.895168) (xy 119.484759 -389.923124) (xy 119.520252 -389.957216) (xy 119.549817 -389.99656)
			(xy 119.572688 -390.040137) (xy 119.588272 -390.086818) (xy 119.596167 -390.135395) (xy 119.596662 -390.160002)
			(xy 120.185446 -390.160002) (xy 120.189406 -390.110948) (xy 120.201183 -390.063164) (xy 120.220474 -390.017888)
			(xy 120.246777 -389.976292) (xy 120.279412 -389.939455) (xy 120.317533 -389.90833) (xy 120.360154 -389.883723)
			(xy 120.40617 -389.866271) (xy 120.454389 -389.856427) (xy 120.503564 -389.854446) (xy 120.552419 -389.860378)
			(xy 120.59969 -389.87407) (xy 120.644152 -389.895168) (xy 120.684655 -389.923124) (xy 120.720148 -389.957216)
			(xy 120.749713 -389.99656) (xy 120.772584 -390.040137) (xy 120.788168 -390.086818) (xy 120.796063 -390.135395)
			(xy 120.796558 -390.160002) (xy 121.385342 -390.160002) (xy 121.389302 -390.110948) (xy 121.401079 -390.063164)
			(xy 121.42037 -390.017888) (xy 121.446673 -389.976292) (xy 121.479308 -389.939455) (xy 121.517429 -389.90833)
			(xy 121.56005 -389.883723) (xy 121.606066 -389.866271) (xy 121.654285 -389.856427) (xy 121.70346 -389.854446)
			(xy 121.752315 -389.860378) (xy 121.799586 -389.87407) (xy 121.844048 -389.895168) (xy 121.884551 -389.923124)
			(xy 121.920044 -389.957216) (xy 121.949609 -389.99656) (xy 121.97248 -390.040137) (xy 121.988064 -390.086818)
			(xy 121.995959 -390.135395) (xy 121.996454 -390.160002) (xy 122.585492 -390.160002) (xy 122.589452 -390.110948)
			(xy 122.601229 -390.063164) (xy 122.62052 -390.017888) (xy 122.646823 -389.976292) (xy 122.679458 -389.939455)
			(xy 122.717579 -389.90833) (xy 122.7602 -389.883723) (xy 122.806216 -389.866271) (xy 122.854435 -389.856427)
			(xy 122.90361 -389.854446) (xy 122.952465 -389.860378) (xy 122.999736 -389.87407) (xy 123.044198 -389.895168)
			(xy 123.084701 -389.923124) (xy 123.120194 -389.957216) (xy 123.149759 -389.99656) (xy 123.17263 -390.040137)
			(xy 123.188214 -390.086818) (xy 123.196109 -390.135395) (xy 123.196604 -390.160002) (xy 123.785388 -390.160002)
			(xy 123.789348 -390.110948) (xy 123.801125 -390.063164) (xy 123.820416 -390.017888) (xy 123.846719 -389.976292)
			(xy 123.879354 -389.939455) (xy 123.917475 -389.90833) (xy 123.960096 -389.883723) (xy 124.006112 -389.866271)
			(xy 124.054331 -389.856427) (xy 124.103506 -389.854446) (xy 124.152361 -389.860378) (xy 124.199632 -389.87407)
			(xy 124.244094 -389.895168) (xy 124.284597 -389.923124) (xy 124.32009 -389.957216) (xy 124.349655 -389.99656)
			(xy 124.372526 -390.040137) (xy 124.38811 -390.086818) (xy 124.396005 -390.135395) (xy 124.3965 -390.160002)
			(xy 124.985538 -390.160002) (xy 124.989498 -390.110948) (xy 125.001275 -390.063164) (xy 125.020566 -390.017888)
			(xy 125.046869 -389.976292) (xy 125.079504 -389.939455) (xy 125.117625 -389.90833) (xy 125.160246 -389.883723)
			(xy 125.206262 -389.866271) (xy 125.254481 -389.856427) (xy 125.303656 -389.854446) (xy 125.352511 -389.860378)
			(xy 125.399782 -389.87407) (xy 125.444244 -389.895168) (xy 125.484747 -389.923124) (xy 125.52024 -389.957216)
			(xy 125.549805 -389.99656) (xy 125.572676 -390.040137) (xy 125.58826 -390.086818) (xy 125.596155 -390.135395)
			(xy 125.59665 -390.160002) (xy 126.185434 -390.160002) (xy 126.189394 -390.110948) (xy 126.201171 -390.063164)
			(xy 126.220462 -390.017888) (xy 126.246765 -389.976292) (xy 126.2794 -389.939455) (xy 126.317521 -389.90833)
			(xy 126.360142 -389.883723) (xy 126.406158 -389.866271) (xy 126.454377 -389.856427) (xy 126.503552 -389.854446)
			(xy 126.552407 -389.860378) (xy 126.599678 -389.87407) (xy 126.64414 -389.895168) (xy 126.684643 -389.923124)
			(xy 126.720136 -389.957216) (xy 126.749701 -389.99656) (xy 126.772572 -390.040137) (xy 126.788156 -390.086818)
			(xy 126.796051 -390.135395) (xy 126.796546 -390.160002) (xy 127.38533 -390.160002) (xy 127.38929 -390.110948)
			(xy 127.401067 -390.063164) (xy 127.420358 -390.017888) (xy 127.446661 -389.976292) (xy 127.479296 -389.939455)
			(xy 127.517417 -389.90833) (xy 127.560038 -389.883723) (xy 127.606054 -389.866271) (xy 127.654273 -389.856427)
			(xy 127.703448 -389.854446) (xy 127.752303 -389.860378) (xy 127.799574 -389.87407) (xy 127.844036 -389.895168)
			(xy 127.884539 -389.923124) (xy 127.920032 -389.957216) (xy 127.949597 -389.99656) (xy 127.972468 -390.040137)
			(xy 127.988052 -390.086818) (xy 127.995947 -390.135395) (xy 127.996442 -390.160002) (xy 128.58548 -390.160002)
			(xy 128.58944 -390.110948) (xy 128.601217 -390.063164) (xy 128.620508 -390.017888) (xy 128.646811 -389.976292)
			(xy 128.679446 -389.939455) (xy 128.717567 -389.90833) (xy 128.760188 -389.883723) (xy 128.806204 -389.866271)
			(xy 128.854423 -389.856427) (xy 128.903598 -389.854446) (xy 128.952453 -389.860378) (xy 128.999724 -389.87407)
			(xy 129.044186 -389.895168) (xy 129.084689 -389.923124) (xy 129.120182 -389.957216) (xy 129.149747 -389.99656)
			(xy 129.172618 -390.040137) (xy 129.188202 -390.086818) (xy 129.196097 -390.135395) (xy 129.196592 -390.160002)
			(xy 129.785376 -390.160002) (xy 129.789336 -390.110948) (xy 129.801113 -390.063164) (xy 129.820404 -390.017888)
			(xy 129.846707 -389.976292) (xy 129.879342 -389.939455) (xy 129.917463 -389.90833) (xy 129.960084 -389.883723)
			(xy 130.0061 -389.866271) (xy 130.054319 -389.856427) (xy 130.103494 -389.854446) (xy 130.152349 -389.860378)
			(xy 130.19962 -389.87407) (xy 130.244082 -389.895168) (xy 130.284585 -389.923124) (xy 130.320078 -389.957216)
			(xy 130.349643 -389.99656) (xy 130.372514 -390.040137) (xy 130.388098 -390.086818) (xy 130.395993 -390.135395)
			(xy 130.396488 -390.160002) (xy 130.985526 -390.160002) (xy 130.989486 -390.110948) (xy 131.001263 -390.063164)
			(xy 131.020554 -390.017888) (xy 131.046857 -389.976292) (xy 131.079492 -389.939455) (xy 131.117613 -389.90833)
			(xy 131.160234 -389.883723) (xy 131.20625 -389.866271) (xy 131.254469 -389.856427) (xy 131.303644 -389.854446)
			(xy 131.352499 -389.860378) (xy 131.39977 -389.87407) (xy 131.444232 -389.895168) (xy 131.484735 -389.923124)
			(xy 131.520228 -389.957216) (xy 131.549793 -389.99656) (xy 131.572664 -390.040137) (xy 131.588248 -390.086818)
			(xy 131.596143 -390.135395) (xy 131.596638 -390.160002) (xy 132.185422 -390.160002) (xy 132.189382 -390.110948)
			(xy 132.201159 -390.063164) (xy 132.22045 -390.017888) (xy 132.246753 -389.976292) (xy 132.279388 -389.939455)
			(xy 132.317509 -389.90833) (xy 132.36013 -389.883723) (xy 132.406146 -389.866271) (xy 132.454365 -389.856427)
			(xy 132.50354 -389.854446) (xy 132.552395 -389.860378) (xy 132.599666 -389.87407) (xy 132.644128 -389.895168)
			(xy 132.684631 -389.923124) (xy 132.720124 -389.957216) (xy 132.749689 -389.99656) (xy 132.77256 -390.040137)
			(xy 132.788144 -390.086818) (xy 132.796039 -390.135395) (xy 132.796534 -390.160002) (xy 132.796039 -390.184609)
			(xy 132.795815 -390.185989) (xy 133.515102 -390.185989) (xy 133.515102 -390.134015) (xy 133.523232 -390.08268)
			(xy 133.539293 -390.03325) (xy 133.562889 -389.98694) (xy 133.593439 -389.944892) (xy 133.63019 -389.908141)
			(xy 133.672238 -389.877591) (xy 133.718548 -389.853995) (xy 133.767978 -389.837934) (xy 133.819313 -389.829804)
			(xy 133.871287 -389.829804) (xy 133.922622 -389.837934) (xy 133.972052 -389.853995) (xy 134.018362 -389.877591)
			(xy 134.06041 -389.908141) (xy 134.097161 -389.944892) (xy 134.127711 -389.98694) (xy 134.151307 -390.03325)
			(xy 134.167368 -390.08268) (xy 134.175498 -390.134015) (xy 134.176008 -390.160002) (xy 134.175498 -390.185989)
			(xy 134.167368 -390.237324) (xy 134.151307 -390.286754) (xy 134.127711 -390.333064) (xy 134.097161 -390.375112)
			(xy 134.06041 -390.411863) (xy 134.018362 -390.442413) (xy 133.972052 -390.466009) (xy 133.922622 -390.48207)
			(xy 133.871287 -390.4902) (xy 133.819313 -390.4902) (xy 133.767978 -390.48207) (xy 133.718548 -390.466009)
			(xy 133.672238 -390.442413) (xy 133.63019 -390.411863) (xy 133.593439 -390.375112) (xy 133.562889 -390.333064)
			(xy 133.539293 -390.286754) (xy 133.523232 -390.237324) (xy 133.515102 -390.185989) (xy 132.795815 -390.185989)
			(xy 132.788144 -390.233186) (xy 132.77256 -390.279867) (xy 132.749689 -390.323444) (xy 132.720124 -390.362788)
			(xy 132.684631 -390.39688) (xy 132.644128 -390.424836) (xy 132.599666 -390.445934) (xy 132.552395 -390.459626)
			(xy 132.50354 -390.465558) (xy 132.454365 -390.463577) (xy 132.406146 -390.453733) (xy 132.36013 -390.436281)
			(xy 132.317509 -390.411674) (xy 132.279388 -390.380549) (xy 132.246753 -390.343712) (xy 132.22045 -390.302116)
			(xy 132.201159 -390.25684) (xy 132.189382 -390.209056) (xy 132.185422 -390.160002) (xy 131.596638 -390.160002)
			(xy 131.596143 -390.184609) (xy 131.588248 -390.233186) (xy 131.572664 -390.279867) (xy 131.549793 -390.323444)
			(xy 131.520228 -390.362788) (xy 131.484735 -390.39688) (xy 131.444232 -390.424836) (xy 131.39977 -390.445934)
			(xy 131.352499 -390.459626) (xy 131.303644 -390.465558) (xy 131.254469 -390.463577) (xy 131.20625 -390.453733)
			(xy 131.160234 -390.436281) (xy 131.117613 -390.411674) (xy 131.079492 -390.380549) (xy 131.046857 -390.343712)
			(xy 131.020554 -390.302116) (xy 131.001263 -390.25684) (xy 130.989486 -390.209056) (xy 130.985526 -390.160002)
			(xy 130.396488 -390.160002) (xy 130.395993 -390.184609) (xy 130.388098 -390.233186) (xy 130.372514 -390.279867)
			(xy 130.349643 -390.323444) (xy 130.320078 -390.362788) (xy 130.284585 -390.39688) (xy 130.244082 -390.424836)
			(xy 130.19962 -390.445934) (xy 130.152349 -390.459626) (xy 130.103494 -390.465558) (xy 130.054319 -390.463577)
			(xy 130.0061 -390.453733) (xy 129.960084 -390.436281) (xy 129.917463 -390.411674) (xy 129.879342 -390.380549)
			(xy 129.846707 -390.343712) (xy 129.820404 -390.302116) (xy 129.801113 -390.25684) (xy 129.789336 -390.209056)
			(xy 129.785376 -390.160002) (xy 129.196592 -390.160002) (xy 129.196097 -390.184609) (xy 129.188202 -390.233186)
			(xy 129.172618 -390.279867) (xy 129.149747 -390.323444) (xy 129.120182 -390.362788) (xy 129.084689 -390.39688)
			(xy 129.044186 -390.424836) (xy 128.999724 -390.445934) (xy 128.952453 -390.459626) (xy 128.903598 -390.465558)
			(xy 128.854423 -390.463577) (xy 128.806204 -390.453733) (xy 128.760188 -390.436281) (xy 128.717567 -390.411674)
			(xy 128.679446 -390.380549) (xy 128.646811 -390.343712) (xy 128.620508 -390.302116) (xy 128.601217 -390.25684)
			(xy 128.58944 -390.209056) (xy 128.58548 -390.160002) (xy 127.996442 -390.160002) (xy 127.995947 -390.184609)
			(xy 127.988052 -390.233186) (xy 127.972468 -390.279867) (xy 127.949597 -390.323444) (xy 127.920032 -390.362788)
			(xy 127.884539 -390.39688) (xy 127.844036 -390.424836) (xy 127.799574 -390.445934) (xy 127.752303 -390.459626)
			(xy 127.703448 -390.465558) (xy 127.654273 -390.463577) (xy 127.606054 -390.453733) (xy 127.560038 -390.436281)
			(xy 127.517417 -390.411674) (xy 127.479296 -390.380549) (xy 127.446661 -390.343712) (xy 127.420358 -390.302116)
			(xy 127.401067 -390.25684) (xy 127.38929 -390.209056) (xy 127.38533 -390.160002) (xy 126.796546 -390.160002)
			(xy 126.796051 -390.184609) (xy 126.788156 -390.233186) (xy 126.772572 -390.279867) (xy 126.749701 -390.323444)
			(xy 126.720136 -390.362788) (xy 126.684643 -390.39688) (xy 126.64414 -390.424836) (xy 126.599678 -390.445934)
			(xy 126.552407 -390.459626) (xy 126.503552 -390.465558) (xy 126.454377 -390.463577) (xy 126.406158 -390.453733)
			(xy 126.360142 -390.436281) (xy 126.317521 -390.411674) (xy 126.2794 -390.380549) (xy 126.246765 -390.343712)
			(xy 126.220462 -390.302116) (xy 126.201171 -390.25684) (xy 126.189394 -390.209056) (xy 126.185434 -390.160002)
			(xy 125.59665 -390.160002) (xy 125.596155 -390.184609) (xy 125.58826 -390.233186) (xy 125.572676 -390.279867)
			(xy 125.549805 -390.323444) (xy 125.52024 -390.362788) (xy 125.484747 -390.39688) (xy 125.444244 -390.424836)
			(xy 125.399782 -390.445934) (xy 125.352511 -390.459626) (xy 125.303656 -390.465558) (xy 125.254481 -390.463577)
			(xy 125.206262 -390.453733) (xy 125.160246 -390.436281) (xy 125.117625 -390.411674) (xy 125.079504 -390.380549)
			(xy 125.046869 -390.343712) (xy 125.020566 -390.302116) (xy 125.001275 -390.25684) (xy 124.989498 -390.209056)
			(xy 124.985538 -390.160002) (xy 124.3965 -390.160002) (xy 124.396005 -390.184609) (xy 124.38811 -390.233186)
			(xy 124.372526 -390.279867) (xy 124.349655 -390.323444) (xy 124.32009 -390.362788) (xy 124.284597 -390.39688)
			(xy 124.244094 -390.424836) (xy 124.199632 -390.445934) (xy 124.152361 -390.459626) (xy 124.103506 -390.465558)
			(xy 124.054331 -390.463577) (xy 124.006112 -390.453733) (xy 123.960096 -390.436281) (xy 123.917475 -390.411674)
			(xy 123.879354 -390.380549) (xy 123.846719 -390.343712) (xy 123.820416 -390.302116) (xy 123.801125 -390.25684)
			(xy 123.789348 -390.209056) (xy 123.785388 -390.160002) (xy 123.196604 -390.160002) (xy 123.196109 -390.184609)
			(xy 123.188214 -390.233186) (xy 123.17263 -390.279867) (xy 123.149759 -390.323444) (xy 123.120194 -390.362788)
			(xy 123.084701 -390.39688) (xy 123.044198 -390.424836) (xy 122.999736 -390.445934) (xy 122.952465 -390.459626)
			(xy 122.90361 -390.465558) (xy 122.854435 -390.463577) (xy 122.806216 -390.453733) (xy 122.7602 -390.436281)
			(xy 122.717579 -390.411674) (xy 122.679458 -390.380549) (xy 122.646823 -390.343712) (xy 122.62052 -390.302116)
			(xy 122.601229 -390.25684) (xy 122.589452 -390.209056) (xy 122.585492 -390.160002) (xy 121.996454 -390.160002)
			(xy 121.995959 -390.184609) (xy 121.988064 -390.233186) (xy 121.97248 -390.279867) (xy 121.949609 -390.323444)
			(xy 121.920044 -390.362788) (xy 121.884551 -390.39688) (xy 121.844048 -390.424836) (xy 121.799586 -390.445934)
			(xy 121.752315 -390.459626) (xy 121.70346 -390.465558) (xy 121.654285 -390.463577) (xy 121.606066 -390.453733)
			(xy 121.56005 -390.436281) (xy 121.517429 -390.411674) (xy 121.479308 -390.380549) (xy 121.446673 -390.343712)
			(xy 121.42037 -390.302116) (xy 121.401079 -390.25684) (xy 121.389302 -390.209056) (xy 121.385342 -390.160002)
			(xy 120.796558 -390.160002) (xy 120.796063 -390.184609) (xy 120.788168 -390.233186) (xy 120.772584 -390.279867)
			(xy 120.749713 -390.323444) (xy 120.720148 -390.362788) (xy 120.684655 -390.39688) (xy 120.644152 -390.424836)
			(xy 120.59969 -390.445934) (xy 120.552419 -390.459626) (xy 120.503564 -390.465558) (xy 120.454389 -390.463577)
			(xy 120.40617 -390.453733) (xy 120.360154 -390.436281) (xy 120.317533 -390.411674) (xy 120.279412 -390.380549)
			(xy 120.246777 -390.343712) (xy 120.220474 -390.302116) (xy 120.201183 -390.25684) (xy 120.189406 -390.209056)
			(xy 120.185446 -390.160002) (xy 119.596662 -390.160002) (xy 119.596167 -390.184609) (xy 119.588272 -390.233186)
			(xy 119.572688 -390.279867) (xy 119.549817 -390.323444) (xy 119.520252 -390.362788) (xy 119.484759 -390.39688)
			(xy 119.444256 -390.424836) (xy 119.399794 -390.445934) (xy 119.352523 -390.459626) (xy 119.303668 -390.465558)
			(xy 119.254493 -390.463577) (xy 119.206274 -390.453733) (xy 119.160258 -390.436281) (xy 119.117637 -390.411674)
			(xy 119.079516 -390.380549) (xy 119.046881 -390.343712) (xy 119.020578 -390.302116) (xy 119.001287 -390.25684)
			(xy 118.98951 -390.209056) (xy 118.98555 -390.160002) (xy 118.396512 -390.160002) (xy 118.396017 -390.184609)
			(xy 118.388122 -390.233186) (xy 118.372538 -390.279867) (xy 118.349667 -390.323444) (xy 118.320102 -390.362788)
			(xy 118.284609 -390.39688) (xy 118.244106 -390.424836) (xy 118.199644 -390.445934) (xy 118.152373 -390.459626)
			(xy 118.103518 -390.465558) (xy 118.054343 -390.463577) (xy 118.006124 -390.453733) (xy 117.960108 -390.436281)
			(xy 117.917487 -390.411674) (xy 117.879366 -390.380549) (xy 117.846731 -390.343712) (xy 117.820428 -390.302116)
			(xy 117.801137 -390.25684) (xy 117.78936 -390.209056) (xy 117.7854 -390.160002) (xy 117.196616 -390.160002)
			(xy 117.196121 -390.184609) (xy 117.188226 -390.233186) (xy 117.172642 -390.279867) (xy 117.149771 -390.323444)
			(xy 117.120206 -390.362788) (xy 117.084713 -390.39688) (xy 117.04421 -390.424836) (xy 116.999748 -390.445934)
			(xy 116.952477 -390.459626) (xy 116.903622 -390.465558) (xy 116.854447 -390.463577) (xy 116.806228 -390.453733)
			(xy 116.760212 -390.436281) (xy 116.717591 -390.411674) (xy 116.67947 -390.380549) (xy 116.646835 -390.343712)
			(xy 116.620532 -390.302116) (xy 116.601241 -390.25684) (xy 116.589464 -390.209056) (xy 116.585504 -390.160002)
			(xy 115.996466 -390.160002) (xy 115.995971 -390.184609) (xy 115.988076 -390.233186) (xy 115.972492 -390.279867)
			(xy 115.949621 -390.323444) (xy 115.920056 -390.362788) (xy 115.884563 -390.39688) (xy 115.84406 -390.424836)
			(xy 115.799598 -390.445934) (xy 115.752327 -390.459626) (xy 115.703472 -390.465558) (xy 115.654297 -390.463577)
			(xy 115.606078 -390.453733) (xy 115.560062 -390.436281) (xy 115.517441 -390.411674) (xy 115.47932 -390.380549)
			(xy 115.446685 -390.343712) (xy 115.420382 -390.302116) (xy 115.401091 -390.25684) (xy 115.389314 -390.209056)
			(xy 115.385354 -390.160002) (xy 114.796316 -390.160002) (xy 114.795821 -390.184609) (xy 114.787926 -390.233186)
			(xy 114.772342 -390.279867) (xy 114.749471 -390.323444) (xy 114.719906 -390.362788) (xy 114.684413 -390.39688)
			(xy 114.64391 -390.424836) (xy 114.599448 -390.445934) (xy 114.552177 -390.459626) (xy 114.503322 -390.465558)
			(xy 114.454147 -390.463577) (xy 114.405928 -390.453733) (xy 114.359912 -390.436281) (xy 114.317291 -390.411674)
			(xy 114.27917 -390.380549) (xy 114.246535 -390.343712) (xy 114.220232 -390.302116) (xy 114.200941 -390.25684)
			(xy 114.189164 -390.209056) (xy 114.185204 -390.160002) (xy 112.641788 -390.160002) (xy 112.640844 -390.166468)
			(xy 112.621769 -390.230259) (xy 112.59364 -390.290608) (xy 112.575848 -390.318752) (xy 112.570803 -390.327277)
			(xy 112.566985 -390.346693) (xy 112.570798 -390.366111) (xy 112.575848 -390.374632) (xy 112.593623 -390.402783)
			(xy 112.621716 -390.463142) (xy 112.640786 -390.526929) (xy 112.650429 -390.592804) (xy 112.651032 -390.626092)
			(xy 112.650587 -390.655392) (xy 112.643141 -390.713515) (xy 112.628318 -390.770208) (xy 112.617758 -390.797542)
			(xy 112.613694 -390.807194) (xy 112.614202 -390.82726) (xy 112.652048 -390.913112) (xy 112.666526 -390.927082)
			(xy 112.676432 -390.930638) (xy 112.699801 -390.939818) (xy 112.743646 -390.964279) (xy 112.783291 -390.995085)
			(xy 112.817825 -391.031528) (xy 112.846454 -391.072773) (xy 112.868522 -391.11787) (xy 112.88352 -391.165784)
			(xy 112.891105 -391.215415) (xy 112.89157 -391.240518) (xy 112.89106 -391.266505) (xy 112.88293 -391.31784)
			(xy 112.866869 -391.36727) (xy 112.843273 -391.41358) (xy 112.812723 -391.455628) (xy 112.775972 -391.492379)
			(xy 112.733924 -391.522929) (xy 112.687614 -391.546525) (xy 112.638184 -391.562586) (xy 112.586849 -391.570716)
			(xy 112.534875 -391.570716) (xy 112.48354 -391.562586) (xy 112.43411 -391.546525) (xy 112.3878 -391.522929)
			(xy 112.345752 -391.492379) (xy 112.309001 -391.455628) (xy 112.278451 -391.41358) (xy 112.254855 -391.36727)
			(xy 112.238794 -391.31784) (xy 112.230664 -391.266505) (xy 112.230154 -391.240518) (xy 112.230256 -391.229307)
			(xy 112.231782 -391.206936) (xy 112.233202 -391.195814) (xy 112.234726 -391.1854) (xy 112.229392 -391.165842)
			(xy 112.171734 -391.091928) (xy 112.153954 -391.082276) (xy 112.14354 -391.081006) (xy 112.113355 -391.077184)
			(xy 112.054279 -391.062624) (xy 111.997654 -391.040363) (xy 111.944478 -391.010794) (xy 111.895691 -390.974439)
			(xy 111.852151 -390.931939) (xy 111.814628 -390.884044) (xy 111.783783 -390.831598) (xy 111.76016 -390.775528)
			(xy 111.744177 -390.716821) (xy 111.736115 -390.656514) (xy 111.735616 -390.626092) (xy 111.736172 -390.5928)
			(xy 111.745792 -390.526915) (xy 111.764871 -390.463123) (xy 111.793006 -390.402776) (xy 111.8108 -390.374632)
			(xy 111.815862 -390.366115) (xy 111.81968 -390.346693) (xy 111.815857 -390.327272) (xy 111.8108 -390.318752)
			(xy 111.793024 -390.290601) (xy 111.76493 -390.230242) (xy 111.745861 -390.166455) (xy 111.736218 -390.10058)
			(xy 111.735616 -390.067292) (xy 111.735953 -390.042018) (xy 111.741526 -389.991777) (xy 111.752604 -389.942457)
			(xy 111.760508 -389.918448) (xy 111.764318 -389.907272) (xy 111.761778 -389.88492) (xy 111.708184 -389.798306)
			(xy 111.689134 -389.786114) (xy 111.677704 -389.78459) (xy 111.644735 -389.779733) (xy 111.580345 -389.762563)
			(xy 111.51875 -389.737128) (xy 111.461006 -389.703863) (xy 111.408102 -389.66334) (xy 111.360947 -389.616253)
			(xy 111.320347 -389.563408) (xy 111.286999 -389.505712) (xy 111.261474 -389.444154) (xy 111.244211 -389.379789)
			(xy 111.235505 -389.31372) (xy 111.234982 -389.2804) (xy 108.974724 -389.2804) (xy 108.972085 -389.286179)
			(xy 108.942619 -389.332029) (xy 108.906928 -389.37322) (xy 108.865737 -389.408911) (xy 108.819887 -389.438377)
			(xy 108.77031 -389.461019) (xy 108.718015 -389.476374) (xy 108.664067 -389.48413) (xy 108.609565 -389.48413)
			(xy 108.555617 -389.476374) (xy 108.503322 -389.461019) (xy 108.453745 -389.438377) (xy 108.407895 -389.408911)
			(xy 108.366704 -389.37322) (xy 108.331013 -389.332029) (xy 108.301547 -389.286179) (xy 108.278905 -389.236602)
			(xy 108.26355 -389.184307) (xy 108.255794 -389.130359) (xy 108.255308 -389.103108) (xy 108.255777 -389.075738)
			(xy 108.263594 -389.021559) (xy 108.279082 -388.969056) (xy 108.301923 -388.919309) (xy 108.331647 -388.873342)
			(xy 108.349288 -388.85241) (xy 108.355384 -388.845298) (xy 108.361734 -388.82828) (xy 108.361734 -388.742936)
			(xy 108.355384 -388.725918) (xy 108.349288 -388.718806) (xy 108.331636 -388.697884) (xy 108.301927 -388.651908)
			(xy 108.279094 -388.602158) (xy 108.263605 -388.549655) (xy 108.25578 -388.495478) (xy 108.255308 -388.468108)
			(xy 108.255595 -388.446584) (xy 108.260432 -388.403809) (xy 108.26496 -388.382764) (xy 108.266992 -388.37362)
			(xy 108.264706 -388.355586) (xy 108.22432 -388.280148) (xy 108.210858 -388.26821) (xy 108.201968 -388.264908)
			(xy 108.173445 -388.25354) (xy 108.119099 -388.224958) (xy 108.068592 -388.190039) (xy 108.022659 -388.14929)
			(xy 107.981968 -388.103306) (xy 107.947112 -388.052755) (xy 107.918598 -387.998374) (xy 107.896843 -387.940954)
			(xy 107.882162 -387.881332) (xy 107.874769 -387.820376) (xy 107.874308 -387.789674) (xy 105.248368 -387.789674)
			(xy 105.248456 -387.7945) (xy 105.247947 -387.822386) (xy 105.239827 -387.877562) (xy 105.223759 -387.930969)
			(xy 105.200087 -387.981466) (xy 105.169314 -388.027979) (xy 105.132097 -388.069516) (xy 105.089229 -388.105191)
			(xy 105.041623 -388.134245) (xy 104.990294 -388.156057) (xy 104.936337 -388.170163) (xy 104.8809 -388.176263)
			(xy 104.825166 -388.174226) (xy 104.770323 -388.164096) (xy 104.717539 -388.146089) (xy 104.667939 -388.120588)
			(xy 104.622581 -388.088137) (xy 104.582432 -388.049428) (xy 104.548346 -388.005285) (xy 104.52105 -387.95665)
			(xy 104.501127 -387.904559) (xy 104.489001 -387.850122) (xy 104.48493 -387.7945) (xy 98.492498 -387.7945)
			(xy 98.481671 -387.836374) (xy 98.460173 -387.890252) (xy 98.432041 -387.940982) (xy 98.397727 -387.987753)
			(xy 98.35778 -388.029814) (xy 98.335592 -388.0485) (xy 98.32848 -388.054088) (xy 98.319336 -388.069328)
			(xy 98.304096 -388.152132) (xy 98.30689 -388.169404) (xy 98.311462 -388.177532) (xy 98.324039 -388.200718)
			(xy 98.341912 -388.25034) (xy 98.348735 -388.289292) (xy 99.89693 -388.289292) (xy 99.89742 -388.259324)
			(xy 99.905243 -388.199902) (xy 99.920756 -388.142009) (xy 99.943692 -388.086636) (xy 99.973659 -388.03473)
			(xy 100.010146 -387.98718) (xy 100.052526 -387.9448) (xy 100.100076 -387.908313) (xy 100.151982 -387.878346)
			(xy 100.207355 -387.85541) (xy 100.265248 -387.839897) (xy 100.32467 -387.832074) (xy 100.384606 -387.832074)
			(xy 100.444028 -387.839897) (xy 100.501921 -387.85541) (xy 100.557294 -387.878346) (xy 100.6092 -387.908313)
			(xy 100.65675 -387.9448) (xy 100.69913 -387.98718) (xy 100.735617 -388.03473) (xy 100.765584 -388.086636)
			(xy 100.78852 -388.142009) (xy 100.804033 -388.199902) (xy 100.811856 -388.259324) (xy 100.812346 -388.289292)
			(xy 100.811783 -388.321116) (xy 100.802966 -388.384151) (xy 100.7855 -388.445356) (xy 100.759723 -388.503551)
			(xy 100.726132 -388.557614) (xy 100.706174 -388.582408) (xy 100.700332 -388.58952) (xy 100.694236 -388.607046)
			(xy 100.696776 -388.693152) (xy 100.703888 -388.71017) (xy 100.710238 -388.717028) (xy 100.722725 -388.730555)
			(xy 100.745739 -388.759292) (xy 100.756212 -388.774432) (xy 100.76434 -388.786116) (xy 100.789994 -388.798054)
			(xy 100.907596 -388.784846) (xy 100.929948 -388.767574) (xy 100.935028 -388.754366) (xy 100.94587 -388.72786)
			(xy 100.974353 -388.67818) (xy 101.009943 -388.633316) (xy 101.051839 -388.594275) (xy 101.099099 -388.561936)
			(xy 101.150663 -388.537025) (xy 101.205372 -388.520101) (xy 101.261995 -388.511545) (xy 101.290628 -388.511034)
			(xy 101.317999 -388.511475) (xy 101.37218 -388.519298) (xy 101.424683 -388.534792) (xy 101.47443 -388.55764)
			(xy 101.520395 -388.58737) (xy 101.541326 -388.605014) (xy 101.548438 -388.61111) (xy 101.565456 -388.61746)
			(xy 101.6508 -388.61746) (xy 101.667818 -388.61111) (xy 101.67493 -388.605014) (xy 101.695863 -388.587373)
			(xy 101.741831 -388.557649) (xy 101.791577 -388.534803) (xy 101.844079 -388.519307) (xy 101.898257 -388.511478)
			(xy 101.952999 -388.511478) (xy 102.007177 -388.519307) (xy 102.059679 -388.534803) (xy 102.109425 -388.557649)
			(xy 102.155393 -388.587373) (xy 102.176326 -388.605014) (xy 102.183438 -388.61111) (xy 102.200456 -388.61746)
			(xy 102.2858 -388.61746) (xy 102.302818 -388.61111) (xy 102.30993 -388.605014) (xy 102.330879 -388.587396)
			(xy 102.376847 -388.557681) (xy 102.42659 -388.534841) (xy 102.479087 -388.519345) (xy 102.53326 -388.511511)
			(xy 102.560628 -388.511034) (xy 102.587881 -388.511438) (xy 102.641832 -388.519198) (xy 102.694129 -388.534558)
			(xy 102.743708 -388.557203) (xy 102.78956 -388.586673) (xy 102.830751 -388.622369) (xy 102.866444 -388.663563)
			(xy 102.895911 -388.709417) (xy 102.918552 -388.758998) (xy 102.933908 -388.811296) (xy 102.941664 -388.865247)
			(xy 102.941664 -388.919753) (xy 102.933908 -388.973704) (xy 102.918552 -389.026002) (xy 102.895911 -389.075583)
			(xy 102.866444 -389.121437) (xy 102.830751 -389.162631) (xy 102.78956 -389.198327) (xy 102.743708 -389.227797)
			(xy 102.694129 -389.250442) (xy 102.641832 -389.265802) (xy 102.587881 -389.273562) (xy 102.560628 -389.27405)
			(xy 102.533258 -389.27358) (xy 102.479078 -389.265765) (xy 102.426575 -389.250277) (xy 102.376828 -389.227436)
			(xy 102.330861 -389.197712) (xy 102.30993 -389.18007) (xy 102.302818 -389.173974) (xy 102.2858 -389.167624)
			(xy 102.200456 -389.167624) (xy 102.183438 -389.173974) (xy 102.176326 -389.18007) (xy 102.155393 -389.197711)
			(xy 102.109425 -389.227435) (xy 102.059679 -389.250281) (xy 102.007177 -389.265777) (xy 101.952999 -389.273606)
			(xy 101.898257 -389.273606) (xy 101.844079 -389.265777) (xy 101.791577 -389.250281) (xy 101.741831 -389.227435)
			(xy 101.695863 -389.197711) (xy 101.67493 -389.18007) (xy 101.667818 -389.173974) (xy 101.6508 -389.167624)
			(xy 101.565456 -389.167624) (xy 101.548438 -389.173974) (xy 101.541326 -389.18007) (xy 101.520391 -389.197706)
			(xy 101.47442 -389.227419) (xy 101.424673 -389.250256) (xy 101.372173 -389.265748) (xy 101.317997 -389.273576)
			(xy 101.290628 -389.27405) (xy 101.262027 -389.27353) (xy 101.205464 -389.264999) (xy 101.150808 -389.248124)
			(xy 101.099281 -389.223283) (xy 101.052037 -389.191032) (xy 101.010135 -389.152092) (xy 100.991924 -389.130032)
			(xy 100.983288 -389.118856) (xy 100.956618 -389.10895) (xy 100.840286 -389.131302) (xy 100.819458 -389.150098)
			(xy 100.815394 -389.163814) (xy 100.805297 -389.19516) (xy 100.777325 -389.254779) (xy 100.741085 -389.309766)
			(xy 100.719636 -389.334756) (xy 100.713286 -389.341868) (xy 100.706682 -389.35914) (xy 100.706682 -389.445246)
			(xy 100.713286 -389.462518) (xy 100.719636 -389.46963) (xy 100.741215 -389.494865) (xy 100.777588 -389.550413)
			(xy 100.805554 -389.610632) (xy 100.824528 -389.67426) (xy 100.834111 -389.739962) (xy 100.834698 -389.77316)
			(xy 100.834179 -389.804762) (xy 100.825475 -389.867363) (xy 100.808228 -389.928168) (xy 100.782766 -389.986016)
			(xy 100.766626 -390.01319) (xy 100.762111 -390.021424) (xy 100.758677 -390.039866) (xy 100.762086 -390.058312)
			(xy 100.766626 -390.06653) (xy 100.782752 -390.09371) (xy 100.808179 -390.151567) (xy 100.825419 -390.212368)
			(xy 100.834146 -390.274961) (xy 100.834698 -390.30656) (xy 100.834154 -390.338174) (xy 100.825437 -390.400798)
			(xy 100.80819 -390.461628) (xy 100.78274 -390.519508) (xy 100.749573 -390.573339) (xy 100.709318 -390.622096)
			(xy 100.66274 -390.664854) (xy 100.610724 -390.7008) (xy 100.58273 -390.7155) (xy 100.573422 -390.720772)
			(xy 100.559907 -390.737327) (xy 100.554252 -390.757937) (xy 100.555298 -390.768586) (xy 100.557103 -390.781144)
			(xy 100.559009 -390.806445) (xy 100.559108 -390.819132) (xy 100.558598 -390.845119) (xy 100.550468 -390.896454)
			(xy 100.534407 -390.945884) (xy 100.510811 -390.992194) (xy 100.480261 -391.034242) (xy 100.44351 -391.070993)
			(xy 100.401462 -391.101543) (xy 100.355152 -391.125139) (xy 100.305722 -391.1412) (xy 100.254387 -391.14933)
			(xy 100.202413 -391.14933) (xy 100.151078 -391.1412) (xy 100.101648 -391.125139) (xy 100.055338 -391.101543)
			(xy 100.01329 -391.070993) (xy 99.976539 -391.034242) (xy 99.945989 -390.992194) (xy 99.922393 -390.945884)
			(xy 99.906332 -390.896454) (xy 99.898202 -390.845119) (xy 99.897692 -390.819132) (xy 99.898096 -390.795394)
			(xy 99.904893 -390.748407) (xy 99.918336 -390.702875) (xy 99.93815 -390.659731) (xy 99.963928 -390.619864)
			(xy 99.979226 -390.601708) (xy 99.985937 -390.59331) (xy 99.992271 -390.572789) (xy 99.989681 -390.551469)
			(xy 99.98456 -390.542018) (xy 99.969052 -390.51525) (xy 99.944637 -390.458408) (xy 99.928114 -390.398792)
			(xy 99.919785 -390.337492) (xy 99.919282 -390.30656) (xy 99.919799 -390.274958) (xy 99.928501 -390.212356)
			(xy 99.945749 -390.151551) (xy 99.971213 -390.093704) (xy 99.987354 -390.06653) (xy 99.991935 -390.058328)
			(xy 99.995349 -390.039866) (xy 99.991911 -390.021408) (xy 99.987354 -390.01319) (xy 99.971234 -389.986007)
			(xy 99.945806 -389.928151) (xy 99.928564 -389.86735) (xy 99.919836 -389.804758) (xy 99.919282 -389.77316)
			(xy 99.919842 -389.739925) (xy 99.929452 -389.674154) (xy 99.948476 -389.610466) (xy 99.976516 -389.550201)
			(xy 100.012982 -389.494627) (xy 100.034598 -389.469376) (xy 100.040948 -389.462264) (xy 100.047552 -389.444992)
			(xy 100.047552 -389.358886) (xy 100.040948 -389.341614) (xy 100.034598 -389.334502) (xy 100.013024 -389.309263)
			(xy 99.976653 -389.253716) (xy 99.948686 -389.193497) (xy 99.929711 -389.12987) (xy 99.920125 -389.06417)
			(xy 99.919536 -389.030972) (xy 99.920083 -388.999147) (xy 99.928904 -388.936112) (xy 99.946374 -388.874907)
			(xy 99.972154 -388.816712) (xy 100.005748 -388.76265) (xy 100.025708 -388.737856) (xy 100.03155 -388.730744)
			(xy 100.037646 -388.713218) (xy 100.035106 -388.627112) (xy 100.027994 -388.610094) (xy 100.021644 -388.603236)
			(xy 100.002155 -388.581968) (xy 99.968162 -388.535359) (xy 99.940298 -388.484846) (xy 99.919004 -388.431232)
			(xy 99.904618 -388.375367) (xy 99.897368 -388.318136) (xy 99.89693 -388.289292) (xy 98.348735 -388.289292)
			(xy 98.351012 -388.302291) (xy 98.351594 -388.328662) (xy 98.351526 -388.338021) (xy 98.350382 -388.356703)
			(xy 98.349308 -388.366) (xy 98.348292 -388.37489) (xy 98.352102 -388.391654) (xy 98.396044 -388.461504)
			(xy 98.40976 -388.471918) (xy 98.418142 -388.474712) (xy 98.442171 -388.483179) (xy 98.487343 -388.506732)
			(xy 98.528148 -388.537232) (xy 98.563527 -388.573887) (xy 98.592562 -388.615746) (xy 98.614501 -388.661724)
			(xy 98.622104 -388.68604) (xy 98.623628 -388.691882) (xy 98.943922 -389.245602) (xy 98.947986 -389.24992)
			(xy 98.964188 -389.267616) (xy 98.991549 -389.307029) (xy 99.012631 -389.350129) (xy 99.026948 -389.395922)
			(xy 99.034172 -389.443354) (xy 99.0346 -389.467344) (xy 99.034123 -389.492133) (xy 99.026361 -389.5411)
			(xy 99.011036 -389.588251) (xy 98.988525 -389.632424) (xy 98.959382 -389.672533) (xy 98.924324 -389.70759)
			(xy 98.884214 -389.736731) (xy 98.84004 -389.759241) (xy 98.792889 -389.774564) (xy 98.743921 -389.782324)
			(xy 98.719132 -389.782812) (xy 98.693739 -389.782283) (xy 98.643606 -389.774158) (xy 98.595421 -389.758111)
			(xy 98.550427 -389.734557) (xy 98.509784 -389.704103) (xy 98.474541 -389.667536) (xy 98.445606 -389.625797)
			(xy 98.423727 -389.579965) (xy 98.41611 -389.555736) (xy 98.414586 -389.549894) (xy 98.094292 -388.996174)
			(xy 98.090228 -388.991856) (xy 98.07403 -388.974143) (xy 98.046603 -388.934754) (xy 98.025459 -388.891666)
			(xy 98.011084 -388.845873) (xy 98.003811 -388.79843) (xy 98.00336 -388.774432) (xy 98.003501 -388.76238)
			(xy 98.005408 -388.73835) (xy 98.00717 -388.726426) (xy 98.00844 -388.717536) (xy 98.005392 -388.700518)
			(xy 97.963228 -388.629652) (xy 97.95002 -388.618476) (xy 97.941638 -388.615428) (xy 97.919883 -388.60705)
			(xy 97.879026 -388.584605) (xy 97.842056 -388.556208) (xy 97.809835 -388.52252) (xy 97.783111 -388.484324)
			(xy 97.762506 -388.442508) (xy 97.748499 -388.398046) (xy 97.741416 -388.35197) (xy 97.740978 -388.328662)
			(xy 97.741547 -388.302289) (xy 97.750629 -388.250331) (xy 97.768516 -388.20071) (xy 97.78111 -388.177532)
			(xy 97.785682 -388.169404) (xy 97.788476 -388.152132) (xy 97.773236 -388.069328) (xy 97.764092 -388.054088)
			(xy 97.75698 -388.0485) (xy 97.734805 -388.029799) (xy 97.694859 -387.987736) (xy 97.660543 -387.940967)
			(xy 97.632405 -387.89024) (xy 97.610895 -387.836367) (xy 97.596359 -387.780209) (xy 97.589029 -387.722666)
			(xy 97.588578 -387.693662) (xy 97.589175 -387.660341) (xy 97.598834 -387.594402) (xy 97.617957 -387.530563)
			(xy 97.631504 -387.500114) (xy 97.635735 -387.489643) (xy 97.63563 -387.467088) (xy 97.625902 -387.446738)
			(xy 97.617534 -387.439154) (xy 97.595274 -387.420495) (xy 97.55521 -387.378438) (xy 97.52079 -387.331649)
			(xy 97.492566 -387.280882) (xy 97.470993 -387.226951) (xy 97.456417 -387.170724) (xy 97.449072 -387.113105)
			(xy 97.448624 -387.084062) (xy 97.449086 -387.055136) (xy 97.456369 -386.997745) (xy 97.470827 -386.941728)
			(xy 97.492229 -386.887981) (xy 97.520234 -386.83736) (xy 97.554396 -386.790671) (xy 97.594169 -386.74866)
			(xy 97.616264 -386.729986) (xy 97.623236 -386.723639) (xy 97.632494 -386.707235) (xy 97.634298 -386.697982)
			(xy 97.638616 -386.666994) (xy 97.639525 -386.657758) (xy 97.635498 -386.639657) (xy 97.630742 -386.631688)
			(xy 97.614438 -386.60584) (xy 97.590532 -386.549606) (xy 97.583244 -386.519928) (xy 97.581173 -386.51177)
			(xy 97.57248 -386.497367) (xy 97.566226 -386.491734) (xy 97.543112 -386.472684) (xy 97.536224 -386.467451)
			(xy 97.52 -386.461477) (xy 97.511362 -386.461) (xy 97.481725 -386.459991) (xy 97.423061 -386.451342)
			(xy 97.366003 -386.435191) (xy 97.311509 -386.411808) (xy 97.26049 -386.381585) (xy 97.2138 -386.345028)
			(xy 97.172221 -386.302749) (xy 97.136449 -386.255455) (xy 97.107082 -386.203938) (xy 97.084613 -386.149061)
			(xy 97.069417 -386.091742) (xy 97.061749 -386.032941) (xy 97.061274 -386.003292) (xy 97.061794 -385.972229)
			(xy 97.070211 -385.910675) (xy 97.078038 -385.88061) (xy 97.080832 -385.87045) (xy 97.078292 -385.850638)
			(xy 97.030794 -385.768342) (xy 97.014792 -385.75615) (xy 97.004632 -385.75361) (xy 96.975544 -385.745579)
			(xy 96.919617 -385.722912) (xy 96.867151 -385.693096) (xy 96.819057 -385.656647) (xy 96.776167 -385.614197)
			(xy 96.739224 -385.566481) (xy 96.708869 -385.514325) (xy 96.685627 -385.458635) (xy 96.669902 -385.400374)
			(xy 96.661965 -385.340553) (xy 96.661478 -385.31038) (xy 96.662007 -385.279492) (xy 96.670311 -385.218277)
			(xy 96.686767 -385.158733) (xy 96.711076 -385.101941) (xy 96.726502 -385.075176) (xy 96.732344 -385.06527)
			(xy 96.73463 -385.042918) (xy 96.701356 -384.947668) (xy 96.685608 -384.931666) (xy 96.67494 -384.927602)
			(xy 96.651546 -384.918448) (xy 96.607651 -384.894022) (xy 96.567957 -384.863236) (xy 96.533378 -384.826798)
			(xy 96.50471 -384.785547) (xy 96.482614 -384.740434) (xy 96.467599 -384.692496) (xy 96.46001 -384.642839)
			(xy 96.459548 -384.617722) (xy 95.920814 -384.617722) (xy 95.920281 -384.644824) (xy 95.911473 -384.698306)
			(xy 95.903288 -384.724148) (xy 95.899478 -384.73507) (xy 95.902018 -384.757422) (xy 95.954596 -384.843274)
			(xy 95.973646 -384.85572) (xy 95.984822 -384.857498) (xy 96.014139 -384.862212) (xy 96.071309 -384.87826)
			(xy 96.125923 -384.901568) (xy 96.177063 -384.931747) (xy 96.223869 -384.968287) (xy 96.265554 -385.010575)
			(xy 96.301419 -385.057901) (xy 96.330859 -385.109469) (xy 96.353381 -385.164412) (xy 96.368605 -385.221808)
			(xy 96.376277 -385.28069) (xy 96.376744 -385.31038) (xy 96.376217 -385.341443) (xy 96.367805 -385.402996)
			(xy 96.35998 -385.433062) (xy 96.357186 -385.443222) (xy 96.359726 -385.463034) (xy 96.407224 -385.54533)
			(xy 96.423226 -385.557522) (xy 96.433386 -385.560062) (xy 96.462502 -385.568039) (xy 96.518468 -385.590677)
			(xy 96.570973 -385.620475) (xy 96.619105 -385.656916) (xy 96.66203 -385.699367) (xy 96.699003 -385.747092)
			(xy 96.729383 -385.799263) (xy 96.752641 -385.854974) (xy 96.768375 -385.913259) (xy 96.776311 -385.973106)
			(xy 96.776794 -386.003292) (xy 96.776669 -386.017427) (xy 96.774887 -386.045641) (xy 96.773238 -386.05968)
			(xy 96.77248 -386.068287) (xy 96.776118 -386.085167) (xy 96.78035 -386.0927) (xy 96.796098 -386.1181)
			(xy 96.800805 -386.125162) (xy 96.813913 -386.13593) (xy 96.821752 -386.139182) (xy 96.845138 -386.148353)
			(xy 96.889033 -386.172777) (xy 96.928728 -386.203561) (xy 96.963307 -386.239996) (xy 96.991976 -386.281244)
			(xy 97.014073 -386.326355) (xy 97.02909 -386.37429) (xy 97.036681 -386.423946) (xy 97.037144 -386.449062)
			(xy 97.036728 -386.473265) (xy 97.029653 -386.52115) (xy 97.015664 -386.56749) (xy 96.995061 -386.611291)
			(xy 96.982026 -386.631688) (xy 96.977235 -386.639643) (xy 96.973204 -386.657756) (xy 96.974152 -386.666994)
			(xy 96.97847 -386.697982) (xy 96.980161 -386.707276) (xy 96.989436 -386.723718) (xy 96.996504 -386.729986)
			(xy 97.01858 -386.748683) (xy 97.058354 -386.79069) (xy 97.092519 -386.837375) (xy 97.120529 -386.887992)
			(xy 97.141938 -386.941736) (xy 97.156405 -386.997748) (xy 97.163699 -387.055137) (xy 97.164144 -387.084062)
			(xy 97.163554 -387.117383) (xy 97.153891 -387.183322) (xy 97.134766 -387.247161) (xy 97.121218 -387.27761)
			(xy 97.116957 -387.288071) (xy 97.11707 -387.310635) (xy 97.126812 -387.330988) (xy 97.135188 -387.33857)
			(xy 97.157416 -387.357266) (xy 97.197481 -387.399317) (xy 97.231903 -387.446099) (xy 97.260131 -387.496861)
			(xy 97.281709 -387.550785) (xy 97.296292 -387.607007) (xy 97.303645 -387.664621) (xy 97.304098 -387.693662)
			(xy 97.30364 -387.722668) (xy 97.296329 -387.780216) (xy 97.281805 -387.83638) (xy 97.260302 -387.890259)
			(xy 97.232164 -387.940989) (xy 97.197842 -387.987758) (xy 97.157887 -388.029816) (xy 97.135696 -388.0485)
			(xy 97.128584 -388.054088) (xy 97.11944 -388.069328) (xy 97.1042 -388.152132) (xy 97.106994 -388.169404)
			(xy 97.111566 -388.177532) (xy 97.124143 -388.200718) (xy 97.142016 -388.25034) (xy 97.151116 -388.302291)
			(xy 97.151698 -388.328662) (xy 97.15163 -388.338021) (xy 97.150486 -388.356703) (xy 97.149412 -388.366)
			(xy 97.148396 -388.37489) (xy 97.152206 -388.391654) (xy 97.196148 -388.461504) (xy 97.209864 -388.471918)
			(xy 97.218246 -388.474712) (xy 97.242353 -388.483167) (xy 97.287643 -388.506799) (xy 97.328536 -388.537416)
			(xy 97.363965 -388.574218) (xy 97.393006 -388.616245) (xy 97.414901 -388.6624) (xy 97.422462 -388.686802)
			(xy 97.423986 -388.692644) (xy 97.743772 -389.245602) (xy 97.747836 -389.24992) (xy 97.764034 -389.267633)
			(xy 97.791458 -389.307023) (xy 97.812601 -389.350112) (xy 97.826976 -389.395904) (xy 97.834252 -389.443346)
			(xy 97.834704 -389.467344) (xy 97.834247 -389.492148) (xy 97.826477 -389.541143) (xy 97.811136 -389.588319)
			(xy 97.788601 -389.632512) (xy 97.759428 -389.672635) (xy 97.724335 -389.707698) (xy 97.684188 -389.736838)
			(xy 97.639976 -389.759336) (xy 97.592788 -389.774638) (xy 97.543786 -389.782367) (xy 97.518982 -389.782812)
			(xy 97.493587 -389.782327) (xy 97.443453 -389.774194) (xy 97.395267 -389.75814) (xy 97.350272 -389.734579)
			(xy 97.30963 -389.70412) (xy 97.274387 -389.667547) (xy 97.245454 -389.625804) (xy 97.223576 -389.579967)
			(xy 97.21596 -389.555736) (xy 97.214436 -389.549894) (xy 96.893888 -388.995412) (xy 96.889824 -388.991094)
			(xy 96.873716 -388.973429) (xy 96.846469 -388.934148) (xy 96.82546 -388.891207) (xy 96.811169 -388.845587)
			(xy 96.803922 -388.798334) (xy 96.803464 -388.774432) (xy 96.803605 -388.76238) (xy 96.805512 -388.73835)
			(xy 96.807274 -388.726426) (xy 96.808544 -388.717536) (xy 96.805496 -388.700518) (xy 96.763332 -388.629652)
			(xy 96.750124 -388.618476) (xy 96.741742 -388.615428) (xy 96.719988 -388.607048) (xy 96.67913 -388.584604)
			(xy 96.642161 -388.556207) (xy 96.609939 -388.522519) (xy 96.583215 -388.484324) (xy 96.56261 -388.442508)
			(xy 96.548603 -388.398046) (xy 96.54152 -388.35197) (xy 96.541082 -388.328662) (xy 96.54165 -388.302289)
			(xy 96.550732 -388.250331) (xy 96.56862 -388.20071) (xy 96.581214 -388.177532) (xy 96.585786 -388.169404)
			(xy 96.58858 -388.152132) (xy 96.57334 -388.069328) (xy 96.564196 -388.054088) (xy 96.557084 -388.0485)
			(xy 96.53491 -388.029798) (xy 96.494964 -387.987735) (xy 96.460647 -387.940967) (xy 96.432509 -387.89024)
			(xy 96.411 -387.836367) (xy 96.396463 -387.780209) (xy 96.389133 -387.722666) (xy 96.388682 -387.693662)
			(xy 96.389278 -387.660341) (xy 96.398938 -387.594402) (xy 96.418061 -387.530563) (xy 96.431608 -387.500114)
			(xy 96.435838 -387.489643) (xy 96.435732 -387.467088) (xy 96.426005 -387.446739) (xy 96.417638 -387.439154)
			(xy 96.395379 -387.420494) (xy 96.355315 -387.378437) (xy 96.320894 -387.331649) (xy 96.29267 -387.280881)
			(xy 96.271097 -387.226951) (xy 96.256521 -387.170724) (xy 96.249176 -387.113105) (xy 96.248728 -387.084062)
			(xy 96.249188 -387.055136) (xy 96.256471 -386.997744) (xy 96.27093 -386.941728) (xy 96.292332 -386.887981)
			(xy 96.320338 -386.837359) (xy 96.3545 -386.790671) (xy 96.394273 -386.74866) (xy 96.416368 -386.729986)
			(xy 96.423341 -386.72364) (xy 96.432598 -386.707235) (xy 96.434402 -386.697982) (xy 96.43872 -386.666994)
			(xy 96.439628 -386.657757) (xy 96.435602 -386.639657) (xy 96.430846 -386.631688) (xy 96.414542 -386.60584)
			(xy 96.390636 -386.549606) (xy 96.383348 -386.519928) (xy 96.381276 -386.51177) (xy 96.372583 -386.497368)
			(xy 96.36633 -386.491734) (xy 96.343216 -386.472684) (xy 96.336327 -386.467452) (xy 96.320103 -386.461478)
			(xy 96.311466 -386.461) (xy 96.28183 -386.459987) (xy 96.223165 -386.451338) (xy 96.166108 -386.435188)
			(xy 96.111614 -386.411806) (xy 96.060594 -386.381583) (xy 96.013905 -386.345027) (xy 95.972325 -386.302748)
			(xy 95.936553 -386.255454) (xy 95.907186 -386.203938) (xy 95.884717 -386.149061) (xy 95.869521 -386.091742)
			(xy 95.861853 -386.032941) (xy 95.861378 -386.003292) (xy 95.861898 -385.972229) (xy 95.870315 -385.910675)
			(xy 95.878142 -385.88061) (xy 95.880936 -385.87045) (xy 95.878396 -385.850638) (xy 95.830898 -385.768342)
			(xy 95.814896 -385.75615) (xy 95.804736 -385.75361) (xy 95.775617 -385.745644) (xy 95.719649 -385.723006)
			(xy 95.667143 -385.693208) (xy 95.619009 -385.656767) (xy 95.576083 -385.614314) (xy 95.53911 -385.566588)
			(xy 95.508731 -385.514415) (xy 95.485474 -385.458702) (xy 95.469743 -385.400415) (xy 95.461809 -385.340566)
			(xy 95.461328 -385.31038) (xy 95.46185 -385.279492) (xy 95.470155 -385.218276) (xy 95.486613 -385.158732)
			(xy 95.510925 -385.10194) (xy 95.526352 -385.075176) (xy 95.532194 -385.06527) (xy 95.53448 -385.042918)
			(xy 95.501206 -384.947668) (xy 95.485458 -384.931666) (xy 95.47479 -384.927602) (xy 95.451407 -384.918421)
			(xy 95.40751 -384.894002) (xy 95.367814 -384.863221) (xy 95.333233 -384.826787) (xy 95.304564 -384.785539)
			(xy 95.282466 -384.740429) (xy 95.26745 -384.692494) (xy 95.25986 -384.642838) (xy 95.259398 -384.617722)
			(xy 94.720918 -384.617722) (xy 94.720385 -384.644824) (xy 94.711577 -384.698306) (xy 94.703392 -384.724148)
			(xy 94.699582 -384.73507) (xy 94.702122 -384.757422) (xy 94.7547 -384.843274) (xy 94.77375 -384.85572)
			(xy 94.784926 -384.857498) (xy 94.814243 -384.862209) (xy 94.871414 -384.878257) (xy 94.926028 -384.901566)
			(xy 94.977168 -384.931745) (xy 95.023973 -384.968286) (xy 95.065659 -385.010574) (xy 95.101523 -385.057901)
			(xy 95.130963 -385.109469) (xy 95.153485 -385.164412) (xy 95.168709 -385.221807) (xy 95.176381 -385.28069)
			(xy 95.176848 -385.31038) (xy 95.176325 -385.341506) (xy 95.167919 -385.403188) (xy 95.160084 -385.433316)
			(xy 95.15729 -385.443476) (xy 95.15983 -385.463542) (xy 95.207074 -385.54533) (xy 95.223076 -385.557522)
			(xy 95.233236 -385.560062) (xy 95.262342 -385.568073) (xy 95.318309 -385.590705) (xy 95.370815 -385.620498)
			(xy 95.418948 -385.656934) (xy 95.461875 -385.699381) (xy 95.498849 -385.747103) (xy 95.52923 -385.79927)
			(xy 95.552489 -385.854979) (xy 95.568224 -385.913262) (xy 95.57616 -385.973107) (xy 95.576644 -386.003292)
			(xy 95.576519 -386.017427) (xy 95.574737 -386.045641) (xy 95.573088 -386.05968) (xy 95.572323 -386.068287)
			(xy 95.575965 -386.085168) (xy 95.5802 -386.0927) (xy 95.595948 -386.1181) (xy 95.600639 -386.125174)
			(xy 95.613758 -386.135936) (xy 95.621602 -386.139182) (xy 95.644977 -386.14838) (xy 95.688874 -386.172797)
			(xy 95.72857 -386.203576) (xy 95.763152 -386.240007) (xy 95.791822 -386.281252) (xy 95.813921 -386.32636)
			(xy 95.828939 -386.374293) (xy 95.836531 -386.423947) (xy 95.836994 -386.449062) (xy 95.83657 -386.473264)
			(xy 95.829496 -386.521149) (xy 95.815509 -386.567488) (xy 95.794909 -386.61129) (xy 95.781876 -386.631688)
			(xy 95.777089 -386.639645) (xy 95.773054 -386.657756) (xy 95.774002 -386.666994) (xy 95.77832 -386.697982)
			(xy 95.779996 -386.70728) (xy 95.789281 -386.723721) (xy 95.796354 -386.729986) (xy 95.81844 -386.74867)
			(xy 95.858212 -386.790681) (xy 95.892375 -386.837369) (xy 95.920383 -386.887988) (xy 95.94179 -386.941733)
			(xy 95.956256 -386.997747) (xy 95.963549 -387.055136) (xy 95.963994 -387.084062) (xy 95.963399 -387.117383)
			(xy 95.953738 -387.183321) (xy 95.934614 -387.247161) (xy 95.921068 -387.27761) (xy 95.916823 -387.288076)
			(xy 95.916937 -387.310634) (xy 95.926669 -387.330985) (xy 95.935038 -387.33857) (xy 95.957276 -387.357254)
			(xy 95.997338 -387.399308) (xy 96.031759 -387.446093) (xy 96.059984 -387.496857) (xy 96.081561 -387.550783)
			(xy 96.096143 -387.607005) (xy 96.103495 -387.664621) (xy 96.103948 -387.693662) (xy 96.103473 -387.722667)
			(xy 96.096162 -387.780214) (xy 96.08164 -387.836377) (xy 96.060139 -387.890255) (xy 96.032004 -387.940986)
			(xy 95.997687 -387.987756) (xy 95.957735 -388.029815) (xy 95.935546 -388.0485) (xy 95.928434 -388.054088)
			(xy 95.91929 -388.069328) (xy 95.90405 -388.152132) (xy 95.906844 -388.169404) (xy 95.911416 -388.177532)
			(xy 95.923989 -388.20072) (xy 95.941864 -388.25034) (xy 95.950966 -388.302291) (xy 95.951548 -388.328662)
			(xy 95.951479 -388.338021) (xy 95.950336 -388.356703) (xy 95.949262 -388.366) (xy 95.948246 -388.37489)
			(xy 95.952056 -388.391654) (xy 95.995998 -388.461504) (xy 96.009714 -388.471918) (xy 96.018096 -388.474712)
			(xy 96.042116 -388.483203) (xy 96.087289 -388.50675) (xy 96.128096 -388.537244) (xy 96.163477 -388.573895)
			(xy 96.192514 -388.615751) (xy 96.214454 -388.661726) (xy 96.222058 -388.68604) (xy 96.223582 -388.691882)
			(xy 96.543876 -389.245602) (xy 96.54794 -389.24992) (xy 96.564138 -389.267633) (xy 96.591562 -389.307023)
			(xy 96.612705 -389.350111) (xy 96.62708 -389.395904) (xy 96.634356 -389.443346) (xy 96.634808 -389.467344)
			(xy 96.634347 -389.492147) (xy 96.626577 -389.541142) (xy 96.611236 -389.588318) (xy 96.588701 -389.632511)
			(xy 96.559529 -389.672634) (xy 96.524437 -389.707697) (xy 96.484291 -389.736836) (xy 96.440079 -389.759335)
			(xy 96.392891 -389.774637) (xy 96.34389 -389.782367) (xy 96.319086 -389.782812) (xy 96.293691 -389.782324)
			(xy 96.243557 -389.774191) (xy 96.195371 -389.758138) (xy 96.150377 -389.734577) (xy 96.109734 -389.704118)
			(xy 96.074492 -389.667546) (xy 96.045558 -389.625803) (xy 96.02368 -389.579967) (xy 96.016064 -389.555736)
			(xy 96.01454 -389.549894) (xy 95.694246 -388.996174) (xy 95.690182 -388.991856) (xy 95.674027 -388.974118)
			(xy 95.646657 -388.934717) (xy 95.625565 -388.891629) (xy 95.611237 -388.845845) (xy 95.604002 -388.798419)
			(xy 95.603568 -388.774432) (xy 95.603648 -388.762384) (xy 95.605431 -388.738355) (xy 95.607124 -388.726426)
			(xy 95.608394 -388.717536) (xy 95.605346 -388.700518) (xy 95.563182 -388.629652) (xy 95.549974 -388.618476)
			(xy 95.541592 -388.615428) (xy 95.519849 -388.607021) (xy 95.47899 -388.584583) (xy 95.442018 -388.556192)
			(xy 95.409795 -388.522508) (xy 95.383069 -388.484316) (xy 95.362462 -388.442503) (xy 95.348454 -388.398043)
			(xy 95.34137 -388.351969) (xy 95.340932 -388.328662) (xy 95.341494 -388.302289) (xy 95.350578 -388.25033)
			(xy 95.368468 -388.20071) (xy 95.381064 -388.177532) (xy 95.385636 -388.169404) (xy 95.38843 -388.152132)
			(xy 95.37319 -388.069328) (xy 95.364046 -388.054088) (xy 95.356934 -388.0485) (xy 95.33477 -388.029786)
			(xy 95.294822 -387.987727) (xy 95.260503 -387.940961) (xy 95.232362 -387.890236) (xy 95.210851 -387.836364)
			(xy 95.196314 -387.780208) (xy 95.188983 -387.722666) (xy 95.188532 -387.693662) (xy 95.189133 -387.660341)
			(xy 95.198791 -387.594403) (xy 95.217913 -387.530563) (xy 95.231458 -387.500114) (xy 95.235704 -387.489647)
			(xy 95.2356 -387.467087) (xy 95.225862 -387.446735) (xy 95.217488 -387.439154) (xy 95.195218 -387.420506)
			(xy 95.155157 -387.378446) (xy 95.120739 -387.331655) (xy 95.092517 -387.280885) (xy 95.070945 -387.226953)
			(xy 95.05637 -387.170725) (xy 95.049026 -387.113105) (xy 95.048578 -387.084062) (xy 95.04902 -387.055135)
			(xy 95.056304 -386.997742) (xy 95.070764 -386.941725) (xy 95.092169 -386.887977) (xy 95.120178 -386.837355)
			(xy 95.154343 -386.790668) (xy 95.194121 -386.748659) (xy 95.216218 -386.729986) (xy 95.223183 -386.723632)
			(xy 95.232446 -386.707233) (xy 95.234252 -386.697982) (xy 95.23857 -386.666994) (xy 95.239471 -386.657757)
			(xy 95.235448 -386.639658) (xy 95.230696 -386.631688) (xy 95.214387 -386.605843) (xy 95.190484 -386.549607)
			(xy 95.183198 -386.519928) (xy 95.181139 -386.511766) (xy 95.172438 -386.497365) (xy 95.16618 -386.491734)
			(xy 95.143066 -386.472684) (xy 95.13619 -386.467432) (xy 95.119956 -386.46147) (xy 95.111316 -386.461)
			(xy 95.081681 -386.459941) (xy 95.023018 -386.451299) (xy 94.965962 -386.435154) (xy 94.911468 -386.411777)
			(xy 94.860449 -386.38156) (xy 94.813758 -386.345007) (xy 94.772178 -386.302732) (xy 94.736405 -386.255442)
			(xy 94.707038 -386.203929) (xy 94.684568 -386.149055) (xy 94.669371 -386.091739) (xy 94.661703 -386.03294)
			(xy 94.661228 -386.003292) (xy 94.661749 -385.972229) (xy 94.670165 -385.910675) (xy 94.677992 -385.88061)
			(xy 94.680786 -385.87045) (xy 94.678246 -385.850638) (xy 94.630748 -385.768342) (xy 94.614746 -385.75615)
			(xy 94.604586 -385.75361) (xy 94.575508 -385.745543) (xy 94.51958 -385.722883) (xy 94.467114 -385.693073)
			(xy 94.419018 -385.656629) (xy 94.376126 -385.614182) (xy 94.339182 -385.56647) (xy 94.308825 -385.514318)
			(xy 94.285582 -385.45863) (xy 94.269856 -385.400371) (xy 94.261919 -385.340552) (xy 94.261432 -385.31038)
			(xy 94.261953 -385.279492) (xy 94.270259 -385.218276) (xy 94.286717 -385.158732) (xy 94.311029 -385.10194)
			(xy 94.326456 -385.075176) (xy 94.332298 -385.06527) (xy 94.334584 -385.042918) (xy 94.30131 -384.947668)
			(xy 94.285562 -384.931666) (xy 94.274894 -384.927602) (xy 94.251512 -384.918419) (xy 94.207615 -384.894)
			(xy 94.167919 -384.863219) (xy 94.133337 -384.826786) (xy 94.104668 -384.785539) (xy 94.08257 -384.740428)
			(xy 94.067554 -384.692493) (xy 94.059964 -384.642838) (xy 94.059502 -384.617722) (xy 93.520768 -384.617722)
			(xy 93.520237 -384.644824) (xy 93.511428 -384.698307) (xy 93.503242 -384.724148) (xy 93.499432 -384.73507)
			(xy 93.501972 -384.757422) (xy 93.55455 -384.843274) (xy 93.5736 -384.85572) (xy 93.584776 -384.857498)
			(xy 93.6141 -384.86217) (xy 93.671271 -384.878224) (xy 93.725885 -384.901539) (xy 93.777024 -384.931722)
			(xy 93.823828 -384.968268) (xy 93.865513 -385.01056) (xy 93.901376 -385.05789) (xy 93.930815 -385.109461)
			(xy 93.953336 -385.164407) (xy 93.96856 -385.221804) (xy 93.976231 -385.280689) (xy 93.976698 -385.31038)
			(xy 93.976173 -385.341443) (xy 93.96776 -385.402997) (xy 93.959934 -385.433062) (xy 93.95714 -385.443222)
			(xy 93.95968 -385.463034) (xy 94.007178 -385.54533) (xy 94.02318 -385.557522) (xy 94.03334 -385.560062)
			(xy 94.062447 -385.56807) (xy 94.118413 -385.590703) (xy 94.170919 -385.620496) (xy 94.219053 -385.656932)
			(xy 94.261979 -385.69938) (xy 94.298954 -385.747102) (xy 94.329334 -385.79927) (xy 94.352593 -385.854979)
			(xy 94.368328 -385.913262) (xy 94.376264 -385.973107) (xy 94.376748 -386.003292) (xy 94.376623 -386.017427)
			(xy 94.374841 -386.045641) (xy 94.373192 -386.05968) (xy 94.372426 -386.068287) (xy 94.376068 -386.085168)
			(xy 94.380304 -386.0927) (xy 94.396052 -386.1181) (xy 94.400774 -386.125151) (xy 94.413871 -386.135925)
			(xy 94.421706 -386.139182) (xy 94.445082 -386.148378) (xy 94.488979 -386.172796) (xy 94.528675 -386.203575)
			(xy 94.563256 -386.240006) (xy 94.591926 -386.281251) (xy 94.614025 -386.32636) (xy 94.629043 -386.374293)
			(xy 94.636635 -386.423947) (xy 94.637098 -386.449062) (xy 94.636673 -386.473264) (xy 94.6296 -386.521149)
			(xy 94.615613 -386.567488) (xy 94.595013 -386.61129) (xy 94.58198 -386.631688) (xy 94.577193 -386.639645)
			(xy 94.573158 -386.657756) (xy 94.574106 -386.666994) (xy 94.578424 -386.697982) (xy 94.580099 -386.70728)
			(xy 94.589384 -386.723721) (xy 94.596458 -386.729986) (xy 94.618545 -386.748669) (xy 94.658317 -386.790681)
			(xy 94.692479 -386.837368) (xy 94.720487 -386.887988) (xy 94.741894 -386.941733) (xy 94.75636 -386.997747)
			(xy 94.763653 -387.055136) (xy 94.764098 -387.084062) (xy 94.763512 -387.117384) (xy 94.753849 -387.183322)
			(xy 94.734721 -387.247161) (xy 94.721172 -387.27761) (xy 94.716926 -387.288075) (xy 94.71704 -387.310634)
			(xy 94.726773 -387.330985) (xy 94.735142 -387.33857) (xy 94.75736 -387.357277) (xy 94.797427 -387.399325)
			(xy 94.831852 -387.446105) (xy 94.860082 -387.496864) (xy 94.881662 -387.550787) (xy 94.896246 -387.607008)
			(xy 94.903599 -387.664621) (xy 94.904052 -387.693662) (xy 94.903575 -387.722667) (xy 94.896264 -387.780214)
			(xy 94.881742 -387.836377) (xy 94.860242 -387.890255) (xy 94.832108 -387.940985) (xy 94.79779 -387.987755)
			(xy 94.757839 -388.029815) (xy 94.73565 -388.0485) (xy 94.728538 -388.054088) (xy 94.719394 -388.069328)
			(xy 94.704154 -388.152132) (xy 94.706948 -388.169404) (xy 94.71152 -388.177532) (xy 94.724093 -388.200719)
			(xy 94.741969 -388.25034) (xy 94.75107 -388.302291) (xy 94.751652 -388.328662) (xy 94.751583 -388.338021)
			(xy 94.75044 -388.356703) (xy 94.749366 -388.366) (xy 94.74835 -388.37489) (xy 94.75216 -388.391654)
			(xy 94.796102 -388.461504) (xy 94.809818 -388.471918) (xy 94.8182 -388.474712) (xy 94.842298 -388.483192)
			(xy 94.887589 -388.506817) (xy 94.928484 -388.537428) (xy 94.963915 -388.574226) (xy 94.992958 -388.616249)
			(xy 95.014854 -388.662401) (xy 95.022416 -388.686802) (xy 95.02394 -388.692644) (xy 95.343726 -389.245602)
			(xy 95.34779 -389.24992) (xy 95.363993 -389.267616) (xy 95.391353 -389.307029) (xy 95.412435 -389.350129)
			(xy 95.426752 -389.395922) (xy 95.433976 -389.443354) (xy 95.434404 -389.467344) (xy 95.433923 -389.492133)
			(xy 95.426161 -389.5411) (xy 95.410837 -389.58825) (xy 95.388326 -389.632423) (xy 95.359183 -389.672532)
			(xy 95.324126 -389.707588) (xy 95.284016 -389.73673) (xy 95.239843 -389.75924) (xy 95.192692 -389.774563)
			(xy 95.143725 -389.782323) (xy 95.118936 -389.782812) (xy 95.093543 -389.78228) (xy 95.043411 -389.774155)
			(xy 94.995226 -389.758109) (xy 94.950231 -389.734555) (xy 94.909588 -389.704102) (xy 94.874345 -389.667535)
			(xy 94.84541 -389.625797) (xy 94.823531 -389.579965) (xy 94.815914 -389.555736) (xy 94.81439 -389.549894)
			(xy 94.493842 -388.995412) (xy 94.489778 -388.991094) (xy 94.473683 -388.973429) (xy 94.446493 -388.934132)
			(xy 94.42554 -388.891184) (xy 94.411303 -388.845567) (xy 94.404107 -388.798325) (xy 94.403672 -388.774432)
			(xy 94.403752 -388.762384) (xy 94.405535 -388.738355) (xy 94.407228 -388.726426) (xy 94.408498 -388.717536)
			(xy 94.40545 -388.700518) (xy 94.363286 -388.629652) (xy 94.350078 -388.618476) (xy 94.341696 -388.615428)
			(xy 94.319954 -388.607019) (xy 94.279095 -388.584581) (xy 94.242123 -388.55619) (xy 94.209899 -388.522507)
			(xy 94.183173 -388.484315) (xy 94.162566 -388.442503) (xy 94.148558 -388.398043) (xy 94.141474 -388.351969)
			(xy 94.141036 -388.328662) (xy 94.141597 -388.302289) (xy 94.150681 -388.25033) (xy 94.168572 -388.20071)
			(xy 94.181168 -388.177532) (xy 94.18574 -388.169404) (xy 94.188534 -388.152132) (xy 94.173294 -388.069328)
			(xy 94.16415 -388.054088) (xy 94.157038 -388.0485) (xy 94.134875 -388.029785) (xy 94.094926 -387.987726)
			(xy 94.060607 -387.94096) (xy 94.032467 -387.890236) (xy 94.010956 -387.836364) (xy 93.996418 -387.780208)
			(xy 93.989087 -387.722666) (xy 93.988636 -387.693662) (xy 93.989236 -387.660341) (xy 93.998895 -387.594403)
			(xy 94.018017 -387.530563) (xy 94.031562 -387.500114) (xy 94.035807 -387.489647) (xy 94.035702 -387.467087)
			(xy 94.025966 -387.446735) (xy 94.017592 -387.439154) (xy 93.995323 -387.420505) (xy 93.955262 -387.378445)
			(xy 93.920843 -387.331654) (xy 93.892621 -387.280885) (xy 93.871049 -387.226953) (xy 93.856474 -387.170725)
			(xy 93.84913 -387.113105) (xy 93.848682 -387.084062) (xy 93.849122 -387.055135) (xy 93.856407 -386.997742)
			(xy 93.870867 -386.941725) (xy 93.892272 -386.887977) (xy 93.920281 -386.837355) (xy 93.954447 -386.790668)
			(xy 93.994225 -386.748659) (xy 94.016322 -386.729986) (xy 94.023288 -386.723632) (xy 94.03255 -386.707234)
			(xy 94.034356 -386.697982) (xy 94.038674 -386.666994) (xy 94.039574 -386.657757) (xy 94.035552 -386.639658)
			(xy 94.0308 -386.631688) (xy 94.014492 -386.605843) (xy 93.990588 -386.549607) (xy 93.983302 -386.519928)
			(xy 93.981242 -386.511766) (xy 93.972542 -386.497365) (xy 93.966284 -386.491734) (xy 93.94317 -386.472684)
			(xy 93.936293 -386.467434) (xy 93.92006 -386.461471) (xy 93.91142 -386.461) (xy 93.881782 -386.460029)
			(xy 93.823116 -386.451375) (xy 93.766058 -386.435219) (xy 93.711564 -386.411832) (xy 93.660545 -386.381605)
			(xy 93.613855 -386.345044) (xy 93.572277 -386.302762) (xy 93.536505 -386.255465) (xy 93.507139 -386.203946)
			(xy 93.48467 -386.149066) (xy 93.469475 -386.091745) (xy 93.461807 -386.032942) (xy 93.461332 -386.003292)
			(xy 93.461853 -385.972229) (xy 93.470269 -385.910675) (xy 93.478096 -385.88061) (xy 93.48089 -385.87045)
			(xy 93.47835 -385.850638) (xy 93.430852 -385.768342) (xy 93.41485 -385.75615) (xy 93.40469 -385.75361)
			(xy 93.375581 -385.745608) (xy 93.319613 -385.722977) (xy 93.267105 -385.693184) (xy 93.21897 -385.656748)
			(xy 93.176043 -385.6143) (xy 93.139068 -385.566577) (xy 93.108688 -385.514407) (xy 93.08543 -385.458697)
			(xy 93.069698 -385.400412) (xy 93.061764 -385.340565) (xy 93.061282 -385.31038) (xy 93.06181 -385.279492)
			(xy 93.070115 -385.218277) (xy 93.086571 -385.158733) (xy 93.11088 -385.101941) (xy 93.126306 -385.075176)
			(xy 93.132148 -385.06527) (xy 93.134434 -385.042918) (xy 93.10116 -384.947668) (xy 93.085412 -384.931666)
			(xy 93.074744 -384.927602) (xy 93.051351 -384.918446) (xy 93.007456 -384.894021) (xy 92.967761 -384.863235)
			(xy 92.933182 -384.826797) (xy 92.904514 -384.785547) (xy 92.882418 -384.740433) (xy 92.867403 -384.692496)
			(xy 92.859814 -384.642839) (xy 92.859352 -384.617722) (xy 92.320872 -384.617722) (xy 92.320341 -384.644824)
			(xy 92.311532 -384.698307) (xy 92.303346 -384.724148) (xy 92.299536 -384.73507) (xy 92.302076 -384.757422)
			(xy 92.354654 -384.843274) (xy 92.373704 -384.85572) (xy 92.38488 -384.857498) (xy 92.414205 -384.862167)
			(xy 92.471376 -384.878222) (xy 92.525989 -384.901537) (xy 92.577128 -384.931721) (xy 92.623933 -384.968266)
			(xy 92.665617 -385.010559) (xy 92.70148 -385.057889) (xy 92.730919 -385.10946) (xy 92.75344 -385.164406)
			(xy 92.768664 -385.221804) (xy 92.776335 -385.280689) (xy 92.776802 -385.31038) (xy 92.776277 -385.341443)
			(xy 92.767864 -385.402997) (xy 92.760038 -385.433062) (xy 92.757244 -385.443222) (xy 92.759784 -385.463034)
			(xy 92.807282 -385.54533) (xy 92.823284 -385.557522) (xy 92.833444 -385.560062) (xy 92.862552 -385.568067)
			(xy 92.918518 -385.5907) (xy 92.971024 -385.620494) (xy 93.019158 -385.656931) (xy 93.062084 -385.699379)
			(xy 93.099058 -385.747101) (xy 93.129439 -385.799269) (xy 93.152698 -385.854978) (xy 93.168432 -385.913261)
			(xy 93.176369 -385.973107) (xy 93.176852 -386.003292) (xy 93.176727 -386.017427) (xy 93.174945 -386.045641)
			(xy 93.173296 -386.05968) (xy 93.172529 -386.068287) (xy 93.176172 -386.085168) (xy 93.180408 -386.0927)
			(xy 93.196156 -386.1181) (xy 93.200864 -386.125164) (xy 93.213964 -386.135942) (xy 93.22181 -386.139182)
			(xy 93.245154 -386.148421) (xy 93.288998 -386.172873) (xy 93.328643 -386.203671) (xy 93.363178 -386.240106)
			(xy 93.39181 -386.281341) (xy 93.413882 -386.32643) (xy 93.428887 -386.374337) (xy 93.436479 -386.423961)
			(xy 93.436948 -386.449062) (xy 93.436531 -386.473264) (xy 93.429457 -386.52115) (xy 93.415468 -386.56749)
			(xy 93.394865 -386.611291) (xy 93.38183 -386.631688) (xy 93.377039 -386.639643) (xy 93.373008 -386.657756)
			(xy 93.373956 -386.666994) (xy 93.378274 -386.697982) (xy 93.379964 -386.707276) (xy 93.38924 -386.723718)
			(xy 93.396308 -386.729986) (xy 93.418384 -386.748682) (xy 93.458159 -386.79069) (xy 93.492323 -386.837375)
			(xy 93.520333 -386.887992) (xy 93.541742 -386.941735) (xy 93.556209 -386.997748) (xy 93.563503 -387.055137)
			(xy 93.563948 -387.084062) (xy 93.563358 -387.117383) (xy 93.553695 -387.183322) (xy 93.534569 -387.247161)
			(xy 93.521022 -387.27761) (xy 93.51676 -387.288071) (xy 93.516873 -387.310635) (xy 93.526616 -387.330988)
			(xy 93.534992 -387.33857) (xy 93.557221 -387.357265) (xy 93.597285 -387.399316) (xy 93.631708 -387.446099)
			(xy 93.659935 -387.49686) (xy 93.681513 -387.550785) (xy 93.696096 -387.607006) (xy 93.703449 -387.664621)
			(xy 93.703902 -387.693662) (xy 93.703443 -387.722668) (xy 93.696131 -387.780216) (xy 93.681608 -387.83638)
			(xy 93.660105 -387.890259) (xy 93.631967 -387.940989) (xy 93.597646 -387.987758) (xy 93.557691 -388.029816)
			(xy 93.5355 -388.0485) (xy 93.528388 -388.054088) (xy 93.519244 -388.069328) (xy 93.504004 -388.152132)
			(xy 93.506798 -388.169404) (xy 93.51137 -388.177532) (xy 93.523939 -388.200722) (xy 93.541817 -388.250341)
			(xy 93.55092 -388.302292) (xy 93.551502 -388.328662) (xy 93.551434 -388.338021) (xy 93.55029 -388.356703)
			(xy 93.549216 -388.366) (xy 93.5482 -388.37489) (xy 93.55201 -388.391654) (xy 93.595952 -388.461504)
			(xy 93.609668 -388.471918) (xy 93.61805 -388.474712) (xy 93.64208 -388.483174) (xy 93.687252 -388.506729)
			(xy 93.728057 -388.537229) (xy 93.763436 -388.573885) (xy 93.792471 -388.615746) (xy 93.814409 -388.661724)
			(xy 93.822012 -388.68604) (xy 93.823536 -388.691882) (xy 94.14383 -389.245602) (xy 94.147894 -389.24992)
			(xy 94.164098 -389.267615) (xy 94.191458 -389.307029) (xy 94.212539 -389.350128) (xy 94.226856 -389.395922)
			(xy 94.23408 -389.443354) (xy 94.234508 -389.467344) (xy 94.234023 -389.492133) (xy 94.226262 -389.541099)
			(xy 94.210937 -389.588249) (xy 94.188427 -389.632422) (xy 94.159284 -389.67253) (xy 94.124227 -389.707587)
			(xy 94.084119 -389.736729) (xy 94.039946 -389.759239) (xy 93.992795 -389.774562) (xy 93.943829 -389.782323)
			(xy 93.91904 -389.782812) (xy 93.893647 -389.782276) (xy 93.843515 -389.774152) (xy 93.79533 -389.758106)
			(xy 93.750336 -389.734553) (xy 93.709693 -389.704101) (xy 93.674449 -389.667534) (xy 93.645514 -389.625796)
			(xy 93.623635 -389.579965) (xy 93.616018 -389.555736) (xy 93.614494 -389.549894) (xy 93.2942 -388.996174)
			(xy 93.290136 -388.991856) (xy 93.273922 -388.974157) (xy 93.246502 -388.934763) (xy 93.225362 -388.891671)
			(xy 93.21099 -388.845875) (xy 93.203718 -388.798431) (xy 93.203268 -388.774432) (xy 93.20341 -388.76238)
			(xy 93.205316 -388.73835) (xy 93.207078 -388.726426) (xy 93.208348 -388.717536) (xy 93.2053 -388.700518)
			(xy 93.163136 -388.629652) (xy 93.149928 -388.618476) (xy 93.141546 -388.615428) (xy 93.119793 -388.607046)
			(xy 93.078935 -388.584602) (xy 93.041966 -388.556206) (xy 93.009744 -388.522518) (xy 92.983019 -388.484323)
			(xy 92.962414 -388.442508) (xy 92.948407 -388.398045) (xy 92.941324 -388.35197) (xy 92.940886 -388.328662)
			(xy 92.941454 -388.302289) (xy 92.950536 -388.250331) (xy 92.968424 -388.20071) (xy 92.981018 -388.177532)
			(xy 92.98559 -388.169404) (xy 92.988384 -388.152132) (xy 92.973144 -388.069328) (xy 92.964 -388.054088)
			(xy 92.956888 -388.0485) (xy 92.934715 -388.029797) (xy 92.894768 -387.987735) (xy 92.860451 -387.940966)
			(xy 92.832313 -387.890239) (xy 92.810804 -387.836366) (xy 92.796267 -387.780209) (xy 92.788937 -387.722666)
			(xy 92.788486 -387.693662) (xy 92.789082 -387.660341) (xy 92.798741 -387.594402) (xy 92.817865 -387.530563)
			(xy 92.831412 -387.500114) (xy 92.835641 -387.489643) (xy 92.835536 -387.467088) (xy 92.825809 -387.446739)
			(xy 92.817442 -387.439154) (xy 92.795184 -387.420493) (xy 92.755119 -387.378436) (xy 92.720699 -387.331648)
			(xy 92.692475 -387.280881) (xy 92.670901 -387.226951) (xy 92.656325 -387.170724) (xy 92.64898 -387.113105)
			(xy 92.648532 -387.084062) (xy 92.648991 -387.055136) (xy 92.656274 -386.997744) (xy 92.670732 -386.941728)
			(xy 92.692135 -386.887981) (xy 92.720141 -386.837359) (xy 92.754303 -386.790671) (xy 92.794077 -386.74866)
			(xy 92.816172 -386.729986) (xy 92.823146 -386.723641) (xy 92.832402 -386.707235) (xy 92.834206 -386.697982)
			(xy 92.838524 -386.666994) (xy 92.839432 -386.657757) (xy 92.835405 -386.639657) (xy 92.83065 -386.631688)
			(xy 92.814338 -386.605845) (xy 92.790437 -386.549608) (xy 92.783152 -386.519928) (xy 92.781079 -386.51177)
			(xy 92.772387 -386.497368) (xy 92.766134 -386.491734) (xy 92.74302 -386.472684) (xy 92.736188 -386.467481)
			(xy 92.720097 -386.461509) (xy 92.711524 -386.461) (xy 92.681886 -386.460025) (xy 92.62322 -386.451372)
			(xy 92.566162 -386.435216) (xy 92.511668 -386.41183) (xy 92.460649 -386.381603) (xy 92.41396 -386.345043)
			(xy 92.372381 -386.302761) (xy 92.336609 -386.255464) (xy 92.307243 -386.203945) (xy 92.284774 -386.149066)
			(xy 92.269579 -386.091745) (xy 92.261911 -386.032942) (xy 92.261436 -386.003292) (xy 92.261957 -385.972229)
			(xy 92.270373 -385.910675) (xy 92.2782 -385.88061) (xy 92.280994 -385.87045) (xy 92.278454 -385.850638)
			(xy 92.230956 -385.768342) (xy 92.214954 -385.75615) (xy 92.204794 -385.75361) (xy 92.175686 -385.745605)
			(xy 92.119717 -385.722974) (xy 92.06721 -385.693183) (xy 92.019075 -385.656747) (xy 91.976147 -385.614299)
			(xy 91.939173 -385.566576) (xy 91.908792 -385.514407) (xy 91.885534 -385.458696) (xy 91.869802 -385.400412)
			(xy 91.861868 -385.340565) (xy 91.861386 -385.31038) (xy 91.861914 -385.279492) (xy 91.870219 -385.218277)
			(xy 91.886675 -385.158733) (xy 91.910984 -385.101941) (xy 91.92641 -385.075176) (xy 91.932252 -385.06527)
			(xy 91.934538 -385.042918) (xy 91.901264 -384.947668) (xy 91.885516 -384.931666) (xy 91.874848 -384.927602)
			(xy 91.851456 -384.918444) (xy 91.80756 -384.894019) (xy 91.767866 -384.863233) (xy 91.733286 -384.826796)
			(xy 91.704619 -384.785546) (xy 91.682523 -384.740433) (xy 91.667507 -384.692496) (xy 91.659918 -384.642839)
			(xy 91.659456 -384.617722) (xy 91.120976 -384.617722) (xy 91.120445 -384.644824) (xy 91.111636 -384.698307)
			(xy 91.10345 -384.724148) (xy 91.09964 -384.73507) (xy 91.10218 -384.757422) (xy 91.154758 -384.843528)
			(xy 91.173554 -384.85572) (xy 91.184984 -384.857498) (xy 91.214278 -384.862274) (xy 91.271413 -384.878352)
			(xy 91.325989 -384.901682) (xy 91.377092 -384.931872) (xy 91.423862 -384.968414) (xy 91.465516 -385.010697)
			(xy 91.501354 -385.05801) (xy 91.530774 -385.109559) (xy 91.553283 -385.164479) (xy 91.568504 -385.221848)
			(xy 91.57618 -385.280703) (xy 91.576652 -385.31038) (xy 91.576125 -385.341443) (xy 91.567713 -385.402996)
			(xy 91.559888 -385.433062) (xy 91.557094 -385.443222) (xy 91.559634 -385.463034) (xy 91.607132 -385.54533)
			(xy 91.623134 -385.557522) (xy 91.633294 -385.560062) (xy 91.662411 -385.568034) (xy 91.718377 -385.590673)
			(xy 91.770882 -385.620472) (xy 91.819014 -385.656913) (xy 91.861939 -385.699365) (xy 91.898912 -385.747091)
			(xy 91.929291 -385.799262) (xy 91.952549 -385.854974) (xy 91.968283 -385.913259) (xy 91.976219 -385.973106)
			(xy 91.976702 -386.003292) (xy 91.976577 -386.017427) (xy 91.974795 -386.045641) (xy 91.973146 -386.05968)
			(xy 91.972387 -386.068287) (xy 91.976026 -386.085167) (xy 91.980258 -386.0927) (xy 91.996006 -386.1181)
			(xy 92.000711 -386.125164) (xy 92.01382 -386.135931) (xy 92.02166 -386.139182) (xy 92.045048 -386.148349)
			(xy 92.088943 -386.172773) (xy 92.128637 -386.203558) (xy 92.163216 -386.239994) (xy 92.191884 -386.281243)
			(xy 92.213981 -386.326354) (xy 92.228998 -386.37429) (xy 92.236589 -386.423946) (xy 92.237052 -386.449062)
			(xy 92.236635 -386.473264) (xy 92.22956 -386.52115) (xy 92.215572 -386.567489) (xy 92.194969 -386.611291)
			(xy 92.181934 -386.631688) (xy 92.177144 -386.639643) (xy 92.173112 -386.657756) (xy 92.17406 -386.666994)
			(xy 92.178378 -386.697982) (xy 92.180067 -386.707276) (xy 92.189343 -386.723718) (xy 92.196412 -386.729986)
			(xy 92.218489 -386.748681) (xy 92.258263 -386.790689) (xy 92.292428 -386.837374) (xy 92.320437 -386.887992)
			(xy 92.341846 -386.941735) (xy 92.356313 -386.997748) (xy 92.363607 -387.055137) (xy 92.364052 -387.084062)
			(xy 92.363461 -387.117383) (xy 92.353799 -387.183322) (xy 92.334673 -387.247161) (xy 92.321126 -387.27761)
			(xy 92.316862 -387.288071) (xy 92.316976 -387.310635) (xy 92.32672 -387.330988) (xy 92.335096 -387.33857)
			(xy 92.357325 -387.357264) (xy 92.39739 -387.399316) (xy 92.431812 -387.446098) (xy 92.460039 -387.49686)
			(xy 92.481618 -387.550785) (xy 92.4962 -387.607006) (xy 92.503553 -387.664621) (xy 92.504006 -387.693662)
			(xy 92.503546 -387.722668) (xy 92.496234 -387.780216) (xy 92.481711 -387.83638) (xy 92.460208 -387.890259)
			(xy 92.432071 -387.940989) (xy 92.39775 -387.987758) (xy 92.357795 -388.029817) (xy 92.335604 -388.0485)
			(xy 92.328492 -388.054088) (xy 92.319348 -388.069328) (xy 92.304108 -388.152132) (xy 92.306902 -388.169404)
			(xy 92.311474 -388.177532) (xy 92.324044 -388.200721) (xy 92.341921 -388.250341) (xy 92.351024 -388.302292)
			(xy 92.351606 -388.328662) (xy 92.351537 -388.338021) (xy 92.350394 -388.356703) (xy 92.34932 -388.366)
			(xy 92.348304 -388.37489) (xy 92.352114 -388.391654) (xy 92.396056 -388.461504) (xy 92.409772 -388.471918)
			(xy 92.418154 -388.474712) (xy 92.442185 -388.483172) (xy 92.487357 -388.506727) (xy 92.528162 -388.537228)
			(xy 92.56354 -388.573885) (xy 92.592575 -388.615745) (xy 92.614513 -388.661724) (xy 92.622116 -388.68604)
			(xy 92.62364 -388.691882) (xy 92.943934 -389.245602) (xy 92.947998 -389.24992) (xy 92.964186 -389.26763)
			(xy 92.991552 -389.307037) (xy 93.012638 -389.350133) (xy 93.026958 -389.395924) (xy 93.034183 -389.443355)
			(xy 93.034612 -389.467344) (xy 93.034123 -389.492133) (xy 93.026362 -389.541099) (xy 93.011038 -389.588248)
			(xy 92.988527 -389.632421) (xy 92.959385 -389.672529) (xy 92.924329 -389.707585) (xy 92.884221 -389.736727)
			(xy 92.840048 -389.759238) (xy 92.792899 -389.774562) (xy 92.743933 -389.782323) (xy 92.719144 -389.782812)
			(xy 92.693751 -389.782273) (xy 92.643619 -389.774149) (xy 92.595434 -389.758104) (xy 92.55044 -389.734552)
			(xy 92.509797 -389.704099) (xy 92.474553 -389.667533) (xy 92.445619 -389.625796) (xy 92.423739 -389.579965)
			(xy 92.416122 -389.555736) (xy 92.414598 -389.549894) (xy 92.094304 -388.996174) (xy 92.09024 -388.991856)
			(xy 92.074027 -388.974156) (xy 92.046606 -388.934762) (xy 92.025466 -388.89167) (xy 92.011094 -388.845875)
			(xy 92.003822 -388.798431) (xy 92.003372 -388.774432) (xy 92.003514 -388.76238) (xy 92.00542 -388.73835)
			(xy 92.007182 -388.726426) (xy 92.008452 -388.717536) (xy 92.005404 -388.700518) (xy 91.96324 -388.629652)
			(xy 91.950032 -388.618476) (xy 91.94165 -388.615428) (xy 91.919898 -388.607044) (xy 91.87904 -388.5846)
			(xy 91.84207 -388.556205) (xy 91.809848 -388.522518) (xy 91.783124 -388.484322) (xy 91.762518 -388.442507)
			(xy 91.748511 -388.398045) (xy 91.741428 -388.35197) (xy 91.74099 -388.328662) (xy 91.741557 -388.302289)
			(xy 91.75064 -388.250331) (xy 91.768528 -388.20071) (xy 91.781122 -388.177532) (xy 91.785694 -388.169404)
			(xy 91.788488 -388.152132) (xy 91.773248 -388.069328) (xy 91.764104 -388.054088) (xy 91.756992 -388.0485)
			(xy 91.73482 -388.029796) (xy 91.694873 -387.987734) (xy 91.660556 -387.940966) (xy 91.632417 -387.890239)
			(xy 91.610908 -387.836366) (xy 91.596371 -387.780209) (xy 91.589041 -387.722666) (xy 91.58859 -387.693662)
			(xy 91.589185 -387.660341) (xy 91.598845 -387.594402) (xy 91.617969 -387.530563) (xy 91.631516 -387.500114)
			(xy 91.635743 -387.489642) (xy 91.635638 -387.467088) (xy 91.625912 -387.446739) (xy 91.617546 -387.439154)
			(xy 91.595289 -387.420492) (xy 91.555224 -387.378436) (xy 91.520803 -387.331648) (xy 91.492579 -387.280881)
			(xy 91.471005 -387.22695) (xy 91.456429 -387.170724) (xy 91.449084 -387.113105) (xy 91.448636 -387.084062)
			(xy 91.449093 -387.055136) (xy 91.456377 -386.997744) (xy 91.470835 -386.941728) (xy 91.492238 -386.88798)
			(xy 91.520244 -386.837359) (xy 91.554407 -386.790671) (xy 91.594181 -386.74866) (xy 91.616276 -386.729986)
			(xy 91.62325 -386.723641) (xy 91.632506 -386.707235) (xy 91.63431 -386.697982) (xy 91.638628 -386.666994)
			(xy 91.639535 -386.657757) (xy 91.635509 -386.639657) (xy 91.630754 -386.631688) (xy 91.614442 -386.605845)
			(xy 91.590541 -386.549608) (xy 91.583256 -386.519928) (xy 91.581182 -386.511771) (xy 91.572491 -386.497368)
			(xy 91.566238 -386.491734) (xy 91.543124 -386.472684) (xy 91.536232 -386.467455) (xy 91.520011 -386.461479)
			(xy 91.511374 -386.461) (xy 91.481738 -386.45998) (xy 91.423073 -386.451332) (xy 91.366016 -386.435183)
			(xy 91.311522 -386.411801) (xy 91.260503 -386.38158) (xy 91.213813 -386.345024) (xy 91.172234 -386.302745)
			(xy 91.136461 -386.255452) (xy 91.107095 -386.203936) (xy 91.084625 -386.14906) (xy 91.069429 -386.091742)
			(xy 91.061761 -386.032941) (xy 91.061286 -386.003292) (xy 91.061806 -385.972229) (xy 91.070222 -385.910675)
			(xy 91.07805 -385.88061) (xy 91.080844 -385.87045) (xy 91.078304 -385.850638) (xy 91.030806 -385.768342)
			(xy 91.014804 -385.75615) (xy 91.004644 -385.75361) (xy 90.975526 -385.745639) (xy 90.919558 -385.723002)
			(xy 90.867052 -385.693205) (xy 90.818918 -385.656764) (xy 90.775992 -385.614312) (xy 90.739018 -385.566586)
			(xy 90.70864 -385.514414) (xy 90.685383 -385.458701) (xy 90.669651 -385.400415) (xy 90.661717 -385.340566)
			(xy 90.661236 -385.31038) (xy 90.66171 -385.279458) (xy 90.669992 -385.218171) (xy 90.686457 -385.158559)
			(xy 90.710805 -385.10171) (xy 90.72626 -385.074922) (xy 90.732356 -385.06527) (xy 90.734642 -385.042918)
			(xy 90.701114 -384.947668) (xy 90.685366 -384.931666) (xy 90.674698 -384.927602) (xy 90.65135 -384.918372)
			(xy 90.607505 -384.893919) (xy 90.56786 -384.863121) (xy 90.533325 -384.826685) (xy 90.504692 -384.785448)
			(xy 90.482621 -384.740357) (xy 90.467618 -384.692449) (xy 90.460028 -384.642823) (xy 90.45956 -384.617722)
			(xy 89.920826 -384.617722) (xy 89.920297 -384.644824) (xy 89.911487 -384.698307) (xy 89.9033 -384.724148)
			(xy 89.89949 -384.73507) (xy 89.90203 -384.757422) (xy 89.954608 -384.843274) (xy 89.973658 -384.85572)
			(xy 89.984834 -384.857498) (xy 90.014153 -384.862203) (xy 90.071323 -384.878252) (xy 90.125937 -384.901562)
			(xy 90.177077 -384.931741) (xy 90.223882 -384.968283) (xy 90.265567 -385.010572) (xy 90.301431 -385.057899)
			(xy 90.330871 -385.109467) (xy 90.353393 -385.164411) (xy 90.368617 -385.221807) (xy 90.376289 -385.28069)
			(xy 90.376756 -385.31038) (xy 90.376229 -385.341443) (xy 90.367818 -385.402997) (xy 90.359992 -385.433062)
			(xy 90.357198 -385.443222) (xy 90.359738 -385.463034) (xy 90.407236 -385.54533) (xy 90.423238 -385.557522)
			(xy 90.433398 -385.560062) (xy 90.462516 -385.568031) (xy 90.518482 -385.590671) (xy 90.570987 -385.62047)
			(xy 90.619119 -385.656912) (xy 90.662044 -385.699364) (xy 90.699016 -385.74709) (xy 90.729395 -385.799261)
			(xy 90.752653 -385.854973) (xy 90.768387 -385.913259) (xy 90.776323 -385.973106) (xy 90.776806 -386.003292)
			(xy 90.776681 -386.017427) (xy 90.774899 -386.045641) (xy 90.77325 -386.05968) (xy 90.77249 -386.068287)
			(xy 90.77613 -386.085167) (xy 90.780362 -386.0927) (xy 90.79611 -386.1181) (xy 90.800833 -386.125152)
			(xy 90.813923 -386.135937) (xy 90.821764 -386.139182) (xy 90.84512 -386.148392) (xy 90.888962 -386.172851)
			(xy 90.928605 -386.203654) (xy 90.963138 -386.240094) (xy 90.991768 -386.281333) (xy 91.013838 -386.326425)
			(xy 91.028842 -386.374334) (xy 91.036433 -386.42396) (xy 91.036902 -386.449062) (xy 91.036476 -386.473264)
			(xy 91.029403 -386.521149) (xy 91.015417 -386.567488) (xy 90.994817 -386.61129) (xy 90.981784 -386.631688)
			(xy 90.976997 -386.639645) (xy 90.972962 -386.657756) (xy 90.97391 -386.666994) (xy 90.978228 -386.697982)
			(xy 90.979901 -386.70728) (xy 90.989188 -386.723722) (xy 90.996262 -386.729986) (xy 91.01835 -386.748668)
			(xy 91.058122 -386.79068) (xy 91.092284 -386.837368) (xy 91.120291 -386.887988) (xy 91.141699 -386.941733)
			(xy 91.156164 -386.997746) (xy 91.163457 -387.055136) (xy 91.163902 -387.084062) (xy 91.163316 -387.117384)
			(xy 91.153652 -387.183322) (xy 91.134525 -387.247161) (xy 91.120976 -387.27761) (xy 91.116729 -387.288075)
			(xy 91.116843 -387.310634) (xy 91.126576 -387.330985) (xy 91.134946 -387.33857) (xy 91.157165 -387.357276)
			(xy 91.197232 -387.399324) (xy 91.231657 -387.446104) (xy 91.259886 -387.496864) (xy 91.281466 -387.550787)
			(xy 91.29605 -387.607008) (xy 91.303403 -387.664621) (xy 91.303856 -387.693662) (xy 91.303378 -387.722667)
			(xy 91.296067 -387.780214) (xy 91.281545 -387.836376) (xy 91.260045 -387.890255) (xy 91.231911 -387.940985)
			(xy 91.197594 -387.987755) (xy 91.157643 -388.029815) (xy 91.135454 -388.0485) (xy 91.128342 -388.054088)
			(xy 91.119198 -388.069328) (xy 91.103958 -388.152132) (xy 91.106752 -388.169404) (xy 91.111324 -388.177532)
			(xy 91.123898 -388.200719) (xy 91.141773 -388.25034) (xy 91.150874 -388.302291) (xy 91.151456 -388.328662)
			(xy 91.151387 -388.338021) (xy 91.150244 -388.356703) (xy 91.14917 -388.366) (xy 91.148154 -388.37489)
			(xy 91.151964 -388.391654) (xy 91.195906 -388.461504) (xy 91.209622 -388.471918) (xy 91.218004 -388.474712)
			(xy 91.242025 -388.483199) (xy 91.287198 -388.506747) (xy 91.328005 -388.537242) (xy 91.363385 -388.573893)
			(xy 91.392422 -388.61575) (xy 91.414362 -388.661725) (xy 91.421966 -388.68604) (xy 91.42349 -388.691882)
			(xy 91.743784 -389.245602) (xy 91.747848 -389.24992) (xy 91.764048 -389.267631) (xy 91.791471 -389.307022)
			(xy 91.812613 -389.350111) (xy 91.826988 -389.395904) (xy 91.834264 -389.443346) (xy 91.834716 -389.467344)
			(xy 91.834247 -389.492147) (xy 91.826477 -389.541141) (xy 91.811137 -389.588316) (xy 91.788603 -389.632509)
			(xy 91.759431 -389.672631) (xy 91.72434 -389.707694) (xy 91.684195 -389.736834) (xy 91.639984 -389.759332)
			(xy 91.592798 -389.774636) (xy 91.543797 -389.782366) (xy 91.518994 -389.782812) (xy 91.493599 -389.782317)
			(xy 91.443466 -389.774185) (xy 91.39528 -389.758133) (xy 91.350286 -389.734574) (xy 91.309643 -389.704116)
			(xy 91.2744 -389.667544) (xy 91.245467 -389.625802) (xy 91.223589 -389.579967) (xy 91.215972 -389.555736)
			(xy 91.214448 -389.549894) (xy 90.894154 -388.996174) (xy 90.89009 -388.991856) (xy 90.873937 -388.974117)
			(xy 90.846566 -388.934717) (xy 90.825474 -388.891628) (xy 90.811145 -388.845844) (xy 90.80391 -388.798419)
			(xy 90.803476 -388.774432) (xy 90.803556 -388.762384) (xy 90.805339 -388.738355) (xy 90.807032 -388.726426)
			(xy 90.808302 -388.717536) (xy 90.805254 -388.700518) (xy 90.76309 -388.629652) (xy 90.749882 -388.618476)
			(xy 90.7415 -388.615428) (xy 90.719759 -388.607016) (xy 90.678899 -388.584579) (xy 90.641928 -388.556189)
			(xy 90.609704 -388.522506) (xy 90.582977 -388.484315) (xy 90.56237 -388.442502) (xy 90.548362 -388.398042)
			(xy 90.541278 -388.351969) (xy 90.54084 -388.328662) (xy 90.541401 -388.302289) (xy 90.550485 -388.25033)
			(xy 90.568376 -388.20071) (xy 90.580972 -388.177532) (xy 90.585544 -388.169404) (xy 90.588338 -388.152132)
			(xy 90.573098 -388.069328) (xy 90.563954 -388.054088) (xy 90.556842 -388.0485) (xy 90.53468 -388.029784)
			(xy 90.494731 -387.987725) (xy 90.460411 -387.94096) (xy 90.432271 -387.890235) (xy 90.41076 -387.836364)
			(xy 90.396222 -387.780208) (xy 90.388891 -387.722666) (xy 90.38844 -387.693662) (xy 90.38904 -387.660341)
			(xy 90.398699 -387.594403) (xy 90.417821 -387.530563) (xy 90.431366 -387.500114) (xy 90.43561 -387.489646)
			(xy 90.435505 -387.467087) (xy 90.425769 -387.446736) (xy 90.417396 -387.439154) (xy 90.395128 -387.420504)
			(xy 90.355066 -387.378444) (xy 90.320648 -387.331654) (xy 90.292426 -387.280885) (xy 90.270853 -387.226953)
			(xy 90.256278 -387.170725) (xy 90.248934 -387.113105) (xy 90.248486 -387.084062) (xy 90.248925 -387.055135)
			(xy 90.256209 -386.997742) (xy 90.270669 -386.941724) (xy 90.292075 -386.887976) (xy 90.320084 -386.837355)
			(xy 90.35425 -386.790667) (xy 90.394029 -386.748659) (xy 90.416126 -386.729986) (xy 90.423092 -386.723633)
			(xy 90.432354 -386.707234) (xy 90.43416 -386.697982) (xy 90.438478 -386.666994) (xy 90.439377 -386.657757)
			(xy 90.435355 -386.639658) (xy 90.430604 -386.631688) (xy 90.414296 -386.605842) (xy 90.390392 -386.549607)
			(xy 90.383106 -386.519928) (xy 90.381045 -386.511766) (xy 90.372345 -386.497365) (xy 90.366088 -386.491734)
			(xy 90.342974 -386.472684) (xy 90.336154 -386.467463) (xy 90.320054 -386.461502) (xy 90.311478 -386.461)
			(xy 90.281842 -386.459976) (xy 90.223178 -386.451329) (xy 90.166121 -386.43518) (xy 90.111627 -386.411799)
			(xy 90.060607 -386.381578) (xy 90.013917 -386.345022) (xy 89.972338 -386.302744) (xy 89.936566 -386.255451)
			(xy 89.907199 -386.203936) (xy 89.884729 -386.149059) (xy 89.869533 -386.091741) (xy 89.861865 -386.032941)
			(xy 89.86139 -386.003292) (xy 89.86191 -385.972229) (xy 89.870326 -385.910675) (xy 89.878154 -385.88061)
			(xy 89.880948 -385.87045) (xy 89.878408 -385.850638) (xy 89.83091 -385.768342) (xy 89.814908 -385.75615)
			(xy 89.804748 -385.75361) (xy 89.775631 -385.745636) (xy 89.719663 -385.723) (xy 89.667156 -385.693203)
			(xy 89.619022 -385.656763) (xy 89.576096 -385.614311) (xy 89.539123 -385.566585) (xy 89.508744 -385.514414)
			(xy 89.485487 -385.458701) (xy 89.469755 -385.400415) (xy 89.461821 -385.340566) (xy 89.46134 -385.31038)
			(xy 89.46186 -385.279492) (xy 89.470166 -385.218276) (xy 89.486624 -385.158732) (xy 89.510936 -385.10194)
			(xy 89.526364 -385.075176) (xy 89.532206 -385.06527) (xy 89.534492 -385.042918) (xy 89.501218 -384.947668)
			(xy 89.48547 -384.931666) (xy 89.474802 -384.927602) (xy 89.451422 -384.918415) (xy 89.407525 -384.893997)
			(xy 89.367828 -384.863217) (xy 89.333246 -384.826784) (xy 89.304576 -384.785538) (xy 89.282479 -384.740428)
			(xy 89.267462 -384.692493) (xy 89.259872 -384.642838) (xy 89.25941 -384.617722) (xy 88.72093 -384.617722)
			(xy 88.720401 -384.644824) (xy 88.711591 -384.698307) (xy 88.703404 -384.724148) (xy 88.699594 -384.73507)
			(xy 88.702134 -384.757422) (xy 88.754712 -384.843274) (xy 88.773762 -384.85572) (xy 88.784938 -384.857498)
			(xy 88.814257 -384.8622) (xy 88.871428 -384.878249) (xy 88.926042 -384.90156) (xy 88.977181 -384.931739)
			(xy 89.023987 -384.968281) (xy 89.065672 -385.010571) (xy 89.101535 -385.057898) (xy 89.130976 -385.109467)
			(xy 89.153497 -385.164411) (xy 89.168721 -385.221807) (xy 89.176393 -385.28069) (xy 89.17686 -385.31038)
			(xy 89.176337 -385.341506) (xy 89.167931 -385.403188) (xy 89.160096 -385.433316) (xy 89.157302 -385.443476)
			(xy 89.159842 -385.463542) (xy 89.207086 -385.54533) (xy 89.223088 -385.557522) (xy 89.233248 -385.560062)
			(xy 89.262357 -385.568064) (xy 89.318323 -385.590698) (xy 89.370829 -385.620492) (xy 89.418962 -385.656929)
			(xy 89.461889 -385.699377) (xy 89.498863 -385.7471) (xy 89.529243 -385.799269) (xy 89.552502 -385.854978)
			(xy 89.568236 -385.913261) (xy 89.576173 -385.973107) (xy 89.576656 -386.003292) (xy 89.576531 -386.017427)
			(xy 89.574749 -386.045641) (xy 89.5731 -386.05968) (xy 89.572333 -386.068287) (xy 89.575976 -386.085168)
			(xy 89.580212 -386.0927) (xy 89.59596 -386.1181) (xy 89.600679 -386.125153) (xy 89.613778 -386.135926)
			(xy 89.621614 -386.139182) (xy 89.644992 -386.148374) (xy 89.688888 -386.172792) (xy 89.728584 -386.203572)
			(xy 89.763165 -386.240005) (xy 89.791835 -386.28125) (xy 89.813933 -386.326359) (xy 89.828951 -386.374292)
			(xy 89.836543 -386.423946) (xy 89.837006 -386.449062) (xy 89.83658 -386.473264) (xy 89.829506 -386.521149)
			(xy 89.81552 -386.567488) (xy 89.794921 -386.61129) (xy 89.781888 -386.631688) (xy 89.777101 -386.639645)
			(xy 89.773066 -386.657756) (xy 89.774014 -386.666994) (xy 89.778332 -386.697982) (xy 89.780004 -386.707281)
			(xy 89.789291 -386.723722) (xy 89.796366 -386.729986) (xy 89.818455 -386.748667) (xy 89.858226 -386.790679)
			(xy 89.892388 -386.837367) (xy 89.920396 -386.887987) (xy 89.941803 -386.941732) (xy 89.956268 -386.997746)
			(xy 89.963561 -387.055136) (xy 89.964006 -387.084062) (xy 89.963419 -387.117384) (xy 89.953756 -387.183322)
			(xy 89.934629 -387.247161) (xy 89.92108 -387.27761) (xy 89.916831 -387.288075) (xy 89.916945 -387.310634)
			(xy 89.92668 -387.330985) (xy 89.93505 -387.33857) (xy 89.95727 -387.357275) (xy 89.997337 -387.399324)
			(xy 90.031761 -387.446104) (xy 90.05999 -387.496864) (xy 90.08157 -387.550787) (xy 90.096154 -387.607008)
			(xy 90.103507 -387.664621) (xy 90.10396 -387.693662) (xy 90.10348 -387.722667) (xy 90.09617 -387.780214)
			(xy 90.081648 -387.836376) (xy 90.060148 -387.890254) (xy 90.032014 -387.940985) (xy 89.997697 -387.987755)
			(xy 89.957747 -388.029815) (xy 89.935558 -388.0485) (xy 89.928446 -388.054088) (xy 89.919302 -388.069328)
			(xy 89.904062 -388.152132) (xy 89.906856 -388.169404) (xy 89.911428 -388.177532) (xy 89.924002 -388.200719)
			(xy 89.941877 -388.25034) (xy 89.950978 -388.302291) (xy 89.95156 -388.328662) (xy 89.951491 -388.338021)
			(xy 89.950348 -388.356703) (xy 89.949274 -388.366) (xy 89.948258 -388.37489) (xy 89.952068 -388.391654)
			(xy 89.99601 -388.461504) (xy 90.009726 -388.471918) (xy 90.018108 -388.474712) (xy 90.04213 -388.483197)
			(xy 90.087303 -388.506745) (xy 90.128109 -388.537241) (xy 90.16349 -388.573893) (xy 90.192527 -388.61575)
			(xy 90.214466 -388.661725) (xy 90.22207 -388.68604) (xy 90.223594 -388.691882) (xy 90.543888 -389.245602)
			(xy 90.547952 -389.24992) (xy 90.564152 -389.267631) (xy 90.591575 -389.307022) (xy 90.612718 -389.350111)
			(xy 90.627092 -389.395904) (xy 90.634368 -389.443346) (xy 90.63482 -389.467344) (xy 90.634446 -389.492152)
			(xy 90.626674 -389.541155) (xy 90.611328 -389.588338) (xy 90.588785 -389.632537) (xy 90.559603 -389.672664)
			(xy 90.5245 -389.707728) (xy 90.484342 -389.736866) (xy 90.440118 -389.75936) (xy 90.392918 -389.774655)
			(xy 90.343906 -389.782374) (xy 90.319098 -389.782812) (xy 90.293704 -389.782313) (xy 90.24357 -389.774182)
			(xy 90.195384 -389.758131) (xy 90.15039 -389.734572) (xy 90.109747 -389.704114) (xy 90.074504 -389.667543)
			(xy 90.045571 -389.625802) (xy 90.023693 -389.579967) (xy 90.016076 -389.555736) (xy 90.014552 -389.549894)
			(xy 89.694258 -388.996174) (xy 89.690194 -388.991856) (xy 89.674041 -388.974116) (xy 89.646671 -388.934716)
			(xy 89.625578 -388.891628) (xy 89.611249 -388.845844) (xy 89.604014 -388.798419) (xy 89.60358 -388.774432)
			(xy 89.60366 -388.762384) (xy 89.605443 -388.738355) (xy 89.607136 -388.726426) (xy 89.608406 -388.717536)
			(xy 89.605358 -388.700518) (xy 89.563194 -388.629652) (xy 89.549986 -388.618476) (xy 89.541604 -388.615428)
			(xy 89.519864 -388.607014) (xy 89.479004 -388.584578) (xy 89.442032 -388.556188) (xy 89.409808 -388.522505)
			(xy 89.383082 -388.484314) (xy 89.362474 -388.442502) (xy 89.348466 -388.398042) (xy 89.341382 -388.351969)
			(xy 89.340944 -388.328662) (xy 89.341504 -388.302289) (xy 89.350588 -388.25033) (xy 89.36848 -388.20071)
			(xy 89.381076 -388.177532) (xy 89.385648 -388.169404) (xy 89.388442 -388.152132) (xy 89.373202 -388.069328)
			(xy 89.364058 -388.054088) (xy 89.356946 -388.0485) (xy 89.334764 -388.029807) (xy 89.29482 -387.987742)
			(xy 89.260505 -387.940971) (xy 89.232368 -387.890243) (xy 89.21086 -387.836369) (xy 89.196325 -387.78021)
			(xy 89.188994 -387.722666) (xy 89.188544 -387.693662) (xy 89.189144 -387.660341) (xy 89.198802 -387.594403)
			(xy 89.217924 -387.530563) (xy 89.23147 -387.500114) (xy 89.235712 -387.489646) (xy 89.235608 -387.467087)
			(xy 89.225873 -387.446736) (xy 89.2175 -387.439154) (xy 89.195233 -387.420503) (xy 89.155171 -387.378444)
			(xy 89.120752 -387.331653) (xy 89.09253 -387.280884) (xy 89.070958 -387.226953) (xy 89.056382 -387.170725)
			(xy 89.049038 -387.113105) (xy 89.04859 -387.084062) (xy 89.049028 -387.055135) (xy 89.056312 -386.997742)
			(xy 89.070772 -386.941724) (xy 89.092178 -386.887976) (xy 89.120187 -386.837355) (xy 89.154354 -386.790667)
			(xy 89.194133 -386.748659) (xy 89.21623 -386.729986) (xy 89.223197 -386.723634) (xy 89.232458 -386.707234)
			(xy 89.234264 -386.697982) (xy 89.238582 -386.666994) (xy 89.239481 -386.657757) (xy 89.235459 -386.639658)
			(xy 89.230708 -386.631688) (xy 89.2144 -386.605842) (xy 89.190497 -386.549607) (xy 89.18321 -386.519928)
			(xy 89.181148 -386.511767) (xy 89.172449 -386.497365) (xy 89.166192 -386.491734) (xy 89.143078 -386.472684)
			(xy 89.136199 -386.467437) (xy 89.119968 -386.461472) (xy 89.111328 -386.461) (xy 89.08169 -386.460022)
			(xy 89.023024 -386.451369) (xy 88.965967 -386.435214) (xy 88.911472 -386.411827) (xy 88.860453 -386.381601)
			(xy 88.813764 -386.345041) (xy 88.772185 -386.302759) (xy 88.736413 -386.255463) (xy 88.707047 -386.203944)
			(xy 88.684578 -386.149065) (xy 88.669383 -386.091745) (xy 88.661715 -386.032942) (xy 88.66124 -386.003292)
			(xy 88.661761 -385.972229) (xy 88.670177 -385.910675) (xy 88.678004 -385.88061) (xy 88.680798 -385.87045)
			(xy 88.678258 -385.850638) (xy 88.63076 -385.768342) (xy 88.614758 -385.75615) (xy 88.604598 -385.75361)
			(xy 88.575503 -385.745601) (xy 88.519577 -385.722931) (xy 88.467112 -385.693111) (xy 88.419019 -385.656659)
			(xy 88.376129 -385.614206) (xy 88.339188 -385.566487) (xy 88.308833 -385.51433) (xy 88.285592 -385.458638)
			(xy 88.269867 -385.400376) (xy 88.261931 -385.340553) (xy 88.261444 -385.31038) (xy 88.261964 -385.279492)
			(xy 88.27027 -385.218276) (xy 88.286728 -385.158732) (xy 88.31104 -385.10194) (xy 88.326468 -385.075176)
			(xy 88.33231 -385.06527) (xy 88.334596 -385.042918) (xy 88.301322 -384.947668) (xy 88.285574 -384.931666)
			(xy 88.274906 -384.927602) (xy 88.251527 -384.918413) (xy 88.207629 -384.893995) (xy 88.167932 -384.863216)
			(xy 88.133351 -384.826783) (xy 88.104681 -384.785537) (xy 88.082583 -384.740427) (xy 88.067566 -384.692493)
			(xy 88.059976 -384.642838) (xy 88.059514 -384.617722) (xy 87.52078 -384.617722) (xy 87.520248 -384.644824)
			(xy 87.51144 -384.698307) (xy 87.503254 -384.724148) (xy 87.499444 -384.73507) (xy 87.501984 -384.757422)
			(xy 87.554562 -384.843274) (xy 87.573612 -384.85572) (xy 87.584788 -384.857498) (xy 87.6141 -384.862239)
			(xy 87.671271 -384.878282) (xy 87.725885 -384.901587) (xy 87.777025 -384.931762) (xy 87.823831 -384.968299)
			(xy 87.865518 -385.010585) (xy 87.901383 -385.057909) (xy 87.930824 -385.109475) (xy 87.953346 -385.164416)
			(xy 87.968571 -385.22181) (xy 87.976243 -385.280691) (xy 87.97671 -385.31038) (xy 87.976185 -385.341443)
			(xy 87.967772 -385.402997) (xy 87.959946 -385.433062) (xy 87.957152 -385.443222) (xy 87.959692 -385.463034)
			(xy 88.00719 -385.54533) (xy 88.023192 -385.557522) (xy 88.033352 -385.560062) (xy 88.062462 -385.568062)
			(xy 88.118428 -385.590696) (xy 88.170933 -385.62049) (xy 88.219067 -385.656928) (xy 88.261993 -385.699376)
			(xy 88.298967 -385.747099) (xy 88.329347 -385.799268) (xy 88.352606 -385.854978) (xy 88.36834 -385.913261)
			(xy 88.376277 -385.973107) (xy 88.37676 -386.003292) (xy 88.376635 -386.017427) (xy 88.374853 -386.045641)
			(xy 88.373204 -386.05968) (xy 88.372437 -386.068287) (xy 88.37608 -386.085168) (xy 88.380316 -386.0927)
			(xy 88.396064 -386.1181) (xy 88.400782 -386.125154) (xy 88.413882 -386.135926) (xy 88.421718 -386.139182)
			(xy 88.445097 -386.148372) (xy 88.488993 -386.172791) (xy 88.528689 -386.203571) (xy 88.563269 -386.240004)
			(xy 88.591939 -386.281249) (xy 88.614037 -386.326359) (xy 88.629055 -386.374292) (xy 88.636647 -386.423946)
			(xy 88.63711 -386.449062) (xy 88.636683 -386.473264) (xy 88.62961 -386.521149) (xy 88.615624 -386.567488)
			(xy 88.595025 -386.61129) (xy 88.581992 -386.631688) (xy 88.577205 -386.639646) (xy 88.57317 -386.657756)
			(xy 88.574118 -386.666994) (xy 88.578436 -386.697982) (xy 88.580107 -386.707281) (xy 88.589395 -386.723722)
			(xy 88.59647 -386.729986) (xy 88.61856 -386.748666) (xy 88.658331 -386.790679) (xy 88.692493 -386.837367)
			(xy 88.7205 -386.887987) (xy 88.741907 -386.941732) (xy 88.756372 -386.997746) (xy 88.763665 -387.055136)
			(xy 88.76411 -387.084062) (xy 88.763523 -387.117384) (xy 88.75386 -387.183322) (xy 88.734732 -387.247161)
			(xy 88.721184 -387.27761) (xy 88.716934 -387.288074) (xy 88.717048 -387.310634) (xy 88.726783 -387.330986)
			(xy 88.735154 -387.33857) (xy 88.757375 -387.357274) (xy 88.797441 -387.399323) (xy 88.831865 -387.446103)
			(xy 88.860094 -387.496863) (xy 88.881674 -387.550787) (xy 88.896258 -387.607007) (xy 88.903611 -387.664621)
			(xy 88.904064 -387.693662) (xy 88.903583 -387.722667) (xy 88.896272 -387.780214) (xy 88.881751 -387.836376)
			(xy 88.860251 -387.890254) (xy 88.832117 -387.940984) (xy 88.797801 -387.987755) (xy 88.757851 -388.029815)
			(xy 88.735662 -388.0485) (xy 88.72855 -388.054088) (xy 88.719406 -388.069328) (xy 88.704166 -388.152132)
			(xy 88.70696 -388.169404) (xy 88.711532 -388.177532) (xy 88.724106 -388.200719) (xy 88.741981 -388.25034)
			(xy 88.751082 -388.302291) (xy 88.751664 -388.328662) (xy 88.751595 -388.338021) (xy 88.750452 -388.356703)
			(xy 88.749378 -388.366) (xy 88.748362 -388.37489) (xy 88.752172 -388.391654) (xy 88.796114 -388.461504)
			(xy 88.80983 -388.471918) (xy 88.818212 -388.474712) (xy 88.842312 -388.483186) (xy 88.887603 -388.506813)
			(xy 88.928497 -388.537425) (xy 88.963928 -388.574224) (xy 88.992971 -388.616248) (xy 89.014866 -388.6624)
			(xy 89.022428 -388.686802) (xy 89.023952 -388.692644) (xy 89.343738 -389.245602) (xy 89.347802 -389.24992)
			(xy 89.36399 -389.267629) (xy 89.391356 -389.307037) (xy 89.412442 -389.350133) (xy 89.426762 -389.395924)
			(xy 89.433987 -389.443355) (xy 89.434416 -389.467344) (xy 89.433923 -389.492132) (xy 89.426162 -389.541098)
			(xy 89.410838 -389.588247) (xy 89.388328 -389.63242) (xy 89.359187 -389.672528) (xy 89.324131 -389.707584)
			(xy 89.284023 -389.736726) (xy 89.239851 -389.759236) (xy 89.192702 -389.774561) (xy 89.143736 -389.782322)
			(xy 89.118948 -389.782812) (xy 89.093555 -389.782269) (xy 89.043423 -389.774146) (xy 88.995239 -389.758102)
			(xy 88.950245 -389.73455) (xy 88.909601 -389.704098) (xy 88.874358 -389.667532) (xy 88.845423 -389.625796)
			(xy 88.823543 -389.579965) (xy 88.815926 -389.555736) (xy 88.814402 -389.549894) (xy 88.493854 -388.995412)
			(xy 88.48979 -388.991094) (xy 88.473697 -388.973428) (xy 88.446507 -388.934131) (xy 88.425553 -388.891183)
			(xy 88.411315 -388.845567) (xy 88.404119 -388.798325) (xy 88.403684 -388.774432) (xy 88.403764 -388.762384)
			(xy 88.405547 -388.738355) (xy 88.40724 -388.726426) (xy 88.40851 -388.717536) (xy 88.405462 -388.700518)
			(xy 88.363298 -388.629652) (xy 88.35009 -388.618476) (xy 88.341708 -388.615428) (xy 88.319968 -388.607012)
			(xy 88.279109 -388.584576) (xy 88.242137 -388.556187) (xy 88.209913 -388.522505) (xy 88.183186 -388.484313)
			(xy 88.162578 -388.442502) (xy 88.14857 -388.398042) (xy 88.141486 -388.351969) (xy 88.141048 -388.328662)
			(xy 88.141608 -388.302289) (xy 88.150692 -388.25033) (xy 88.168583 -388.20071) (xy 88.18118 -388.177532)
			(xy 88.185752 -388.169404) (xy 88.188546 -388.152132) (xy 88.173306 -388.069328) (xy 88.164162 -388.054088)
			(xy 88.15705 -388.0485) (xy 88.134869 -388.029806) (xy 88.094924 -387.987741) (xy 88.060609 -387.940971)
			(xy 88.032473 -387.890242) (xy 88.010964 -387.836368) (xy 87.996429 -387.78021) (xy 87.989098 -387.722666)
			(xy 87.988648 -387.693662) (xy 87.989247 -387.660341) (xy 87.998906 -387.594403) (xy 88.018028 -387.530563)
			(xy 88.031574 -387.500114) (xy 88.035815 -387.489646) (xy 88.03571 -387.467087) (xy 88.025976 -387.446736)
			(xy 88.017604 -387.439154) (xy 87.995338 -387.420502) (xy 87.955275 -387.378443) (xy 87.920857 -387.331653)
			(xy 87.892634 -387.280884) (xy 87.871062 -387.226952) (xy 87.856486 -387.170725) (xy 87.849142 -387.113105)
			(xy 87.848694 -387.084062) (xy 87.84913 -387.055135) (xy 87.856415 -386.997741) (xy 87.870875 -386.941724)
			(xy 87.892281 -386.887976) (xy 87.92029 -386.837354) (xy 87.954457 -386.790667) (xy 87.994236 -386.748659)
			(xy 88.016334 -386.729986) (xy 88.023301 -386.723634) (xy 88.032562 -386.707234) (xy 88.034368 -386.697982)
			(xy 88.038686 -386.666994) (xy 88.039584 -386.657757) (xy 88.035563 -386.639658) (xy 88.030812 -386.631688)
			(xy 88.014505 -386.605842) (xy 87.990601 -386.549607) (xy 87.983314 -386.519928) (xy 87.981251 -386.511767)
			(xy 87.972553 -386.497365) (xy 87.966296 -386.491734) (xy 87.943182 -386.472684) (xy 87.936302 -386.467439)
			(xy 87.920071 -386.461473) (xy 87.911432 -386.461) (xy 87.881794 -386.460018) (xy 87.823129 -386.451365)
			(xy 87.766071 -386.435211) (xy 87.711577 -386.411825) (xy 87.660558 -386.381599) (xy 87.613868 -386.34504)
			(xy 87.572289 -386.302758) (xy 87.536518 -386.255462) (xy 87.507151 -386.203944) (xy 87.484683 -386.149065)
			(xy 87.469487 -386.091745) (xy 87.461819 -386.032942) (xy 87.461344 -386.003292) (xy 87.461865 -385.972229)
			(xy 87.470281 -385.910675) (xy 87.478108 -385.88061) (xy 87.480902 -385.87045) (xy 87.478362 -385.850638)
			(xy 87.430864 -385.768342) (xy 87.414862 -385.75615) (xy 87.404702 -385.75361) (xy 87.375576 -385.745666)
			(xy 87.319609 -385.723025) (xy 87.267103 -385.693223) (xy 87.21897 -385.656778) (xy 87.176045 -385.614323)
			(xy 87.139073 -385.566594) (xy 87.108696 -385.51442) (xy 87.08544 -385.458705) (xy 87.069708 -385.400417)
			(xy 87.061775 -385.340567) (xy 87.061294 -385.31038) (xy 87.061821 -385.279492) (xy 87.070126 -385.218277)
			(xy 87.086582 -385.158733) (xy 87.110892 -385.101941) (xy 87.126318 -385.075176) (xy 87.13216 -385.06527)
			(xy 87.134446 -385.042918) (xy 87.101172 -384.947668) (xy 87.085424 -384.931666) (xy 87.074756 -384.927602)
			(xy 87.051366 -384.91844) (xy 87.00747 -384.894016) (xy 86.967775 -384.863231) (xy 86.933195 -384.826794)
			(xy 86.904527 -384.785545) (xy 86.882431 -384.740432) (xy 86.867415 -384.692496) (xy 86.859826 -384.642839)
			(xy 86.859364 -384.617722) (xy 86.320884 -384.617722) (xy 86.320352 -384.644824) (xy 86.311544 -384.698307)
			(xy 86.303358 -384.724148) (xy 86.299548 -384.73507) (xy 86.302088 -384.757422) (xy 86.354666 -384.843274)
			(xy 86.373716 -384.85572) (xy 86.384892 -384.857498) (xy 86.414205 -384.862236) (xy 86.471375 -384.87828)
			(xy 86.525989 -384.901585) (xy 86.577129 -384.93176) (xy 86.623936 -384.968298) (xy 86.665622 -385.010584)
			(xy 86.701487 -385.057908) (xy 86.730928 -385.109474) (xy 86.75345 -385.164416) (xy 86.768675 -385.221809)
			(xy 86.776347 -385.280691) (xy 86.776814 -385.31038) (xy 86.776288 -385.341443) (xy 86.767876 -385.402997)
			(xy 86.76005 -385.433062) (xy 86.757256 -385.443222) (xy 86.759796 -385.463034) (xy 86.807294 -385.54533)
			(xy 86.823296 -385.557522) (xy 86.833456 -385.560062) (xy 86.862566 -385.568059) (xy 86.918533 -385.590694)
			(xy 86.971038 -385.620489) (xy 87.019171 -385.656927) (xy 87.062097 -385.699375) (xy 87.099071 -385.747098)
			(xy 87.129451 -385.799267) (xy 87.15271 -385.854977) (xy 87.168444 -385.913261) (xy 87.176381 -385.973107)
			(xy 87.176864 -386.003292) (xy 87.176739 -386.017427) (xy 87.174957 -386.045641) (xy 87.173308 -386.05968)
			(xy 87.172554 -386.068287) (xy 87.17619 -386.085166) (xy 87.18042 -386.0927) (xy 87.196168 -386.1181)
			(xy 87.200872 -386.125167) (xy 87.213975 -386.135944) (xy 87.221822 -386.139182) (xy 87.245169 -386.148414)
			(xy 87.289012 -386.172868) (xy 87.328656 -386.203667) (xy 87.363191 -386.240103) (xy 87.391823 -386.281339)
			(xy 87.413895 -386.326429) (xy 87.428899 -386.374336) (xy 87.436491 -386.423961) (xy 87.43696 -386.449062)
			(xy 87.436541 -386.473264) (xy 87.429467 -386.52115) (xy 87.415479 -386.567489) (xy 87.394877 -386.611291)
			(xy 87.381842 -386.631688) (xy 87.377052 -386.639644) (xy 87.37302 -386.657756) (xy 87.373968 -386.666994)
			(xy 87.378286 -386.697982) (xy 87.379972 -386.707277) (xy 87.389251 -386.723719) (xy 87.39632 -386.729986)
			(xy 87.418399 -386.748679) (xy 87.458173 -386.790688) (xy 87.492337 -386.837373) (xy 87.520346 -386.887991)
			(xy 87.541755 -386.941735) (xy 87.556221 -386.997748) (xy 87.563515 -387.055137) (xy 87.56396 -387.084062)
			(xy 87.563368 -387.117383) (xy 87.553706 -387.183322) (xy 87.534581 -387.247161) (xy 87.521034 -387.27761)
			(xy 87.516768 -387.28807) (xy 87.516881 -387.310636) (xy 87.526626 -387.330989) (xy 87.535004 -387.33857)
			(xy 87.557235 -387.357262) (xy 87.597299 -387.399314) (xy 87.631721 -387.446097) (xy 87.659948 -387.496859)
			(xy 87.681526 -387.550784) (xy 87.696109 -387.607006) (xy 87.703461 -387.664621) (xy 87.703914 -387.693662)
			(xy 87.703451 -387.722668) (xy 87.69614 -387.780216) (xy 87.681616 -387.836379) (xy 87.660114 -387.890258)
			(xy 87.631977 -387.940988) (xy 87.597657 -387.987758) (xy 87.557703 -388.029816) (xy 87.535512 -388.0485)
			(xy 87.5284 -388.054088) (xy 87.519256 -388.069328) (xy 87.504016 -388.152132) (xy 87.50681 -388.169404)
			(xy 87.511382 -388.177532) (xy 87.523952 -388.200721) (xy 87.541829 -388.250341) (xy 87.550932 -388.302292)
			(xy 87.551514 -388.328662) (xy 87.551445 -388.338021) (xy 87.550302 -388.356703) (xy 87.549228 -388.366)
			(xy 87.548212 -388.37489) (xy 87.552022 -388.391654) (xy 87.595964 -388.461504) (xy 87.60968 -388.471918)
			(xy 87.618062 -388.474712) (xy 87.642095 -388.483168) (xy 87.687266 -388.506724) (xy 87.728071 -388.537226)
			(xy 87.763449 -388.573883) (xy 87.792484 -388.615744) (xy 87.814421 -388.661724) (xy 87.822024 -388.68604)
			(xy 87.823548 -388.691882) (xy 88.143842 -389.245602) (xy 88.147906 -389.24992) (xy 88.164095 -389.267628)
			(xy 88.19146 -389.307037) (xy 88.212546 -389.350133) (xy 88.226867 -389.395924) (xy 88.234091 -389.443355)
			(xy 88.23452 -389.467344) (xy 88.234147 -389.492139) (xy 88.226383 -389.541118) (xy 88.211052 -389.588279)
			(xy 88.188532 -389.632461) (xy 88.159377 -389.672577) (xy 88.124307 -389.707637) (xy 88.084183 -389.73678)
			(xy 88.039994 -389.759287) (xy 87.992828 -389.774604) (xy 87.943847 -389.782355) (xy 87.919052 -389.782812)
			(xy 87.893656 -389.782354) (xy 87.843521 -389.774216) (xy 87.795334 -389.758157) (xy 87.75034 -389.734593)
			(xy 87.709697 -389.704129) (xy 87.674456 -389.667553) (xy 87.645523 -389.625807) (xy 87.623646 -389.579968)
			(xy 87.61603 -389.555736) (xy 87.614506 -389.549894) (xy 87.294212 -388.996174) (xy 87.290148 -388.991856)
			(xy 87.273936 -388.974155) (xy 87.246515 -388.934761) (xy 87.225375 -388.89167) (xy 87.211003 -388.845874)
			(xy 87.20373 -388.798431) (xy 87.20328 -388.774432) (xy 87.203422 -388.76238) (xy 87.205328 -388.73835)
			(xy 87.20709 -388.726426) (xy 87.20836 -388.717536) (xy 87.205312 -388.700518) (xy 87.163148 -388.629652)
			(xy 87.14994 -388.618476) (xy 87.141558 -388.615428) (xy 87.119808 -388.607039) (xy 87.078949 -388.584597)
			(xy 87.041979 -388.556202) (xy 87.009757 -388.522516) (xy 86.983032 -388.484321) (xy 86.962427 -388.442507)
			(xy 86.948419 -388.398045) (xy 86.941336 -388.35197) (xy 86.940898 -388.328662) (xy 86.941464 -388.302289)
			(xy 86.950547 -388.250331) (xy 86.968435 -388.20071) (xy 86.98103 -388.177532) (xy 86.985602 -388.169404)
			(xy 86.988396 -388.152132) (xy 86.973156 -388.069328) (xy 86.964012 -388.054088) (xy 86.9569 -388.0485)
			(xy 86.934729 -388.029794) (xy 86.894782 -387.987733) (xy 86.860465 -387.940965) (xy 86.832326 -387.890239)
			(xy 86.810816 -387.836366) (xy 86.796279 -387.780209) (xy 86.788949 -387.722666) (xy 86.788498 -387.693662)
			(xy 86.789093 -387.660341) (xy 86.798753 -387.594402) (xy 86.817877 -387.530563) (xy 86.831424 -387.500114)
			(xy 86.835649 -387.489642) (xy 86.835543 -387.467089) (xy 86.825819 -387.446739) (xy 86.817454 -387.439154)
			(xy 86.795198 -387.42049) (xy 86.755133 -387.378434) (xy 86.720712 -387.331647) (xy 86.692488 -387.28088)
			(xy 86.670914 -387.22695) (xy 86.656337 -387.170724) (xy 86.648992 -387.113105) (xy 86.648544 -387.084062)
			(xy 86.648998 -387.055136) (xy 86.656282 -386.997744) (xy 86.670741 -386.941727) (xy 86.692144 -386.88798)
			(xy 86.72015 -386.837358) (xy 86.754314 -386.79067) (xy 86.794089 -386.74866) (xy 86.816184 -386.729986)
			(xy 86.82316 -386.723642) (xy 86.832415 -386.707236) (xy 86.834218 -386.697982) (xy 86.838536 -386.666994)
			(xy 86.839442 -386.657757) (xy 86.835416 -386.639657) (xy 86.830662 -386.631688) (xy 86.814351 -386.605845)
			(xy 86.79045 -386.549607) (xy 86.783164 -386.519928) (xy 86.781115 -386.511763) (xy 86.772408 -386.497363)
			(xy 86.766146 -386.491734) (xy 86.743032 -386.472684) (xy 86.736196 -386.467486) (xy 86.720108 -386.461511)
			(xy 86.711536 -386.461) (xy 86.681898 -386.460014) (xy 86.623233 -386.451362) (xy 86.566175 -386.435208)
			(xy 86.511681 -386.411823) (xy 86.460662 -386.381598) (xy 86.413972 -386.345038) (xy 86.372394 -386.302757)
			(xy 86.336622 -386.255461) (xy 86.307256 -386.203943) (xy 86.284787 -386.149064) (xy 86.269591 -386.091744)
			(xy 86.261923 -386.032942) (xy 86.261448 -386.003292) (xy 86.261969 -385.972229) (xy 86.270385 -385.910675)
			(xy 86.278212 -385.88061) (xy 86.281006 -385.87045) (xy 86.278466 -385.850638) (xy 86.230968 -385.768342)
			(xy 86.214966 -385.75615) (xy 86.204806 -385.75361) (xy 86.175681 -385.745664) (xy 86.119714 -385.723023)
			(xy 86.067208 -385.693221) (xy 86.019075 -385.656777) (xy 85.97615 -385.614322) (xy 85.939178 -385.566594)
			(xy 85.9088 -385.514419) (xy 85.885544 -385.458705) (xy 85.869812 -385.400417) (xy 85.861879 -385.340567)
			(xy 85.861398 -385.31038) (xy 85.861924 -385.279492) (xy 85.870229 -385.218277) (xy 85.886686 -385.158733)
			(xy 85.910996 -385.101941) (xy 85.926422 -385.075176) (xy 85.932264 -385.06527) (xy 85.93455 -385.042918)
			(xy 85.901276 -384.947668) (xy 85.885528 -384.931666) (xy 85.87486 -384.927602) (xy 85.851471 -384.918438)
			(xy 85.807575 -384.894014) (xy 85.76788 -384.86323) (xy 85.7333 -384.826793) (xy 85.704631 -384.785544)
			(xy 85.682535 -384.740432) (xy 85.667519 -384.692495) (xy 85.65993 -384.642839) (xy 85.659468 -384.617722)
			(xy 85.120988 -384.617722) (xy 85.120456 -384.644824) (xy 85.111648 -384.698306) (xy 85.103462 -384.724148)
			(xy 85.099652 -384.73507) (xy 85.102192 -384.757422) (xy 85.15477 -384.843528) (xy 85.173566 -384.85572)
			(xy 85.184996 -384.857498) (xy 85.214292 -384.862264) (xy 85.271427 -384.878344) (xy 85.326003 -384.901675)
			(xy 85.377105 -384.931866) (xy 85.423875 -384.96841) (xy 85.465529 -385.010694) (xy 85.501366 -385.058007)
			(xy 85.530787 -385.109557) (xy 85.553296 -385.164478) (xy 85.568516 -385.221847) (xy 85.576192 -385.280703)
			(xy 85.576664 -385.31038) (xy 85.576137 -385.341443) (xy 85.567725 -385.402996) (xy 85.5599 -385.433062)
			(xy 85.557106 -385.443222) (xy 85.559646 -385.463034) (xy 85.607144 -385.54533) (xy 85.623146 -385.557522)
			(xy 85.633306 -385.560062) (xy 85.662407 -385.568092) (xy 85.718373 -385.590721) (xy 85.77088 -385.620511)
			(xy 85.819014 -385.656944) (xy 85.861942 -385.699389) (xy 85.898917 -385.747109) (xy 85.929298 -385.799275)
			(xy 85.952558 -385.854982) (xy 85.968293 -385.913264) (xy 85.97623 -385.973108) (xy 85.976714 -386.003292)
			(xy 85.976589 -386.017427) (xy 85.974807 -386.045641) (xy 85.973158 -386.05968) (xy 85.972397 -386.068287)
			(xy 85.976037 -386.085167) (xy 85.98027 -386.0927) (xy 85.996018 -386.1181) (xy 86.000719 -386.125167)
			(xy 86.013831 -386.135932) (xy 86.021672 -386.139182) (xy 86.045062 -386.148343) (xy 86.088957 -386.172768)
			(xy 86.128651 -386.203554) (xy 86.163229 -386.239992) (xy 86.191897 -386.281241) (xy 86.213993 -386.326353)
			(xy 86.22901 -386.374289) (xy 86.236601 -386.423945) (xy 86.237064 -386.449062) (xy 86.236645 -386.473264)
			(xy 86.22957 -386.521149) (xy 86.215582 -386.567489) (xy 86.19498 -386.611291) (xy 86.181946 -386.631688)
			(xy 86.177156 -386.639644) (xy 86.173124 -386.657756) (xy 86.174072 -386.666994) (xy 86.17839 -386.697982)
			(xy 86.180075 -386.707277) (xy 86.189354 -386.723719) (xy 86.196424 -386.729986) (xy 86.218504 -386.748678)
			(xy 86.258277 -386.790687) (xy 86.292441 -386.837373) (xy 86.32045 -386.887991) (xy 86.341859 -386.941735)
			(xy 86.356325 -386.997747) (xy 86.363619 -387.055137) (xy 86.364064 -387.084062) (xy 86.363472 -387.117383)
			(xy 86.35381 -387.183322) (xy 86.334685 -387.247161) (xy 86.321138 -387.27761) (xy 86.31687 -387.28807)
			(xy 86.316984 -387.310636) (xy 86.32673 -387.330989) (xy 86.335108 -387.33857) (xy 86.35734 -387.357261)
			(xy 86.397404 -387.399314) (xy 86.431825 -387.446097) (xy 86.460052 -387.496859) (xy 86.48163 -387.550784)
			(xy 86.496213 -387.607006) (xy 86.503565 -387.664621) (xy 86.504018 -387.693662) (xy 86.503554 -387.722667)
			(xy 86.496242 -387.780216) (xy 86.481719 -387.836379) (xy 86.460217 -387.890258) (xy 86.43208 -387.940988)
			(xy 86.39776 -387.987757) (xy 86.357807 -388.029816) (xy 86.335616 -388.0485) (xy 86.328504 -388.054088)
			(xy 86.31936 -388.069328) (xy 86.30412 -388.152132) (xy 86.306914 -388.169404) (xy 86.311486 -388.177532)
			(xy 86.324057 -388.200721) (xy 86.341934 -388.250341) (xy 86.351036 -388.302292) (xy 86.351618 -388.328662)
			(xy 86.351549 -388.338021) (xy 86.350406 -388.356703) (xy 86.349332 -388.366) (xy 86.348316 -388.37489)
			(xy 86.352126 -388.391654) (xy 86.396068 -388.461504) (xy 86.409784 -388.471918) (xy 86.418166 -388.474712)
			(xy 86.442199 -388.483166) (xy 86.487371 -388.506722) (xy 86.528175 -388.537225) (xy 86.563553 -388.573883)
			(xy 86.592588 -388.615744) (xy 86.614525 -388.661724) (xy 86.622128 -388.68604) (xy 86.623652 -388.691882)
			(xy 86.943946 -389.245602) (xy 86.94801 -389.24992) (xy 86.9642 -389.267628) (xy 86.991565 -389.307036)
			(xy 87.01265 -389.350133) (xy 87.026971 -389.395924) (xy 87.034195 -389.443355) (xy 87.034624 -389.467344)
			(xy 87.034222 -389.492137) (xy 87.026459 -389.541112) (xy 87.011129 -389.588269) (xy 86.988611 -389.632447)
			(xy 86.95946 -389.672559) (xy 86.924392 -389.707617) (xy 86.884272 -389.736757) (xy 86.840087 -389.759263)
			(xy 86.792926 -389.774579) (xy 86.743949 -389.782329) (xy 86.719156 -389.782812) (xy 86.69376 -389.78235)
			(xy 86.643625 -389.774213) (xy 86.595439 -389.758155) (xy 86.550444 -389.734591) (xy 86.509802 -389.704128)
			(xy 86.47456 -389.667552) (xy 86.445627 -389.625807) (xy 86.42375 -389.579968) (xy 86.416134 -389.555736)
			(xy 86.41461 -389.549894) (xy 86.094316 -388.996174) (xy 86.090252 -388.991856) (xy 86.074041 -388.974155)
			(xy 86.046619 -388.934761) (xy 86.025479 -388.89167) (xy 86.011107 -388.845874) (xy 86.003834 -388.798431)
			(xy 86.003384 -388.774432) (xy 86.003526 -388.76238) (xy 86.005432 -388.73835) (xy 86.007194 -388.726426)
			(xy 86.008464 -388.717536) (xy 86.005416 -388.700518) (xy 85.963252 -388.629652) (xy 85.950044 -388.618476)
			(xy 85.941662 -388.615428) (xy 85.919913 -388.607037) (xy 85.879054 -388.584595) (xy 85.842084 -388.556201)
			(xy 85.809862 -388.522515) (xy 85.783137 -388.48432) (xy 85.762531 -388.442506) (xy 85.748523 -388.398045)
			(xy 85.74144 -388.35197) (xy 85.741002 -388.328662) (xy 85.741567 -388.302289) (xy 85.750651 -388.25033)
			(xy 85.768539 -388.20071) (xy 85.781134 -388.177532) (xy 85.785706 -388.169404) (xy 85.7885 -388.152132)
			(xy 85.77326 -388.069328) (xy 85.764116 -388.054088) (xy 85.757004 -388.0485) (xy 85.734834 -388.029793)
			(xy 85.694887 -387.987732) (xy 85.660569 -387.940964) (xy 85.63243 -387.890238) (xy 85.61092 -387.836366)
			(xy 85.596384 -387.780209) (xy 85.589053 -387.722666) (xy 85.588602 -387.693662) (xy 85.589196 -387.660341)
			(xy 85.598856 -387.594402) (xy 85.617981 -387.530563) (xy 85.631528 -387.500114) (xy 85.635751 -387.489641)
			(xy 85.635646 -387.467089) (xy 85.625923 -387.44674) (xy 85.617558 -387.439154) (xy 85.595303 -387.420489)
			(xy 85.555238 -387.378433) (xy 85.520817 -387.331646) (xy 85.492592 -387.28088) (xy 85.471018 -387.22695)
			(xy 85.456441 -387.170723) (xy 85.449096 -387.113105) (xy 85.448648 -387.084062) (xy 85.449101 -387.055136)
			(xy 85.456384 -386.997743) (xy 85.470843 -386.941727) (xy 85.492247 -386.887979) (xy 85.520254 -386.837358)
			(xy 85.554417 -386.79067) (xy 85.594192 -386.74866) (xy 85.616288 -386.729986) (xy 85.623264 -386.723643)
			(xy 85.632519 -386.707236) (xy 85.634322 -386.697982) (xy 85.63864 -386.666994) (xy 85.639545 -386.657757)
			(xy 85.63552 -386.639657) (xy 85.630766 -386.631688) (xy 85.614455 -386.605844) (xy 85.590554 -386.549607)
			(xy 85.583268 -386.519928) (xy 85.581218 -386.511763) (xy 85.572511 -386.497363) (xy 85.56625 -386.491734)
			(xy 85.543136 -386.472684) (xy 85.536241 -386.46746) (xy 85.520022 -386.461481) (xy 85.511386 -386.461)
			(xy 85.48175 -386.459969) (xy 85.423086 -386.451323) (xy 85.366029 -386.435174) (xy 85.311535 -386.411794)
			(xy 85.260516 -386.381574) (xy 85.213826 -386.345019) (xy 85.172247 -386.302742) (xy 85.136474 -386.255449)
			(xy 85.107107 -386.203934) (xy 85.084637 -386.149058) (xy 85.069441 -386.091741) (xy 85.061773 -386.032941)
			(xy 85.061298 -386.003292) (xy 85.061818 -385.972229) (xy 85.070234 -385.910675) (xy 85.078062 -385.88061)
			(xy 85.080856 -385.87045) (xy 85.078316 -385.850638) (xy 85.030818 -385.768342) (xy 85.014816 -385.75615)
			(xy 85.004656 -385.75361) (xy 84.97554 -385.745631) (xy 84.919572 -385.722995) (xy 84.867066 -385.6932)
			(xy 84.818931 -385.65676) (xy 84.776005 -385.614309) (xy 84.739031 -385.566584) (xy 84.708652 -385.514412)
			(xy 84.685395 -385.4587) (xy 84.669663 -385.400414) (xy 84.661729 -385.340566) (xy 84.661248 -385.31038)
			(xy 84.66172 -385.279458) (xy 84.670003 -385.218171) (xy 84.686468 -385.158559) (xy 84.710817 -385.101709)
			(xy 84.726272 -385.074922) (xy 84.732368 -385.06527) (xy 84.734654 -385.042918) (xy 84.701126 -384.947668)
			(xy 84.685378 -384.931666) (xy 84.67471 -384.927602) (xy 84.651365 -384.918366) (xy 84.60752 -384.893914)
			(xy 84.567874 -384.863117) (xy 84.533338 -384.826682) (xy 84.504705 -384.785446) (xy 84.482634 -384.740356)
			(xy 84.46763 -384.692448) (xy 84.46004 -384.642823) (xy 84.459572 -384.617722) (xy 83.920838 -384.617722)
			(xy 83.920309 -384.644824) (xy 83.911499 -384.698307) (xy 83.903312 -384.724148) (xy 83.899502 -384.73507)
			(xy 83.902042 -384.757422) (xy 83.95462 -384.843274) (xy 83.97367 -384.85572) (xy 83.984846 -384.857498)
			(xy 84.014166 -384.862193) (xy 84.071337 -384.878244) (xy 84.125951 -384.901555) (xy 84.17709 -384.931736)
			(xy 84.223895 -384.968278) (xy 84.26558 -385.010569) (xy 84.301444 -385.057896) (xy 84.330884 -385.109466)
			(xy 84.353405 -385.16441) (xy 84.36863 -385.221806) (xy 84.376301 -385.280689) (xy 84.376768 -385.31038)
			(xy 84.376241 -385.341443) (xy 84.367829 -385.402996) (xy 84.360004 -385.433062) (xy 84.35721 -385.443222)
			(xy 84.35975 -385.463034) (xy 84.407248 -385.54533) (xy 84.42325 -385.557522) (xy 84.43341 -385.560062)
			(xy 84.462511 -385.56809) (xy 84.518478 -385.590719) (xy 84.570984 -385.620509) (xy 84.619119 -385.656943)
			(xy 84.662046 -385.699388) (xy 84.699021 -385.747108) (xy 84.729403 -385.799274) (xy 84.752662 -385.854982)
			(xy 84.768397 -385.913263) (xy 84.776334 -385.973108) (xy 84.776818 -386.003292) (xy 84.776693 -386.017427)
			(xy 84.774911 -386.045641) (xy 84.773262 -386.05968) (xy 84.772501 -386.068287) (xy 84.776141 -386.085167)
			(xy 84.780374 -386.0927) (xy 84.796122 -386.1181) (xy 84.800841 -386.125155) (xy 84.813934 -386.135938)
			(xy 84.821776 -386.139182) (xy 84.845135 -386.148385) (xy 84.888976 -386.172845) (xy 84.928619 -386.20365)
			(xy 84.963151 -386.240091) (xy 84.991781 -386.281331) (xy 85.013851 -386.326424) (xy 85.028854 -386.374333)
			(xy 85.036446 -386.42396) (xy 85.036914 -386.449062) (xy 85.036486 -386.473264) (xy 85.029413 -386.521148)
			(xy 85.015428 -386.567488) (xy 84.994829 -386.61129) (xy 84.981796 -386.631688) (xy 84.97701 -386.639646)
			(xy 84.972974 -386.657756) (xy 84.973922 -386.666994) (xy 84.97824 -386.697982) (xy 84.97991 -386.707281)
			(xy 84.989199 -386.723722) (xy 84.996274 -386.729986) (xy 85.018364 -386.748665) (xy 85.058136 -386.790678)
			(xy 85.092297 -386.837366) (xy 85.120304 -386.887987) (xy 85.141711 -386.941732) (xy 85.156176 -386.997746)
			(xy 85.163469 -387.055136) (xy 85.163914 -387.084062) (xy 85.163327 -387.117384) (xy 85.153664 -387.183322)
			(xy 85.134536 -387.247161) (xy 85.120988 -387.27761) (xy 85.116737 -387.288074) (xy 85.116851 -387.310634)
			(xy 85.126587 -387.330986) (xy 85.134958 -387.33857) (xy 85.15718 -387.357273) (xy 85.197246 -387.399322)
			(xy 85.23167 -387.446103) (xy 85.259899 -387.496863) (xy 85.281478 -387.550787) (xy 85.296062 -387.607007)
			(xy 85.303415 -387.664621) (xy 85.303868 -387.693662) (xy 85.303385 -387.722667) (xy 85.296075 -387.780213)
			(xy 85.281553 -387.836376) (xy 85.260054 -387.890254) (xy 85.231921 -387.940984) (xy 85.197604 -387.987754)
			(xy 85.157655 -388.029815) (xy 85.135466 -388.0485) (xy 85.128354 -388.054088) (xy 85.11921 -388.069328)
			(xy 85.10397 -388.152132) (xy 85.106764 -388.169404) (xy 85.111336 -388.177532) (xy 85.123911 -388.200719)
			(xy 85.141785 -388.25034) (xy 85.150886 -388.302291) (xy 85.151468 -388.328662) (xy 85.151399 -388.338021)
			(xy 85.150256 -388.356703) (xy 85.149182 -388.366) (xy 85.148166 -388.37489) (xy 85.151976 -388.391654)
			(xy 85.195918 -388.461504) (xy 85.209634 -388.471918) (xy 85.218016 -388.474712) (xy 85.24204 -388.483193)
			(xy 85.287212 -388.506742) (xy 85.328018 -388.537239) (xy 85.363398 -388.573891) (xy 85.392435 -388.615749)
			(xy 85.414374 -388.661725) (xy 85.421978 -388.68604) (xy 85.423502 -388.691882) (xy 85.743796 -389.245602)
			(xy 85.74786 -389.24992) (xy 85.764062 -389.26763) (xy 85.791484 -389.307021) (xy 85.812626 -389.35011)
			(xy 85.827001 -389.395904) (xy 85.834276 -389.443346) (xy 85.834728 -389.467344) (xy 85.834346 -389.492151)
			(xy 85.826574 -389.541154) (xy 85.811228 -389.588336) (xy 85.788687 -389.632535) (xy 85.759506 -389.672661)
			(xy 85.724404 -389.707725) (xy 85.684246 -389.736864) (xy 85.640023 -389.759358) (xy 85.592825 -389.774653)
			(xy 85.543814 -389.782373) (xy 85.519006 -389.782812) (xy 85.493612 -389.782306) (xy 85.443478 -389.774177)
			(xy 85.395293 -389.758126) (xy 85.350299 -389.734568) (xy 85.309656 -389.704112) (xy 85.274413 -389.667541)
			(xy 85.245479 -389.625801) (xy 85.223601 -389.579966) (xy 85.215984 -389.555736) (xy 85.21446 -389.549894)
			(xy 84.894166 -388.996174) (xy 84.890102 -388.991856) (xy 84.873951 -388.974115) (xy 84.84658 -388.934716)
			(xy 84.825487 -388.891628) (xy 84.811157 -388.845844) (xy 84.803922 -388.798419) (xy 84.803488 -388.774432)
			(xy 84.803569 -388.762384) (xy 84.805352 -388.738355) (xy 84.807044 -388.726426) (xy 84.808314 -388.717536)
			(xy 84.805266 -388.700518) (xy 84.763102 -388.629652) (xy 84.749894 -388.618476) (xy 84.741512 -388.615428)
			(xy 84.719773 -388.60701) (xy 84.678914 -388.584574) (xy 84.641941 -388.556185) (xy 84.609717 -388.522504)
			(xy 84.58299 -388.484313) (xy 84.562383 -388.442501) (xy 84.548374 -388.398042) (xy 84.54129 -388.351969)
			(xy 84.540852 -388.328662) (xy 84.541424 -388.302289) (xy 84.550505 -388.250331) (xy 84.568391 -388.200711)
			(xy 84.580984 -388.177532) (xy 84.585556 -388.169404) (xy 84.58835 -388.152132) (xy 84.57311 -388.069328)
			(xy 84.563966 -388.054088) (xy 84.556854 -388.0485) (xy 84.534674 -388.029805) (xy 84.494729 -387.987741)
			(xy 84.460414 -387.94097) (xy 84.432277 -387.890242) (xy 84.410768 -387.836368) (xy 84.396233 -387.78021)
			(xy 84.388903 -387.722666) (xy 84.388452 -387.693662) (xy 84.389051 -387.660341) (xy 84.39871 -387.594403)
			(xy 84.417832 -387.530563) (xy 84.431378 -387.500114) (xy 84.435618 -387.489645) (xy 84.435513 -387.467087)
			(xy 84.425779 -387.446737) (xy 84.417408 -387.439154) (xy 84.395143 -387.420501) (xy 84.35508 -387.378442)
			(xy 84.320661 -387.331652) (xy 84.292438 -387.280884) (xy 84.270866 -387.226952) (xy 84.25629 -387.170725)
			(xy 84.248946 -387.113105) (xy 84.248498 -387.084062) (xy 84.248933 -387.055135) (xy 84.256217 -386.997741)
			(xy 84.270678 -386.941724) (xy 84.292084 -386.887975) (xy 84.320094 -386.837354) (xy 84.354261 -386.790667)
			(xy 84.39404 -386.748658) (xy 84.416138 -386.729986) (xy 84.423106 -386.723635) (xy 84.432367 -386.707234)
			(xy 84.434172 -386.697982) (xy 84.43849 -386.666994) (xy 84.439387 -386.657757) (xy 84.435366 -386.639658)
			(xy 84.430616 -386.631688) (xy 84.414309 -386.605842) (xy 84.390405 -386.549607) (xy 84.383118 -386.519928)
			(xy 84.381054 -386.511767) (xy 84.372357 -386.497366) (xy 84.3661 -386.491734) (xy 84.342986 -386.472684)
			(xy 84.336163 -386.467467) (xy 84.320065 -386.461504) (xy 84.31149 -386.461) (xy 84.281854 -386.459965)
			(xy 84.22319 -386.451319) (xy 84.166134 -386.435172) (xy 84.11164 -386.411792) (xy 84.06062 -386.381572)
			(xy 84.01393 -386.345017) (xy 83.972351 -386.30274) (xy 83.936578 -386.255448) (xy 83.907211 -386.203933)
			(xy 83.884741 -386.149058) (xy 83.869545 -386.09174) (xy 83.861877 -386.032941) (xy 83.861402 -386.003292)
			(xy 83.861921 -385.972229) (xy 83.870338 -385.910675) (xy 83.878166 -385.88061) (xy 83.88096 -385.87045)
			(xy 83.87842 -385.850638) (xy 83.830922 -385.768342) (xy 83.81492 -385.75615) (xy 83.80476 -385.75361)
			(xy 83.775645 -385.745627) (xy 83.719677 -385.722993) (xy 83.667171 -385.693197) (xy 83.619036 -385.656758)
			(xy 83.57611 -385.614308) (xy 83.539136 -385.566583) (xy 83.508757 -385.514412) (xy 83.485499 -385.4587)
			(xy 83.469767 -385.400414) (xy 83.461834 -385.340566) (xy 83.461352 -385.31038) (xy 83.46187 -385.279492)
			(xy 83.470177 -385.218276) (xy 83.486635 -385.158732) (xy 83.510948 -385.10194) (xy 83.526376 -385.075176)
			(xy 83.532218 -385.06527) (xy 83.534504 -385.042918) (xy 83.50123 -384.947668) (xy 83.485482 -384.931666)
			(xy 83.474814 -384.927602) (xy 83.451437 -384.918408) (xy 83.407539 -384.893992) (xy 83.367842 -384.863213)
			(xy 83.33326 -384.826781) (xy 83.304589 -384.785536) (xy 83.282491 -384.740426) (xy 83.267474 -384.692492)
			(xy 83.259884 -384.642838) (xy 83.259422 -384.617722) (xy 82.720942 -384.617722) (xy 82.720412 -384.644824)
			(xy 82.711603 -384.698307) (xy 82.703416 -384.724148) (xy 82.699606 -384.73507) (xy 82.702146 -384.757422)
			(xy 82.754724 -384.843274) (xy 82.773774 -384.85572) (xy 82.78495 -384.857498) (xy 82.814271 -384.86219)
			(xy 82.871441 -384.878241) (xy 82.926055 -384.901553) (xy 82.977194 -384.931734) (xy 83.024 -384.968277)
			(xy 83.065685 -385.010568) (xy 83.101548 -385.057895) (xy 83.130988 -385.109465) (xy 83.153509 -385.16441)
			(xy 83.168734 -385.221806) (xy 83.176405 -385.280689) (xy 83.176872 -385.31038) (xy 83.176349 -385.341506)
			(xy 83.167943 -385.403188) (xy 83.160108 -385.433316) (xy 83.157314 -385.443476) (xy 83.159854 -385.463542)
			(xy 83.207098 -385.54533) (xy 83.2231 -385.557522) (xy 83.23326 -385.560062) (xy 83.262371 -385.568056)
			(xy 83.318337 -385.590691) (xy 83.370843 -385.620487) (xy 83.418976 -385.656925) (xy 83.461902 -385.699374)
			(xy 83.498875 -385.747098) (xy 83.529255 -385.799267) (xy 83.552514 -385.854977) (xy 83.568248 -385.913261)
			(xy 83.576185 -385.973107) (xy 83.576668 -386.003292) (xy 83.576543 -386.017427) (xy 83.574761 -386.045641)
			(xy 83.573112 -386.05968) (xy 83.572357 -386.068287) (xy 83.575994 -386.085166) (xy 83.580224 -386.0927)
			(xy 83.595972 -386.1181) (xy 83.600688 -386.125156) (xy 83.613789 -386.135927) (xy 83.621626 -386.139182)
			(xy 83.645006 -386.148367) (xy 83.688902 -386.172787) (xy 83.728598 -386.203569) (xy 83.763178 -386.240002)
			(xy 83.791848 -386.281248) (xy 83.813946 -386.326358) (xy 83.828963 -386.374292) (xy 83.836555 -386.423946)
			(xy 83.837018 -386.449062) (xy 83.83659 -386.473264) (xy 83.829517 -386.521148) (xy 83.815531 -386.567488)
			(xy 83.794932 -386.61129) (xy 83.7819 -386.631688) (xy 83.777114 -386.639646) (xy 83.773078 -386.657756)
			(xy 83.774026 -386.666994) (xy 83.778344 -386.697982) (xy 83.780013 -386.707282) (xy 83.789302 -386.723722)
			(xy 83.796378 -386.729986) (xy 83.818469 -386.748664) (xy 83.85824 -386.790677) (xy 83.892401 -386.837366)
			(xy 83.920409 -386.887986) (xy 83.941815 -386.941732) (xy 83.95628 -386.997746) (xy 83.963573 -387.055136)
			(xy 83.964018 -387.084062) (xy 83.96343 -387.117384) (xy 83.953767 -387.183322) (xy 83.93464 -387.247161)
			(xy 83.921092 -387.27761) (xy 83.916839 -387.288074) (xy 83.916953 -387.310634) (xy 83.92669 -387.330986)
			(xy 83.935062 -387.33857) (xy 83.957284 -387.357272) (xy 83.99735 -387.399322) (xy 84.031774 -387.446102)
			(xy 84.060003 -387.496863) (xy 84.081582 -387.550787) (xy 84.096166 -387.607007) (xy 84.103519 -387.664621)
			(xy 84.103972 -387.693662) (xy 84.103488 -387.722667) (xy 84.096177 -387.780213) (xy 84.081656 -387.836375)
			(xy 84.060157 -387.890253) (xy 84.032024 -387.940984) (xy 83.997708 -387.987754) (xy 83.957758 -388.029815)
			(xy 83.93557 -388.0485) (xy 83.928458 -388.054088) (xy 83.919314 -388.069328) (xy 83.904074 -388.152132)
			(xy 83.906868 -388.169404) (xy 83.91144 -388.177532) (xy 83.924015 -388.200719) (xy 83.941889 -388.25034)
			(xy 83.95099 -388.302291) (xy 83.951572 -388.328662) (xy 83.951503 -388.338021) (xy 83.95036 -388.356703)
			(xy 83.949286 -388.366) (xy 83.94827 -388.37489) (xy 83.95208 -388.391654) (xy 83.996022 -388.461504)
			(xy 84.009738 -388.471918) (xy 84.01812 -388.474712) (xy 84.042144 -388.48319) (xy 84.087317 -388.506741)
			(xy 84.128123 -388.537238) (xy 84.163503 -388.573891) (xy 84.192539 -388.615748) (xy 84.214479 -388.661725)
			(xy 84.222082 -388.68604) (xy 84.223606 -388.691882) (xy 84.5439 -389.245602) (xy 84.547964 -389.24992)
			(xy 84.564166 -389.267629) (xy 84.591588 -389.307021) (xy 84.61273 -389.35011) (xy 84.627105 -389.395904)
			(xy 84.63438 -389.443346) (xy 84.634832 -389.467344) (xy 84.634447 -389.492151) (xy 84.626674 -389.541153)
			(xy 84.611329 -389.588335) (xy 84.588788 -389.632534) (xy 84.559607 -389.67266) (xy 84.524505 -389.707724)
			(xy 84.484349 -389.736862) (xy 84.440126 -389.759357) (xy 84.392928 -389.774652) (xy 84.343918 -389.782373)
			(xy 84.31911 -389.782812) (xy 84.293716 -389.782303) (xy 84.243583 -389.774174) (xy 84.195397 -389.758124)
			(xy 84.150403 -389.734567) (xy 84.10976 -389.70411) (xy 84.074517 -389.66754) (xy 84.045583 -389.6258)
			(xy 84.023705 -389.579966) (xy 84.016088 -389.555736) (xy 84.014564 -389.549894) (xy 83.69427 -388.996174)
			(xy 83.690206 -388.991856) (xy 83.674039 -388.974129) (xy 83.646673 -388.934724) (xy 83.625585 -388.891633)
			(xy 83.611259 -388.845846) (xy 83.604026 -388.79842) (xy 83.603592 -388.774432) (xy 83.603673 -388.762384)
			(xy 83.605456 -388.738355) (xy 83.607148 -388.726426) (xy 83.608418 -388.717536) (xy 83.60537 -388.700518)
			(xy 83.563206 -388.629652) (xy 83.549998 -388.618476) (xy 83.541616 -388.615428) (xy 83.519878 -388.607008)
			(xy 83.479018 -388.584573) (xy 83.442046 -388.556184) (xy 83.409821 -388.522503) (xy 83.383094 -388.484312)
			(xy 83.362487 -388.442501) (xy 83.348478 -388.398042) (xy 83.341394 -388.351969) (xy 83.340956 -388.328662)
			(xy 83.341527 -388.302289) (xy 83.350609 -388.250331) (xy 83.368495 -388.200711) (xy 83.381088 -388.177532)
			(xy 83.38566 -388.169404) (xy 83.388454 -388.152132) (xy 83.373214 -388.069328) (xy 83.36407 -388.054088)
			(xy 83.356958 -388.0485) (xy 83.334779 -388.029804) (xy 83.294834 -387.98774) (xy 83.260518 -387.94097)
			(xy 83.232381 -387.890242) (xy 83.210873 -387.836368) (xy 83.196337 -387.78021) (xy 83.189007 -387.722666)
			(xy 83.188556 -387.693662) (xy 83.189155 -387.660341) (xy 83.198813 -387.594403) (xy 83.217936 -387.530563)
			(xy 83.231482 -387.500114) (xy 83.23572 -387.489645) (xy 83.235615 -387.467087) (xy 83.225883 -387.446737)
			(xy 83.217512 -387.439154) (xy 83.195247 -387.4205) (xy 83.155185 -387.378441) (xy 83.120765 -387.331652)
			(xy 83.092543 -387.280883) (xy 83.07097 -387.226952) (xy 83.056394 -387.170725) (xy 83.04905 -387.113105)
			(xy 83.048602 -387.084062) (xy 83.049035 -387.055135) (xy 83.05632 -386.997741) (xy 83.07078 -386.941723)
			(xy 83.092187 -386.887975) (xy 83.120197 -386.837354) (xy 83.154364 -386.790666) (xy 83.194144 -386.748658)
			(xy 83.216242 -386.729986) (xy 83.223211 -386.723635) (xy 83.232471 -386.707234) (xy 83.234276 -386.697982)
			(xy 83.238594 -386.666994) (xy 83.239491 -386.657757) (xy 83.23547 -386.639658) (xy 83.23072 -386.631688)
			(xy 83.214414 -386.605841) (xy 83.190509 -386.549607) (xy 83.183222 -386.519928) (xy 83.181157 -386.511768)
			(xy 83.17246 -386.497366) (xy 83.166204 -386.491734) (xy 83.14309 -386.472684) (xy 83.136207 -386.467442)
			(xy 83.119979 -386.461474) (xy 83.11134 -386.461) (xy 83.081703 -386.460011) (xy 83.023037 -386.451359)
			(xy 82.96598 -386.435206) (xy 82.911485 -386.411821) (xy 82.860466 -386.381596) (xy 82.813777 -386.345037)
			(xy 82.772198 -386.302756) (xy 82.736426 -386.25546) (xy 82.70706 -386.203942) (xy 82.684591 -386.149064)
			(xy 82.669395 -386.091744) (xy 82.661727 -386.032942) (xy 82.661252 -386.003292) (xy 82.661773 -385.972229)
			(xy 82.670189 -385.910675) (xy 82.678016 -385.88061) (xy 82.68081 -385.87045) (xy 82.67827 -385.850638)
			(xy 82.630772 -385.768342) (xy 82.61477 -385.75615) (xy 82.60461 -385.75361) (xy 82.575517 -385.745593)
			(xy 82.519591 -385.722924) (xy 82.467126 -385.693106) (xy 82.419032 -385.656655) (xy 82.376143 -385.614202)
			(xy 82.3392 -385.566485) (xy 82.308846 -385.514328) (xy 82.285605 -385.458637) (xy 82.269879 -385.400375)
			(xy 82.261943 -385.340553) (xy 82.261456 -385.31038) (xy 82.261974 -385.279492) (xy 82.27028 -385.218276)
			(xy 82.286739 -385.158732) (xy 82.311052 -385.10194) (xy 82.32648 -385.075176) (xy 82.332322 -385.06527)
			(xy 82.334608 -385.042918) (xy 82.301334 -384.947668) (xy 82.285586 -384.931666) (xy 82.274918 -384.927602)
			(xy 82.251541 -384.918406) (xy 82.207644 -384.89399) (xy 82.167946 -384.863212) (xy 82.133364 -384.826781)
			(xy 82.104694 -384.785535) (xy 82.082595 -384.740426) (xy 82.067578 -384.692492) (xy 82.059988 -384.642838)
			(xy 82.059526 -384.617722) (xy 81.520792 -384.617722) (xy 81.52026 -384.644824) (xy 81.511452 -384.698306)
			(xy 81.503266 -384.724148) (xy 81.499456 -384.73507) (xy 81.501996 -384.757422) (xy 81.554574 -384.843274)
			(xy 81.573624 -384.85572) (xy 81.5848 -384.857498) (xy 81.614114 -384.862229) (xy 81.671284 -384.878274)
			(xy 81.725898 -384.90158) (xy 81.777038 -384.931756) (xy 81.823845 -384.968295) (xy 81.865531 -385.010582)
			(xy 81.901395 -385.057906) (xy 81.930836 -385.109473) (xy 81.953358 -385.164415) (xy 81.968583 -385.221809)
			(xy 81.976255 -385.28069) (xy 81.976722 -385.31038) (xy 81.976196 -385.341443) (xy 81.967784 -385.402996)
			(xy 81.959958 -385.433062) (xy 81.957164 -385.443222) (xy 81.959704 -385.463034) (xy 82.007202 -385.54533)
			(xy 82.023204 -385.557522) (xy 82.033364 -385.560062) (xy 82.062476 -385.568054) (xy 82.118442 -385.590689)
			(xy 82.170947 -385.620485) (xy 82.21908 -385.656924) (xy 82.262006 -385.699373) (xy 82.29898 -385.747097)
			(xy 82.32936 -385.799266) (xy 82.352618 -385.854976) (xy 82.368352 -385.91326) (xy 82.376289 -385.973107)
			(xy 82.376772 -386.003292) (xy 82.376646 -386.017427) (xy 82.374865 -386.045641) (xy 82.373216 -386.05968)
			(xy 82.372461 -386.068287) (xy 82.376098 -386.085166) (xy 82.380328 -386.0927) (xy 82.396076 -386.1181)
			(xy 82.40079 -386.125156) (xy 82.413893 -386.135927) (xy 82.42173 -386.139182) (xy 82.445111 -386.148365)
			(xy 82.489007 -386.172786) (xy 82.528702 -386.203567) (xy 82.563283 -386.240001) (xy 82.591952 -386.281248)
			(xy 82.61405 -386.326357) (xy 82.629067 -386.374292) (xy 82.636659 -386.423946) (xy 82.637122 -386.449062)
			(xy 82.636693 -386.473264) (xy 82.62962 -386.521148) (xy 82.615635 -386.567488) (xy 82.595036 -386.61129)
			(xy 82.582004 -386.631688) (xy 82.577218 -386.639646) (xy 82.573182 -386.657756) (xy 82.57413 -386.666994)
			(xy 82.578448 -386.697982) (xy 82.580145 -386.707274) (xy 82.589417 -386.723716) (xy 82.596482 -386.729986)
			(xy 82.618574 -386.748663) (xy 82.658345 -386.790677) (xy 82.692506 -386.837365) (xy 82.720513 -386.887986)
			(xy 82.741919 -386.941732) (xy 82.756384 -386.997746) (xy 82.763677 -387.055136) (xy 82.764122 -387.084062)
			(xy 82.763534 -387.117383) (xy 82.753871 -387.183322) (xy 82.734744 -387.247161) (xy 82.721196 -387.27761)
			(xy 82.716942 -387.288073) (xy 82.717056 -387.310634) (xy 82.726793 -387.330986) (xy 82.735166 -387.33857)
			(xy 82.757389 -387.357271) (xy 82.797455 -387.399321) (xy 82.831879 -387.446102) (xy 82.860107 -387.496862)
			(xy 82.881687 -387.550786) (xy 82.89627 -387.607007) (xy 82.903623 -387.664621) (xy 82.904076 -387.693662)
			(xy 82.90359 -387.722667) (xy 82.89628 -387.780213) (xy 82.881759 -387.836375) (xy 82.86026 -387.890253)
			(xy 82.832127 -387.940983) (xy 82.797811 -387.987754) (xy 82.757862 -388.029815) (xy 82.735674 -388.0485)
			(xy 82.728562 -388.054088) (xy 82.719418 -388.069328) (xy 82.704178 -388.152132) (xy 82.706972 -388.169404)
			(xy 82.711544 -388.177532) (xy 82.724119 -388.200718) (xy 82.741993 -388.25034) (xy 82.751094 -388.302291)
			(xy 82.751676 -388.328662) (xy 82.751607 -388.338021) (xy 82.750464 -388.356703) (xy 82.74939 -388.366)
			(xy 82.748374 -388.37489) (xy 82.752184 -388.391654) (xy 82.796126 -388.461504) (xy 82.809842 -388.471918)
			(xy 82.818224 -388.474712) (xy 82.842326 -388.483179) (xy 82.887617 -388.506808) (xy 82.928511 -388.537422)
			(xy 82.963941 -388.574222) (xy 82.992983 -388.616247) (xy 83.014878 -388.6624) (xy 83.02244 -388.686802)
			(xy 83.023964 -388.692644) (xy 83.34375 -389.245602) (xy 83.347814 -389.24992) (xy 83.364004 -389.267627)
			(xy 83.391369 -389.307036) (xy 83.412455 -389.350132) (xy 83.426775 -389.395924) (xy 83.433999 -389.443355)
			(xy 83.434428 -389.467344) (xy 83.434022 -389.492137) (xy 83.426259 -389.541111) (xy 83.410929 -389.588268)
			(xy 83.388412 -389.632446) (xy 83.359261 -389.672558) (xy 83.324194 -389.707615) (xy 83.284074 -389.736756)
			(xy 83.23989 -389.759262) (xy 83.192729 -389.774578) (xy 83.143753 -389.782329) (xy 83.11896 -389.782812)
			(xy 83.093564 -389.782347) (xy 83.043429 -389.77421) (xy 82.995243 -389.758153) (xy 82.950248 -389.734589)
			(xy 82.909606 -389.704127) (xy 82.874364 -389.667551) (xy 82.845431 -389.625806) (xy 82.823554 -389.579968)
			(xy 82.815938 -389.555736) (xy 82.814414 -389.549894) (xy 82.493866 -388.995412) (xy 82.489802 -388.991094)
			(xy 82.473695 -388.973441) (xy 82.446509 -388.934139) (xy 82.42556 -388.891188) (xy 82.411325 -388.845569)
			(xy 82.404131 -388.798326) (xy 82.403696 -388.774432) (xy 82.403777 -388.762384) (xy 82.40556 -388.738355)
			(xy 82.407252 -388.726426) (xy 82.408522 -388.717536) (xy 82.405474 -388.700518) (xy 82.36331 -388.629652)
			(xy 82.350102 -388.618476) (xy 82.34172 -388.615428) (xy 82.319983 -388.607005) (xy 82.279123 -388.584571)
			(xy 82.242151 -388.556183) (xy 82.209926 -388.522502) (xy 82.183199 -388.484311) (xy 82.162591 -388.4425)
			(xy 82.148582 -388.398041) (xy 82.141498 -388.351969) (xy 82.14106 -388.328662) (xy 82.141631 -388.302289)
			(xy 82.150713 -388.250331) (xy 82.168599 -388.200711) (xy 82.181192 -388.177532) (xy 82.185764 -388.169404)
			(xy 82.188558 -388.152132) (xy 82.173318 -388.069328) (xy 82.164174 -388.054088) (xy 82.157062 -388.0485)
			(xy 82.134883 -388.029803) (xy 82.094938 -387.987739) (xy 82.060623 -387.940969) (xy 82.032485 -387.890241)
			(xy 82.010977 -387.836368) (xy 81.996441 -387.78021) (xy 81.989111 -387.722666) (xy 81.98866 -387.693662)
			(xy 81.989258 -387.660341) (xy 81.998917 -387.594403) (xy 82.01804 -387.530563) (xy 82.031586 -387.500114)
			(xy 82.035823 -387.489645) (xy 82.035718 -387.467087) (xy 82.025986 -387.446737) (xy 82.017616 -387.439154)
			(xy 81.995352 -387.420499) (xy 81.955289 -387.378441) (xy 81.92087 -387.331651) (xy 81.892647 -387.280883)
			(xy 81.871074 -387.226952) (xy 81.856498 -387.170725) (xy 81.849154 -387.113105) (xy 81.848706 -387.084062)
			(xy 81.849174 -387.055136) (xy 81.856457 -386.997745) (xy 81.870914 -386.94173) (xy 81.892316 -386.887983)
			(xy 81.92032 -386.837361) (xy 81.95448 -386.790672) (xy 81.994252 -386.748661) (xy 82.016346 -386.729986)
			(xy 82.023315 -386.723636) (xy 82.032575 -386.707234) (xy 82.03438 -386.697982) (xy 82.038698 -386.666994)
			(xy 82.039594 -386.657757) (xy 82.035574 -386.639659) (xy 82.030824 -386.631688) (xy 82.014518 -386.605841)
			(xy 81.990613 -386.549607) (xy 81.983326 -386.519928) (xy 81.98126 -386.511768) (xy 81.972564 -386.497366)
			(xy 81.966308 -386.491734) (xy 81.943194 -386.472684) (xy 81.93631 -386.467443) (xy 81.920083 -386.461475)
			(xy 81.911444 -386.461) (xy 81.881807 -386.460007) (xy 81.823141 -386.451356) (xy 81.766084 -386.435203)
			(xy 81.71159 -386.411818) (xy 81.660571 -386.381594) (xy 81.613881 -386.345035) (xy 81.572302 -386.302754)
			(xy 81.53653 -386.255459) (xy 81.507164 -386.203942) (xy 81.484695 -386.149063) (xy 81.469499 -386.091744)
			(xy 81.461831 -386.032942) (xy 81.461356 -386.003292) (xy 81.461877 -385.972229) (xy 81.470293 -385.910675)
			(xy 81.47812 -385.88061) (xy 81.480914 -385.87045) (xy 81.478374 -385.850638) (xy 81.430876 -385.768342)
			(xy 81.414874 -385.75615) (xy 81.404714 -385.75361) (xy 81.37559 -385.745658) (xy 81.319623 -385.723018)
			(xy 81.267117 -385.693218) (xy 81.218984 -385.656774) (xy 81.176059 -385.61432) (xy 81.139086 -385.566592)
			(xy 81.108708 -385.514418) (xy 81.085452 -385.458704) (xy 81.069721 -385.400416) (xy 81.061787 -385.340567)
			(xy 81.061306 -385.31038) (xy 81.061831 -385.279492) (xy 81.070136 -385.218276) (xy 81.086593 -385.158733)
			(xy 81.110903 -385.101941) (xy 81.12633 -385.075176) (xy 81.132172 -385.06527) (xy 81.134458 -385.042918)
			(xy 81.101184 -384.947668) (xy 81.085436 -384.931666) (xy 81.074768 -384.927602) (xy 81.051381 -384.918433)
			(xy 81.007484 -384.894011) (xy 80.967789 -384.863227) (xy 80.933209 -384.826792) (xy 80.90454 -384.785543)
			(xy 80.882443 -384.740431) (xy 80.867427 -384.692495) (xy 80.859838 -384.642839) (xy 80.859376 -384.617722)
			(xy 80.320896 -384.617722) (xy 80.320364 -384.644824) (xy 80.311556 -384.698306) (xy 80.30337 -384.724148)
			(xy 80.29956 -384.73507) (xy 80.3021 -384.757422) (xy 80.354678 -384.843274) (xy 80.373728 -384.85572)
			(xy 80.384904 -384.857498) (xy 80.414219 -384.862226) (xy 80.471389 -384.878272) (xy 80.526003 -384.901578)
			(xy 80.577143 -384.931755) (xy 80.623949 -384.968293) (xy 80.665635 -385.010581) (xy 80.701499 -385.057905)
			(xy 80.73094 -385.109472) (xy 80.753462 -385.164414) (xy 80.768687 -385.221809) (xy 80.776359 -385.28069)
			(xy 80.776826 -385.31038) (xy 80.7763 -385.341443) (xy 80.767888 -385.402996) (xy 80.760062 -385.433062)
			(xy 80.757268 -385.443222) (xy 80.759808 -385.463034) (xy 80.807306 -385.54533) (xy 80.823308 -385.557522)
			(xy 80.833468 -385.560062) (xy 80.862581 -385.568051) (xy 80.918547 -385.590687) (xy 80.971052 -385.620483)
			(xy 81.019185 -385.656922) (xy 81.062111 -385.699372) (xy 81.099084 -385.747096) (xy 81.129464 -385.799266)
			(xy 81.152722 -385.854976) (xy 81.168456 -385.91326) (xy 81.176393 -385.973107) (xy 81.176876 -386.003292)
			(xy 81.17675 -386.017427) (xy 81.174969 -386.045641) (xy 81.17332 -386.05968) (xy 81.172564 -386.068287)
			(xy 81.176201 -386.085166) (xy 81.180432 -386.0927) (xy 81.19618 -386.1181) (xy 81.20088 -386.12517)
			(xy 81.213986 -386.135945) (xy 81.221834 -386.139182) (xy 81.245183 -386.148408) (xy 81.289026 -386.172863)
			(xy 81.32867 -386.203663) (xy 81.363205 -386.2401) (xy 81.391836 -386.281338) (xy 81.413907 -386.326428)
			(xy 81.428911 -386.374336) (xy 81.436503 -386.423961) (xy 81.436972 -386.449062) (xy 81.436551 -386.473264)
			(xy 81.429477 -386.521149) (xy 81.41549 -386.567489) (xy 81.394888 -386.611291) (xy 81.381854 -386.631688)
			(xy 81.377065 -386.639644) (xy 81.373032 -386.657756) (xy 81.37398 -386.666994) (xy 81.378298 -386.697982)
			(xy 81.379981 -386.707278) (xy 81.389261 -386.72372) (xy 81.396332 -386.729986) (xy 81.418413 -386.748676)
			(xy 81.458187 -386.790686) (xy 81.49235 -386.837372) (xy 81.520359 -386.88799) (xy 81.541767 -386.941734)
			(xy 81.556233 -386.997747) (xy 81.563527 -387.055137) (xy 81.563972 -387.084062) (xy 81.563379 -387.117383)
			(xy 81.553718 -387.183322) (xy 81.534593 -387.247161) (xy 81.521046 -387.27761) (xy 81.516776 -387.288069)
			(xy 81.516889 -387.310636) (xy 81.526637 -387.33099) (xy 81.535016 -387.33857) (xy 81.55725 -387.357259)
			(xy 81.597313 -387.399312) (xy 81.631734 -387.446096) (xy 81.659961 -387.496858) (xy 81.681538 -387.550784)
			(xy 81.696121 -387.607006) (xy 81.703473 -387.664621) (xy 81.703926 -387.693662) (xy 81.703459 -387.722667)
			(xy 81.696147 -387.780215) (xy 81.681625 -387.836378) (xy 81.660123 -387.890257) (xy 81.631987 -387.940987)
			(xy 81.597667 -387.987757) (xy 81.557714 -388.029816) (xy 81.535524 -388.0485) (xy 81.528412 -388.054088)
			(xy 81.519268 -388.069328) (xy 81.504028 -388.152132) (xy 81.506822 -388.169404) (xy 81.511394 -388.177532)
			(xy 81.523965 -388.200721) (xy 81.541842 -388.250341) (xy 81.550944 -388.302292) (xy 81.551526 -388.328662)
			(xy 81.551457 -388.338021) (xy 81.550314 -388.356703) (xy 81.54924 -388.366) (xy 81.548224 -388.37489)
			(xy 81.552034 -388.391654) (xy 81.595976 -388.461504) (xy 81.609692 -388.471918) (xy 81.618074 -388.474712)
			(xy 81.642089 -388.483215) (xy 81.687263 -388.506759) (xy 81.72807 -388.53725) (xy 81.763452 -388.573899)
			(xy 81.792491 -388.615753) (xy 81.814432 -388.661726) (xy 81.822036 -388.68604) (xy 81.82356 -388.691882)
			(xy 82.143854 -389.245602) (xy 82.147918 -389.24992) (xy 82.164109 -389.267627) (xy 82.191474 -389.307036)
			(xy 82.212559 -389.350132) (xy 82.226879 -389.395923) (xy 82.234103 -389.443355) (xy 82.234532 -389.467344)
			(xy 82.234122 -389.492137) (xy 82.226359 -389.54111) (xy 82.21103 -389.588267) (xy 82.188513 -389.632445)
			(xy 82.159362 -389.672556) (xy 82.124295 -389.707614) (xy 82.084176 -389.736755) (xy 82.039993 -389.75926)
			(xy 81.992833 -389.774578) (xy 81.943857 -389.782329) (xy 81.919064 -389.782812) (xy 81.893669 -389.782343)
			(xy 81.843533 -389.774207) (xy 81.795347 -389.75815) (xy 81.750353 -389.734587) (xy 81.70971 -389.704125)
			(xy 81.674468 -389.66755) (xy 81.645536 -389.625806) (xy 81.623658 -389.579968) (xy 81.616042 -389.555736)
			(xy 81.614518 -389.549894) (xy 81.294224 -388.996174) (xy 81.29016 -388.991856) (xy 81.27395 -388.974153)
			(xy 81.246528 -388.93476) (xy 81.225387 -388.891669) (xy 81.211015 -388.845874) (xy 81.203742 -388.798431)
			(xy 81.203292 -388.774432) (xy 81.203434 -388.76238) (xy 81.20534 -388.73835) (xy 81.207102 -388.726426)
			(xy 81.208372 -388.717536) (xy 81.205324 -388.700518) (xy 81.16316 -388.629652) (xy 81.149952 -388.618476)
			(xy 81.14157 -388.615428) (xy 81.119822 -388.607033) (xy 81.078964 -388.584592) (xy 81.041993 -388.556199)
			(xy 81.00977 -388.522513) (xy 80.983045 -388.484319) (xy 80.962439 -388.442505) (xy 80.948431 -388.398044)
			(xy 80.941348 -388.35197) (xy 80.94091 -388.328662) (xy 80.941474 -388.302289) (xy 80.950558 -388.25033)
			(xy 80.968447 -388.20071) (xy 80.981042 -388.177532) (xy 80.985614 -388.169404) (xy 80.988408 -388.152132)
			(xy 80.973168 -388.069328) (xy 80.964024 -388.054088) (xy 80.956912 -388.0485) (xy 80.934744 -388.029791)
			(xy 80.894796 -387.98773) (xy 80.860478 -387.940963) (xy 80.832339 -387.890238) (xy 80.810829 -387.836365)
			(xy 80.796292 -387.780209) (xy 80.788961 -387.722666) (xy 80.78851 -387.693662) (xy 80.789113 -387.660341)
			(xy 80.798771 -387.594403) (xy 80.817891 -387.530564) (xy 80.831436 -387.500114) (xy 80.835657 -387.489641)
			(xy 80.835551 -387.467089) (xy 80.82583 -387.44674) (xy 80.817466 -387.439154) (xy 80.795192 -387.420512)
			(xy 80.755131 -387.37845) (xy 80.720714 -387.331657) (xy 80.692493 -387.280887) (xy 80.670922 -387.226954)
			(xy 80.656348 -387.170726) (xy 80.649004 -387.113105) (xy 80.648556 -387.084062) (xy 80.649006 -387.055136)
			(xy 80.65629 -386.997743) (xy 80.670749 -386.941726) (xy 80.692153 -386.887979) (xy 80.72016 -386.837357)
			(xy 80.754324 -386.790669) (xy 80.7941 -386.74866) (xy 80.816196 -386.729986) (xy 80.823173 -386.723644)
			(xy 80.832427 -386.707236) (xy 80.83423 -386.697982) (xy 80.838548 -386.666994) (xy 80.839452 -386.657757)
			(xy 80.835427 -386.639658) (xy 80.830674 -386.631688) (xy 80.814364 -386.605844) (xy 80.790462 -386.549607)
			(xy 80.783176 -386.519928) (xy 80.781123 -386.511764) (xy 80.772418 -386.497363) (xy 80.766158 -386.491734)
			(xy 80.743044 -386.472684) (xy 80.736205 -386.46749) (xy 80.720119 -386.461513) (xy 80.711548 -386.461)
			(xy 80.681911 -386.460003) (xy 80.623246 -386.451353) (xy 80.566188 -386.4352) (xy 80.511694 -386.411816)
			(xy 80.460675 -386.381592) (xy 80.413985 -386.345034) (xy 80.372406 -386.302753) (xy 80.336634 -386.255458)
			(xy 80.307268 -386.203941) (xy 80.284799 -386.149063) (xy 80.269603 -386.091743) (xy 80.261935 -386.032942)
			(xy 80.26146 -386.003292) (xy 80.261981 -385.972229) (xy 80.270397 -385.910675) (xy 80.278224 -385.88061)
			(xy 80.281018 -385.87045) (xy 80.278478 -385.850638) (xy 80.23098 -385.768342) (xy 80.214978 -385.75615)
			(xy 80.204818 -385.75361) (xy 80.193097 -385.750462) (xy 80.169971 -385.743093) (xy 80.15859 -385.738878)
			(xy 80.146144 -385.734306) (xy 80.120236 -385.738116) (xy 80.030828 -385.806696) (xy 80.020414 -385.830826)
			(xy 80.021684 -385.84378) (xy 80.023208 -385.87553) (xy 80.02282 -385.899206) (xy 80.016088 -385.946077)
			(xy 80.002725 -385.991503) (xy 79.993236 -386.013198) (xy 79.988918 -386.022596) (xy 79.988156 -386.042662)
			(xy 80.020414 -386.129022) (xy 80.03413 -386.143754) (xy 80.043528 -386.148072) (xy 80.067892 -386.159773)
			(xy 80.112763 -386.189897) (xy 80.152142 -386.226913) (xy 80.184981 -386.269836) (xy 80.210408 -386.317526)
			(xy 80.227747 -386.368714) (xy 80.236536 -386.42204) (xy 80.237076 -386.449062) (xy 80.236655 -386.473264)
			(xy 80.229581 -386.521149) (xy 80.215593 -386.567489) (xy 80.194992 -386.611291) (xy 80.181958 -386.631688)
			(xy 80.177169 -386.639644) (xy 80.173136 -386.657756) (xy 80.174084 -386.666994) (xy 80.178402 -386.697982)
			(xy 80.180083 -386.707278) (xy 80.189365 -386.72372) (xy 80.196436 -386.729986) (xy 80.218518 -386.748675)
			(xy 80.258291 -386.790685) (xy 80.292454 -386.837371) (xy 80.320463 -386.88799) (xy 80.341871 -386.941734)
			(xy 80.356337 -386.997747) (xy 80.363631 -387.055137) (xy 80.364076 -387.084062) (xy 80.363483 -387.117383)
			(xy 80.353821 -387.183322) (xy 80.334697 -387.247161) (xy 80.32115 -387.27761) (xy 80.316878 -387.288069)
			(xy 80.316992 -387.310636) (xy 80.32674 -387.33099) (xy 80.33512 -387.33857) (xy 80.357354 -387.357258)
			(xy 80.397418 -387.399312) (xy 80.431839 -387.446096) (xy 80.460065 -387.496858) (xy 80.481643 -387.550784)
			(xy 80.496225 -387.607006) (xy 80.503577 -387.664621) (xy 80.50403 -387.693662) (xy 80.503561 -387.722667)
			(xy 80.49625 -387.780215) (xy 80.481727 -387.836378) (xy 80.460226 -387.890257) (xy 80.43209 -387.940987)
			(xy 80.397771 -387.987757) (xy 80.357818 -388.029816) (xy 80.335628 -388.0485) (xy 80.328516 -388.054088)
			(xy 80.319372 -388.069328) (xy 80.304132 -388.152132) (xy 80.306926 -388.169404) (xy 80.311498 -388.177532)
			(xy 80.32407 -388.20072) (xy 80.341946 -388.250341) (xy 80.351048 -388.302292) (xy 80.35163 -388.328662)
			(xy 80.351561 -388.338021) (xy 80.350418 -388.356703) (xy 80.349344 -388.366) (xy 80.348328 -388.37489)
			(xy 80.352138 -388.391654) (xy 80.39608 -388.461504) (xy 80.409796 -388.471918) (xy 80.418178 -388.474712)
			(xy 80.442194 -388.483213) (xy 80.487368 -388.506757) (xy 80.528175 -388.537249) (xy 80.563557 -388.573898)
			(xy 80.592595 -388.615752) (xy 80.614536 -388.661726) (xy 80.62214 -388.68604) (xy 80.623664 -388.691882)
			(xy 80.943958 -389.245602) (xy 80.948022 -389.24992) (xy 80.964214 -389.267626) (xy 80.991578 -389.307035)
			(xy 81.012663 -389.350132) (xy 81.026983 -389.395923) (xy 81.034207 -389.443355) (xy 81.034636 -389.467344)
			(xy 81.034222 -389.492136) (xy 81.026459 -389.54111) (xy 81.01113 -389.588266) (xy 80.988613 -389.632444)
			(xy 80.959463 -389.672555) (xy 80.924397 -389.707613) (xy 80.884279 -389.736753) (xy 80.840096 -389.759259)
			(xy 80.792936 -389.774577) (xy 80.743961 -389.782328) (xy 80.719168 -389.782812) (xy 80.693773 -389.78234)
			(xy 80.643638 -389.774204) (xy 80.595452 -389.758148) (xy 80.550457 -389.734585) (xy 80.509815 -389.704124)
			(xy 80.474573 -389.66755) (xy 80.44564 -389.625805) (xy 80.423762 -389.579968) (xy 80.416146 -389.555736)
			(xy 80.414622 -389.549894) (xy 80.094328 -388.996174) (xy 80.090264 -388.991856) (xy 80.074055 -388.974153)
			(xy 80.046633 -388.93476) (xy 80.025492 -388.891669) (xy 80.011119 -388.845874) (xy 80.003846 -388.798431)
			(xy 80.003396 -388.774432) (xy 80.003538 -388.76238) (xy 80.005444 -388.73835) (xy 80.007206 -388.726426)
			(xy 80.008476 -388.717536) (xy 80.005428 -388.700518) (xy 79.963264 -388.629652) (xy 79.950056 -388.618476)
			(xy 79.941674 -388.615428) (xy 79.919927 -388.607031) (xy 79.879068 -388.58459) (xy 79.842098 -388.556197)
			(xy 79.809875 -388.522512) (xy 79.783149 -388.484319) (xy 79.762543 -388.442505) (xy 79.748535 -388.398044)
			(xy 79.741452 -388.35197) (xy 79.741014 -388.328662) (xy 79.741578 -388.302289) (xy 79.750661 -388.25033)
			(xy 79.768551 -388.20071) (xy 79.781146 -388.177532) (xy 79.785718 -388.169404) (xy 79.788512 -388.152132)
			(xy 79.773272 -388.069328) (xy 79.764128 -388.054088) (xy 79.757016 -388.0485) (xy 79.734849 -388.02979)
			(xy 79.694901 -387.98773) (xy 79.660583 -387.940963) (xy 79.632443 -387.890237) (xy 79.610933 -387.836365)
			(xy 79.596396 -387.780208) (xy 79.589065 -387.722666) (xy 79.588614 -387.693662) (xy 79.589216 -387.660341)
			(xy 79.598874 -387.594403) (xy 79.617995 -387.530564) (xy 79.63154 -387.500114) (xy 79.635792 -387.489649)
			(xy 79.635687 -387.467086) (xy 79.625947 -387.446734) (xy 79.61757 -387.439154) (xy 79.595297 -387.420511)
			(xy 79.555236 -387.378449) (xy 79.520819 -387.331657) (xy 79.492598 -387.280887) (xy 79.471027 -387.226954)
			(xy 79.456452 -387.170726) (xy 79.449108 -387.113105) (xy 79.44866 -387.084062) (xy 79.449109 -387.055135)
			(xy 79.456392 -386.997743) (xy 79.470852 -386.941726) (xy 79.492256 -386.887978) (xy 79.520263 -386.837357)
			(xy 79.554428 -386.790669) (xy 79.594204 -386.748659) (xy 79.6163 -386.729986) (xy 79.623278 -386.723645)
			(xy 79.632531 -386.707236) (xy 79.634334 -386.697982) (xy 79.638652 -386.666994) (xy 79.639555 -386.657757)
			(xy 79.635531 -386.639658) (xy 79.630778 -386.631688) (xy 79.617788 -386.611267) (xy 79.597209 -386.567464)
			(xy 79.583222 -386.521133) (xy 79.576127 -386.47326) (xy 79.57566 -386.449062) (xy 79.57604 -386.425386)
			(xy 79.582774 -386.378515) (xy 79.596141 -386.333088) (xy 79.605632 -386.311394) (xy 79.60995 -386.301996)
			(xy 79.610712 -386.28193) (xy 79.578454 -386.19557) (xy 79.564738 -386.180838) (xy 79.55534 -386.17652)
			(xy 79.530966 -386.16484) (xy 79.486096 -386.134711) (xy 79.446719 -386.097691) (xy 79.413881 -386.054764)
			(xy 79.388456 -386.007071) (xy 79.371119 -385.955881) (xy 79.362331 -385.902553) (xy 79.361792 -385.87553)
			(xy 77.874744 -385.87553) (xy 77.845327 -385.912288) (xy 77.823314 -385.93395) (xy 77.814678 -385.942332)
			(xy 77.80655 -385.964684) (xy 77.818488 -386.069078) (xy 77.831442 -386.08889) (xy 77.841856 -386.09524)
			(xy 77.867194 -386.110751) (xy 77.914047 -386.147276) (xy 77.955779 -386.189558) (xy 77.991688 -386.236885)
			(xy 78.021169 -386.288462) (xy 78.043727 -386.343421) (xy 78.058982 -386.400837) (xy 78.066677 -386.459744)
			(xy 78.067154 -386.489448) (xy 78.06668 -386.520107) (xy 78.058488 -386.580875) (xy 78.042258 -386.640005)
			(xy 78.018279 -386.69644) (xy 77.986982 -386.749169) (xy 77.948926 -386.797248) (xy 77.9272 -386.818886)
			(xy 77.919463 -386.827199) (xy 77.911465 -386.84842) (xy 77.913372 -386.871017) (xy 77.918564 -386.881116)
			(xy 77.9327 -386.906586) (xy 77.952771 -386.961264) (xy 77.962934 -387.018617) (xy 77.963522 -387.04774)
			(xy 77.963012 -387.073727) (xy 77.954882 -387.125062) (xy 77.938821 -387.174492) (xy 77.915225 -387.220802)
			(xy 77.884675 -387.26285) (xy 77.847924 -387.299601) (xy 77.805876 -387.330151) (xy 77.759566 -387.353747)
			(xy 77.710136 -387.369808) (xy 77.658801 -387.377938) (xy 77.606827 -387.377938) (xy 77.555492 -387.369808)
			(xy 77.506062 -387.353747) (xy 77.459752 -387.330151) (xy 77.417704 -387.299601) (xy 77.380953 -387.26285)
			(xy 77.350403 -387.220802) (xy 77.326807 -387.174492) (xy 77.310746 -387.125062) (xy 77.302616 -387.073727)
			(xy 77.302106 -387.04774) (xy 77.302526 -387.023227) (xy 77.30971 -386.97473) (xy 77.323987 -386.927829)
			(xy 77.33411 -386.9055) (xy 77.338485 -386.895032) (xy 77.338531 -386.872371) (xy 77.328805 -386.851903)
			(xy 77.320394 -386.844286) (xy 77.298182 -386.825611) (xy 77.258171 -386.783577) (xy 77.223798 -386.736821)
			(xy 77.195613 -386.686093) (xy 77.174071 -386.632208) (xy 77.159517 -386.576031) (xy 77.152184 -386.518464)
			(xy 77.151738 -386.489448) (xy 77.152227 -386.458567) (xy 77.160545 -386.397369) (xy 77.177022 -386.337847)
			(xy 77.20136 -386.281083) (xy 77.233114 -386.22811) (xy 77.271708 -386.179893) (xy 77.293724 -386.158232)
			(xy 77.30236 -386.14985) (xy 77.310488 -386.127498) (xy 77.29855 -386.023104) (xy 77.285596 -386.003292)
			(xy 77.275182 -385.996942) (xy 77.251793 -385.982726) (xy 77.208283 -385.949519) (xy 77.169051 -385.911354)
			(xy 77.134656 -385.868776) (xy 77.105593 -385.822395) (xy 77.093572 -385.797806) (xy 77.087476 -385.785106)
			(xy 77.064616 -385.769612) (xy 76.947776 -385.762246) (xy 76.923392 -385.774692) (xy 76.915772 -385.78663)
			(xy 76.900682 -385.809509) (xy 76.864991 -385.851102) (xy 76.823716 -385.887159) (xy 76.777706 -385.916937)
			(xy 76.727907 -385.939825) (xy 76.675346 -385.95535) (xy 76.621103 -385.963194) (xy 76.5937 -385.963668)
			(xy 76.566446 -385.963262) (xy 76.512493 -385.955505) (xy 76.460192 -385.940148) (xy 76.41061 -385.917505)
			(xy 76.364755 -385.888035) (xy 76.32356 -385.85234) (xy 76.287865 -385.811145) (xy 76.258395 -385.76529)
			(xy 76.235752 -385.715708) (xy 76.220395 -385.663407) (xy 76.212638 -385.609454) (xy 70.5612 -385.609454)
			(xy 70.5612 -385.804918) (xy 70.560773 -385.814987) (xy 70.553054 -385.833586) (xy 70.546214 -385.840986)
			(xy 69.788786 -386.598414) (xy 69.781932 -386.605809) (xy 69.77419 -386.624408) (xy 69.7738 -386.634482)
			(xy 69.7738 -387.084062) (xy 69.88378 -387.084062) (xy 69.887851 -387.02844) (xy 69.899977 -386.974003)
			(xy 69.9199 -386.921912) (xy 69.947196 -386.873277) (xy 69.981282 -386.829134) (xy 70.021431 -386.790425)
			(xy 70.066789 -386.757974) (xy 70.116389 -386.732473) (xy 70.169173 -386.714466) (xy 70.224016 -386.704336)
			(xy 70.27975 -386.702299) (xy 70.335187 -386.708399) (xy 70.389144 -386.722505) (xy 70.440473 -386.744317)
			(xy 70.488079 -386.773371) (xy 70.530947 -386.809046) (xy 70.568164 -386.850583) (xy 70.598937 -386.897096)
			(xy 70.622609 -386.947593) (xy 70.638677 -387.001) (xy 70.646797 -387.056176) (xy 70.647306 -387.084062)
			(xy 70.646797 -387.111948) (xy 70.638677 -387.167124) (xy 70.622609 -387.220531) (xy 70.598937 -387.271028)
			(xy 70.568164 -387.317541) (xy 70.530947 -387.359078) (xy 70.488079 -387.394753) (xy 70.440473 -387.423807)
			(xy 70.389144 -387.445619) (xy 70.335187 -387.459725) (xy 70.27975 -387.465825) (xy 70.224016 -387.463788)
			(xy 70.169173 -387.453658) (xy 70.116389 -387.435651) (xy 70.066789 -387.41015) (xy 70.021431 -387.377699)
			(xy 69.981282 -387.33899) (xy 69.947196 -387.294847) (xy 69.9199 -387.246212) (xy 69.899977 -387.194121)
			(xy 69.887851 -387.139684) (xy 69.88378 -387.084062) (xy 69.7738 -387.084062) (xy 69.7738 -387.7945)
			(xy 71.957182 -387.7945) (xy 71.961253 -387.738878) (xy 71.973379 -387.684441) (xy 71.993302 -387.63235)
			(xy 72.020598 -387.583715) (xy 72.054684 -387.539572) (xy 72.094833 -387.500863) (xy 72.140191 -387.468412)
			(xy 72.189791 -387.442911) (xy 72.242575 -387.424904) (xy 72.297418 -387.414774) (xy 72.353152 -387.412737)
			(xy 72.408589 -387.418837) (xy 72.462546 -387.432943) (xy 72.513875 -387.454755) (xy 72.561481 -387.483809)
			(xy 72.604349 -387.519484) (xy 72.641566 -387.561021) (xy 72.672339 -387.607534) (xy 72.696011 -387.658031)
			(xy 72.712079 -387.711438) (xy 72.720199 -387.766614) (xy 72.72062 -387.789674) (xy 73.302114 -387.789674)
			(xy 73.302678 -387.754718) (xy 73.312243 -387.685464) (xy 73.331204 -387.618173) (xy 73.359203 -387.554113)
			(xy 73.395713 -387.494491) (xy 73.41743 -387.467094) (xy 73.422706 -387.460099) (xy 73.428549 -387.443593)
			(xy 73.42886 -387.434836) (xy 73.42886 -387.280912) (xy 73.428498 -387.272165) (xy 73.422661 -387.255673)
			(xy 73.41743 -387.248654) (xy 73.395746 -387.221233) (xy 73.359243 -387.161613) (xy 73.331244 -387.097559)
			(xy 73.312277 -387.030274) (xy 73.302698 -386.961027) (xy 73.302114 -386.926074) (xy 73.302532 -386.895342)
			(xy 73.309944 -386.834325) (xy 73.324656 -386.774647) (xy 73.346455 -386.717178) (xy 73.375021 -386.662755)
			(xy 73.40994 -386.612172) (xy 73.450701 -386.566167) (xy 73.49671 -386.52541) (xy 73.547296 -386.490497)
			(xy 73.601722 -386.461935) (xy 73.659193 -386.440142) (xy 73.718873 -386.425435) (xy 73.77989 -386.418029)
			(xy 73.810622 -386.417566) (xy 73.831547 -386.417766) (xy 73.873257 -386.421204) (xy 73.893934 -386.424424)
			(xy 73.903078 -386.425948) (xy 73.920858 -386.422646) (xy 73.992994 -386.378958) (xy 74.00417 -386.364988)
			(xy 74.007218 -386.356352) (xy 74.016011 -386.331342) (xy 74.039496 -386.283814) (xy 74.069338 -386.239998)
			(xy 74.104963 -386.200738) (xy 74.145682 -386.166792) (xy 74.190711 -386.138813) (xy 74.239182 -386.117342)
			(xy 74.29016 -386.102792) (xy 74.342661 -386.095444) (xy 74.369168 -386.094986) (xy 74.39642 -386.095485)
			(xy 74.450369 -386.103238) (xy 74.502666 -386.118589) (xy 74.552246 -386.141228) (xy 74.598099 -386.170692)
			(xy 74.639291 -386.206382) (xy 74.674986 -386.247571) (xy 74.704454 -386.293421) (xy 74.727098 -386.342998)
			(xy 74.742454 -386.395294) (xy 74.750212 -386.449242) (xy 74.750676 -386.476494) (xy 74.750108 -386.504464)
			(xy 74.741967 -386.559807) (xy 74.725828 -386.613368) (xy 74.702039 -386.663996) (xy 74.671109 -386.710607)
			(xy 74.633703 -386.752199) (xy 74.590622 -386.787882) (xy 74.542791 -386.816888) (xy 74.491236 -386.838596)
			(xy 74.437063 -386.852541) (xy 74.4093 -386.85597) (xy 74.400156 -386.856732) (xy 74.3839 -386.86486)
			(xy 74.325988 -386.926074) (xy 74.318876 -386.942584) (xy 74.318368 -386.951728) (xy 74.316278 -386.984047)
			(xy 74.304867 -387.047799) (xy 74.285445 -387.109584) (xy 74.258328 -387.1684) (xy 74.223955 -387.223292)
			(xy 74.203814 -387.248654) (xy 74.198564 -387.255667) (xy 74.192705 -387.272159) (xy 74.192384 -387.280912)
			(xy 74.192384 -387.434836) (xy 74.192735 -387.443584) (xy 74.198581 -387.460075) (xy 74.203814 -387.467094)
			(xy 74.225526 -387.494494) (xy 74.262024 -387.554119) (xy 74.290016 -387.61818) (xy 74.308977 -387.685469)
			(xy 74.318549 -387.754719) (xy 74.31913 -387.789674) (xy 74.318679 -387.820891) (xy 74.311063 -387.88286)
			(xy 74.295918 -387.943429) (xy 74.273472 -388.001689) (xy 74.259186 -388.02945) (xy 74.254614 -388.037578)
			(xy 74.252328 -388.055612) (xy 74.271378 -388.138924) (xy 74.281284 -388.15391) (xy 74.288904 -388.159498)
			(xy 74.30943 -388.174952) (xy 74.346567 -388.210457) (xy 74.378602 -388.250627) (xy 74.404954 -388.294733)
			(xy 74.406211 -388.297674) (xy 76.33665 -388.297674) (xy 76.340721 -388.242052) (xy 76.352847 -388.187615)
			(xy 76.37277 -388.135524) (xy 76.400066 -388.086889) (xy 76.434152 -388.042746) (xy 76.474301 -388.004037)
			(xy 76.519659 -387.971586) (xy 76.569259 -387.946085) (xy 76.622043 -387.928078) (xy 76.676886 -387.917948)
			(xy 76.73262 -387.915911) (xy 76.788057 -387.922011) (xy 76.842014 -387.936117) (xy 76.893343 -387.957929)
			(xy 76.940949 -387.986983) (xy 76.983817 -388.022658) (xy 77.021034 -388.064195) (xy 77.051807 -388.110708)
			(xy 77.075479 -388.161205) (xy 77.091547 -388.214612) (xy 77.099667 -388.269788) (xy 77.100176 -388.297674)
			(xy 77.099729 -388.322137) (xy 77.302616 -388.322137) (xy 77.302616 -388.270163) (xy 77.310746 -388.218828)
			(xy 77.326807 -388.169398) (xy 77.350403 -388.123088) (xy 77.380953 -388.08104) (xy 77.417704 -388.044289)
			(xy 77.459752 -388.013739) (xy 77.506062 -387.990143) (xy 77.555492 -387.974082) (xy 77.606827 -387.965952)
			(xy 77.658801 -387.965952) (xy 77.710136 -387.974082) (xy 77.759566 -387.990143) (xy 77.805876 -388.013739)
			(xy 77.847924 -388.044289) (xy 77.884675 -388.08104) (xy 77.915225 -388.123088) (xy 77.938821 -388.169398)
			(xy 77.954882 -388.218828) (xy 77.963012 -388.270163) (xy 77.963522 -388.29615) (xy 77.963012 -388.322137)
			(xy 77.954882 -388.373472) (xy 77.938821 -388.422902) (xy 77.915225 -388.469212) (xy 77.884675 -388.51126)
			(xy 77.847924 -388.548011) (xy 77.805876 -388.578561) (xy 77.759566 -388.602157) (xy 77.710136 -388.618218)
			(xy 77.658801 -388.626348) (xy 77.606827 -388.626348) (xy 77.555492 -388.618218) (xy 77.506062 -388.602157)
			(xy 77.459752 -388.578561) (xy 77.417704 -388.548011) (xy 77.380953 -388.51126) (xy 77.350403 -388.469212)
			(xy 77.326807 -388.422902) (xy 77.310746 -388.373472) (xy 77.302616 -388.322137) (xy 77.099729 -388.322137)
			(xy 77.099667 -388.32556) (xy 77.091547 -388.380736) (xy 77.075479 -388.434143) (xy 77.051807 -388.48464)
			(xy 77.021034 -388.531153) (xy 76.983817 -388.57269) (xy 76.940949 -388.608365) (xy 76.893343 -388.637419)
			(xy 76.842014 -388.659231) (xy 76.788057 -388.673337) (xy 76.73262 -388.679437) (xy 76.676886 -388.6774)
			(xy 76.622043 -388.66727) (xy 76.569259 -388.649263) (xy 76.519659 -388.623762) (xy 76.474301 -388.591311)
			(xy 76.434152 -388.552602) (xy 76.400066 -388.508459) (xy 76.37277 -388.459824) (xy 76.352847 -388.407733)
			(xy 76.340721 -388.353296) (xy 76.33665 -388.297674) (xy 74.406211 -388.297674) (xy 74.425147 -388.341977)
			(xy 74.438815 -388.391505) (xy 74.445711 -388.442419) (xy 74.44613 -388.468108) (xy 74.445686 -388.495479)
			(xy 74.437865 -388.54966) (xy 74.422372 -388.602164) (xy 74.399525 -388.651911) (xy 74.369794 -388.697876)
			(xy 74.35215 -388.718806) (xy 74.346054 -388.725918) (xy 74.339704 -388.742936) (xy 74.339704 -388.82828)
			(xy 74.346054 -388.845298) (xy 74.35215 -388.85241) (xy 74.369799 -388.873334) (xy 74.399511 -388.919308)
			(xy 74.422346 -388.969058) (xy 74.437835 -389.02156) (xy 74.445659 -389.075738) (xy 74.44613 -389.103108)
			(xy 74.445644 -389.130359) (xy 74.437888 -389.184307) (xy 74.422533 -389.236602) (xy 74.399891 -389.286179)
			(xy 74.370425 -389.332029) (xy 74.334734 -389.37322) (xy 74.293543 -389.408911) (xy 74.247693 -389.438377)
			(xy 74.198116 -389.461019) (xy 74.145821 -389.476374) (xy 74.091873 -389.48413) (xy 74.037371 -389.48413)
			(xy 73.983423 -389.476374) (xy 73.931128 -389.461019) (xy 73.881551 -389.438377) (xy 73.835701 -389.408911)
			(xy 73.79451 -389.37322) (xy 73.758819 -389.332029) (xy 73.729353 -389.286179) (xy 73.706711 -389.236602)
			(xy 73.691356 -389.184307) (xy 73.6836 -389.130359) (xy 73.683114 -389.103108) (xy 73.683581 -389.075738)
			(xy 73.691398 -389.021559) (xy 73.706887 -388.969055) (xy 73.729728 -388.919308) (xy 73.759453 -388.873342)
			(xy 73.777094 -388.85241) (xy 73.78319 -388.845298) (xy 73.78954 -388.82828) (xy 73.78954 -388.742936)
			(xy 73.78319 -388.725918) (xy 73.777094 -388.718806) (xy 73.759443 -388.697883) (xy 73.729733 -388.651908)
			(xy 73.7069 -388.602158) (xy 73.691411 -388.549655) (xy 73.683586 -388.495478) (xy 73.683114 -388.468108)
			(xy 73.683401 -388.446584) (xy 73.688238 -388.403809) (xy 73.692766 -388.382764) (xy 73.694798 -388.37362)
			(xy 73.692512 -388.355586) (xy 73.652126 -388.280148) (xy 73.638664 -388.26821) (xy 73.629774 -388.264908)
			(xy 73.601252 -388.253536) (xy 73.546906 -388.224955) (xy 73.496399 -388.190037) (xy 73.450465 -388.149289)
			(xy 73.409774 -388.103304) (xy 73.374918 -388.052754) (xy 73.346405 -387.998373) (xy 73.324649 -387.940954)
			(xy 73.309968 -387.881332) (xy 73.302575 -387.820375) (xy 73.302114 -387.789674) (xy 72.72062 -387.789674)
			(xy 72.720708 -387.7945) (xy 72.720199 -387.822386) (xy 72.712079 -387.877562) (xy 72.696011 -387.930969)
			(xy 72.672339 -387.981466) (xy 72.641566 -388.027979) (xy 72.604349 -388.069516) (xy 72.561481 -388.105191)
			(xy 72.513875 -388.134245) (xy 72.462546 -388.156057) (xy 72.408589 -388.170163) (xy 72.353152 -388.176263)
			(xy 72.297418 -388.174226) (xy 72.242575 -388.164096) (xy 72.189791 -388.146089) (xy 72.140191 -388.120588)
			(xy 72.094833 -388.088137) (xy 72.054684 -388.049428) (xy 72.020598 -388.005285) (xy 71.993302 -387.95665)
			(xy 71.973379 -387.904559) (xy 71.961253 -387.850122) (xy 71.957182 -387.7945) (xy 69.7738 -387.7945)
			(xy 69.7738 -388.43585) (xy 69.774501 -388.448007) (xy 69.785646 -388.469619) (xy 69.795136 -388.477252)
			(xy 69.872606 -388.53237) (xy 69.896736 -388.535926) (xy 69.90842 -388.531862) (xy 69.938605 -388.522109)
			(xy 70.001165 -388.511642) (xy 70.03288 -388.511034) (xy 70.060131 -388.511496) (xy 70.114078 -388.51925)
			(xy 70.166372 -388.534602) (xy 70.21595 -388.557241) (xy 70.2618 -388.586705) (xy 70.302991 -388.622395)
			(xy 70.338683 -388.663584) (xy 70.368149 -388.709433) (xy 70.390791 -388.759009) (xy 70.402342 -388.798348)
			(xy 71.741308 -388.798348) (xy 71.741308 -388.743852) (xy 71.749064 -388.68991) (xy 71.764417 -388.63762)
			(xy 71.787055 -388.588048) (xy 71.816517 -388.542202) (xy 71.852204 -388.501016) (xy 71.893389 -388.465327)
			(xy 71.939234 -388.435863) (xy 71.988805 -388.413222) (xy 72.041094 -388.397867) (xy 72.095036 -388.390109)
			(xy 72.122284 -388.389622) (xy 72.149654 -388.390092) (xy 72.203833 -388.397908) (xy 72.256337 -388.413396)
			(xy 72.306083 -388.436237) (xy 72.35205 -388.465961) (xy 72.372982 -388.483602) (xy 72.380094 -388.489698)
			(xy 72.397112 -388.496048) (xy 72.482456 -388.496048) (xy 72.499474 -388.489698) (xy 72.506586 -388.483602)
			(xy 72.527513 -388.465956) (xy 72.573487 -388.436245) (xy 72.623236 -388.413411) (xy 72.675738 -388.397921)
			(xy 72.729914 -388.390095) (xy 72.757284 -388.389622) (xy 72.78454 -388.390024) (xy 72.838497 -388.39778)
			(xy 72.890801 -388.413135) (xy 72.940387 -388.435779) (xy 72.986246 -388.465249) (xy 73.027443 -388.500945)
			(xy 73.063142 -388.542142) (xy 73.092613 -388.587999) (xy 73.115259 -388.637584) (xy 73.130617 -388.689888)
			(xy 73.138375 -388.743844) (xy 73.138375 -388.798356) (xy 73.130617 -388.852312) (xy 73.115259 -388.904616)
			(xy 73.092613 -388.954201) (xy 73.063142 -389.000058) (xy 73.027443 -389.041255) (xy 72.986246 -389.076951)
			(xy 72.940387 -389.106421) (xy 72.890801 -389.129065) (xy 72.838497 -389.14442) (xy 72.78454 -389.152176)
			(xy 72.757284 -389.152638) (xy 72.729913 -389.152196) (xy 72.675732 -389.144375) (xy 72.623228 -389.128881)
			(xy 72.573481 -389.106033) (xy 72.527516 -389.076303) (xy 72.506586 -389.058658) (xy 72.499474 -389.052562)
			(xy 72.482456 -389.046212) (xy 72.397112 -389.046212) (xy 72.380094 -389.052562) (xy 72.372982 -389.058658)
			(xy 72.352024 -389.076266) (xy 72.306059 -389.105984) (xy 72.256318 -389.128826) (xy 72.203823 -389.144325)
			(xy 72.149652 -389.15216) (xy 72.122284 -389.152638) (xy 72.095036 -389.152091) (xy 72.041094 -389.144333)
			(xy 71.988805 -389.128978) (xy 71.939234 -389.106337) (xy 71.893389 -389.076873) (xy 71.852204 -389.041184)
			(xy 71.816517 -388.999998) (xy 71.787055 -388.954152) (xy 71.764417 -388.90458) (xy 71.749064 -388.85229)
			(xy 71.741308 -388.798348) (xy 70.402342 -388.798348) (xy 70.406146 -388.811302) (xy 70.413903 -388.865249)
			(xy 70.413903 -388.919751) (xy 70.406146 -388.973698) (xy 70.390791 -389.025991) (xy 70.368149 -389.075567)
			(xy 70.338683 -389.121416) (xy 70.302991 -389.162605) (xy 70.2618 -389.198295) (xy 70.21595 -389.227759)
			(xy 70.166372 -389.250398) (xy 70.114078 -389.26575) (xy 70.060131 -389.273504) (xy 70.03288 -389.27405)
			(xy 70.001167 -389.27342) (xy 69.93861 -389.262953) (xy 69.90842 -389.253222) (xy 69.896736 -389.249158)
			(xy 69.872606 -389.252714) (xy 69.795136 -389.307832) (xy 69.78562 -389.315444) (xy 69.774461 -389.337067)
			(xy 69.7738 -389.349234) (xy 69.7738 -390.097518) (xy 69.774227 -390.107587) (xy 69.781946 -390.126186)
			(xy 69.788786 -390.133586) (xy 69.959982 -390.304782) (xy 69.966667 -390.310898) (xy 69.983156 -390.318377)
			(xy 70.001218 -390.31964) (xy 70.01002 -390.317482) (xy 70.10908 -390.28878) (xy 70.127876 -390.268714)
			(xy 70.130924 -390.254998) (xy 70.137655 -390.227128) (xy 70.158343 -390.173658) (xy 70.186797 -390.123885)
			(xy 70.222377 -390.078929) (xy 70.264283 -390.039801) (xy 70.31157 -390.007383) (xy 70.363176 -389.982404)
			(xy 70.417937 -389.965427) (xy 70.474622 -389.956833) (xy 70.503288 -389.956294) (xy 70.530656 -389.956772)
			(xy 70.584828 -389.964607) (xy 70.637325 -389.980103) (xy 70.687067 -390.002943) (xy 70.733036 -390.032658)
			(xy 70.753986 -390.050274) (xy 70.761098 -390.05637) (xy 70.778116 -390.06272) (xy 70.86346 -390.06272)
			(xy 70.880478 -390.05637) (xy 70.88759 -390.050274) (xy 70.908522 -390.032633) (xy 70.954488 -390.002907)
			(xy 71.004235 -389.980064) (xy 71.056738 -389.964574) (xy 71.110918 -389.956755) (xy 71.138288 -389.956294)
			(xy 71.165541 -389.956757) (xy 71.219493 -389.964512) (xy 71.271792 -389.979867) (xy 71.321374 -390.002509)
			(xy 71.367228 -390.031976) (xy 71.408422 -390.06767) (xy 71.444117 -390.108862) (xy 71.473586 -390.154716)
			(xy 71.496229 -390.204297) (xy 71.511585 -390.256595) (xy 71.519343 -390.310547) (xy 71.519343 -390.365053)
			(xy 71.511585 -390.419005) (xy 71.496229 -390.471303) (xy 71.473586 -390.520884) (xy 71.444117 -390.566738)
			(xy 71.408422 -390.60793) (xy 71.367228 -390.643624) (xy 71.321374 -390.673091) (xy 71.271792 -390.695733)
			(xy 71.219493 -390.711088) (xy 71.165541 -390.718843) (xy 71.138288 -390.71931) (xy 71.110918 -390.718837)
			(xy 71.056741 -390.711012) (xy 71.004238 -390.695524) (xy 70.954487 -390.672691) (xy 70.908511 -390.642983)
			(xy 70.88759 -390.62533) (xy 70.880478 -390.619234) (xy 70.86346 -390.612884) (xy 70.778116 -390.612884)
			(xy 70.761098 -390.619234) (xy 70.753986 -390.62533) (xy 70.729682 -390.645692) (xy 70.675666 -390.678885)
			(xy 70.616903 -390.702685) (xy 70.586092 -390.710166) (xy 70.572376 -390.713214) (xy 70.55231 -390.73201)
			(xy 70.523608 -390.83107) (xy 70.521427 -390.839865) (xy 70.522715 -390.857928) (xy 70.530192 -390.874422)
			(xy 70.536308 -390.881108) (xy 70.946518 -391.291318) (xy 70.953914 -391.29817) (xy 70.972513 -391.305911)
			(xy 70.982586 -391.306304) (xy 71.211948 -391.306304) (xy 71.223056 -391.305741) (xy 71.24321 -391.296391)
			(xy 71.25081 -391.28827) (xy 71.271309 -391.26467) (xy 71.317138 -391.222156) (xy 71.367838 -391.185586)
			(xy 71.422641 -391.155513) (xy 71.480721 -391.132392) (xy 71.541198 -391.116573) (xy 71.57212 -391.111994)
			(xy 71.58355 -391.11047) (xy 71.602092 -391.098532) (xy 71.65594 -391.013188) (xy 71.658734 -390.991344)
			(xy 71.655178 -390.980168) (xy 71.643905 -390.942429) (xy 71.631786 -390.864608) (xy 71.631048 -390.825228)
			(xy 71.63151 -390.794495) (xy 71.638915 -390.733477) (xy 71.653622 -390.673796) (xy 71.675414 -390.616322)
			(xy 71.703975 -390.561895) (xy 71.738889 -390.511307) (xy 71.779645 -390.465296) (xy 71.82565 -390.424533)
			(xy 71.876233 -390.389613) (xy 71.930657 -390.361044) (xy 71.988127 -390.339243) (xy 72.047806 -390.324528)
			(xy 72.108823 -390.317114) (xy 72.139556 -390.31672) (xy 72.17025 -390.317202) (xy 72.231188 -390.324629)
			(xy 72.29079 -390.339331) (xy 72.348192 -390.361096) (xy 72.402558 -390.389607) (xy 72.4281 -390.406636)
			(xy 72.436852 -390.412107) (xy 72.457056 -390.416235) (xy 72.47726 -390.412107) (xy 72.486012 -390.406636)
			(xy 72.511539 -390.389581) (xy 72.565901 -390.361053) (xy 72.623305 -390.339283) (xy 72.682914 -390.32459)
			(xy 72.743859 -390.317187) (xy 72.774556 -390.31672) (xy 72.805289 -390.317163) (xy 72.866308 -390.324567)
			(xy 72.925989 -390.339273) (xy 72.983462 -390.361067) (xy 73.037889 -390.389629) (xy 73.088476 -390.424544)
			(xy 73.134486 -390.465303) (xy 73.175246 -390.511311) (xy 73.210163 -390.561897) (xy 73.238727 -390.616323)
			(xy 73.260522 -390.673795) (xy 73.27523 -390.733476) (xy 73.282636 -390.794495) (xy 73.283064 -390.825228)
			(xy 73.28249 -390.860073) (xy 73.272972 -390.929111) (xy 73.254118 -390.996203) (xy 73.226281 -391.060093)
			(xy 73.208642 -391.09015) (xy 73.203562 -391.098278) (xy 73.20026 -391.116058) (xy 73.214738 -391.200386)
			(xy 73.223882 -391.21588) (xy 73.230994 -391.221976) (xy 73.249211 -391.237143) (xy 73.283048 -391.270345)
			(xy 73.298558 -391.28827) (xy 73.306151 -391.296398) (xy 73.32631 -391.305739) (xy 73.33742 -391.306304)
			(xy 73.591928 -391.306304) (xy 73.603038 -391.305745) (xy 73.623198 -391.2964) (xy 73.63079 -391.28827)
			(xy 73.649775 -391.266346) (xy 73.691914 -391.226498) (xy 73.714864 -391.208768) (xy 73.721964 -391.203006)
			(xy 73.731861 -391.187644) (xy 73.734168 -391.178796) (xy 73.740518 -391.149078) (xy 73.742018 -391.140189)
			(xy 73.739433 -391.12236) (xy 73.735438 -391.11428) (xy 73.721051 -391.086238) (xy 73.700659 -391.026607)
			(xy 73.690346 -390.964435) (xy 73.689718 -390.932924) (xy 73.690195 -390.905556) (xy 73.698029 -390.851383)
			(xy 73.713525 -390.798886) (xy 73.736365 -390.749143) (xy 73.76608 -390.703175) (xy 73.783698 -390.682226)
			(xy 73.789794 -390.675114) (xy 73.796144 -390.658096) (xy 73.796144 -390.572752) (xy 73.789794 -390.555734)
			(xy 73.783698 -390.548622) (xy 73.766055 -390.527691) (xy 73.736326 -390.481725) (xy 73.71348 -390.431978)
			(xy 73.697987 -390.379475) (xy 73.690166 -390.325295) (xy 73.689718 -390.297924) (xy 73.690204 -390.270673)
			(xy 73.69796 -390.216725) (xy 73.713315 -390.16443) (xy 73.735957 -390.114853) (xy 73.765423 -390.069003)
			(xy 73.801114 -390.027812) (xy 73.842305 -389.992121) (xy 73.888155 -389.962655) (xy 73.937732 -389.940013)
			(xy 73.990027 -389.924658) (xy 74.043975 -389.916902) (xy 74.098477 -389.916902) (xy 74.152425 -389.924658)
			(xy 74.20472 -389.940013) (xy 74.254297 -389.962655) (xy 74.300147 -389.992121) (xy 74.341338 -390.027812)
			(xy 74.377029 -390.069003) (xy 74.406495 -390.114853) (xy 74.429137 -390.16443) (xy 74.444492 -390.216725)
			(xy 74.452248 -390.270673) (xy 74.452734 -390.297924) (xy 74.45226 -390.325293) (xy 74.444432 -390.379469)
			(xy 74.428941 -390.431969) (xy 74.406103 -390.481715) (xy 74.376389 -390.527687) (xy 74.358754 -390.548622)
			(xy 74.352658 -390.555734) (xy 74.346308 -390.572752) (xy 74.346308 -390.658096) (xy 74.352658 -390.675114)
			(xy 74.358754 -390.682226) (xy 74.376396 -390.703157) (xy 74.406123 -390.749123) (xy 74.428965 -390.79887)
			(xy 74.444454 -390.851374) (xy 74.45227 -390.905554) (xy 74.452734 -390.932924) (xy 74.452563 -390.949263)
			(xy 74.449769 -390.98182) (xy 74.447146 -390.997948) (xy 74.445114 -391.010394) (xy 74.45248 -391.034016)
			(xy 74.529188 -391.110216) (xy 74.55281 -391.117582) (xy 74.565002 -391.115296) (xy 74.587231 -391.111585)
			(xy 74.632129 -391.107643) (xy 74.654664 -391.107422) (xy 74.685358 -391.107904) (xy 74.746296 -391.115332)
			(xy 74.805897 -391.130035) (xy 74.863298 -391.151801) (xy 74.917664 -391.180313) (xy 74.943208 -391.197338)
			(xy 74.95196 -391.202809) (xy 74.972164 -391.206937) (xy 74.992368 -391.202809) (xy 75.00112 -391.197338)
			(xy 75.026647 -391.180284) (xy 75.08101 -391.151756) (xy 75.138414 -391.129987) (xy 75.198023 -391.115295)
			(xy 75.258968 -391.107892) (xy 75.289664 -391.107422) (xy 75.320358 -391.107904) (xy 75.381296 -391.115332)
			(xy 75.440897 -391.130035) (xy 75.498298 -391.151801) (xy 75.552664 -391.180313) (xy 75.578208 -391.197338)
			(xy 75.58696 -391.202809) (xy 75.607164 -391.206937) (xy 75.627368 -391.202809) (xy 75.63612 -391.197338)
			(xy 75.661647 -391.180284) (xy 75.71601 -391.151756) (xy 75.773414 -391.129987) (xy 75.833023 -391.115295)
			(xy 75.893968 -391.107892) (xy 75.924664 -391.107422) (xy 75.956298 -391.107901) (xy 76.019079 -391.115746)
			(xy 76.080401 -391.131319) (xy 76.139317 -391.15438) (xy 76.194917 -391.184572) (xy 76.246341 -391.221428)
			(xy 76.292796 -391.26438) (xy 76.313538 -391.28827) (xy 76.32113 -391.296402) (xy 76.341288 -391.305751)
			(xy 76.3524 -391.306304) (xy 77.557884 -391.306304) (xy 77.567327 -391.305808) (xy 77.584909 -391.298895)
			(xy 77.592174 -391.292842) (xy 77.650086 -391.239756) (xy 77.658214 -391.222738) (xy 77.658976 -391.213086)
			(xy 77.661008 -391.195814) (xy 77.662532 -391.1854) (xy 77.657198 -391.165842) (xy 77.59954 -391.091928)
			(xy 77.58176 -391.082276) (xy 77.571346 -391.081006) (xy 77.54116 -391.077198) (xy 77.48209 -391.06262)
			(xy 77.425471 -391.040347) (xy 77.372301 -391.010771) (xy 77.323517 -390.974413) (xy 77.279978 -390.931913)
			(xy 77.242452 -390.884022) (xy 77.211601 -390.831581) (xy 77.187967 -390.775517) (xy 77.171967 -390.716816)
			(xy 77.163883 -390.656513) (xy 77.163422 -390.626092) (xy 77.164025 -390.592804) (xy 77.17367 -390.52693)
			(xy 77.192741 -390.463144) (xy 77.220837 -390.402787) (xy 77.238606 -390.374632) (xy 77.24366 -390.366112)
			(xy 77.247476 -390.346693) (xy 77.243654 -390.327276) (xy 77.238606 -390.318752) (xy 77.220812 -390.290608)
			(xy 77.19268 -390.23026) (xy 77.173603 -390.166469) (xy 77.163985 -390.100584) (xy 77.163422 -390.067292)
			(xy 77.163912 -390.037324) (xy 77.171735 -389.977902) (xy 77.187248 -389.920009) (xy 77.210184 -389.864636)
			(xy 77.240151 -389.81273) (xy 77.276638 -389.76518) (xy 77.319018 -389.7228) (xy 77.366568 -389.686313)
			(xy 77.418474 -389.656346) (xy 77.473847 -389.63341) (xy 77.53174 -389.617897) (xy 77.591162 -389.610074)
			(xy 77.651098 -389.610074) (xy 77.71052 -389.617897) (xy 77.768413 -389.63341) (xy 77.823786 -389.656346)
			(xy 77.875692 -389.686313) (xy 77.923242 -389.7228) (xy 77.965622 -389.76518) (xy 78.002109 -389.81273)
			(xy 78.032076 -389.864636) (xy 78.055012 -389.920009) (xy 78.070525 -389.977902) (xy 78.078348 -390.037324)
			(xy 78.078838 -390.067292) (xy 78.078237 -390.100581) (xy 78.06954 -390.160002) (xy 79.61301 -390.160002)
			(xy 79.61697 -390.110948) (xy 79.628747 -390.063164) (xy 79.648038 -390.017888) (xy 79.674341 -389.976292)
			(xy 79.706976 -389.939455) (xy 79.745097 -389.90833) (xy 79.787718 -389.883723) (xy 79.833734 -389.866271)
			(xy 79.881953 -389.856427) (xy 79.931128 -389.854446) (xy 79.979983 -389.860378) (xy 80.027254 -389.87407)
			(xy 80.071716 -389.895168) (xy 80.112219 -389.923124) (xy 80.147712 -389.957216) (xy 80.177277 -389.99656)
			(xy 80.200148 -390.040137) (xy 80.215732 -390.086818) (xy 80.223627 -390.135395) (xy 80.224122 -390.160002)
			(xy 80.81316 -390.160002) (xy 80.81712 -390.110948) (xy 80.828897 -390.063164) (xy 80.848188 -390.017888)
			(xy 80.874491 -389.976292) (xy 80.907126 -389.939455) (xy 80.945247 -389.90833) (xy 80.987868 -389.883723)
			(xy 81.033884 -389.866271) (xy 81.082103 -389.856427) (xy 81.131278 -389.854446) (xy 81.180133 -389.860378)
			(xy 81.227404 -389.87407) (xy 81.271866 -389.895168) (xy 81.312369 -389.923124) (xy 81.347862 -389.957216)
			(xy 81.377427 -389.99656) (xy 81.400298 -390.040137) (xy 81.415882 -390.086818) (xy 81.423777 -390.135395)
			(xy 81.424272 -390.160002) (xy 82.01331 -390.160002) (xy 82.01727 -390.110948) (xy 82.029047 -390.063164)
			(xy 82.048338 -390.017888) (xy 82.074641 -389.976292) (xy 82.107276 -389.939455) (xy 82.145397 -389.90833)
			(xy 82.188018 -389.883723) (xy 82.234034 -389.866271) (xy 82.282253 -389.856427) (xy 82.331428 -389.854446)
			(xy 82.380283 -389.860378) (xy 82.427554 -389.87407) (xy 82.472016 -389.895168) (xy 82.512519 -389.923124)
			(xy 82.548012 -389.957216) (xy 82.577577 -389.99656) (xy 82.600448 -390.040137) (xy 82.616032 -390.086818)
			(xy 82.623927 -390.135395) (xy 82.624422 -390.160002) (xy 83.213206 -390.160002) (xy 83.217166 -390.110948)
			(xy 83.228943 -390.063164) (xy 83.248234 -390.017888) (xy 83.274537 -389.976292) (xy 83.307172 -389.939455)
			(xy 83.345293 -389.90833) (xy 83.387914 -389.883723) (xy 83.43393 -389.866271) (xy 83.482149 -389.856427)
			(xy 83.531324 -389.854446) (xy 83.580179 -389.860378) (xy 83.62745 -389.87407) (xy 83.671912 -389.895168)
			(xy 83.712415 -389.923124) (xy 83.747908 -389.957216) (xy 83.777473 -389.99656) (xy 83.800344 -390.040137)
			(xy 83.815928 -390.086818) (xy 83.823823 -390.135395) (xy 83.824318 -390.160002) (xy 84.413356 -390.160002)
			(xy 84.417316 -390.110948) (xy 84.429093 -390.063164) (xy 84.448384 -390.017888) (xy 84.474687 -389.976292)
			(xy 84.507322 -389.939455) (xy 84.545443 -389.90833) (xy 84.588064 -389.883723) (xy 84.63408 -389.866271)
			(xy 84.682299 -389.856427) (xy 84.731474 -389.854446) (xy 84.780329 -389.860378) (xy 84.8276 -389.87407)
			(xy 84.872062 -389.895168) (xy 84.912565 -389.923124) (xy 84.948058 -389.957216) (xy 84.977623 -389.99656)
			(xy 85.000494 -390.040137) (xy 85.016078 -390.086818) (xy 85.023973 -390.135395) (xy 85.024468 -390.160002)
			(xy 85.613252 -390.160002) (xy 85.617212 -390.110948) (xy 85.628989 -390.063164) (xy 85.64828 -390.017888)
			(xy 85.674583 -389.976292) (xy 85.707218 -389.939455) (xy 85.745339 -389.90833) (xy 85.78796 -389.883723)
			(xy 85.833976 -389.866271) (xy 85.882195 -389.856427) (xy 85.93137 -389.854446) (xy 85.980225 -389.860378)
			(xy 86.027496 -389.87407) (xy 86.071958 -389.895168) (xy 86.112461 -389.923124) (xy 86.147954 -389.957216)
			(xy 86.177519 -389.99656) (xy 86.20039 -390.040137) (xy 86.215974 -390.086818) (xy 86.223869 -390.135395)
			(xy 86.224364 -390.160002) (xy 86.813148 -390.160002) (xy 86.817108 -390.110948) (xy 86.828885 -390.063164)
			(xy 86.848176 -390.017888) (xy 86.874479 -389.976292) (xy 86.907114 -389.939455) (xy 86.945235 -389.90833)
			(xy 86.987856 -389.883723) (xy 87.033872 -389.866271) (xy 87.082091 -389.856427) (xy 87.131266 -389.854446)
			(xy 87.180121 -389.860378) (xy 87.227392 -389.87407) (xy 87.271854 -389.895168) (xy 87.312357 -389.923124)
			(xy 87.34785 -389.957216) (xy 87.377415 -389.99656) (xy 87.400286 -390.040137) (xy 87.41587 -390.086818)
			(xy 87.423765 -390.135395) (xy 87.42426 -390.160002) (xy 88.013298 -390.160002) (xy 88.017258 -390.110948)
			(xy 88.029035 -390.063164) (xy 88.048326 -390.017888) (xy 88.074629 -389.976292) (xy 88.107264 -389.939455)
			(xy 88.145385 -389.90833) (xy 88.188006 -389.883723) (xy 88.234022 -389.866271) (xy 88.282241 -389.856427)
			(xy 88.331416 -389.854446) (xy 88.380271 -389.860378) (xy 88.427542 -389.87407) (xy 88.472004 -389.895168)
			(xy 88.512507 -389.923124) (xy 88.548 -389.957216) (xy 88.577565 -389.99656) (xy 88.600436 -390.040137)
			(xy 88.61602 -390.086818) (xy 88.623915 -390.135395) (xy 88.62441 -390.160002) (xy 89.213194 -390.160002)
			(xy 89.217154 -390.110948) (xy 89.228931 -390.063164) (xy 89.248222 -390.017888) (xy 89.274525 -389.976292)
			(xy 89.30716 -389.939455) (xy 89.345281 -389.90833) (xy 89.387902 -389.883723) (xy 89.433918 -389.866271)
			(xy 89.482137 -389.856427) (xy 89.531312 -389.854446) (xy 89.580167 -389.860378) (xy 89.627438 -389.87407)
			(xy 89.6719 -389.895168) (xy 89.712403 -389.923124) (xy 89.747896 -389.957216) (xy 89.777461 -389.99656)
			(xy 89.800332 -390.040137) (xy 89.815916 -390.086818) (xy 89.823811 -390.135395) (xy 89.824306 -390.160002)
			(xy 90.413344 -390.160002) (xy 90.417304 -390.110948) (xy 90.429081 -390.063164) (xy 90.448372 -390.017888)
			(xy 90.474675 -389.976292) (xy 90.50731 -389.939455) (xy 90.545431 -389.90833) (xy 90.588052 -389.883723)
			(xy 90.634068 -389.866271) (xy 90.682287 -389.856427) (xy 90.731462 -389.854446) (xy 90.780317 -389.860378)
			(xy 90.827588 -389.87407) (xy 90.87205 -389.895168) (xy 90.912553 -389.923124) (xy 90.948046 -389.957216)
			(xy 90.977611 -389.99656) (xy 91.000482 -390.040137) (xy 91.016066 -390.086818) (xy 91.023961 -390.135395)
			(xy 91.024456 -390.160002) (xy 91.61324 -390.160002) (xy 91.6172 -390.110948) (xy 91.628977 -390.063164)
			(xy 91.648268 -390.017888) (xy 91.674571 -389.976292) (xy 91.707206 -389.939455) (xy 91.745327 -389.90833)
			(xy 91.787948 -389.883723) (xy 91.833964 -389.866271) (xy 91.882183 -389.856427) (xy 91.931358 -389.854446)
			(xy 91.980213 -389.860378) (xy 92.027484 -389.87407) (xy 92.071946 -389.895168) (xy 92.112449 -389.923124)
			(xy 92.147942 -389.957216) (xy 92.177507 -389.99656) (xy 92.200378 -390.040137) (xy 92.215962 -390.086818)
			(xy 92.223857 -390.135395) (xy 92.224352 -390.160002) (xy 92.813136 -390.160002) (xy 92.817096 -390.110948)
			(xy 92.828873 -390.063164) (xy 92.848164 -390.017888) (xy 92.874467 -389.976292) (xy 92.907102 -389.939455)
			(xy 92.945223 -389.90833) (xy 92.987844 -389.883723) (xy 93.03386 -389.866271) (xy 93.082079 -389.856427)
			(xy 93.131254 -389.854446) (xy 93.180109 -389.860378) (xy 93.22738 -389.87407) (xy 93.271842 -389.895168)
			(xy 93.312345 -389.923124) (xy 93.347838 -389.957216) (xy 93.377403 -389.99656) (xy 93.400274 -390.040137)
			(xy 93.415858 -390.086818) (xy 93.423753 -390.135395) (xy 93.424248 -390.160002) (xy 94.013286 -390.160002)
			(xy 94.017246 -390.110948) (xy 94.029023 -390.063164) (xy 94.048314 -390.017888) (xy 94.074617 -389.976292)
			(xy 94.107252 -389.939455) (xy 94.145373 -389.90833) (xy 94.187994 -389.883723) (xy 94.23401 -389.866271)
			(xy 94.282229 -389.856427) (xy 94.331404 -389.854446) (xy 94.380259 -389.860378) (xy 94.42753 -389.87407)
			(xy 94.471992 -389.895168) (xy 94.512495 -389.923124) (xy 94.547988 -389.957216) (xy 94.577553 -389.99656)
			(xy 94.600424 -390.040137) (xy 94.616008 -390.086818) (xy 94.623903 -390.135395) (xy 94.624398 -390.160002)
			(xy 95.213182 -390.160002) (xy 95.217142 -390.110948) (xy 95.228919 -390.063164) (xy 95.24821 -390.017888)
			(xy 95.274513 -389.976292) (xy 95.307148 -389.939455) (xy 95.345269 -389.90833) (xy 95.38789 -389.883723)
			(xy 95.433906 -389.866271) (xy 95.482125 -389.856427) (xy 95.5313 -389.854446) (xy 95.580155 -389.860378)
			(xy 95.627426 -389.87407) (xy 95.671888 -389.895168) (xy 95.712391 -389.923124) (xy 95.747884 -389.957216)
			(xy 95.777449 -389.99656) (xy 95.80032 -390.040137) (xy 95.815904 -390.086818) (xy 95.823799 -390.135395)
			(xy 95.824294 -390.160002) (xy 96.413332 -390.160002) (xy 96.417292 -390.110948) (xy 96.429069 -390.063164)
			(xy 96.44836 -390.017888) (xy 96.474663 -389.976292) (xy 96.507298 -389.939455) (xy 96.545419 -389.90833)
			(xy 96.58804 -389.883723) (xy 96.634056 -389.866271) (xy 96.682275 -389.856427) (xy 96.73145 -389.854446)
			(xy 96.780305 -389.860378) (xy 96.827576 -389.87407) (xy 96.872038 -389.895168) (xy 96.912541 -389.923124)
			(xy 96.948034 -389.957216) (xy 96.977599 -389.99656) (xy 97.00047 -390.040137) (xy 97.016054 -390.086818)
			(xy 97.023949 -390.135395) (xy 97.024444 -390.160002) (xy 97.613228 -390.160002) (xy 97.617188 -390.110948)
			(xy 97.628965 -390.063164) (xy 97.648256 -390.017888) (xy 97.674559 -389.976292) (xy 97.707194 -389.939455)
			(xy 97.745315 -389.90833) (xy 97.787936 -389.883723) (xy 97.833952 -389.866271) (xy 97.882171 -389.856427)
			(xy 97.931346 -389.854446) (xy 97.980201 -389.860378) (xy 98.027472 -389.87407) (xy 98.071934 -389.895168)
			(xy 98.112437 -389.923124) (xy 98.14793 -389.957216) (xy 98.177495 -389.99656) (xy 98.200366 -390.040137)
			(xy 98.21595 -390.086818) (xy 98.223845 -390.135395) (xy 98.22434 -390.160002) (xy 98.223845 -390.184609)
			(xy 98.223621 -390.185989) (xy 98.942908 -390.185989) (xy 98.942908 -390.134015) (xy 98.951038 -390.08268)
			(xy 98.967099 -390.03325) (xy 98.990695 -389.98694) (xy 99.021245 -389.944892) (xy 99.057996 -389.908141)
			(xy 99.100044 -389.877591) (xy 99.146354 -389.853995) (xy 99.195784 -389.837934) (xy 99.247119 -389.829804)
			(xy 99.299093 -389.829804) (xy 99.350428 -389.837934) (xy 99.399858 -389.853995) (xy 99.446168 -389.877591)
			(xy 99.488216 -389.908141) (xy 99.524967 -389.944892) (xy 99.555517 -389.98694) (xy 99.579113 -390.03325)
			(xy 99.595174 -390.08268) (xy 99.603304 -390.134015) (xy 99.603814 -390.160002) (xy 99.603304 -390.185989)
			(xy 99.595174 -390.237324) (xy 99.579113 -390.286754) (xy 99.555517 -390.333064) (xy 99.524967 -390.375112)
			(xy 99.488216 -390.411863) (xy 99.446168 -390.442413) (xy 99.399858 -390.466009) (xy 99.350428 -390.48207)
			(xy 99.299093 -390.4902) (xy 99.247119 -390.4902) (xy 99.195784 -390.48207) (xy 99.146354 -390.466009)
			(xy 99.100044 -390.442413) (xy 99.057996 -390.411863) (xy 99.021245 -390.375112) (xy 98.990695 -390.333064)
			(xy 98.967099 -390.286754) (xy 98.951038 -390.237324) (xy 98.942908 -390.185989) (xy 98.223621 -390.185989)
			(xy 98.21595 -390.233186) (xy 98.200366 -390.279867) (xy 98.177495 -390.323444) (xy 98.14793 -390.362788)
			(xy 98.112437 -390.39688) (xy 98.071934 -390.424836) (xy 98.027472 -390.445934) (xy 97.980201 -390.459626)
			(xy 97.931346 -390.465558) (xy 97.882171 -390.463577) (xy 97.833952 -390.453733) (xy 97.787936 -390.436281)
			(xy 97.745315 -390.411674) (xy 97.707194 -390.380549) (xy 97.674559 -390.343712) (xy 97.648256 -390.302116)
			(xy 97.628965 -390.25684) (xy 97.617188 -390.209056) (xy 97.613228 -390.160002) (xy 97.024444 -390.160002)
			(xy 97.023949 -390.184609) (xy 97.016054 -390.233186) (xy 97.00047 -390.279867) (xy 96.977599 -390.323444)
			(xy 96.948034 -390.362788) (xy 96.912541 -390.39688) (xy 96.872038 -390.424836) (xy 96.827576 -390.445934)
			(xy 96.780305 -390.459626) (xy 96.73145 -390.465558) (xy 96.682275 -390.463577) (xy 96.634056 -390.453733)
			(xy 96.58804 -390.436281) (xy 96.545419 -390.411674) (xy 96.507298 -390.380549) (xy 96.474663 -390.343712)
			(xy 96.44836 -390.302116) (xy 96.429069 -390.25684) (xy 96.417292 -390.209056) (xy 96.413332 -390.160002)
			(xy 95.824294 -390.160002) (xy 95.823799 -390.184609) (xy 95.815904 -390.233186) (xy 95.80032 -390.279867)
			(xy 95.777449 -390.323444) (xy 95.747884 -390.362788) (xy 95.712391 -390.39688) (xy 95.671888 -390.424836)
			(xy 95.627426 -390.445934) (xy 95.580155 -390.459626) (xy 95.5313 -390.465558) (xy 95.482125 -390.463577)
			(xy 95.433906 -390.453733) (xy 95.38789 -390.436281) (xy 95.345269 -390.411674) (xy 95.307148 -390.380549)
			(xy 95.274513 -390.343712) (xy 95.24821 -390.302116) (xy 95.228919 -390.25684) (xy 95.217142 -390.209056)
			(xy 95.213182 -390.160002) (xy 94.624398 -390.160002) (xy 94.623903 -390.184609) (xy 94.616008 -390.233186)
			(xy 94.600424 -390.279867) (xy 94.577553 -390.323444) (xy 94.547988 -390.362788) (xy 94.512495 -390.39688)
			(xy 94.471992 -390.424836) (xy 94.42753 -390.445934) (xy 94.380259 -390.459626) (xy 94.331404 -390.465558)
			(xy 94.282229 -390.463577) (xy 94.23401 -390.453733) (xy 94.187994 -390.436281) (xy 94.145373 -390.411674)
			(xy 94.107252 -390.380549) (xy 94.074617 -390.343712) (xy 94.048314 -390.302116) (xy 94.029023 -390.25684)
			(xy 94.017246 -390.209056) (xy 94.013286 -390.160002) (xy 93.424248 -390.160002) (xy 93.423753 -390.184609)
			(xy 93.415858 -390.233186) (xy 93.400274 -390.279867) (xy 93.377403 -390.323444) (xy 93.347838 -390.362788)
			(xy 93.312345 -390.39688) (xy 93.271842 -390.424836) (xy 93.22738 -390.445934) (xy 93.180109 -390.459626)
			(xy 93.131254 -390.465558) (xy 93.082079 -390.463577) (xy 93.03386 -390.453733) (xy 92.987844 -390.436281)
			(xy 92.945223 -390.411674) (xy 92.907102 -390.380549) (xy 92.874467 -390.343712) (xy 92.848164 -390.302116)
			(xy 92.828873 -390.25684) (xy 92.817096 -390.209056) (xy 92.813136 -390.160002) (xy 92.224352 -390.160002)
			(xy 92.223857 -390.184609) (xy 92.215962 -390.233186) (xy 92.200378 -390.279867) (xy 92.177507 -390.323444)
			(xy 92.147942 -390.362788) (xy 92.112449 -390.39688) (xy 92.071946 -390.424836) (xy 92.027484 -390.445934)
			(xy 91.980213 -390.459626) (xy 91.931358 -390.465558) (xy 91.882183 -390.463577) (xy 91.833964 -390.453733)
			(xy 91.787948 -390.436281) (xy 91.745327 -390.411674) (xy 91.707206 -390.380549) (xy 91.674571 -390.343712)
			(xy 91.648268 -390.302116) (xy 91.628977 -390.25684) (xy 91.6172 -390.209056) (xy 91.61324 -390.160002)
			(xy 91.024456 -390.160002) (xy 91.023961 -390.184609) (xy 91.016066 -390.233186) (xy 91.000482 -390.279867)
			(xy 90.977611 -390.323444) (xy 90.948046 -390.362788) (xy 90.912553 -390.39688) (xy 90.87205 -390.424836)
			(xy 90.827588 -390.445934) (xy 90.780317 -390.459626) (xy 90.731462 -390.465558) (xy 90.682287 -390.463577)
			(xy 90.634068 -390.453733) (xy 90.588052 -390.436281) (xy 90.545431 -390.411674) (xy 90.50731 -390.380549)
			(xy 90.474675 -390.343712) (xy 90.448372 -390.302116) (xy 90.429081 -390.25684) (xy 90.417304 -390.209056)
			(xy 90.413344 -390.160002) (xy 89.824306 -390.160002) (xy 89.823811 -390.184609) (xy 89.815916 -390.233186)
			(xy 89.800332 -390.279867) (xy 89.777461 -390.323444) (xy 89.747896 -390.362788) (xy 89.712403 -390.39688)
			(xy 89.6719 -390.424836) (xy 89.627438 -390.445934) (xy 89.580167 -390.459626) (xy 89.531312 -390.465558)
			(xy 89.482137 -390.463577) (xy 89.433918 -390.453733) (xy 89.387902 -390.436281) (xy 89.345281 -390.411674)
			(xy 89.30716 -390.380549) (xy 89.274525 -390.343712) (xy 89.248222 -390.302116) (xy 89.228931 -390.25684)
			(xy 89.217154 -390.209056) (xy 89.213194 -390.160002) (xy 88.62441 -390.160002) (xy 88.623915 -390.184609)
			(xy 88.61602 -390.233186) (xy 88.600436 -390.279867) (xy 88.577565 -390.323444) (xy 88.548 -390.362788)
			(xy 88.512507 -390.39688) (xy 88.472004 -390.424836) (xy 88.427542 -390.445934) (xy 88.380271 -390.459626)
			(xy 88.331416 -390.465558) (xy 88.282241 -390.463577) (xy 88.234022 -390.453733) (xy 88.188006 -390.436281)
			(xy 88.145385 -390.411674) (xy 88.107264 -390.380549) (xy 88.074629 -390.343712) (xy 88.048326 -390.302116)
			(xy 88.029035 -390.25684) (xy 88.017258 -390.209056) (xy 88.013298 -390.160002) (xy 87.42426 -390.160002)
			(xy 87.423765 -390.184609) (xy 87.41587 -390.233186) (xy 87.400286 -390.279867) (xy 87.377415 -390.323444)
			(xy 87.34785 -390.362788) (xy 87.312357 -390.39688) (xy 87.271854 -390.424836) (xy 87.227392 -390.445934)
			(xy 87.180121 -390.459626) (xy 87.131266 -390.465558) (xy 87.082091 -390.463577) (xy 87.033872 -390.453733)
			(xy 86.987856 -390.436281) (xy 86.945235 -390.411674) (xy 86.907114 -390.380549) (xy 86.874479 -390.343712)
			(xy 86.848176 -390.302116) (xy 86.828885 -390.25684) (xy 86.817108 -390.209056) (xy 86.813148 -390.160002)
			(xy 86.224364 -390.160002) (xy 86.223869 -390.184609) (xy 86.215974 -390.233186) (xy 86.20039 -390.279867)
			(xy 86.177519 -390.323444) (xy 86.147954 -390.362788) (xy 86.112461 -390.39688) (xy 86.071958 -390.424836)
			(xy 86.027496 -390.445934) (xy 85.980225 -390.459626) (xy 85.93137 -390.465558) (xy 85.882195 -390.463577)
			(xy 85.833976 -390.453733) (xy 85.78796 -390.436281) (xy 85.745339 -390.411674) (xy 85.707218 -390.380549)
			(xy 85.674583 -390.343712) (xy 85.64828 -390.302116) (xy 85.628989 -390.25684) (xy 85.617212 -390.209056)
			(xy 85.613252 -390.160002) (xy 85.024468 -390.160002) (xy 85.023973 -390.184609) (xy 85.016078 -390.233186)
			(xy 85.000494 -390.279867) (xy 84.977623 -390.323444) (xy 84.948058 -390.362788) (xy 84.912565 -390.39688)
			(xy 84.872062 -390.424836) (xy 84.8276 -390.445934) (xy 84.780329 -390.459626) (xy 84.731474 -390.465558)
			(xy 84.682299 -390.463577) (xy 84.63408 -390.453733) (xy 84.588064 -390.436281) (xy 84.545443 -390.411674)
			(xy 84.507322 -390.380549) (xy 84.474687 -390.343712) (xy 84.448384 -390.302116) (xy 84.429093 -390.25684)
			(xy 84.417316 -390.209056) (xy 84.413356 -390.160002) (xy 83.824318 -390.160002) (xy 83.823823 -390.184609)
			(xy 83.815928 -390.233186) (xy 83.800344 -390.279867) (xy 83.777473 -390.323444) (xy 83.747908 -390.362788)
			(xy 83.712415 -390.39688) (xy 83.671912 -390.424836) (xy 83.62745 -390.445934) (xy 83.580179 -390.459626)
			(xy 83.531324 -390.465558) (xy 83.482149 -390.463577) (xy 83.43393 -390.453733) (xy 83.387914 -390.436281)
			(xy 83.345293 -390.411674) (xy 83.307172 -390.380549) (xy 83.274537 -390.343712) (xy 83.248234 -390.302116)
			(xy 83.228943 -390.25684) (xy 83.217166 -390.209056) (xy 83.213206 -390.160002) (xy 82.624422 -390.160002)
			(xy 82.623927 -390.184609) (xy 82.616032 -390.233186) (xy 82.600448 -390.279867) (xy 82.577577 -390.323444)
			(xy 82.548012 -390.362788) (xy 82.512519 -390.39688) (xy 82.472016 -390.424836) (xy 82.427554 -390.445934)
			(xy 82.380283 -390.459626) (xy 82.331428 -390.465558) (xy 82.282253 -390.463577) (xy 82.234034 -390.453733)
			(xy 82.188018 -390.436281) (xy 82.145397 -390.411674) (xy 82.107276 -390.380549) (xy 82.074641 -390.343712)
			(xy 82.048338 -390.302116) (xy 82.029047 -390.25684) (xy 82.01727 -390.209056) (xy 82.01331 -390.160002)
			(xy 81.424272 -390.160002) (xy 81.423777 -390.184609) (xy 81.415882 -390.233186) (xy 81.400298 -390.279867)
			(xy 81.377427 -390.323444) (xy 81.347862 -390.362788) (xy 81.312369 -390.39688) (xy 81.271866 -390.424836)
			(xy 81.227404 -390.445934) (xy 81.180133 -390.459626) (xy 81.131278 -390.465558) (xy 81.082103 -390.463577)
			(xy 81.033884 -390.453733) (xy 80.987868 -390.436281) (xy 80.945247 -390.411674) (xy 80.907126 -390.380549)
			(xy 80.874491 -390.343712) (xy 80.848188 -390.302116) (xy 80.828897 -390.25684) (xy 80.81712 -390.209056)
			(xy 80.81316 -390.160002) (xy 80.224122 -390.160002) (xy 80.223627 -390.184609) (xy 80.215732 -390.233186)
			(xy 80.200148 -390.279867) (xy 80.177277 -390.323444) (xy 80.147712 -390.362788) (xy 80.112219 -390.39688)
			(xy 80.071716 -390.424836) (xy 80.027254 -390.445934) (xy 79.979983 -390.459626) (xy 79.931128 -390.465558)
			(xy 79.881953 -390.463577) (xy 79.833734 -390.453733) (xy 79.787718 -390.436281) (xy 79.745097 -390.411674)
			(xy 79.706976 -390.380549) (xy 79.674341 -390.343712) (xy 79.648038 -390.302116) (xy 79.628747 -390.25684)
			(xy 79.61697 -390.209056) (xy 79.61301 -390.160002) (xy 78.06954 -390.160002) (xy 78.068595 -390.166456)
			(xy 78.049528 -390.230244) (xy 78.021436 -390.290605) (xy 78.003654 -390.318752) (xy 77.9986 -390.327273)
			(xy 77.994781 -390.346693) (xy 77.998595 -390.366114) (xy 78.003654 -390.374632) (xy 78.021447 -390.402776)
			(xy 78.049578 -390.463124) (xy 78.068655 -390.526916) (xy 78.078274 -390.5928) (xy 78.078838 -390.626092)
			(xy 78.07837 -390.655389) (xy 78.070901 -390.713506) (xy 78.056098 -390.7702) (xy 78.045564 -390.797542)
			(xy 78.0415 -390.807194) (xy 78.042008 -390.82726) (xy 78.079854 -390.913112) (xy 78.094332 -390.927082)
			(xy 78.104238 -390.930638) (xy 78.129105 -390.940464) (xy 78.175543 -390.966963) (xy 78.217119 -391.000581)
			(xy 78.252751 -391.040443) (xy 78.281515 -391.085513) (xy 78.302662 -391.13462) (xy 78.315642 -391.186487)
			(xy 78.31836 -391.213086) (xy 78.319122 -391.222738) (xy 78.32725 -391.239756) (xy 78.385162 -391.292842)
			(xy 78.392369 -391.298984) (xy 78.40999 -391.305884) (xy 78.419452 -391.306304) (xy 98.9711 -391.306304)
			(xy 98.98117 -391.306727) (xy 98.999774 -391.314442) (xy 99.007168 -391.32129) (xy 100.086414 -392.400536)
			(xy 100.122228 -392.404092) (xy 100.137722 -392.393678) (xy 100.162939 -392.377277) (xy 100.216487 -392.349867)
			(xy 100.272895 -392.328964) (xy 100.331374 -392.31486) (xy 100.391108 -392.307752) (xy 100.421186 -392.307318)
			(xy 100.451918 -392.307763) (xy 100.512934 -392.31517) (xy 100.572613 -392.329879) (xy 100.630083 -392.351674)
			(xy 100.684507 -392.380237) (xy 100.735091 -392.415153) (xy 100.781097 -392.455912) (xy 100.821854 -392.501919)
			(xy 100.856769 -392.552504) (xy 100.885331 -392.606928) (xy 100.907125 -392.664399) (xy 100.921832 -392.724078)
			(xy 100.929238 -392.785094) (xy 100.929694 -392.815826) (xy 100.927916 -392.857228) (xy 100.9269 -392.86942)
			(xy 100.936298 -392.892026) (xy 101.017578 -392.961368) (xy 101.0412 -392.96721) (xy 101.053138 -392.964162)
			(xy 101.075276 -392.959142) (xy 101.120356 -392.95379) (xy 101.143054 -392.953494) (xy 101.170309 -392.953954)
			(xy 101.224264 -392.961706) (xy 101.276568 -392.977058) (xy 101.326153 -392.999698) (xy 101.372012 -393.029164)
			(xy 101.41321 -393.064858) (xy 101.448908 -393.106051) (xy 101.47838 -393.151906) (xy 101.501026 -393.201489)
			(xy 101.516384 -393.253791) (xy 101.524143 -393.307745) (xy 101.524143 -393.362255) (xy 101.516384 -393.416209)
			(xy 101.501026 -393.468511) (xy 101.47838 -393.518094) (xy 101.476557 -393.52093) (xy 105.06837 -393.52093)
			(xy 105.068832 -393.490233) (xy 105.076238 -393.429288) (xy 105.090933 -393.36968) (xy 105.112703 -393.312276)
			(xy 105.141232 -393.257913) (xy 105.158286 -393.232386) (xy 105.163734 -393.223621) (xy 105.167872 -393.203425)
			(xy 105.163753 -393.183225) (xy 105.158286 -393.174474) (xy 105.141252 -393.148935) (xy 105.11274 -393.094568)
			(xy 105.090976 -393.037166) (xy 105.076275 -392.977563) (xy 105.068851 -392.916624) (xy 105.06837 -392.88593)
			(xy 105.068832 -392.855233) (xy 105.076238 -392.794288) (xy 105.090933 -392.73468) (xy 105.112703 -392.677276)
			(xy 105.141232 -392.622913) (xy 105.158286 -392.597386) (xy 105.163734 -392.588621) (xy 105.167872 -392.568425)
			(xy 105.163753 -392.548225) (xy 105.158286 -392.539474) (xy 105.141252 -392.513935) (xy 105.11274 -392.459568)
			(xy 105.090976 -392.402166) (xy 105.076275 -392.342563) (xy 105.068851 -392.281624) (xy 105.06837 -392.25093)
			(xy 105.068832 -392.220233) (xy 105.076238 -392.159288) (xy 105.090933 -392.09968) (xy 105.112703 -392.042276)
			(xy 105.141232 -391.987913) (xy 105.158286 -391.962386) (xy 105.163734 -391.953621) (xy 105.167872 -391.933425)
			(xy 105.163753 -391.913225) (xy 105.158286 -391.904474) (xy 105.141252 -391.878935) (xy 105.11274 -391.824568)
			(xy 105.090976 -391.767166) (xy 105.076275 -391.707563) (xy 105.068851 -391.646624) (xy 105.06837 -391.61593)
			(xy 105.068828 -391.585437) (xy 105.076141 -391.524889) (xy 105.090642 -391.465651) (xy 105.112122 -391.408572)
			(xy 105.140274 -391.354471) (xy 105.174693 -391.304125) (xy 105.214886 -391.258256) (xy 105.260275 -391.217522)
			(xy 105.31021 -391.182508) (xy 105.363973 -391.153716) (xy 105.39222 -391.14222) (xy 105.40111 -391.138664)
			(xy 105.414826 -391.126218) (xy 105.453942 -391.047986) (xy 105.45572 -391.029444) (xy 105.45318 -391.020046)
			(xy 105.444416 -390.986564) (xy 105.434984 -390.917999) (xy 105.434384 -390.883394) (xy 105.434876 -390.852698)
			(xy 105.442274 -390.791754) (xy 105.456962 -390.732146) (xy 105.478726 -390.674742) (xy 105.507248 -390.620378)
			(xy 105.5243 -390.59485) (xy 105.529777 -390.586101) (xy 105.533904 -390.565895) (xy 105.529773 -390.54569)
			(xy 105.5243 -390.536938) (xy 105.50724 -390.511416) (xy 105.478735 -390.457044) (xy 105.456977 -390.399637)
			(xy 105.442282 -390.340031) (xy 105.434862 -390.279089) (xy 105.434384 -390.248394) (xy 105.434853 -390.217842)
			(xy 105.442166 -390.157177) (xy 105.456698 -390.097825) (xy 105.478239 -390.040644) (xy 105.506479 -389.986457)
			(xy 105.541011 -389.936045) (xy 105.581336 -389.890136) (xy 105.603802 -389.869426) (xy 105.61025 -389.863229)
			(xy 105.618716 -389.847491) (xy 105.620312 -389.838692) (xy 105.624376 -389.80872) (xy 105.625278 -389.800006)
			(xy 105.621762 -389.782856) (xy 105.617518 -389.775192) (xy 105.604224 -389.75261) (xy 105.583229 -389.704598)
			(xy 105.569006 -389.654164) (xy 105.561822 -389.602257) (xy 105.561384 -389.576056) (xy 105.561862 -389.548686)
			(xy 105.569674 -389.494507) (xy 105.585159 -389.442003) (xy 105.607999 -389.392256) (xy 105.637723 -389.346289)
			(xy 105.655364 -389.325358) (xy 105.66146 -389.318246) (xy 105.66781 -389.301228) (xy 105.66781 -389.215884)
			(xy 105.66146 -389.198866) (xy 105.655364 -389.191754) (xy 105.637731 -389.170817) (xy 105.60802 -389.124845)
			(xy 105.585183 -389.075099) (xy 105.56969 -389.022599) (xy 105.56186 -388.968425) (xy 105.561384 -388.941056)
			(xy 105.561837 -388.913804) (xy 105.569599 -388.859856) (xy 105.584959 -388.807561) (xy 105.607605 -388.757984)
			(xy 105.637075 -388.712134) (xy 105.67277 -388.670945) (xy 105.713963 -388.635254) (xy 105.759815 -388.605788)
			(xy 105.809394 -388.583147) (xy 105.861691 -388.567791) (xy 105.91564 -388.560034) (xy 105.942892 -388.559548)
			(xy 105.969653 -388.559964) (xy 106.02265 -388.56744) (xy 106.074084 -388.582247) (xy 106.122944 -388.604094)
			(xy 106.168273 -388.632552) (xy 106.189018 -388.649464) (xy 106.198162 -388.657338) (xy 106.221022 -388.662926)
			(xy 106.323638 -388.639558) (xy 106.341926 -388.624826) (xy 106.347006 -388.61365) (xy 106.358728 -388.588968)
			(xy 106.388149 -388.542925) (xy 106.423838 -388.50155) (xy 106.465065 -388.465691) (xy 106.510986 -388.436081)
			(xy 106.560663 -388.413326) (xy 106.613077 -388.397891) (xy 106.667158 -388.390092) (xy 106.694478 -388.389622)
			(xy 106.721848 -388.390096) (xy 106.776027 -388.397911) (xy 106.82853 -388.413398) (xy 106.878277 -388.436238)
			(xy 106.924244 -388.465961) (xy 106.945176 -388.483602) (xy 106.952288 -388.489698) (xy 106.969306 -388.496048)
			(xy 107.05465 -388.496048) (xy 107.071668 -388.489698) (xy 107.07878 -388.483602) (xy 107.099709 -388.465959)
			(xy 107.145683 -388.436248) (xy 107.195431 -388.413413) (xy 107.247932 -388.397922) (xy 107.302109 -388.390095)
			(xy 107.329478 -388.389622) (xy 107.356734 -388.390023) (xy 107.410692 -388.397778) (xy 107.462996 -388.413134)
			(xy 107.512583 -388.435777) (xy 107.558443 -388.465247) (xy 107.599641 -388.500943) (xy 107.63534 -388.54214)
			(xy 107.664813 -388.587997) (xy 107.687458 -388.637583) (xy 107.702817 -388.689887) (xy 107.710575 -388.743844)
			(xy 107.710575 -388.798356) (xy 107.702817 -388.852313) (xy 107.687458 -388.904617) (xy 107.664813 -388.954203)
			(xy 107.63534 -389.00006) (xy 107.599641 -389.041257) (xy 107.558443 -389.076953) (xy 107.512583 -389.106423)
			(xy 107.462996 -389.129066) (xy 107.410692 -389.144422) (xy 107.356734 -389.152177) (xy 107.329478 -389.152638)
			(xy 107.302107 -389.1522) (xy 107.247926 -389.144378) (xy 107.195422 -389.128883) (xy 107.145675 -389.106035)
			(xy 107.09971 -389.076303) (xy 107.07878 -389.058658) (xy 107.071668 -389.052562) (xy 107.05465 -389.046212)
			(xy 106.969306 -389.046212) (xy 106.952288 -389.052562) (xy 106.945176 -389.058658) (xy 106.924221 -389.076268)
			(xy 106.878255 -389.105986) (xy 106.828513 -389.128828) (xy 106.776018 -389.144326) (xy 106.721846 -389.152161)
			(xy 106.694478 -389.152638) (xy 106.667718 -389.152185) (xy 106.614722 -389.144718) (xy 106.563289 -389.12992)
			(xy 106.514428 -389.108081) (xy 106.469098 -389.07963) (xy 106.448352 -389.062722) (xy 106.439208 -389.054848)
			(xy 106.416348 -389.04926) (xy 106.313732 -389.072628) (xy 106.295444 -389.08736) (xy 106.290364 -389.098536)
			(xy 106.278417 -389.123663) (xy 106.248322 -389.170456) (xy 106.23042 -389.191754) (xy 106.224324 -389.198866)
			(xy 106.217974 -389.215884) (xy 106.217974 -389.301228) (xy 106.224324 -389.318246) (xy 106.23042 -389.325358)
			(xy 106.248056 -389.346293) (xy 106.277768 -389.392265) (xy 106.300604 -389.442012) (xy 106.316096 -389.494512)
			(xy 106.323925 -389.548687) (xy 106.3244 -389.576056) (xy 106.323958 -389.602258) (xy 106.316785 -389.654167)
			(xy 106.30257 -389.704606) (xy 106.28158 -389.752621) (xy 106.268266 -389.775192) (xy 106.26404 -389.782861)
			(xy 106.26054 -389.800006) (xy 106.261408 -389.80872) (xy 106.265472 -389.838692) (xy 106.26717 -389.847459)
			(xy 106.275598 -389.863184) (xy 106.281982 -389.869426) (xy 106.305439 -389.891063) (xy 106.347308 -389.939224)
			(xy 106.382814 -389.992251) (xy 106.397552 -390.020556) (xy 106.401616 -390.028938) (xy 106.415332 -390.041384)
			(xy 106.495342 -390.073388) (xy 106.513884 -390.073642) (xy 106.52252 -390.070594) (xy 106.550182 -390.061092)
			(xy 106.60713 -390.047751) (xy 106.665233 -390.041034) (xy 106.694478 -390.040622) (xy 106.725175 -390.041071)
			(xy 106.786121 -390.048478) (xy 106.84573 -390.063176) (xy 106.903134 -390.084949) (xy 106.957495 -390.113481)
			(xy 106.983022 -390.130538) (xy 106.991774 -390.136009) (xy 107.011978 -390.140137) (xy 107.032182 -390.136009)
			(xy 107.040934 -390.130538) (xy 107.066467 -390.113495) (xy 107.120836 -390.084986) (xy 107.178239 -390.063224)
			(xy 107.237844 -390.048525) (xy 107.298783 -390.041102) (xy 107.329478 -390.040622) (xy 107.360211 -390.041058)
			(xy 107.421228 -390.048465) (xy 107.480908 -390.063173) (xy 107.53838 -390.084968) (xy 107.592805 -390.113532)
			(xy 107.643391 -390.148448) (xy 107.689398 -390.189207) (xy 107.730157 -390.235216) (xy 107.765072 -390.285801)
			(xy 107.793635 -390.340227) (xy 107.815429 -390.397699) (xy 107.830136 -390.457379) (xy 107.837542 -390.518397)
			(xy 107.837986 -390.54913) (xy 107.83742 -390.583316) (xy 107.828282 -390.651074) (xy 107.810149 -390.716997)
			(xy 107.783346 -390.779896) (xy 107.748358 -390.838637) (xy 107.705815 -390.89216) (xy 107.656485 -390.939501)
			(xy 107.629198 -390.960102) (xy 107.617514 -390.968484) (xy 107.606846 -390.994138) (xy 107.623356 -391.111232)
			(xy 107.641136 -391.132822) (xy 107.654598 -391.137648) (xy 107.686136 -391.149661) (xy 107.746007 -391.180809)
			(xy 107.801236 -391.219596) (xy 107.850855 -391.265341) (xy 107.893993 -391.317243) (xy 107.929895 -391.374389)
			(xy 107.944412 -391.404856) (xy 107.950762 -391.418572) (xy 107.975654 -391.43432) (xy 108.098082 -391.43432)
			(xy 108.122974 -391.418572) (xy 108.129324 -391.404856) (xy 108.142939 -391.376116) (xy 108.17631 -391.321977)
			(xy 108.216174 -391.272425) (xy 108.261908 -391.228233) (xy 108.287058 -391.208768) (xy 108.294166 -391.203012)
			(xy 108.304064 -391.187649) (xy 108.306362 -391.178796) (xy 108.312712 -391.149078) (xy 108.314238 -391.14019)
			(xy 108.311637 -391.122359) (xy 108.307632 -391.11428) (xy 108.293233 -391.086244) (xy 108.272847 -391.026609)
			(xy 108.262536 -390.964436) (xy 108.261912 -390.932924) (xy 108.262389 -390.905554) (xy 108.270204 -390.851375)
			(xy 108.28569 -390.798872) (xy 108.30853 -390.749125) (xy 108.338252 -390.703158) (xy 108.355892 -390.682226)
			(xy 108.361988 -390.675114) (xy 108.368338 -390.658096) (xy 108.368338 -390.572752) (xy 108.361988 -390.555734)
			(xy 108.355892 -390.548622) (xy 108.338249 -390.527693) (xy 108.308538 -390.48172) (xy 108.285703 -390.431971)
			(xy 108.270213 -390.37947) (xy 108.262385 -390.325293) (xy 108.261912 -390.297924) (xy 108.262398 -390.270673)
			(xy 108.270154 -390.216725) (xy 108.285509 -390.16443) (xy 108.308151 -390.114853) (xy 108.337617 -390.069003)
			(xy 108.373308 -390.027812) (xy 108.414499 -389.992121) (xy 108.460349 -389.962655) (xy 108.509926 -389.940013)
			(xy 108.562221 -389.924658) (xy 108.616169 -389.916902) (xy 108.670671 -389.916902) (xy 108.724619 -389.924658)
			(xy 108.776914 -389.940013) (xy 108.826491 -389.962655) (xy 108.872341 -389.992121) (xy 108.913532 -390.027812)
			(xy 108.949223 -390.069003) (xy 108.978689 -390.114853) (xy 109.001331 -390.16443) (xy 109.016686 -390.216725)
			(xy 109.024442 -390.270673) (xy 109.024928 -390.297924) (xy 109.024494 -390.325296) (xy 109.016671 -390.379477)
			(xy 109.001175 -390.431981) (xy 108.978326 -390.481727) (xy 108.948593 -390.527692) (xy 108.930948 -390.548622)
			(xy 108.924852 -390.555734) (xy 108.918502 -390.572752) (xy 108.918502 -390.658096) (xy 108.924852 -390.675114)
			(xy 108.930948 -390.682226) (xy 108.948558 -390.703182) (xy 108.978276 -390.749147) (xy 109.001118 -390.798889)
			(xy 109.016616 -390.851384) (xy 109.024451 -390.905556) (xy 109.024928 -390.932924) (xy 109.024754 -390.949262)
			(xy 109.021954 -390.981819) (xy 109.01934 -390.997948) (xy 109.017308 -391.010394) (xy 109.024674 -391.034016)
			(xy 109.101382 -391.110216) (xy 109.125004 -391.117582) (xy 109.137196 -391.115296) (xy 109.159426 -391.111591)
			(xy 109.204323 -391.107644) (xy 109.226858 -391.107422) (xy 109.257555 -391.107881) (xy 109.3185 -391.115286)
			(xy 109.378109 -391.129981) (xy 109.435513 -391.151753) (xy 109.489875 -391.180283) (xy 109.515402 -391.197338)
			(xy 109.524154 -391.202809) (xy 109.544358 -391.206937) (xy 109.564562 -391.202809) (xy 109.573314 -391.197338)
			(xy 109.598852 -391.180303) (xy 109.65322 -391.151793) (xy 109.710622 -391.130029) (xy 109.770225 -391.115328)
			(xy 109.831164 -391.107903) (xy 109.861858 -391.107422) (xy 109.892555 -391.107881) (xy 109.9535 -391.115286)
			(xy 110.013109 -391.129981) (xy 110.070513 -391.151753) (xy 110.124875 -391.180283) (xy 110.150402 -391.197338)
			(xy 110.159154 -391.202809) (xy 110.179358 -391.206937) (xy 110.199562 -391.202809) (xy 110.208314 -391.197338)
			(xy 110.233852 -391.180303) (xy 110.28822 -391.151793) (xy 110.345622 -391.130029) (xy 110.405225 -391.115328)
			(xy 110.466164 -391.107903) (xy 110.496858 -391.107422) (xy 110.52759 -391.107877) (xy 110.588607 -391.115282)
			(xy 110.648287 -391.129987) (xy 110.705759 -391.15178) (xy 110.760184 -391.180342) (xy 110.810769 -391.215257)
			(xy 110.856777 -391.256014) (xy 110.897536 -391.302021) (xy 110.932452 -391.352606) (xy 110.961015 -391.407031)
			(xy 110.982809 -391.464502) (xy 110.997516 -391.524181) (xy 111.004922 -391.585198) (xy 111.005366 -391.61593)
			(xy 111.005314 -391.627376) (xy 111.004296 -391.650245) (xy 111.003334 -391.66165) (xy 111.002318 -391.673334)
			(xy 111.010192 -391.69467) (xy 111.084614 -391.766044) (xy 111.106204 -391.773156) (xy 111.117888 -391.771378)
			(xy 111.134575 -391.769318) (xy 111.168131 -391.76716) (xy 111.184944 -391.76706) (xy 111.215675 -391.767514)
			(xy 111.276688 -391.774927) (xy 111.336362 -391.78964) (xy 111.393829 -391.811437) (xy 111.448249 -391.840002)
			(xy 111.49883 -391.874918) (xy 111.544834 -391.915675) (xy 111.58559 -391.96168) (xy 111.620504 -392.012261)
			(xy 111.649068 -392.066682) (xy 111.670864 -392.124149) (xy 111.685575 -392.183824) (xy 111.692987 -392.244837)
			(xy 111.693452 -392.275568) (xy 111.692989 -392.307582) (xy 111.684971 -392.371106) (xy 111.669047 -392.433122)
			(xy 111.645467 -392.492649) (xy 111.63046 -392.520932) (xy 111.626189 -392.529407) (xy 111.62372 -392.548211)
			(xy 111.625634 -392.557508) (xy 111.633 -392.58748) (xy 111.635489 -392.596489) (xy 111.646067 -392.611883)
			(xy 111.653574 -392.617452) (xy 111.675103 -392.632815) (xy 111.714189 -392.668442) (xy 111.747979 -392.709127)
			(xy 111.775825 -392.75409) (xy 111.797192 -392.802469) (xy 111.81167 -392.853335) (xy 111.818982 -392.905715)
			(xy 111.819436 -392.932158) (xy 111.818906 -392.959409) (xy 111.811155 -393.013356) (xy 111.795806 -393.065651)
			(xy 111.77317 -393.115229) (xy 111.743709 -393.161081) (xy 111.708023 -393.202273) (xy 111.666837 -393.237967)
			(xy 111.62099 -393.267437) (xy 111.571416 -393.290081) (xy 111.519124 -393.30544) (xy 111.465178 -393.313201)
			(xy 111.437928 -393.313666) (xy 111.41025 -393.313184) (xy 111.355478 -393.305163) (xy 111.302439 -393.289314)
			(xy 111.252246 -393.265969) (xy 111.205952 -393.235619) (xy 111.164528 -393.198899) (xy 111.128842 -393.156581)
			(xy 111.113824 -393.133326) (xy 111.106712 -393.121896) (xy 111.083344 -393.109196) (xy 110.968536 -393.111482)
			(xy 110.94593 -393.124944) (xy 110.939072 -393.136882) (xy 110.91545 -393.174474) (xy 110.909956 -393.183213)
			(xy 110.90584 -393.203425) (xy 110.909976 -393.223633) (xy 110.91545 -393.232386) (xy 110.932471 -393.257933)
			(xy 110.960984 -393.312298) (xy 110.982751 -393.369698) (xy 110.997455 -393.429299) (xy 111.004883 -393.490236)
			(xy 111.005366 -393.52093) (xy 111.00499 -393.551664) (xy 110.997578 -393.612685) (xy 110.982863 -393.672366)
			(xy 110.961063 -393.729839) (xy 110.932493 -393.784265) (xy 110.897571 -393.83485) (xy 110.856807 -393.880858)
			(xy 110.810794 -393.921616) (xy 110.760203 -393.95653) (xy 110.705773 -393.985092) (xy 110.648297 -394.006885)
			(xy 110.588614 -394.021591) (xy 110.527592 -394.028995) (xy 110.496858 -394.029438) (xy 110.466162 -394.02896)
			(xy 110.405217 -394.021558) (xy 110.345609 -394.006866) (xy 110.288205 -393.9851) (xy 110.233842 -393.956575)
			(xy 110.208314 -393.939522) (xy 110.199562 -393.934051) (xy 110.179358 -393.929923) (xy 110.159154 -393.934051)
			(xy 110.150402 -393.939522) (xy 110.124856 -393.956545) (xy 110.070491 -393.985058) (xy 110.013091 -394.006825)
			(xy 109.953489 -394.021528) (xy 109.892552 -394.028956) (xy 109.861858 -394.029438) (xy 109.831162 -394.02896)
			(xy 109.770217 -394.021558) (xy 109.710609 -394.006866) (xy 109.653205 -393.9851) (xy 109.598842 -393.956575)
			(xy 109.573314 -393.939522) (xy 109.564562 -393.934051) (xy 109.544358 -393.929923) (xy 109.524154 -393.934051)
			(xy 109.515402 -393.939522) (xy 109.489856 -393.956545) (xy 109.435491 -393.985058) (xy 109.378091 -394.006825)
			(xy 109.318489 -394.021528) (xy 109.257552 -394.028956) (xy 109.226858 -394.029438) (xy 109.196162 -394.02896)
			(xy 109.135217 -394.021558) (xy 109.075609 -394.006866) (xy 109.018205 -393.9851) (xy 108.963842 -393.956575)
			(xy 108.938314 -393.939522) (xy 108.929562 -393.934051) (xy 108.909358 -393.929923) (xy 108.889154 -393.934051)
			(xy 108.880402 -393.939522) (xy 108.865162 -393.949682) (xy 108.856012 -393.956277) (xy 108.844058 -393.975368)
			(xy 108.841357 -393.997732) (xy 108.844334 -394.00861) (xy 108.852475 -394.03445) (xy 108.863901 -394.087411)
			(xy 108.869637 -394.141286) (xy 108.869988 -394.168376) (xy 108.86954 -394.199108) (xy 108.862133 -394.260125)
			(xy 108.847426 -394.319804) (xy 108.825632 -394.377275) (xy 108.797069 -394.4317) (xy 108.762154 -394.482285)
			(xy 108.721395 -394.528293) (xy 108.675388 -394.569051) (xy 108.624804 -394.603967) (xy 108.570379 -394.63253)
			(xy 108.512908 -394.654325) (xy 108.453229 -394.669033) (xy 108.392212 -394.67644) (xy 108.36148 -394.676884)
			(xy 108.327893 -394.67637) (xy 108.261305 -394.667524) (xy 108.196462 -394.649987) (xy 108.134492 -394.624065)
			(xy 108.076474 -394.59021) (xy 108.023419 -394.549011) (xy 107.97625 -394.501185) (xy 107.955588 -394.4747)
			(xy 107.948633 -394.466371) (xy 107.929645 -394.455924) (xy 107.90804 -394.454224) (xy 107.897676 -394.457428)
			(xy 107.869939 -394.466991) (xy 107.812826 -394.480436) (xy 107.754546 -394.487221) (xy 107.72521 -394.487654)
			(xy 107.685364 -394.486921) (xy 107.606642 -394.474541) (xy 107.568492 -394.463016) (xy 107.558476 -394.460314)
			(xy 107.537844 -394.462262) (xy 107.51965 -394.472186) (xy 107.512866 -394.480034) (xy 107.492142 -394.505856)
			(xy 107.445114 -394.552462) (xy 107.392436 -394.592572) (xy 107.334998 -394.625507) (xy 107.273772 -394.650709)
			(xy 107.209793 -394.667753) (xy 107.144143 -394.67635) (xy 107.111038 -394.676884) (xy 107.080306 -394.676427)
			(xy 107.019289 -394.669022) (xy 106.95961 -394.654316) (xy 106.902139 -394.632523) (xy 106.847714 -394.603961)
			(xy 106.797128 -394.569047) (xy 106.751121 -394.528289) (xy 106.710362 -394.482283) (xy 106.675446 -394.431698)
			(xy 106.646883 -394.377274) (xy 106.625088 -394.319804) (xy 106.610381 -394.260125) (xy 106.602974 -394.199108)
			(xy 106.60253 -394.168376) (xy 106.603152 -394.131791) (xy 106.613607 -394.059371) (xy 106.623358 -394.024104)
			(xy 106.626129 -394.012907) (xy 106.622474 -393.990157) (xy 106.609272 -393.971273) (xy 106.599482 -393.965176)
			(xy 106.588928 -393.959202) (xy 106.568346 -393.946367) (xy 106.558334 -393.939522) (xy 106.549582 -393.934051)
			(xy 106.529378 -393.929923) (xy 106.509174 -393.934051) (xy 106.500422 -393.939522) (xy 106.474898 -393.95658)
			(xy 106.420527 -393.985087) (xy 106.363121 -394.006846) (xy 106.303515 -394.021542) (xy 106.242573 -394.028961)
			(xy 106.211878 -394.029438) (xy 106.181182 -394.02895) (xy 106.120238 -394.02155) (xy 106.06063 -394.006861)
			(xy 106.003226 -393.985097) (xy 105.948862 -393.956574) (xy 105.923334 -393.939522) (xy 105.914582 -393.934051)
			(xy 105.894378 -393.929923) (xy 105.874174 -393.934051) (xy 105.865422 -393.939522) (xy 105.839898 -393.95658)
			(xy 105.785527 -393.985087) (xy 105.728121 -394.006846) (xy 105.668515 -394.021542) (xy 105.607573 -394.028961)
			(xy 105.576878 -394.029438) (xy 105.546148 -394.028965) (xy 105.485135 -394.021554) (xy 105.425461 -394.006844)
			(xy 105.367995 -393.985049) (xy 105.313574 -393.956486) (xy 105.262993 -393.921572) (xy 105.216989 -393.880816)
			(xy 105.176233 -393.834813) (xy 105.141318 -393.784232) (xy 105.112755 -393.729812) (xy 105.090958 -393.672347)
			(xy 105.076247 -393.612672) (xy 105.068836 -393.55166) (xy 105.06837 -393.52093) (xy 101.476557 -393.52093)
			(xy 101.448908 -393.563949) (xy 101.41321 -393.605142) (xy 101.372012 -393.640836) (xy 101.326153 -393.670302)
			(xy 101.276568 -393.692942) (xy 101.224264 -393.708294) (xy 101.170309 -393.716046) (xy 101.143054 -393.71651)
			(xy 101.11472 -393.715996) (xy 101.058675 -393.707617) (xy 101.004487 -393.691036) (xy 100.953349 -393.666618)
			(xy 100.906389 -393.634901) (xy 100.86464 -393.596583) (xy 100.829021 -393.552508) (xy 100.800318 -393.503647)
			(xy 100.779162 -393.451076) (xy 100.76602 -393.395953) (xy 100.76307 -393.367768) (xy 100.7618 -393.355576)
			(xy 100.748846 -393.334748) (xy 100.657406 -393.279884) (xy 100.633022 -393.27836) (xy 100.621592 -393.283186)
			(xy 100.589803 -393.296205) (xy 100.523601 -393.314536) (xy 100.455533 -393.323785) (xy 100.421186 -393.324334)
			(xy 100.409756 -393.32408) (xy 100.399342 -393.32408) (xy 100.380546 -393.331446) (xy 100.32111 -393.389358)
			(xy 100.314155 -393.396781) (xy 100.306281 -393.415517) (xy 100.30587 -393.42568) (xy 100.30587 -394.372338)
			(xy 100.306299 -394.382406) (xy 100.31402 -394.401003) (xy 100.320856 -394.408406) (xy 100.538026 -394.625576)
			(xy 103.350822 -394.625576) (xy 103.351324 -394.593615) (xy 103.359335 -394.530197) (xy 103.375232 -394.468283)
			(xy 103.398764 -394.40885) (xy 103.429558 -394.352835) (xy 103.467131 -394.30112) (xy 103.510888 -394.254523)
			(xy 103.560141 -394.213778) (xy 103.614112 -394.179527) (xy 103.671951 -394.15231) (xy 103.732744 -394.132557)
			(xy 103.795534 -394.120579) (xy 103.85933 -394.116566) (xy 103.923126 -394.120579) (xy 103.985916 -394.132557)
			(xy 104.046709 -394.15231) (xy 104.104548 -394.179527) (xy 104.158519 -394.213778) (xy 104.207772 -394.254523)
			(xy 104.251529 -394.30112) (xy 104.289102 -394.352835) (xy 104.319896 -394.40885) (xy 104.343428 -394.468283)
			(xy 104.359325 -394.530197) (xy 104.367336 -394.593615) (xy 104.367838 -394.625576) (xy 104.367373 -394.656918)
			(xy 104.359664 -394.719125) (xy 104.344372 -394.779915) (xy 104.321729 -394.838366) (xy 104.292078 -394.893592)
			(xy 104.274366 -394.919454) (xy 104.265984 -394.931138) (xy 104.263952 -394.959332) (xy 104.318562 -395.064996)
			(xy 104.342692 -395.079728) (xy 104.35717 -395.079728) (xy 104.391304 -395.080348) (xy 104.458937 -395.089654)
			(xy 104.524717 -395.107927) (xy 104.556306 -395.120876) (xy 104.567358 -395.124896) (xy 104.590805 -395.123591)
			(xy 104.611222 -395.111989) (xy 104.618282 -395.102588) (xy 104.636071 -395.077206) (xy 104.676847 -395.030524)
			(xy 104.722995 -394.989144) (xy 104.773831 -394.953681) (xy 104.8286 -394.924659) (xy 104.88649 -394.902509)
			(xy 104.946644 -394.88756) (xy 105.008168 -394.880034) (xy 105.03916 -394.879576) (xy 105.071123 -394.880087)
			(xy 105.134545 -394.888094) (xy 105.196464 -394.903988) (xy 105.255902 -394.927517) (xy 105.311923 -394.95831)
			(xy 105.363641 -394.995883) (xy 105.410243 -395.039641) (xy 105.450993 -395.088895) (xy 105.485248 -395.142869)
			(xy 105.512467 -395.20071) (xy 105.532222 -395.261507) (xy 105.544201 -395.3243) (xy 105.548216 -395.3881)
			(xy 105.544201 -395.4519) (xy 105.532222 -395.514693) (xy 105.512467 -395.57549) (xy 105.485248 -395.633331)
			(xy 105.450993 -395.687305) (xy 105.410243 -395.736559) (xy 105.363641 -395.780317) (xy 105.311923 -395.81789)
			(xy 105.255902 -395.848683) (xy 105.196464 -395.872212) (xy 105.134545 -395.888106) (xy 105.071123 -395.896113)
			(xy 105.03916 -395.896592) (xy 105.004856 -395.896032) (xy 104.936874 -395.886771) (xy 104.870756 -395.86845)
			(xy 104.839008 -395.855444) (xy 104.827983 -395.851331) (xy 104.804512 -395.85267) (xy 104.784088 -395.864312)
			(xy 104.777032 -395.873732) (xy 104.76048 -395.897426) (xy 104.72282 -395.941275) (xy 104.68043 -395.98057)
			(xy 104.633859 -396.014805) (xy 104.583705 -396.043539) (xy 104.557322 -396.055342) (xy 104.544876 -396.060676)
			(xy 104.52862 -396.08252) (xy 104.515412 -396.197074) (xy 104.526334 -396.22222) (xy 104.537256 -396.230348)
			(xy 104.560837 -396.248465) (xy 104.602628 -396.290763) (xy 104.609056 -396.2997) (xy 106.452358 -396.2997)
			(xy 106.456373 -396.235898) (xy 106.468352 -396.173102) (xy 106.488108 -396.112302) (xy 106.515328 -396.054458)
			(xy 106.549584 -396.000483) (xy 106.590335 -395.951226) (xy 106.636939 -395.907465) (xy 106.688659 -395.869891)
			(xy 106.744682 -395.839096) (xy 106.804122 -395.815565) (xy 106.866043 -395.79967) (xy 106.929468 -395.791661)
			(xy 106.961432 -395.791182) (xy 106.99438 -395.791708) (xy 107.059723 -395.800234) (xy 107.123417 -395.817126)
			(xy 107.184398 -395.8421) (xy 107.241643 -395.87474) (xy 107.294194 -395.914498) (xy 107.318048 -395.937232)
			(xy 107.325668 -395.944598) (xy 107.345226 -395.952218) (xy 107.44073 -395.948154) (xy 107.459526 -395.93901)
			(xy 107.466384 -395.930882) (xy 107.487152 -395.907428) (xy 107.53346 -395.865236) (xy 107.584599 -395.829051)
			(xy 107.639796 -395.799422) (xy 107.698214 -395.776797) (xy 107.758969 -395.761519) (xy 107.821141 -395.75382)
			(xy 107.852464 -395.753336) (xy 107.884431 -395.753727) (xy 107.94786 -395.761736) (xy 108.009786 -395.777632)
			(xy 108.06923 -395.801164) (xy 108.125257 -395.831961) (xy 108.176981 -395.869538) (xy 108.223588 -395.913301)
			(xy 108.264342 -395.962561) (xy 108.298601 -396.016541) (xy 108.325823 -396.074389) (xy 108.345581 -396.135192)
			(xy 108.357561 -396.197993) (xy 108.361576 -396.2618) (xy 108.357561 -396.325607) (xy 108.345581 -396.388408)
			(xy 108.331009 -396.433251) (xy 109.232948 -396.433251) (xy 109.232948 -396.369329) (xy 109.240959 -396.305911)
			(xy 109.256856 -396.243997) (xy 109.280388 -396.184564) (xy 109.311182 -396.128549) (xy 109.348755 -396.076834)
			(xy 109.392512 -396.030237) (xy 109.441765 -395.989492) (xy 109.495736 -395.955241) (xy 109.553575 -395.928024)
			(xy 109.614368 -395.908271) (xy 109.677158 -395.896293) (xy 109.740954 -395.89228) (xy 109.80475 -395.896293)
			(xy 109.86754 -395.908271) (xy 109.928333 -395.928024) (xy 109.986172 -395.955241) (xy 110.040143 -395.989492)
			(xy 110.089396 -396.030237) (xy 110.133153 -396.076834) (xy 110.170726 -396.128549) (xy 110.20152 -396.184564)
			(xy 110.225052 -396.243997) (xy 110.240949 -396.305911) (xy 110.24896 -396.369329) (xy 110.249462 -396.40129)
			(xy 110.24896 -396.433251) (xy 110.240949 -396.496669) (xy 110.225052 -396.558583) (xy 110.20152 -396.618016)
			(xy 110.170726 -396.674031) (xy 110.133153 -396.725746) (xy 110.089396 -396.772343) (xy 110.040143 -396.813088)
			(xy 109.986172 -396.847339) (xy 109.928333 -396.874556) (xy 109.86754 -396.894309) (xy 109.80475 -396.906287)
			(xy 109.740954 -396.910301) (xy 109.677158 -396.906287) (xy 109.614368 -396.894309) (xy 109.553575 -396.874556)
			(xy 109.495736 -396.847339) (xy 109.441765 -396.813088) (xy 109.392512 -396.772343) (xy 109.348755 -396.725746)
			(xy 109.311182 -396.674031) (xy 109.280388 -396.618016) (xy 109.256856 -396.558583) (xy 109.240959 -396.496669)
			(xy 109.232948 -396.433251) (xy 108.331009 -396.433251) (xy 108.325823 -396.449211) (xy 108.298601 -396.507059)
			(xy 108.264342 -396.561039) (xy 108.223588 -396.610299) (xy 108.176981 -396.654062) (xy 108.125257 -396.691639)
			(xy 108.06923 -396.722436) (xy 108.009786 -396.745968) (xy 107.94786 -396.761864) (xy 107.884431 -396.769873)
			(xy 107.852464 -396.770352) (xy 107.819515 -396.769846) (xy 107.754171 -396.761319) (xy 107.690475 -396.744425)
			(xy 107.629495 -396.719446) (xy 107.57225 -396.686802) (xy 107.519701 -396.647038) (xy 107.495848 -396.624302)
			(xy 107.488228 -396.616936) (xy 107.46867 -396.609316) (xy 107.373166 -396.61338) (xy 107.35437 -396.622524)
			(xy 107.347512 -396.630652) (xy 107.326753 -396.654114) (xy 107.280443 -396.696305) (xy 107.229302 -396.732488)
			(xy 107.174103 -396.762116) (xy 107.115684 -396.784739) (xy 107.054928 -396.800016) (xy 106.992756 -396.807714)
			(xy 106.961432 -396.808198) (xy 106.929468 -396.807739) (xy 106.866043 -396.79973) (xy 106.804122 -396.783835)
			(xy 106.744682 -396.760304) (xy 106.688659 -396.729509) (xy 106.636939 -396.691935) (xy 106.590335 -396.648174)
			(xy 106.549584 -396.598917) (xy 106.515328 -396.544942) (xy 106.488108 -396.487098) (xy 106.468352 -396.426298)
			(xy 106.456373 -396.363502) (xy 106.452358 -396.2997) (xy 104.609056 -396.2997) (xy 104.637347 -396.339036)
			(xy 104.664151 -396.392114) (xy 104.682391 -396.448709) (xy 104.691625 -396.507449) (xy 104.692196 -396.53718)
			(xy 104.69171 -396.564431) (xy 104.683954 -396.618379) (xy 104.668599 -396.670674) (xy 104.645957 -396.720251)
			(xy 104.616491 -396.766101) (xy 104.5808 -396.807292) (xy 104.539609 -396.842983) (xy 104.493759 -396.872449)
			(xy 104.444182 -396.895091) (xy 104.391887 -396.910446) (xy 104.337939 -396.918202) (xy 104.283437 -396.918202)
			(xy 104.229489 -396.910446) (xy 104.177194 -396.895091) (xy 104.127617 -396.872449) (xy 104.081767 -396.842983)
			(xy 104.040576 -396.807292) (xy 104.004885 -396.766101) (xy 103.975419 -396.720251) (xy 103.952777 -396.670674)
			(xy 103.937422 -396.618379) (xy 103.929666 -396.564431) (xy 103.92918 -396.53718) (xy 103.929647 -396.509075)
			(xy 103.93789 -396.453473) (xy 103.954211 -396.399685) (xy 103.978254 -396.348877) (xy 104.009499 -396.302151)
			(xy 104.047267 -396.260521) (xy 104.09074 -396.224889) (xy 104.1146 -396.210028) (xy 104.126284 -396.202916)
			(xy 104.139492 -396.17904) (xy 104.137206 -396.063724) (xy 104.123236 -396.040356) (xy 104.111298 -396.033752)
			(xy 104.085058 -396.018826) (xy 104.035952 -395.98371) (xy 103.991352 -395.943023) (xy 103.951887 -395.89734)
			(xy 103.91811 -395.847303) (xy 103.890499 -395.793618) (xy 103.869442 -395.73704) (xy 103.855236 -395.678365)
			(xy 103.84808 -395.618421) (xy 103.847646 -395.588236) (xy 103.84812 -395.556895) (xy 103.855827 -395.494688)
			(xy 103.871117 -395.433898) (xy 103.893758 -395.375447) (xy 103.923407 -395.32022) (xy 103.941118 -395.294358)
			(xy 103.9495 -395.282674) (xy 103.951532 -395.25448) (xy 103.896922 -395.148816) (xy 103.872792 -395.134084)
			(xy 103.858314 -395.134084) (xy 103.827623 -395.133556) (xy 103.766699 -395.126047) (xy 103.707123 -395.111259)
			(xy 103.64976 -395.089405) (xy 103.595446 -395.060805) (xy 103.54497 -395.025873) (xy 103.499066 -394.985119)
			(xy 103.458403 -394.939135) (xy 103.423572 -394.888589) (xy 103.395079 -394.834218) (xy 103.37334 -394.776812)
			(xy 103.35867 -394.717207) (xy 103.351282 -394.656268) (xy 103.350822 -394.625576) (xy 100.538026 -394.625576)
			(xy 101.660452 -395.748002) (xy 101.66751 -395.754546) (xy 101.685137 -395.762236) (xy 101.704358 -395.762834)
			(xy 101.713538 -395.75994) (xy 101.814122 -395.723872) (xy 101.832156 -395.700758) (xy 101.833426 -395.686026)
			(xy 101.836895 -395.654955) (xy 101.850466 -395.593925) (xy 101.871419 -395.53502) (xy 101.899437 -395.479129)
			(xy 101.934098 -395.427096) (xy 101.974877 -395.379705) (xy 102.02116 -395.337673) (xy 102.072247 -395.301633)
			(xy 102.127369 -395.272129) (xy 102.185692 -395.249608) (xy 102.246337 -395.234408) (xy 102.308388 -395.22676)
			(xy 102.339648 -395.226286) (xy 102.373436 -395.226861) (xy 102.440411 -395.235846) (xy 102.50561 -395.253613)
			(xy 102.567885 -395.279849) (xy 102.626142 -395.314093) (xy 102.653084 -395.33449) (xy 102.660363 -395.339771)
			(xy 102.677455 -395.345329) (xy 102.695414 -395.344639) (xy 102.71203 -395.337788) (xy 102.71887 -395.33195)
			(xy 102.742363 -395.311014) (xy 102.793611 -395.274495) (xy 102.848977 -395.244584) (xy 102.907613 -395.221738)
			(xy 102.968621 -395.206308) (xy 103.031068 -395.198529) (xy 103.062532 -395.198092) (xy 103.094492 -395.198596)
			(xy 103.157907 -395.206611) (xy 103.219817 -395.22251) (xy 103.279247 -395.246043) (xy 103.335259 -395.276839)
			(xy 103.386969 -395.314412) (xy 103.433563 -395.35817) (xy 103.474306 -395.407421) (xy 103.508554 -395.461391)
			(xy 103.535769 -395.519228) (xy 103.55552 -395.580019) (xy 103.567497 -395.642807) (xy 103.571511 -395.7066)
			(xy 103.567497 -395.770393) (xy 103.55552 -395.833181) (xy 103.535769 -395.893972) (xy 103.508554 -395.951809)
			(xy 103.474306 -396.005779) (xy 103.433563 -396.05503) (xy 103.386969 -396.098788) (xy 103.335259 -396.136361)
			(xy 103.279247 -396.167157) (xy 103.219817 -396.19069) (xy 103.157907 -396.206589) (xy 103.094492 -396.214604)
			(xy 103.062532 -396.215108) (xy 103.028745 -396.214532) (xy 102.96177 -396.205544) (xy 102.896573 -396.187775)
			(xy 102.8343 -396.161536) (xy 102.776046 -396.127291) (xy 102.749096 -396.106904) (xy 102.741817 -396.101627)
			(xy 102.724728 -396.096077) (xy 102.706774 -396.096772) (xy 102.690165 -396.103626) (xy 102.68331 -396.109444)
			(xy 102.658743 -396.13129) (xy 102.604984 -396.169133) (xy 102.546798 -396.199736) (xy 102.485155 -396.222589)
			(xy 102.421082 -396.237311) (xy 102.388416 -396.241016) (xy 102.373684 -396.242286) (xy 102.35057 -396.26032)
			(xy 102.314502 -396.360904) (xy 102.311688 -396.370086) (xy 102.312359 -396.389264) (xy 102.319991 -396.406871)
			(xy 102.32644 -396.41399) (xy 103.04399 -397.13154) (xy 103.083614 -397.133064) (xy 103.098854 -397.12011)
			(xy 103.12189 -397.101084) (xy 103.171626 -397.067978) (xy 103.2249 -397.040928) (xy 103.280976 -397.020307)
			(xy 103.339083 -397.0064) (xy 103.398418 -396.999398) (xy 103.428292 -396.998952) (xy 103.458819 -396.999403)
			(xy 103.519433 -397.006712) (xy 103.578737 -397.021225) (xy 103.635876 -397.042735) (xy 103.690028 -397.070931)
			(xy 103.740416 -397.105408) (xy 103.786312 -397.145669) (xy 103.807006 -397.168116) (xy 103.814572 -397.175735)
			(xy 103.834131 -397.184532) (xy 103.844852 -397.185134) (xy 106.782108 -397.185134) (xy 106.789982 -397.184842)
			(xy 106.804985 -397.180059) (xy 106.811572 -397.175736) (xy 106.83754 -397.157731) (xy 106.893083 -397.127595)
			(xy 106.951933 -397.104577) (xy 107.013182 -397.089031) (xy 107.075886 -397.081197) (xy 107.139078 -397.081197)
			(xy 107.201782 -397.089031) (xy 107.263031 -397.104577) (xy 107.321881 -397.127595) (xy 107.377424 -397.157731)
			(xy 107.403392 -397.175736) (xy 107.409996 -397.180308) (xy 107.424728 -397.185134) (xy 107.535472 -397.185134)
			(xy 107.54868 -397.181324) (xy 107.554776 -397.177768) (xy 107.58147 -397.161985) (xy 107.637919 -397.136306)
			(xy 107.697072 -397.117686) (xy 107.758052 -397.106403) (xy 107.819952 -397.102623) (xy 107.881852 -397.106403)
			(xy 107.942832 -397.117686) (xy 108.001985 -397.136306) (xy 108.058434 -397.161985) (xy 108.085128 -397.177768)
			(xy 108.091184 -397.181197) (xy 108.104587 -397.184922) (xy 108.111544 -397.185134) (xy 113.080038 -397.185134)
			(xy 113.090486 -397.184572) (xy 113.109633 -397.176185) (xy 113.117122 -397.168878) (xy 113.121186 -397.16456)
			(xy 113.122964 -397.116046) (xy 113.12285 -397.107229) (xy 113.117391 -397.090477) (xy 113.112296 -397.08328)
			(xy 113.092337 -397.056497) (xy 113.058858 -396.998698) (xy 113.03323 -396.937015) (xy 113.015891 -396.872509)
			(xy 113.00714 -396.80629) (xy 113.006632 -396.772892) (xy 113.007152 -396.740318) (xy 113.015473 -396.675703)
			(xy 113.031978 -396.612679) (xy 113.056396 -396.55228) (xy 113.088328 -396.495494) (xy 113.12725 -396.44325)
			(xy 113.172526 -396.396405) (xy 113.223413 -396.355725) (xy 113.279079 -396.321878) (xy 113.338611 -396.295416)
			(xy 113.401036 -396.276774) (xy 113.46533 -396.266257) (xy 113.497868 -396.264638) (xy 113.508028 -396.264384)
			(xy 113.525554 -396.25651) (xy 113.581688 -396.198344) (xy 113.588163 -396.19099) (xy 113.595468 -396.172828)
			(xy 113.595912 -396.163038) (xy 113.595912 -394.744194) (xy 113.57737 -394.717778) (xy 113.561876 -394.712444)
			(xy 113.535813 -394.70286) (xy 113.486554 -394.677226) (xy 113.441531 -394.644723) (xy 113.401695 -394.606037)
			(xy 113.367887 -394.561986) (xy 113.340821 -394.513499) (xy 113.321069 -394.461601) (xy 113.309049 -394.407388)
			(xy 113.305013 -394.352006) (xy 113.309047 -394.296623) (xy 113.321066 -394.24241) (xy 113.340816 -394.190512)
			(xy 113.367881 -394.142024) (xy 113.401687 -394.097972) (xy 113.441522 -394.059284) (xy 113.486544 -394.02678)
			(xy 113.535802 -394.001144) (xy 113.561876 -393.991592) (xy 113.57737 -393.986258) (xy 113.595912 -393.959842)
			(xy 113.595912 -393.012168) (xy 113.596491 -392.976096) (xy 113.605513 -392.904517) (xy 113.623362 -392.834614)
			(xy 113.636044 -392.80084) (xy 113.640362 -392.789664) (xy 113.63833 -392.76655) (xy 113.585244 -392.677142)
			(xy 113.565686 -392.664442) (xy 113.554002 -392.662918) (xy 113.527674 -392.659102) (xy 113.47662 -392.64416)
			(xy 113.428615 -392.62124) (xy 113.384898 -392.590932) (xy 113.346595 -392.554018) (xy 113.314694 -392.51145)
			(xy 113.290017 -392.464324) (xy 113.273201 -392.413856) (xy 113.264679 -392.361348) (xy 113.264188 -392.33475)
			(xy 113.264585 -392.311517) (xy 113.271094 -392.26551) (xy 113.283977 -392.220867) (xy 113.30298 -392.178465)
			(xy 113.32773 -392.13914) (xy 113.34242 -392.121136) (xy 113.348516 -392.114024) (xy 113.354612 -392.097514)
			(xy 113.354612 -392.013186) (xy 113.348516 -391.996676) (xy 113.34242 -391.989564) (xy 113.327712 -391.971573)
			(xy 113.302958 -391.932248) (xy 113.283955 -391.889843) (xy 113.271077 -391.845195) (xy 113.264577 -391.799184)
			(xy 113.264188 -391.77595) (xy 113.264698 -391.749963) (xy 113.272828 -391.698628) (xy 113.288889 -391.649198)
			(xy 113.312485 -391.602888) (xy 113.343035 -391.56084) (xy 113.379786 -391.524089) (xy 113.421834 -391.493539)
			(xy 113.468144 -391.469943) (xy 113.517574 -391.453882) (xy 113.568909 -391.445752) (xy 113.620883 -391.445752)
			(xy 113.672218 -391.453882) (xy 113.721648 -391.469943) (xy 113.767958 -391.493539) (xy 113.810006 -391.524089)
			(xy 113.846757 -391.56084) (xy 113.877307 -391.602888) (xy 113.900903 -391.649198) (xy 113.916964 -391.698628)
			(xy 113.925094 -391.749963) (xy 113.925604 -391.77595) (xy 113.925207 -391.799183) (xy 113.918698 -391.84519)
			(xy 113.905815 -391.889833) (xy 113.886811 -391.932235) (xy 113.862061 -391.971559) (xy 113.847372 -391.989564)
			(xy 113.841276 -391.996676) (xy 113.83518 -392.013186) (xy 113.83518 -392.097514) (xy 113.841276 -392.114024)
			(xy 113.847372 -392.121136) (xy 113.864701 -392.142446) (xy 113.89277 -392.189653) (xy 113.91265 -392.24085)
			(xy 113.923795 -392.294629) (xy 113.92535 -392.32205) (xy 113.925858 -392.331956) (xy 113.933224 -392.349228)
			(xy 113.940082 -392.356086) (xy 113.947448 -392.362926) (xy 113.965981 -392.370668) (xy 113.986065 -392.370668)
			(xy 114.004598 -392.362926) (xy 114.011964 -392.356086) (xy 114.070384 -392.29792) (xy 114.097035 -392.272041)
			(xy 114.155821 -392.226623) (xy 114.219932 -392.189096) (xy 114.288317 -392.160077) (xy 114.359851 -392.140042)
			(xy 114.39652 -392.13409) (xy 114.4071 -392.132047) (xy 114.425247 -392.120463) (xy 114.431572 -392.111738)
			(xy 114.45359 -392.079339) (xy 114.504981 -392.020217) (xy 114.563873 -391.968561) (xy 114.596164 -391.946384)
			(xy 114.604371 -391.940402) (xy 114.615607 -391.923504) (xy 114.619414 -391.903572) (xy 114.617754 -391.893552)
			(xy 114.614676 -391.87805) (xy 114.611371 -391.846617) (xy 114.61115 -391.830814) (xy 114.611672 -391.805559)
			(xy 114.619985 -391.755737) (xy 114.636386 -391.707963) (xy 114.660427 -391.66354) (xy 114.691451 -391.62368)
			(xy 114.728613 -391.58947) (xy 114.770899 -391.561844) (xy 114.817155 -391.541554) (xy 114.86612 -391.529154)
			(xy 114.916458 -391.524983) (xy 114.966796 -391.529154) (xy 115.015761 -391.541554) (xy 115.062017 -391.561844)
			(xy 115.104303 -391.58947) (xy 115.141465 -391.62368) (xy 115.172489 -391.66354) (xy 115.19653 -391.707963)
			(xy 115.212931 -391.755737) (xy 115.221244 -391.805559) (xy 115.221766 -391.830814) (xy 115.221532 -391.846616)
			(xy 115.218221 -391.878047) (xy 115.215162 -391.893552) (xy 115.213533 -391.903565) (xy 115.217381 -391.923468)
			(xy 115.228589 -391.940358) (xy 115.236752 -391.946384) (xy 115.264519 -391.965389) (xy 115.315908 -392.008828)
			(xy 115.361926 -392.057922) (xy 115.401955 -392.11201) (xy 115.419124 -392.140948) (xy 115.42386 -392.148563)
			(xy 115.437546 -392.160135) (xy 115.454378 -392.166291) (xy 115.4723 -392.166277) (xy 115.480846 -392.163554)
			(xy 115.509017 -392.153597) (xy 115.566917 -392.138835) (xy 115.596416 -392.13409) (xy 115.606997 -392.132048)
			(xy 115.625144 -392.120465) (xy 115.631468 -392.111738) (xy 115.653483 -392.0793) (xy 115.704867 -392.02009)
			(xy 115.763748 -391.96833) (xy 115.79606 -391.94613) (xy 115.804266 -391.940197) (xy 115.815553 -391.923404)
			(xy 115.819481 -391.903555) (xy 115.817904 -391.893552) (xy 115.814826 -391.87805) (xy 115.81152 -391.846617)
			(xy 115.8113 -391.830814) (xy 115.811822 -391.805559) (xy 115.820135 -391.755737) (xy 115.836536 -391.707963)
			(xy 115.860577 -391.66354) (xy 115.891601 -391.62368) (xy 115.928763 -391.58947) (xy 115.971049 -391.561844)
			(xy 116.017305 -391.541554) (xy 116.06627 -391.529154) (xy 116.116608 -391.524983) (xy 116.166946 -391.529154)
			(xy 116.215911 -391.541554) (xy 116.262167 -391.561844) (xy 116.304453 -391.58947) (xy 116.341615 -391.62368)
			(xy 116.372639 -391.66354) (xy 116.39668 -391.707963) (xy 116.413081 -391.755737) (xy 116.421394 -391.805559)
			(xy 116.421916 -391.830814) (xy 116.4217 -391.84668) (xy 116.418395 -391.878241) (xy 116.415312 -391.893806)
			(xy 116.413648 -391.903791) (xy 116.417457 -391.923656) (xy 116.42868 -391.940482) (xy 116.436902 -391.946384)
			(xy 116.464656 -391.965413) (xy 116.516003 -392.008911) (xy 116.561955 -392.058073) (xy 116.601891 -392.112237)
			(xy 116.61902 -392.141202) (xy 116.62377 -392.148806) (xy 116.637478 -392.160346) (xy 116.654322 -392.166458)
			(xy 116.67224 -392.166394) (xy 116.680742 -392.163554) (xy 116.708976 -392.15359) (xy 116.767003 -392.138827)
			(xy 116.796566 -392.13409) (xy 116.807152 -392.132056) (xy 116.825316 -392.120483) (xy 116.831618 -392.111738)
			(xy 116.853635 -392.079337) (xy 116.905023 -392.020211) (xy 116.963912 -391.968551) (xy 116.99621 -391.946384)
			(xy 117.004424 -391.940406) (xy 117.015672 -391.923508) (xy 117.019484 -391.90357) (xy 117.0178 -391.893552)
			(xy 117.014722 -391.87805) (xy 117.011416 -391.846617) (xy 117.011196 -391.830814) (xy 117.011718 -391.805559)
			(xy 117.020031 -391.755737) (xy 117.036432 -391.707963) (xy 117.060473 -391.66354) (xy 117.091497 -391.62368)
			(xy 117.128659 -391.58947) (xy 117.170945 -391.561844) (xy 117.217201 -391.541554) (xy 117.266166 -391.529154)
			(xy 117.316504 -391.524983) (xy 117.366842 -391.529154) (xy 117.415807 -391.541554) (xy 117.462063 -391.561844)
			(xy 117.504349 -391.58947) (xy 117.541511 -391.62368) (xy 117.572535 -391.66354) (xy 117.596576 -391.707963)
			(xy 117.612977 -391.755737) (xy 117.62129 -391.805559) (xy 117.621812 -391.830814) (xy 117.621577 -391.846616)
			(xy 117.618266 -391.878047) (xy 117.615208 -391.893552) (xy 117.613579 -391.903564) (xy 117.617429 -391.923464)
			(xy 117.628643 -391.940348) (xy 117.636798 -391.946384) (xy 117.664564 -391.96539) (xy 117.715949 -392.008832)
			(xy 117.761964 -392.057928) (xy 117.80199 -392.112017) (xy 117.81917 -392.140948) (xy 117.823905 -392.14857)
			(xy 117.837591 -392.160158) (xy 117.854428 -392.16633) (xy 117.872361 -392.166332) (xy 117.880892 -392.163554)
			(xy 117.909063 -392.153599) (xy 117.966964 -392.138841) (xy 117.996462 -392.13409) (xy 118.007049 -392.132057)
			(xy 118.025213 -392.120484) (xy 118.031514 -392.111738) (xy 118.053531 -392.079337) (xy 118.104919 -392.020211)
			(xy 118.163807 -391.96855) (xy 118.196106 -391.946384) (xy 118.204321 -391.940406) (xy 118.21557 -391.923509)
			(xy 118.219381 -391.90357) (xy 118.217696 -391.893552) (xy 118.214618 -391.87805) (xy 118.211312 -391.846617)
			(xy 118.211092 -391.830814) (xy 118.211614 -391.805559) (xy 118.219927 -391.755737) (xy 118.236328 -391.707963)
			(xy 118.260369 -391.66354) (xy 118.291393 -391.62368) (xy 118.328555 -391.58947) (xy 118.370841 -391.561844)
			(xy 118.417097 -391.541554) (xy 118.466062 -391.529154) (xy 118.5164 -391.524983) (xy 118.566738 -391.529154)
			(xy 118.615703 -391.541554) (xy 118.661959 -391.561844) (xy 118.704245 -391.58947) (xy 118.741407 -391.62368)
			(xy 118.772431 -391.66354) (xy 118.796472 -391.707963) (xy 118.812873 -391.755737) (xy 118.821186 -391.805559)
			(xy 118.821708 -391.830814) (xy 118.821473 -391.846616) (xy 118.818162 -391.878047) (xy 118.815104 -391.893552)
			(xy 118.813475 -391.903564) (xy 118.817324 -391.923464) (xy 118.828538 -391.940349) (xy 118.836694 -391.946384)
			(xy 118.864476 -391.96541) (xy 118.915885 -392.008903) (xy 118.961905 -392.058062) (xy 119.001918 -392.112223)
			(xy 119.019066 -392.141202) (xy 119.023818 -392.1488) (xy 119.037525 -392.160326) (xy 119.054364 -392.166424)
			(xy 119.072273 -392.166347) (xy 119.080788 -392.163554) (xy 119.109022 -392.153592) (xy 119.16705 -392.138833)
			(xy 119.196612 -392.13409) (xy 119.207193 -392.132048) (xy 119.225342 -392.120466) (xy 119.231664 -392.111738)
			(xy 119.253682 -392.079338) (xy 119.305073 -392.020216) (xy 119.363964 -391.96856) (xy 119.396256 -391.946384)
			(xy 119.404464 -391.940402) (xy 119.415702 -391.923505) (xy 119.419509 -391.903572) (xy 119.417846 -391.893552)
			(xy 119.414768 -391.87805) (xy 119.411463 -391.846617) (xy 119.411242 -391.830814) (xy 119.411764 -391.805559)
			(xy 119.420077 -391.755737) (xy 119.436478 -391.707963) (xy 119.460519 -391.66354) (xy 119.491543 -391.62368)
			(xy 119.528705 -391.58947) (xy 119.570991 -391.561844) (xy 119.617247 -391.541554) (xy 119.666212 -391.529154)
			(xy 119.71655 -391.524983) (xy 119.766888 -391.529154) (xy 119.815853 -391.541554) (xy 119.862109 -391.561844)
			(xy 119.904395 -391.58947) (xy 119.941557 -391.62368) (xy 119.972581 -391.66354) (xy 119.996622 -391.707963)
			(xy 120.013023 -391.755737) (xy 120.021336 -391.805559) (xy 120.021858 -391.830814) (xy 120.021624 -391.846616)
			(xy 120.018313 -391.878047) (xy 120.015254 -391.893552) (xy 120.013625 -391.903565) (xy 120.017473 -391.923468)
			(xy 120.02868 -391.94036) (xy 120.036844 -391.946384) (xy 120.064608 -391.965392) (xy 120.11599 -392.008836)
			(xy 120.162002 -392.057933) (xy 120.202025 -392.112023) (xy 120.219216 -392.140948) (xy 120.223952 -392.148564)
			(xy 120.237637 -392.160139) (xy 120.25447 -392.166296) (xy 120.272394 -392.166285) (xy 120.280938 -392.163554)
			(xy 120.309109 -392.153596) (xy 120.367008 -392.138833) (xy 120.396508 -392.13409) (xy 120.40709 -392.132049)
			(xy 120.42524 -392.120467) (xy 120.43156 -392.111738) (xy 120.453578 -392.079338) (xy 120.504968 -392.020215)
			(xy 120.563859 -391.968559) (xy 120.596152 -391.946384) (xy 120.604361 -391.940403) (xy 120.615599 -391.923505)
			(xy 120.619407 -391.903572) (xy 120.617742 -391.893552) (xy 120.614663 -391.87805) (xy 120.611357 -391.846617)
			(xy 120.611138 -391.830814) (xy 120.61166 -391.805559) (xy 120.619973 -391.755737) (xy 120.636374 -391.707963)
			(xy 120.660415 -391.66354) (xy 120.691439 -391.62368) (xy 120.728601 -391.58947) (xy 120.770887 -391.561844)
			(xy 120.817143 -391.541554) (xy 120.866108 -391.529154) (xy 120.916446 -391.524983) (xy 120.966784 -391.529154)
			(xy 121.015749 -391.541554) (xy 121.062005 -391.561844) (xy 121.104291 -391.58947) (xy 121.141453 -391.62368)
			(xy 121.172477 -391.66354) (xy 121.196518 -391.707963) (xy 121.212919 -391.755737) (xy 121.221232 -391.805559)
			(xy 121.221754 -391.830814) (xy 121.22152 -391.846616) (xy 121.218209 -391.878047) (xy 121.21515 -391.893552)
			(xy 121.213522 -391.903565) (xy 121.217369 -391.923469) (xy 121.228575 -391.940361) (xy 121.23674 -391.946384)
			(xy 121.264524 -391.965409) (xy 121.315936 -392.008899) (xy 121.361961 -392.058055) (xy 121.401977 -392.112215)
			(xy 121.419112 -392.141202) (xy 121.423862 -392.148807) (xy 121.43757 -392.160349) (xy 121.454414 -392.166464)
			(xy 121.472334 -392.166402) (xy 121.480834 -392.163554) (xy 121.509068 -392.15359) (xy 121.567095 -392.138825)
			(xy 121.596658 -392.13409) (xy 121.607245 -392.132058) (xy 121.625411 -392.120486) (xy 121.63171 -392.111738)
			(xy 121.653727 -392.079337) (xy 121.705114 -392.02021) (xy 121.764003 -391.96855) (xy 121.796302 -391.946384)
			(xy 121.804517 -391.940406) (xy 121.815767 -391.923509) (xy 121.819579 -391.90357) (xy 121.817892 -391.893552)
			(xy 121.814814 -391.87805) (xy 121.811508 -391.846617) (xy 121.811288 -391.830814) (xy 121.81181 -391.805559)
			(xy 121.820123 -391.755737) (xy 121.836524 -391.707963) (xy 121.860565 -391.66354) (xy 121.891589 -391.62368)
			(xy 121.928751 -391.58947) (xy 121.971037 -391.561844) (xy 122.017293 -391.541554) (xy 122.066258 -391.529154)
			(xy 122.116596 -391.524983) (xy 122.166934 -391.529154) (xy 122.215899 -391.541554) (xy 122.262155 -391.561844)
			(xy 122.304441 -391.58947) (xy 122.341603 -391.62368) (xy 122.372627 -391.66354) (xy 122.396668 -391.707963)
			(xy 122.413069 -391.755737) (xy 122.421382 -391.805559) (xy 122.421904 -391.830814) (xy 122.42167 -391.846616)
			(xy 122.41836 -391.878047) (xy 122.4153 -391.893552) (xy 122.413671 -391.903564) (xy 122.41752 -391.923465)
			(xy 122.428734 -391.940349) (xy 122.43689 -391.946384) (xy 122.464656 -391.96539) (xy 122.516042 -392.008832)
			(xy 122.562057 -392.057927) (xy 122.602084 -392.112015) (xy 122.619262 -392.140948) (xy 122.623997 -392.148571)
			(xy 122.637683 -392.160161) (xy 122.654521 -392.166335) (xy 122.672455 -392.16634) (xy 122.680984 -392.163554)
			(xy 122.709155 -392.153599) (xy 122.767056 -392.13884) (xy 122.796554 -392.13409) (xy 122.807142 -392.132059)
			(xy 122.825309 -392.120487) (xy 122.831606 -392.111738) (xy 122.853623 -392.079337) (xy 122.90501 -392.02021)
			(xy 122.963898 -391.968549) (xy 122.996198 -391.946384) (xy 123.004414 -391.940407) (xy 123.015665 -391.923509)
			(xy 123.019477 -391.90357) (xy 123.017788 -391.893552) (xy 123.01471 -391.87805) (xy 123.011404 -391.846617)
			(xy 123.011184 -391.830814) (xy 123.011706 -391.805559) (xy 123.020019 -391.755737) (xy 123.03642 -391.707963)
			(xy 123.060461 -391.66354) (xy 123.091485 -391.62368) (xy 123.128647 -391.58947) (xy 123.170933 -391.561844)
			(xy 123.217189 -391.541554) (xy 123.266154 -391.529154) (xy 123.316492 -391.524983) (xy 123.36683 -391.529154)
			(xy 123.415795 -391.541554) (xy 123.462051 -391.561844) (xy 123.504337 -391.58947) (xy 123.541499 -391.62368)
			(xy 123.572523 -391.66354) (xy 123.596564 -391.707963) (xy 123.612965 -391.755737) (xy 123.621278 -391.805559)
			(xy 123.6218 -391.830814) (xy 123.621566 -391.846616) (xy 123.618256 -391.878047) (xy 123.615196 -391.893552)
			(xy 123.613567 -391.903564) (xy 123.617416 -391.923465) (xy 123.628629 -391.94035) (xy 123.636786 -391.946384)
			(xy 123.664568 -391.96541) (xy 123.715977 -392.008903) (xy 123.761999 -392.058061) (xy 123.802012 -392.112221)
			(xy 123.819158 -392.141202) (xy 123.82391 -392.148801) (xy 123.837617 -392.16033) (xy 123.854456 -392.16643)
			(xy 123.872367 -392.166355) (xy 123.88088 -392.163554) (xy 123.909114 -392.153592) (xy 123.967142 -392.138832)
			(xy 123.996704 -392.13409) (xy 124.007286 -392.13205) (xy 124.025438 -392.120469) (xy 124.031756 -392.111738)
			(xy 124.053735 -392.079349) (xy 124.105043 -392.020234) (xy 124.163845 -391.968568) (xy 124.196094 -391.946384)
			(xy 124.204244 -391.940407) (xy 124.215431 -391.923593) (xy 124.219326 -391.903776) (xy 124.217684 -391.893806)
			(xy 124.214593 -391.878242) (xy 124.211282 -391.846681) (xy 124.21108 -391.830814) (xy 124.211602 -391.805559)
			(xy 124.219915 -391.755737) (xy 124.236316 -391.707963) (xy 124.260357 -391.66354) (xy 124.291381 -391.62368)
			(xy 124.328543 -391.58947) (xy 124.370829 -391.561844) (xy 124.417085 -391.541554) (xy 124.46605 -391.529154)
			(xy 124.516388 -391.524983) (xy 124.566726 -391.529154) (xy 124.615691 -391.541554) (xy 124.661947 -391.561844)
			(xy 124.704233 -391.58947) (xy 124.741395 -391.62368) (xy 124.772419 -391.66354) (xy 124.79646 -391.707963)
			(xy 124.812861 -391.755737) (xy 124.821174 -391.805559) (xy 124.821696 -391.830814) (xy 124.821462 -391.846616)
			(xy 124.818152 -391.878047) (xy 124.815092 -391.893552) (xy 124.8135 -391.903553) (xy 124.817434 -391.923401)
			(xy 124.828737 -391.940184) (xy 124.836936 -391.94613) (xy 124.866318 -391.966256) (xy 124.920407 -392.012584)
			(xy 124.968404 -392.065199) (xy 125.009583 -392.123306) (xy 125.026928 -392.15441) (xy 125.031449 -392.162053)
			(xy 125.044651 -392.173909) (xy 125.061102 -392.180556) (xy 125.078834 -392.1812) (xy 125.08738 -392.178794)
			(xy 125.110801 -392.171365) (xy 125.158618 -392.160043) (xy 125.182884 -392.156188) (xy 125.193957 -392.153983)
			(xy 125.212706 -392.141461) (xy 125.218952 -392.132058) (xy 125.235948 -392.104508) (xy 125.275156 -392.052996)
			(xy 125.319859 -392.006173) (xy 125.369499 -391.964621) (xy 125.396244 -391.946384) (xy 125.404454 -391.940403)
			(xy 125.415694 -391.923506) (xy 125.419503 -391.903571) (xy 125.417834 -391.893552) (xy 125.414755 -391.87805)
			(xy 125.411449 -391.846617) (xy 125.41123 -391.830814) (xy 125.411752 -391.805559) (xy 125.420065 -391.755737)
			(xy 125.436466 -391.707963) (xy 125.460507 -391.66354) (xy 125.491531 -391.62368) (xy 125.528693 -391.58947)
			(xy 125.570979 -391.561844) (xy 125.617235 -391.541554) (xy 125.6662 -391.529154) (xy 125.716538 -391.524983)
			(xy 125.766876 -391.529154) (xy 125.815841 -391.541554) (xy 125.862097 -391.561844) (xy 125.904383 -391.58947)
			(xy 125.941545 -391.62368) (xy 125.972569 -391.66354) (xy 125.99661 -391.707963) (xy 126.013011 -391.755737)
			(xy 126.021324 -391.805559) (xy 126.021846 -391.830814) (xy 126.021612 -391.846616) (xy 126.018301 -391.878047)
			(xy 126.015242 -391.893552) (xy 126.013613 -391.903563) (xy 126.017464 -391.923461) (xy 126.028683 -391.94034)
			(xy 126.036832 -391.946384) (xy 126.064616 -391.965408) (xy 126.116029 -392.008898) (xy 126.162054 -392.058054)
			(xy 126.202071 -392.112213) (xy 126.219204 -392.141202) (xy 126.223957 -392.148795) (xy 126.237663 -392.16031)
			(xy 126.254499 -392.166396) (xy 126.2724 -392.166308) (xy 126.280926 -392.163554) (xy 126.309159 -392.153589)
			(xy 126.367186 -392.138824) (xy 126.39675 -392.13409) (xy 126.407338 -392.132059) (xy 126.425506 -392.120489)
			(xy 126.431802 -392.111738) (xy 126.453783 -392.07935) (xy 126.505092 -392.020239) (xy 126.563897 -391.968577)
			(xy 126.59614 -391.946384) (xy 126.604234 -391.940354) (xy 126.615395 -391.923562) (xy 126.619282 -391.903777)
			(xy 126.61773 -391.893806) (xy 126.61464 -391.878242) (xy 126.611329 -391.846681) (xy 126.611126 -391.830814)
			(xy 126.611648 -391.805559) (xy 126.619961 -391.755737) (xy 126.636362 -391.707963) (xy 126.660403 -391.66354)
			(xy 126.691427 -391.62368) (xy 126.728589 -391.58947) (xy 126.770875 -391.561844) (xy 126.817131 -391.541554)
			(xy 126.866096 -391.529154) (xy 126.916434 -391.524983) (xy 126.966772 -391.529154) (xy 127.015737 -391.541554)
			(xy 127.061993 -391.561844) (xy 127.104279 -391.58947) (xy 127.141441 -391.62368) (xy 127.172465 -391.66354)
			(xy 127.196506 -391.707963) (xy 127.212907 -391.755737) (xy 127.22122 -391.805559) (xy 127.221742 -391.830814)
			(xy 127.221508 -391.846616) (xy 127.218197 -391.878047) (xy 127.215138 -391.893552) (xy 127.213547 -391.903554)
			(xy 127.217478 -391.923406) (xy 127.228773 -391.940197) (xy 127.236982 -391.94613) (xy 127.264763 -391.965157)
			(xy 127.31617 -392.008651) (xy 127.362188 -392.057811) (xy 127.402198 -392.111974) (xy 127.419354 -392.140948)
			(xy 127.424088 -392.148572) (xy 127.437774 -392.160165) (xy 127.454613 -392.166342) (xy 127.472549 -392.166348)
			(xy 127.481076 -392.163554) (xy 127.509247 -392.153598) (xy 127.567147 -392.138839) (xy 127.596646 -392.13409)
			(xy 127.607235 -392.13206) (xy 127.625404 -392.12049) (xy 127.631698 -392.111738) (xy 127.653714 -392.079336)
			(xy 127.705101 -392.020209) (xy 127.763989 -391.968548) (xy 127.79629 -391.946384) (xy 127.804507 -391.940407)
			(xy 127.81576 -391.92351) (xy 127.819573 -391.90357) (xy 127.81788 -391.893552) (xy 127.814802 -391.87805)
			(xy 127.811496 -391.846617) (xy 127.811276 -391.830814) (xy 127.811798 -391.805559) (xy 127.820111 -391.755737)
			(xy 127.836512 -391.707963) (xy 127.860553 -391.66354) (xy 127.891577 -391.62368) (xy 127.928739 -391.58947)
			(xy 127.971025 -391.561844) (xy 128.017281 -391.541554) (xy 128.066246 -391.529154) (xy 128.116584 -391.524983)
			(xy 128.166922 -391.529154) (xy 128.215887 -391.541554) (xy 128.262143 -391.561844) (xy 128.304429 -391.58947)
			(xy 128.341591 -391.62368) (xy 128.372615 -391.66354) (xy 128.396656 -391.707963) (xy 128.413057 -391.755737)
			(xy 128.42137 -391.805559) (xy 128.421892 -391.830814) (xy 128.421658 -391.846616) (xy 128.418348 -391.878047)
			(xy 128.415288 -391.893552) (xy 128.413659 -391.903565) (xy 128.417508 -391.923465) (xy 128.42872 -391.940352)
			(xy 128.436878 -391.946384) (xy 128.464644 -391.96539) (xy 128.516031 -392.008831) (xy 128.562048 -392.057925)
			(xy 128.602075 -392.112014) (xy 128.61925 -392.140948) (xy 128.623984 -392.148573) (xy 128.63767 -392.160167)
			(xy 128.654509 -392.166344) (xy 128.672446 -392.166352) (xy 128.680972 -392.163554) (xy 128.709143 -392.153598)
			(xy 128.767043 -392.138838) (xy 128.796542 -392.13409) (xy 128.80712 -392.132043) (xy 128.825259 -392.120455)
			(xy 128.831594 -392.111738) (xy 128.85361 -392.079336) (xy 128.904997 -392.020209) (xy 128.963884 -391.968547)
			(xy 128.996186 -391.946384) (xy 129.004403 -391.940408) (xy 129.015657 -391.92351) (xy 129.01947 -391.90357)
			(xy 129.017776 -391.893552) (xy 129.014698 -391.87805) (xy 129.011392 -391.846617) (xy 129.011172 -391.830814)
			(xy 129.011694 -391.805559) (xy 129.020007 -391.755737) (xy 129.036408 -391.707963) (xy 129.060449 -391.66354)
			(xy 129.091473 -391.62368) (xy 129.128635 -391.58947) (xy 129.170921 -391.561844) (xy 129.217177 -391.541554)
			(xy 129.266142 -391.529154) (xy 129.31648 -391.524983) (xy 129.366818 -391.529154) (xy 129.415783 -391.541554)
			(xy 129.462039 -391.561844) (xy 129.504325 -391.58947) (xy 129.541487 -391.62368) (xy 129.572511 -391.66354)
			(xy 129.596552 -391.707963) (xy 129.612953 -391.755737) (xy 129.621266 -391.805559) (xy 129.621788 -391.830814)
			(xy 129.621554 -391.846616) (xy 129.618243 -391.878047) (xy 129.615184 -391.893552) (xy 129.613555 -391.903565)
			(xy 129.617404 -391.923466) (xy 129.628615 -391.940353) (xy 129.636774 -391.946384) (xy 129.66454 -391.965389)
			(xy 129.715928 -392.00883) (xy 129.761944 -392.057925) (xy 129.801972 -392.112013) (xy 129.819146 -392.140948)
			(xy 129.82388 -392.148573) (xy 129.837566 -392.160168) (xy 129.854406 -392.166347) (xy 129.872343 -392.166356)
			(xy 129.880868 -392.163554) (xy 129.909039 -392.153598) (xy 129.966939 -392.138838) (xy 129.996438 -392.13409)
			(xy 130.007016 -392.132044) (xy 130.025157 -392.120456) (xy 130.03149 -392.111738) (xy 130.053506 -392.079336)
			(xy 130.104893 -392.020208) (xy 130.16378 -391.968546) (xy 130.196082 -391.946384) (xy 130.2043 -391.940408)
			(xy 130.215554 -391.923511) (xy 130.219368 -391.90357) (xy 130.217672 -391.893552) (xy 130.214594 -391.87805)
			(xy 130.211288 -391.846617) (xy 130.211068 -391.830814) (xy 130.21159 -391.805559) (xy 130.219903 -391.755737)
			(xy 130.236304 -391.707963) (xy 130.260345 -391.66354) (xy 130.291369 -391.62368) (xy 130.328531 -391.58947)
			(xy 130.370817 -391.561844) (xy 130.417073 -391.541554) (xy 130.466038 -391.529154) (xy 130.516376 -391.524983)
			(xy 130.566714 -391.529154) (xy 130.615679 -391.541554) (xy 130.661935 -391.561844) (xy 130.704221 -391.58947)
			(xy 130.741383 -391.62368) (xy 130.772407 -391.66354) (xy 130.796448 -391.707963) (xy 130.812849 -391.755737)
			(xy 130.821162 -391.805559) (xy 130.821684 -391.830814) (xy 130.82145 -391.846616) (xy 130.818139 -391.878047)
			(xy 130.81508 -391.893552) (xy 130.813451 -391.903565) (xy 130.8173 -391.923466) (xy 130.82851 -391.940354)
			(xy 130.83667 -391.946384) (xy 130.864453 -391.96541) (xy 130.915863 -392.008901) (xy 130.961886 -392.058059)
			(xy 131.0019 -392.112219) (xy 131.019042 -392.141202) (xy 131.023793 -392.148803) (xy 131.0375 -392.160336)
			(xy 131.054342 -392.166442) (xy 131.072255 -392.166371) (xy 131.080764 -392.163554) (xy 131.108998 -392.153591)
			(xy 131.167025 -392.13883) (xy 131.196588 -392.13409) (xy 131.207172 -392.132053) (xy 131.225328 -392.120475)
			(xy 131.23164 -392.111738) (xy 131.253657 -392.079338) (xy 131.305047 -392.020213) (xy 131.363937 -391.968555)
			(xy 131.396232 -391.946384) (xy 131.404443 -391.940404) (xy 131.415686 -391.923506) (xy 131.419496 -391.903571)
			(xy 131.417822 -391.893552) (xy 131.414743 -391.87805) (xy 131.411437 -391.846617) (xy 131.411218 -391.830814)
			(xy 131.41174 -391.805559) (xy 131.420053 -391.755737) (xy 131.436454 -391.707963) (xy 131.460495 -391.66354)
			(xy 131.491519 -391.62368) (xy 131.528681 -391.58947) (xy 131.570967 -391.561844) (xy 131.617223 -391.541554)
			(xy 131.666188 -391.529154) (xy 131.716526 -391.524983) (xy 131.766864 -391.529154) (xy 131.815829 -391.541554)
			(xy 131.862085 -391.561844) (xy 131.904371 -391.58947) (xy 131.941533 -391.62368) (xy 131.972557 -391.66354)
			(xy 131.996598 -391.707963) (xy 132.012999 -391.755737) (xy 132.021312 -391.805559) (xy 132.021834 -391.830814)
			(xy 132.0216 -391.846616) (xy 132.018289 -391.878047) (xy 132.01523 -391.893552) (xy 132.013601 -391.903563)
			(xy 132.017452 -391.923462) (xy 132.028669 -391.940343) (xy 132.03682 -391.946384) (xy 132.064585 -391.965391)
			(xy 132.115969 -392.008834) (xy 132.161982 -392.05793) (xy 132.202007 -392.11202) (xy 132.219192 -392.140948)
			(xy 132.223928 -392.148567) (xy 132.237613 -392.160149) (xy 132.254448 -392.166314) (xy 132.272376 -392.166309)
			(xy 132.280914 -392.163554) (xy 132.309084 -392.153595) (xy 132.366984 -392.13883) (xy 132.396484 -392.13409)
			(xy 132.407068 -392.132053) (xy 132.425226 -392.120476) (xy 132.431536 -392.111738) (xy 132.453553 -392.079337)
			(xy 132.504943 -392.020213) (xy 132.563832 -391.968555) (xy 132.596128 -391.946384) (xy 132.60434 -391.940404)
			(xy 132.615584 -391.923507) (xy 132.619394 -391.903571) (xy 132.617718 -391.893552) (xy 132.614639 -391.87805)
			(xy 132.611333 -391.846617) (xy 132.611114 -391.830814) (xy 132.611636 -391.805559) (xy 132.619949 -391.755737)
			(xy 132.63635 -391.707963) (xy 132.660391 -391.66354) (xy 132.691415 -391.62368) (xy 132.728577 -391.58947)
			(xy 132.770863 -391.561844) (xy 132.817119 -391.541554) (xy 132.866084 -391.529154) (xy 132.916422 -391.524983)
			(xy 132.96676 -391.529154) (xy 133.015725 -391.541554) (xy 133.061981 -391.561844) (xy 133.104267 -391.58947)
			(xy 133.141429 -391.62368) (xy 133.172453 -391.66354) (xy 133.196494 -391.707963) (xy 133.212895 -391.755737)
			(xy 133.221208 -391.805559) (xy 133.22173 -391.830814) (xy 133.221496 -391.846616) (xy 133.218185 -391.878047)
			(xy 133.215126 -391.893552) (xy 133.213497 -391.903564) (xy 133.217347 -391.923462) (xy 133.228564 -391.940343)
			(xy 133.236716 -391.946384) (xy 133.266153 -391.966564) (xy 133.320337 -392.013019) (xy 133.368403 -392.06578)
			(xy 133.409621 -392.124047) (xy 133.443368 -392.186937) (xy 133.469131 -392.253497) (xy 133.486521 -392.322718)
			(xy 133.495274 -392.393552) (xy 133.495796 -392.429238) (xy 133.495796 -392.580622) (xy 133.495351 -392.613215)
			(xy 133.488032 -392.67799) (xy 133.473489 -392.741534) (xy 133.451906 -392.803044) (xy 133.438138 -392.83259)
			(xy 133.433546 -392.843235) (xy 133.433552 -392.866392) (xy 133.438138 -392.87704) (xy 133.451912 -392.906583)
			(xy 133.473493 -392.968095) (xy 133.488032 -393.031639) (xy 133.495348 -393.096414) (xy 133.495796 -393.129008)
			(xy 133.495796 -393.285247) (xy 133.969818 -393.285247) (xy 133.969818 -393.230753) (xy 133.977573 -393.176815)
			(xy 133.992924 -393.124529) (xy 134.01556 -393.07496) (xy 134.045019 -393.029116) (xy 134.080703 -392.987931)
			(xy 134.121884 -392.952243) (xy 134.167724 -392.922779) (xy 134.217291 -392.900138) (xy 134.269576 -392.884781)
			(xy 134.323514 -392.877021) (xy 134.35076 -392.876532) (xy 134.360466 -392.876144) (xy 134.378492 -392.868949)
			(xy 134.385812 -392.862562) (xy 134.443724 -392.807444) (xy 134.451852 -392.789918) (xy 134.45236 -392.780266)
			(xy 134.454445 -392.748117) (xy 134.465811 -392.6847) (xy 134.4851 -392.623228) (xy 134.512001 -392.564686)
			(xy 134.546083 -392.510012) (xy 134.586801 -392.460083) (xy 134.633502 -392.415699) (xy 134.685437 -392.377572)
			(xy 134.741772 -392.346312) (xy 134.801607 -392.322422) (xy 134.86398 -392.306284) (xy 134.927892 -392.298156)
			(xy 134.960106 -392.297666) (xy 134.992065 -392.29822) (xy 135.055479 -392.306232) (xy 135.117389 -392.322128)
			(xy 135.176819 -392.345659) (xy 135.232831 -392.376452) (xy 135.284542 -392.414023) (xy 135.331136 -392.457778)
			(xy 135.371879 -392.507028) (xy 135.406127 -392.560997) (xy 135.433342 -392.618832) (xy 135.453094 -392.679622)
			(xy 135.465071 -392.742408) (xy 135.469085 -392.8062) (xy 135.465071 -392.869992) (xy 135.453094 -392.932778)
			(xy 135.433342 -392.993568) (xy 135.406127 -393.051403) (xy 135.371879 -393.105372) (xy 135.331136 -393.154622)
			(xy 135.284542 -393.198377) (xy 135.232831 -393.235948) (xy 135.176819 -393.266741) (xy 135.117389 -393.290272)
			(xy 135.055479 -393.306168) (xy 134.992065 -393.31418) (xy 134.960106 -393.314682) (xy 134.929121 -393.314225)
			(xy 134.867608 -393.306709) (xy 134.837424 -393.299696) (xy 134.828026 -393.29741) (xy 134.808722 -393.29995)
			(xy 134.730744 -393.344146) (xy 134.718806 -393.359386) (xy 134.715758 -393.368784) (xy 134.707462 -393.394545)
			(xy 134.684603 -393.4436) (xy 134.655039 -393.488931) (xy 134.619362 -393.529626) (xy 134.578291 -393.564869)
			(xy 134.532649 -393.593951) (xy 134.483354 -393.616288) (xy 134.431397 -393.631432) (xy 134.37782 -393.639078)
			(xy 134.35076 -393.639548) (xy 134.323514 -393.638979) (xy 134.269576 -393.631219) (xy 134.217291 -393.615862)
			(xy 134.167724 -393.593221) (xy 134.121884 -393.563757) (xy 134.080703 -393.528069) (xy 134.045019 -393.486884)
			(xy 134.01556 -393.44104) (xy 133.992924 -393.391471) (xy 133.977573 -393.339185) (xy 133.969818 -393.285247)
			(xy 133.495796 -393.285247) (xy 133.495796 -393.292838) (xy 133.495306 -393.32712) (xy 133.487241 -393.395207)
			(xy 133.471192 -393.461865) (xy 133.447383 -393.526162) (xy 133.416149 -393.587198) (xy 133.377926 -393.644118)
			(xy 133.333249 -393.696126) (xy 133.282743 -393.742495) (xy 133.255258 -393.762992) (xy 133.247237 -393.769348)
			(xy 133.236659 -393.786846) (xy 133.233788 -393.80709) (xy 133.235954 -393.817094) (xy 133.2412 -393.838038)
			(xy 133.246801 -393.880849) (xy 133.24713 -393.902438) (xy 133.246832 -393.921276) (xy 133.242501 -393.958704)
			(xy 133.238494 -393.977114) (xy 133.234176 -393.996672) (xy 133.254242 -394.031216) (xy 133.580886 -394.130276)
			(xy 133.585712 -394.131546) (xy 134.547102 -394.323062) (xy 134.551928 -394.32357) (xy 135.075168 -394.375132)
			(xy 135.091424 -394.371322) (xy 135.09879 -394.366496) (xy 135.127007 -394.348797) (xy 135.186713 -394.319265)
			(xy 135.24941 -394.29677) (xy 135.314272 -394.281609) (xy 135.380445 -394.273981) (xy 135.41375 -394.273532)
			(xy 135.427998 -394.27362) (xy 135.456459 -394.275016) (xy 135.470646 -394.276326) (xy 135.895588 -394.318236)
			(xy 135.92787 -394.321866) (xy 135.991408 -394.335411) (xy 136.053035 -394.35597) (xy 136.111978 -394.383287)
			(xy 136.167501 -394.417018) (xy 136.218906 -394.456742) (xy 136.242552 -394.479018) (xy 136.248902 -394.485368)
			(xy 136.264142 -394.49248) (xy 136.36371 -394.502132) (xy 136.374971 -394.502672) (xy 136.396204 -394.495172)
			(xy 136.404604 -394.487654) (xy 136.718802 -394.173456) (xy 136.724737 -394.167059) (xy 136.732301 -394.151344)
			(xy 136.734209 -394.134009) (xy 136.732518 -394.12545) (xy 136.708896 -394.028168) (xy 136.691116 -394.008864)
			(xy 136.678416 -394.0048) (xy 136.648105 -393.994504) (xy 136.590135 -393.967344) (xy 136.536032 -393.933124)
			(xy 136.486651 -393.892385) (xy 136.442772 -393.845771) (xy 136.40509 -393.794019) (xy 136.3742 -393.737948)
			(xy 136.350591 -393.678444) (xy 136.334635 -393.616447) (xy 136.326585 -393.552938) (xy 136.326118 -393.52093)
			(xy 136.326601 -393.490236) (xy 136.334029 -393.429299) (xy 136.348733 -393.369697) (xy 136.370499 -393.312297)
			(xy 136.399011 -393.257932) (xy 136.416034 -393.232386) (xy 136.421509 -393.223633) (xy 136.425646 -393.203425)
			(xy 136.421529 -393.183213) (xy 136.416034 -393.174474) (xy 136.39898 -393.148947) (xy 136.370453 -393.094584)
			(xy 136.348686 -393.03718) (xy 136.333994 -392.977571) (xy 136.326592 -392.916626) (xy 136.326118 -392.88593)
			(xy 136.326562 -392.855197) (xy 136.333968 -392.79418) (xy 136.348675 -392.7345) (xy 136.370469 -392.677028)
			(xy 136.399032 -392.622602) (xy 136.433947 -392.572017) (xy 136.474706 -392.526009) (xy 136.520713 -392.48525)
			(xy 136.571299 -392.450334) (xy 136.625724 -392.42177) (xy 136.683196 -392.399976) (xy 136.742876 -392.385268)
			(xy 136.803893 -392.377862) (xy 136.834626 -392.377422) (xy 136.865321 -392.377902) (xy 136.92626 -392.385326)
			(xy 136.985864 -392.400025) (xy 137.043267 -392.421787) (xy 137.097636 -392.450296) (xy 137.12317 -392.467338)
			(xy 137.131922 -392.472809) (xy 137.152126 -392.476937) (xy 137.17233 -392.472809) (xy 137.181082 -392.467338)
			(xy 137.206609 -392.450282) (xy 137.26097 -392.42175) (xy 137.318374 -392.399977) (xy 137.377983 -392.38528)
			(xy 137.438929 -392.377873) (xy 137.469626 -392.377422) (xy 137.500321 -392.377902) (xy 137.56126 -392.385326)
			(xy 137.620864 -392.400025) (xy 137.678267 -392.421787) (xy 137.732636 -392.450296) (xy 137.75817 -392.467338)
			(xy 137.766922 -392.472809) (xy 137.787126 -392.476937) (xy 137.80733 -392.472809) (xy 137.816082 -392.467338)
			(xy 137.841609 -392.450282) (xy 137.89597 -392.42175) (xy 137.953374 -392.399977) (xy 138.012983 -392.38528)
			(xy 138.073929 -392.377873) (xy 138.104626 -392.377422) (xy 138.125708 -392.37793) (xy 138.13663 -392.378438)
			(xy 138.156188 -392.370818) (xy 138.224514 -392.302492) (xy 138.232134 -392.282934) (xy 138.231626 -392.272012)
			(xy 138.231118 -392.25093) (xy 138.231601 -392.220236) (xy 138.239029 -392.159299) (xy 138.253733 -392.099697)
			(xy 138.275499 -392.042297) (xy 138.304011 -391.987932) (xy 138.321034 -391.962386) (xy 138.326509 -391.953633)
			(xy 138.330646 -391.933425) (xy 138.326529 -391.913213) (xy 138.321034 -391.904474) (xy 138.30398 -391.878947)
			(xy 138.275453 -391.824584) (xy 138.253686 -391.76718) (xy 138.238994 -391.707571) (xy 138.231592 -391.646626)
			(xy 138.231118 -391.61593) (xy 138.231562 -391.585197) (xy 138.238968 -391.52418) (xy 138.253675 -391.4645)
			(xy 138.275469 -391.407028) (xy 138.304032 -391.352602) (xy 138.338947 -391.302017) (xy 138.379706 -391.256009)
			(xy 138.425713 -391.21525) (xy 138.476299 -391.180334) (xy 138.530724 -391.15177) (xy 138.588196 -391.129976)
			(xy 138.647876 -391.115268) (xy 138.708893 -391.107862) (xy 138.739626 -391.107422) (xy 138.770321 -391.107902)
			(xy 138.83126 -391.115326) (xy 138.890864 -391.130025) (xy 138.948267 -391.151787) (xy 139.002636 -391.180296)
			(xy 139.02817 -391.197338) (xy 139.036922 -391.202809) (xy 139.057126 -391.206937) (xy 139.07733 -391.202809)
			(xy 139.086082 -391.197338) (xy 139.120626 -391.175494) (xy 139.128479 -391.170479) (xy 139.140207 -391.156021)
			(xy 139.143486 -391.1473) (xy 139.153138 -391.11809) (xy 139.155622 -391.109161) (xy 139.154704 -391.090666)
			(xy 139.15136 -391.082022) (xy 139.137866 -391.049731) (xy 139.118866 -390.982376) (xy 139.109278 -390.913052)
			(xy 139.108688 -390.87806) (xy 139.109179 -390.845895) (xy 139.11729 -390.782079) (xy 139.133389 -390.719796)
			(xy 139.157219 -390.660043) (xy 139.1884 -390.603775) (xy 139.226432 -390.551892) (xy 139.270708 -390.505224)
			(xy 139.320519 -390.464515) (xy 139.375069 -390.430419) (xy 139.40409 -390.416542) (xy 139.413445 -390.411538)
			(xy 139.427354 -390.39555) (xy 139.433663 -390.375319) (xy 139.433046 -390.364726) (xy 139.431591 -390.350611)
			(xy 139.430068 -390.322273) (xy 139.429998 -390.308084) (xy 139.430463 -390.277354) (xy 139.437873 -390.216342)
			(xy 139.452583 -390.156667) (xy 139.474379 -390.099201) (xy 139.502942 -390.044782) (xy 139.537857 -389.994201)
			(xy 139.578614 -389.948199) (xy 139.624619 -389.907444) (xy 139.6752 -389.872531) (xy 139.729622 -389.84397)
			(xy 139.787088 -389.822177) (xy 139.846763 -389.807469) (xy 139.907776 -389.800062) (xy 139.938506 -389.799576)
			(xy 139.953238 -389.79983) (xy 139.963906 -389.800084) (xy 139.982956 -389.792464) (xy 140.552424 -389.222996)
			(xy 140.558012 -389.191754) (xy 140.551154 -389.177276) (xy 140.540065 -389.152074) (xy 140.524438 -389.099279)
			(xy 140.516568 -389.044786) (xy 140.516102 -389.017256) (xy 140.516591 -388.990007) (xy 140.524353 -388.936065)
			(xy 140.539712 -388.883776) (xy 140.562356 -388.834205) (xy 140.591823 -388.788361) (xy 140.627515 -388.747177)
			(xy 140.668704 -388.711491) (xy 140.714552 -388.68203) (xy 140.764127 -388.659393) (xy 140.816418 -388.644041)
			(xy 140.870361 -388.636287) (xy 140.89761 -388.635748) (xy 140.9065 -388.635748) (xy 140.91793 -388.636002)
			(xy 140.93825 -388.627366) (xy 141.004798 -388.552182) (xy 141.011148 -388.530846) (xy 141.009624 -388.51967)
			(xy 141.007736 -388.506032) (xy 141.005703 -388.478573) (xy 141.00556 -388.464806) (xy 141.005696 -388.451938)
			(xy 141.007477 -388.426262) (xy 141.009116 -388.413498) (xy 141.01064 -388.402576) (xy 141.00429 -388.381748)
			(xy 140.93952 -388.307326) (xy 140.919708 -388.298182) (xy 140.908786 -388.298182) (xy 140.87557 -388.297524)
			(xy 140.809732 -388.288637) (xy 140.745612 -388.271251) (xy 140.684302 -388.245662) (xy 140.626847 -388.212307)
			(xy 140.574225 -388.171752) (xy 140.527333 -388.12469) (xy 140.486969 -388.071922) (xy 140.453822 -388.014347)
			(xy 140.428455 -387.952945) (xy 140.411301 -387.888762) (xy 140.402653 -387.822892) (xy 140.402056 -387.789674)
			(xy 140.402637 -387.754719) (xy 140.412209 -387.685468) (xy 140.431169 -387.618179) (xy 140.459161 -387.554119)
			(xy 140.495658 -387.494492) (xy 140.517372 -387.467094) (xy 140.52271 -387.460115) (xy 140.5287 -387.443614)
			(xy 140.529056 -387.434836) (xy 140.529056 -387.280912) (xy 140.528638 -387.272146) (xy 140.522656 -387.255661)
			(xy 140.517372 -387.248654) (xy 140.49566 -387.221255) (xy 140.459161 -387.161631) (xy 140.431171 -387.097571)
			(xy 140.412219 -387.03028) (xy 140.402662 -386.961028) (xy 140.402056 -386.926074) (xy 140.402521 -386.895343)
			(xy 140.409932 -386.83433) (xy 140.424643 -386.774655) (xy 140.446439 -386.717188) (xy 140.475002 -386.662767)
			(xy 140.509916 -386.612185) (xy 140.550673 -386.56618) (xy 140.596677 -386.525423) (xy 140.647258 -386.490507)
			(xy 140.701679 -386.461943) (xy 140.759145 -386.440146) (xy 140.81882 -386.425434) (xy 140.879833 -386.418022)
			(xy 140.910564 -386.417566) (xy 140.931489 -386.417779) (xy 140.973198 -386.421211) (xy 140.993876 -386.424424)
			(xy 141.00302 -386.425948) (xy 141.0208 -386.422646) (xy 141.092936 -386.378958) (xy 141.104112 -386.364988)
			(xy 141.10716 -386.356352) (xy 141.115928 -386.331332) (xy 141.13941 -386.283802) (xy 141.169252 -386.239984)
			(xy 141.204879 -386.200724) (xy 141.245603 -386.16678) (xy 141.290637 -386.138808) (xy 141.339114 -386.117346)
			(xy 141.390097 -386.102809) (xy 141.442602 -386.095477) (xy 141.46911 -386.094986) (xy 141.496361 -386.095472)
			(xy 141.550308 -386.10323) (xy 141.602602 -386.118586) (xy 141.652178 -386.141228) (xy 141.698028 -386.170694)
			(xy 141.739217 -386.206386) (xy 141.774908 -386.247575) (xy 141.804374 -386.293425) (xy 141.827015 -386.343002)
			(xy 141.842371 -386.395296) (xy 141.850128 -386.449243) (xy 141.850618 -386.476494) (xy 141.850122 -386.504462)
			(xy 141.841944 -386.559799) (xy 141.825779 -386.613349) (xy 141.801971 -386.663967) (xy 141.77103 -386.710568)
			(xy 141.73362 -386.752155) (xy 141.690541 -386.787836) (xy 141.642716 -386.816849) (xy 141.591169 -386.838571)
			(xy 141.537003 -386.852537) (xy 141.509242 -386.85597) (xy 141.500098 -386.856732) (xy 141.483842 -386.86486)
			(xy 141.42593 -386.926074) (xy 141.418818 -386.942584) (xy 141.41831 -386.951728) (xy 141.416179 -386.984041)
			(xy 141.404748 -387.047783) (xy 141.385321 -387.109558) (xy 141.358212 -387.168369) (xy 141.323858 -387.223265)
			(xy 141.303756 -387.248654) (xy 141.298423 -387.255634) (xy 141.292444 -387.272136) (xy 141.292072 -387.280912)
			(xy 141.292072 -387.434836) (xy 141.292482 -387.443604) (xy 141.298454 -387.460099) (xy 141.303756 -387.467094)
			(xy 141.32547 -387.494493) (xy 141.361973 -387.554116) (xy 141.389968 -387.618176) (xy 141.408925 -387.685466)
			(xy 141.418489 -387.754719) (xy 141.419072 -387.789674) (xy 141.418692 -387.818332) (xy 141.41227 -387.875286)
			(xy 141.399481 -387.931156) (xy 141.39037 -387.95833) (xy 141.38656 -387.968744) (xy 141.388592 -387.990334)
			(xy 141.436852 -388.076186) (xy 141.454378 -388.08914) (xy 141.4653 -388.091426) (xy 141.4935 -388.097887)
			(xy 141.547678 -388.118173) (xy 141.598172 -388.146407) (xy 141.643825 -388.181942) (xy 141.683588 -388.223961)
			(xy 141.716552 -388.271503) (xy 141.741959 -388.323477) (xy 141.759227 -388.378692) (xy 141.767961 -388.43588)
			(xy 141.768576 -388.464806) (xy 141.768112 -388.492058) (xy 141.760354 -388.546006) (xy 141.744998 -388.598302)
			(xy 141.722354 -388.647879) (xy 141.692886 -388.693729) (xy 141.657191 -388.734918) (xy 141.615999 -388.770608)
			(xy 141.570146 -388.800072) (xy 141.520566 -388.822711) (xy 141.468269 -388.838062) (xy 141.41432 -388.845815)
			(xy 141.387068 -388.846314) (xy 141.378178 -388.846314) (xy 141.366748 -388.84606) (xy 141.346428 -388.854696)
			(xy 141.27988 -388.92988) (xy 141.27353 -388.951216) (xy 141.275054 -388.962392) (xy 141.276943 -388.97603)
			(xy 141.278979 -389.003489) (xy 141.279118 -389.017256) (xy 141.278926 -389.034692) (xy 141.27575 -389.069418)
			(xy 141.272768 -389.086598) (xy 141.270736 -389.097774) (xy 141.276324 -389.119618) (xy 141.333474 -389.188452)
			(xy 141.341079 -389.196704) (xy 141.361381 -389.206201) (xy 141.37259 -389.20674) (xy 142.008098 -389.20674)
			(xy 142.018167 -389.206316) (xy 142.036766 -389.198595) (xy 142.044166 -389.191754) (xy 144.354296 -386.881624)
			(xy 144.360909 -386.874454) (xy 144.368625 -386.856557) (xy 144.369282 -386.846826) (xy 144.370044 -386.816854)
			(xy 144.369831 -386.807668) (xy 144.3637 -386.790362) (xy 144.358106 -386.783072) (xy 144.338095 -386.758244)
			(xy 144.304413 -386.704098) (xy 144.27857 -386.645803) (xy 144.261066 -386.584485) (xy 144.252239 -386.521332)
			(xy 144.25168 -386.489448) (xy 144.252209 -386.458572) (xy 144.260552 -386.397384) (xy 144.277039 -386.337872)
			(xy 144.30137 -386.281114) (xy 144.333106 -386.228139) (xy 144.371671 -386.179908) (xy 144.393666 -386.158232)
			(xy 144.402302 -386.14985) (xy 144.41043 -386.127498) (xy 144.398492 -386.023104) (xy 144.385538 -386.003292)
			(xy 144.375124 -385.996942) (xy 144.351754 -385.982699) (xy 144.308257 -385.949481) (xy 144.269026 -385.911318)
			(xy 144.234619 -385.868755) (xy 144.205527 -385.822396) (xy 144.193514 -385.797806) (xy 144.187418 -385.785106)
			(xy 144.164558 -385.769612) (xy 144.047718 -385.762246) (xy 144.023334 -385.774692) (xy 144.015714 -385.78663)
			(xy 144.000626 -385.809509) (xy 143.964931 -385.851097) (xy 143.923654 -385.887149) (xy 143.877643 -385.916925)
			(xy 143.827845 -385.939812) (xy 143.775285 -385.955339) (xy 143.721045 -385.963186) (xy 143.693642 -385.963668)
			(xy 143.66639 -385.963208) (xy 143.61244 -385.955456) (xy 143.560143 -385.940106) (xy 143.510563 -385.917468)
			(xy 143.464709 -385.888004) (xy 143.423516 -385.852314) (xy 143.387821 -385.811125) (xy 143.358352 -385.765274)
			(xy 143.335709 -385.715697) (xy 143.320353 -385.663401) (xy 143.312595 -385.609452) (xy 143.312595 -385.554948)
			(xy 143.320353 -385.500999) (xy 143.335709 -385.448703) (xy 143.358352 -385.399126) (xy 143.387821 -385.353275)
			(xy 143.423516 -385.312086) (xy 143.464709 -385.276396) (xy 143.510563 -385.246932) (xy 143.560143 -385.224294)
			(xy 143.61244 -385.208944) (xy 143.66639 -385.201192) (xy 143.693642 -385.200652) (xy 143.722278 -385.201161)
			(xy 143.778909 -385.209715) (xy 143.833624 -385.226639) (xy 143.885194 -385.251553) (xy 143.932459 -385.283897)
			(xy 143.974358 -385.322943) (xy 144.009949 -385.367815) (xy 144.024604 -385.392422) (xy 144.031716 -385.404614)
			(xy 144.055592 -385.41833) (xy 144.172686 -385.416044) (xy 144.196054 -385.40182) (xy 144.202658 -385.389374)
			(xy 144.217607 -385.362131) (xy 144.253754 -385.311585) (xy 144.296405 -385.266392) (xy 144.344776 -385.227382)
			(xy 144.397978 -385.195273) (xy 144.455035 -385.170655) (xy 144.514897 -385.153979) (xy 144.576464 -385.145552)
			(xy 144.607534 -385.145026) (xy 144.637499 -385.145518) (xy 144.696917 -385.153345) (xy 144.754805 -385.168861)
			(xy 144.810172 -385.191799) (xy 144.862071 -385.221769) (xy 144.909615 -385.258256) (xy 144.951989 -385.300636)
			(xy 144.988469 -385.348185) (xy 145.018431 -385.400089) (xy 145.041361 -385.45546) (xy 145.056868 -385.51335)
			(xy 145.064686 -385.572769) (xy 145.065242 -385.602734) (xy 145.064714 -385.63361) (xy 145.056372 -385.694798)
			(xy 145.039885 -385.754309) (xy 145.015552 -385.811067) (xy 144.983813 -385.86404) (xy 144.945245 -385.912268)
			(xy 144.923256 -385.93395) (xy 144.91462 -385.942332) (xy 144.906492 -385.964684) (xy 144.91843 -386.069078)
			(xy 144.931384 -386.08889) (xy 144.941798 -386.09524) (xy 144.957847 -386.104867) (xy 144.98849 -386.12636)
			(xy 145.003012 -386.138166) (xy 145.010282 -386.143795) (xy 145.027602 -386.149924) (xy 145.036794 -386.150104)
			(xy 145.066766 -386.149342) (xy 145.076494 -386.148665) (xy 145.094389 -386.14096) (xy 145.101564 -386.134356)
			(xy 146.687794 -384.548126) (xy 146.695191 -384.541276) (xy 146.713789 -384.533535) (xy 146.723862 -384.53314)
			(xy 146.749516 -384.53314) (xy 146.77517 -384.51536) (xy 146.781012 -384.500374) (xy 146.790303 -384.477186)
			(xy 146.814855 -384.433684) (xy 146.845671 -384.39437) (xy 146.88205 -384.360138) (xy 146.923164 -384.331769)
			(xy 146.968078 -384.309907) (xy 147.01577 -384.29505) (xy 147.065154 -384.287536) (xy 147.115106 -384.287536)
			(xy 147.16449 -384.29505) (xy 147.212182 -384.309907) (xy 147.257096 -384.331769) (xy 147.29821 -384.360138)
			(xy 147.334589 -384.39437) (xy 147.365405 -384.433684) (xy 147.389957 -384.477186) (xy 147.399248 -384.500374)
			(xy 147.40509 -384.51536) (xy 147.430744 -384.53314) (xy 147.949412 -384.53314) (xy 147.975066 -384.51536)
			(xy 147.980908 -384.500374) (xy 147.990199 -384.477186) (xy 148.014751 -384.433684) (xy 148.045567 -384.39437)
			(xy 148.081946 -384.360138) (xy 148.12306 -384.331769) (xy 148.167974 -384.309907) (xy 148.215666 -384.29505)
			(xy 148.26505 -384.287536) (xy 148.315002 -384.287536) (xy 148.364386 -384.29505) (xy 148.412078 -384.309907)
			(xy 148.456992 -384.331769) (xy 148.498106 -384.360138) (xy 148.534485 -384.39437) (xy 148.565301 -384.433684)
			(xy 148.589853 -384.477186) (xy 148.599144 -384.500374) (xy 148.604986 -384.51536) (xy 148.63064 -384.53314)
			(xy 149.149562 -384.53314) (xy 149.175216 -384.51536) (xy 149.181058 -384.500374) (xy 149.190349 -384.477186)
			(xy 149.214901 -384.433684) (xy 149.245717 -384.39437) (xy 149.282096 -384.360138) (xy 149.32321 -384.331769)
			(xy 149.368124 -384.309907) (xy 149.415816 -384.29505) (xy 149.4652 -384.287536) (xy 149.515152 -384.287536)
			(xy 149.564536 -384.29505) (xy 149.612228 -384.309907) (xy 149.657142 -384.331769) (xy 149.698256 -384.360138)
			(xy 149.734635 -384.39437) (xy 149.765451 -384.433684) (xy 149.790003 -384.477186) (xy 149.799294 -384.500374)
			(xy 149.805136 -384.51536) (xy 149.83079 -384.53314) (xy 150.349458 -384.53314) (xy 150.375112 -384.51536)
			(xy 150.380954 -384.500374) (xy 150.390245 -384.477186) (xy 150.414797 -384.433684) (xy 150.445613 -384.39437)
			(xy 150.481992 -384.360138) (xy 150.523106 -384.331769) (xy 150.56802 -384.309907) (xy 150.615712 -384.29505)
			(xy 150.665096 -384.287536) (xy 150.715048 -384.287536) (xy 150.764432 -384.29505) (xy 150.812124 -384.309907)
			(xy 150.857038 -384.331769) (xy 150.898152 -384.360138) (xy 150.934531 -384.39437) (xy 150.965347 -384.433684)
			(xy 150.989899 -384.477186) (xy 150.99919 -384.500374) (xy 151.005032 -384.51536) (xy 151.030686 -384.53314)
			(xy 151.549608 -384.53314) (xy 151.575262 -384.51536) (xy 151.581104 -384.500374) (xy 151.590395 -384.477186)
			(xy 151.614947 -384.433684) (xy 151.645763 -384.39437) (xy 151.682142 -384.360138) (xy 151.723256 -384.331769)
			(xy 151.76817 -384.309907) (xy 151.815862 -384.29505) (xy 151.865246 -384.287536) (xy 151.915198 -384.287536)
			(xy 151.964582 -384.29505) (xy 152.012274 -384.309907) (xy 152.057188 -384.331769) (xy 152.098302 -384.360138)
			(xy 152.134681 -384.39437) (xy 152.165497 -384.433684) (xy 152.190049 -384.477186) (xy 152.19934 -384.500374)
			(xy 152.205182 -384.51536) (xy 152.230836 -384.53314) (xy 152.749504 -384.53314) (xy 152.775158 -384.51536)
			(xy 152.781 -384.500374) (xy 152.790291 -384.477186) (xy 152.814843 -384.433684) (xy 152.845659 -384.39437)
			(xy 152.882038 -384.360138) (xy 152.923152 -384.331769) (xy 152.968066 -384.309907) (xy 153.015758 -384.29505)
			(xy 153.065142 -384.287536) (xy 153.115094 -384.287536) (xy 153.164478 -384.29505) (xy 153.21217 -384.309907)
			(xy 153.257084 -384.331769) (xy 153.298198 -384.360138) (xy 153.334577 -384.39437) (xy 153.365393 -384.433684)
			(xy 153.389945 -384.477186) (xy 153.399236 -384.500374) (xy 153.405078 -384.51536) (xy 153.430732 -384.53314)
			(xy 153.9494 -384.53314) (xy 153.975054 -384.51536) (xy 153.980896 -384.500374) (xy 153.990187 -384.477186)
			(xy 154.014739 -384.433684) (xy 154.045555 -384.39437) (xy 154.081934 -384.360138) (xy 154.123048 -384.331769)
			(xy 154.167962 -384.309907) (xy 154.215654 -384.29505) (xy 154.265038 -384.287536) (xy 154.31499 -384.287536)
			(xy 154.364374 -384.29505) (xy 154.412066 -384.309907) (xy 154.45698 -384.331769) (xy 154.498094 -384.360138)
			(xy 154.534473 -384.39437) (xy 154.565289 -384.433684) (xy 154.589841 -384.477186) (xy 154.599132 -384.500374)
			(xy 154.604974 -384.51536) (xy 154.630628 -384.53314) (xy 155.14955 -384.53314) (xy 155.175204 -384.51536)
			(xy 155.181046 -384.500374) (xy 155.190337 -384.477186) (xy 155.214889 -384.433684) (xy 155.245705 -384.39437)
			(xy 155.282084 -384.360138) (xy 155.323198 -384.331769) (xy 155.368112 -384.309907) (xy 155.415804 -384.29505)
			(xy 155.465188 -384.287536) (xy 155.51514 -384.287536) (xy 155.564524 -384.29505) (xy 155.612216 -384.309907)
			(xy 155.65713 -384.331769) (xy 155.698244 -384.360138) (xy 155.734623 -384.39437) (xy 155.765439 -384.433684)
			(xy 155.789991 -384.477186) (xy 155.799282 -384.500374) (xy 155.805124 -384.51536) (xy 155.830778 -384.53314)
			(xy 156.349446 -384.53314) (xy 156.3751 -384.51536) (xy 156.380942 -384.500374) (xy 156.390233 -384.477186)
			(xy 156.414785 -384.433684) (xy 156.445601 -384.39437) (xy 156.48198 -384.360138) (xy 156.523094 -384.331769)
			(xy 156.568008 -384.309907) (xy 156.6157 -384.29505) (xy 156.665084 -384.287536) (xy 156.715036 -384.287536)
			(xy 156.76442 -384.29505) (xy 156.812112 -384.309907) (xy 156.857026 -384.331769) (xy 156.89814 -384.360138)
			(xy 156.934519 -384.39437) (xy 156.965335 -384.433684) (xy 156.989887 -384.477186) (xy 156.999178 -384.500374)
			(xy 157.00502 -384.51536) (xy 157.030674 -384.53314) (xy 157.549596 -384.53314) (xy 157.57525 -384.51536)
			(xy 157.581092 -384.500374) (xy 157.590383 -384.477186) (xy 157.614935 -384.433684) (xy 157.645751 -384.39437)
			(xy 157.68213 -384.360138) (xy 157.723244 -384.331769) (xy 157.768158 -384.309907) (xy 157.81585 -384.29505)
			(xy 157.865234 -384.287536) (xy 157.915186 -384.287536) (xy 157.96457 -384.29505) (xy 158.012262 -384.309907)
			(xy 158.057176 -384.331769) (xy 158.09829 -384.360138) (xy 158.134669 -384.39437) (xy 158.165485 -384.433684)
			(xy 158.190037 -384.477186) (xy 158.199328 -384.500374) (xy 158.20517 -384.51536) (xy 158.230824 -384.53314)
			(xy 158.749492 -384.53314) (xy 158.775146 -384.51536) (xy 158.780988 -384.500374) (xy 158.790279 -384.477186)
			(xy 158.814831 -384.433684) (xy 158.845647 -384.39437) (xy 158.882026 -384.360138) (xy 158.92314 -384.331769)
			(xy 158.968054 -384.309907) (xy 159.015746 -384.29505) (xy 159.06513 -384.287536) (xy 159.115082 -384.287536)
			(xy 159.164466 -384.29505) (xy 159.212158 -384.309907) (xy 159.257072 -384.331769) (xy 159.298186 -384.360138)
			(xy 159.334565 -384.39437) (xy 159.365381 -384.433684) (xy 159.389933 -384.477186) (xy 159.399224 -384.500374)
			(xy 159.405066 -384.51536) (xy 159.43072 -384.53314) (xy 159.949388 -384.53314) (xy 159.975042 -384.51536)
			(xy 159.980884 -384.500374) (xy 159.990175 -384.477186) (xy 160.014727 -384.433684) (xy 160.045543 -384.39437)
			(xy 160.081922 -384.360138) (xy 160.123036 -384.331769) (xy 160.16795 -384.309907) (xy 160.215642 -384.29505)
			(xy 160.265026 -384.287536) (xy 160.314978 -384.287536) (xy 160.364362 -384.29505) (xy 160.412054 -384.309907)
			(xy 160.456968 -384.331769) (xy 160.498082 -384.360138) (xy 160.534461 -384.39437) (xy 160.565277 -384.433684)
			(xy 160.589829 -384.477186) (xy 160.59912 -384.500374) (xy 160.604962 -384.51536) (xy 160.630616 -384.53314)
			(xy 161.149538 -384.53314) (xy 161.175192 -384.51536) (xy 161.181034 -384.500374) (xy 161.190325 -384.477186)
			(xy 161.214877 -384.433684) (xy 161.245693 -384.39437) (xy 161.282072 -384.360138) (xy 161.323186 -384.331769)
			(xy 161.3681 -384.309907) (xy 161.415792 -384.29505) (xy 161.465176 -384.287536) (xy 161.515128 -384.287536)
			(xy 161.564512 -384.29505) (xy 161.612204 -384.309907) (xy 161.657118 -384.331769) (xy 161.698232 -384.360138)
			(xy 161.734611 -384.39437) (xy 161.765427 -384.433684) (xy 161.789979 -384.477186) (xy 161.79927 -384.500374)
			(xy 161.805112 -384.51536) (xy 161.830766 -384.53314) (xy 162.349434 -384.53314) (xy 162.375088 -384.51536)
			(xy 162.38093 -384.500374) (xy 162.390221 -384.477186) (xy 162.414773 -384.433684) (xy 162.445589 -384.39437)
			(xy 162.481968 -384.360138) (xy 162.523082 -384.331769) (xy 162.567996 -384.309907) (xy 162.615688 -384.29505)
			(xy 162.665072 -384.287536) (xy 162.715024 -384.287536) (xy 162.764408 -384.29505) (xy 162.8121 -384.309907)
			(xy 162.857014 -384.331769) (xy 162.898128 -384.360138) (xy 162.934507 -384.39437) (xy 162.965323 -384.433684)
			(xy 162.989875 -384.477186) (xy 162.999166 -384.500374) (xy 163.005008 -384.51536) (xy 163.030662 -384.53314)
			(xy 163.549584 -384.53314) (xy 163.575238 -384.51536) (xy 163.58108 -384.500374) (xy 163.590372 -384.477182)
			(xy 163.614924 -384.433672) (xy 163.645739 -384.394347) (xy 163.682115 -384.360103) (xy 163.723227 -384.331717)
			(xy 163.76814 -384.309835) (xy 163.815831 -384.294954) (xy 163.865218 -384.287412) (xy 163.890198 -384.287014)
			(xy 163.916187 -384.287497) (xy 163.967524 -384.295628) (xy 164.016958 -384.31169) (xy 164.06327 -384.335288)
			(xy 164.105319 -384.365841) (xy 164.142072 -384.402596) (xy 164.172622 -384.444648) (xy 164.196217 -384.490961)
			(xy 164.212277 -384.540395) (xy 164.220405 -384.591733) (xy 164.220906 -384.617722) (xy 164.220661 -384.636815)
			(xy 164.216327 -384.674755) (xy 164.21227 -384.693414) (xy 164.209222 -384.706368) (xy 164.216334 -384.731514)
			(xy 164.359336 -384.874516) (xy 164.370258 -384.878326) (xy 164.397827 -384.888448) (xy 164.450326 -384.914773)
			(xy 164.499027 -384.947595) (xy 164.54313 -384.986377) (xy 164.581911 -385.030481) (xy 164.614733 -385.079183)
			(xy 164.641056 -385.131683) (xy 164.651182 -385.15925) (xy 164.654992 -385.170172) (xy 164.792914 -385.308094)
			(xy 164.799899 -385.314409) (xy 164.817129 -385.321965) (xy 164.835922 -385.322845) (xy 164.844984 -385.320286)
			(xy 164.94506 -385.28625) (xy 164.963348 -385.264152) (xy 164.96538 -385.249674) (xy 164.97001 -385.218985)
			(xy 164.98647 -385.159144) (xy 165.010846 -385.102068) (xy 165.02634 -385.075176) (xy 165.032182 -385.06527)
			(xy 165.034468 -385.042918) (xy 165.001194 -384.947668) (xy 164.985446 -384.931666) (xy 164.974778 -384.927602)
			(xy 164.951407 -384.918403) (xy 164.90753 -384.893965) (xy 164.867852 -384.863175) (xy 164.833284 -384.826741)
			(xy 164.804621 -384.7855) (xy 164.782522 -384.740399) (xy 164.767494 -384.692477) (xy 164.759884 -384.642834)
			(xy 164.759386 -384.617722) (xy 164.759896 -384.591735) (xy 164.768026 -384.5404) (xy 164.784087 -384.49097)
			(xy 164.807683 -384.44466) (xy 164.838233 -384.402612) (xy 164.874984 -384.365861) (xy 164.917032 -384.335311)
			(xy 164.963342 -384.311715) (xy 165.012772 -384.295654) (xy 165.064107 -384.287524) (xy 165.116081 -384.287524)
			(xy 165.167416 -384.295654) (xy 165.216846 -384.311715) (xy 165.263156 -384.335311) (xy 165.305204 -384.365861)
			(xy 165.341955 -384.402612) (xy 165.372505 -384.44466) (xy 165.396101 -384.49097) (xy 165.412162 -384.5404)
			(xy 165.420292 -384.591735) (xy 165.420802 -384.617722) (xy 165.420277 -384.644824) (xy 165.411465 -384.698307)
			(xy 165.403276 -384.724148) (xy 165.399466 -384.73507) (xy 165.402006 -384.757422) (xy 165.454584 -384.843274)
			(xy 165.473634 -384.85572) (xy 165.48481 -384.857498) (xy 165.514117 -384.862238) (xy 165.571268 -384.87831)
			(xy 165.625863 -384.901634) (xy 165.676983 -384.931821) (xy 165.723772 -384.968363) (xy 165.765445 -385.010648)
			(xy 165.801301 -385.057965) (xy 165.83074 -385.10952) (xy 165.847072 -385.149344) (xy 166.93007 -385.149344)
			(xy 166.930505 -385.120709) (xy 166.937661 -385.063887) (xy 166.951841 -385.0084) (xy 166.972826 -384.955112)
			(xy 167.000287 -384.904854) (xy 167.016684 -384.881374) (xy 167.022364 -384.872858) (xy 167.026978 -384.85293)
			(xy 167.023407 -384.83279) (xy 167.018208 -384.82397) (xy 167.000726 -384.795989) (xy 166.973094 -384.736078)
			(xy 166.954347 -384.672822) (xy 166.944873 -384.60753) (xy 166.944294 -384.574542) (xy 166.9448 -384.544574)
			(xy 166.952619 -384.48515) (xy 166.968127 -384.427255) (xy 166.99106 -384.371879) (xy 167.021025 -384.319971)
			(xy 167.057509 -384.272419) (xy 167.099889 -384.230036) (xy 167.147438 -384.193547) (xy 167.199343 -384.163577)
			(xy 167.254717 -384.14064) (xy 167.31261 -384.125126) (xy 167.372034 -384.117303) (xy 167.402002 -384.116834)
			(xy 167.431747 -384.117291) (xy 167.490735 -384.125) (xy 167.548227 -384.140286) (xy 167.603255 -384.162892)
			(xy 167.654889 -384.192437) (xy 167.678862 -384.210052) (xy 167.688442 -384.216547) (xy 167.711126 -384.22101)
			(xy 167.733484 -384.215128) (xy 167.742616 -384.20802) (xy 167.767032 -384.187714) (xy 167.81998 -384.152651)
			(xy 167.876878 -384.124446) (xy 167.9067 -384.113532) (xy 167.917648 -384.109081) (xy 167.934111 -384.092164)
			(xy 167.941228 -384.069658) (xy 167.939974 -384.057906) (xy 167.937228 -384.038656) (xy 167.9343 -383.99988)
			(xy 167.934132 -383.980436) (xy 167.934634 -383.948475) (xy 167.942645 -383.885057) (xy 167.958542 -383.823143)
			(xy 167.982074 -383.76371) (xy 168.012868 -383.707695) (xy 168.050441 -383.65598) (xy 168.094198 -383.609383)
			(xy 168.143451 -383.568638) (xy 168.197422 -383.534387) (xy 168.255261 -383.50717) (xy 168.316054 -383.487417)
			(xy 168.378844 -383.475439) (xy 168.44264 -383.471426) (xy 168.506436 -383.475439) (xy 168.569226 -383.487417)
			(xy 168.630019 -383.50717) (xy 168.687858 -383.534387) (xy 168.741829 -383.568638) (xy 168.791082 -383.609383)
			(xy 168.834839 -383.65598) (xy 168.872412 -383.707695) (xy 168.903206 -383.76371) (xy 168.926738 -383.823143)
			(xy 168.942635 -383.885057) (xy 168.950646 -383.948475) (xy 168.951148 -383.980436) (xy 168.950666 -384.011842)
			(xy 168.942926 -384.074174) (xy 168.927568 -384.135079) (xy 168.904827 -384.193629) (xy 168.875047 -384.248932)
			(xy 168.838683 -384.300147) (xy 168.796289 -384.346493) (xy 168.748509 -384.387266) (xy 168.696072 -384.421843)
			(xy 168.639775 -384.449699) (xy 168.61028 -384.460496) (xy 168.599361 -384.465003) (xy 168.582902 -384.481897)
			(xy 168.575768 -384.504378) (xy 168.577006 -384.516122) (xy 168.579755 -384.535371) (xy 168.582681 -384.574148)
			(xy 168.582848 -384.593592) (xy 168.582531 -384.617941) (xy 168.577826 -384.666412) (xy 168.57345 -384.690366)
			(xy 168.572112 -384.699232) (xy 168.574966 -384.716922) (xy 168.579038 -384.72491) (xy 168.59377 -384.751326)
			(xy 168.598492 -384.758942) (xy 168.612153 -384.770522) (xy 168.62044 -384.773932) (xy 168.649193 -384.785177)
			(xy 168.703996 -384.813611) (xy 168.754953 -384.84847) (xy 168.801316 -384.889241) (xy 168.842401 -384.935326)
			(xy 168.877605 -384.986046) (xy 168.90641 -385.040654) (xy 168.928391 -385.098349) (xy 168.943226 -385.15828)
			(xy 168.950212 -385.215595) (xy 188.722248 -385.215595) (xy 188.722248 -385.151673) (xy 188.730259 -385.088255)
			(xy 188.746156 -385.026341) (xy 188.769688 -384.966908) (xy 188.800482 -384.910893) (xy 188.838055 -384.859178)
			(xy 188.881812 -384.812581) (xy 188.931065 -384.771836) (xy 188.985036 -384.737585) (xy 189.042875 -384.710368)
			(xy 189.103668 -384.690615) (xy 189.166458 -384.678637) (xy 189.230254 -384.674624) (xy 189.29405 -384.678637)
			(xy 189.35684 -384.690615) (xy 189.417633 -384.710368) (xy 189.475472 -384.737585) (xy 189.529443 -384.771836)
			(xy 189.578696 -384.812581) (xy 189.622453 -384.859178) (xy 189.660026 -384.910893) (xy 189.69082 -384.966908)
			(xy 189.714352 -385.026341) (xy 189.730249 -385.088255) (xy 189.73826 -385.151673) (xy 189.738682 -385.178554)
			(xy 190.030862 -385.178554) (xy 190.031391 -385.145093) (xy 190.040163 -385.078748) (xy 190.057564 -385.014128)
			(xy 190.083292 -384.952349) (xy 190.116902 -384.894479) (xy 190.157814 -384.841519) (xy 190.20532 -384.794383)
			(xy 190.2586 -384.753888) (xy 190.287402 -384.736848) (xy 190.300212 -384.728806) (xy 190.320921 -384.706792)
			(xy 190.33429 -384.679686) (xy 190.339153 -384.649856) (xy 190.335083 -384.619908) (xy 190.322437 -384.592457)
			(xy 190.302319 -384.569901) (xy 190.289688 -384.561588) (xy 190.261927 -384.544289) (xy 190.210687 -384.503628)
			(xy 190.165084 -384.456733) (xy 190.12587 -384.404378) (xy 190.093694 -384.347426) (xy 190.069085 -384.286819)
			(xy 190.052452 -384.223557) (xy 190.044067 -384.158684) (xy 190.043562 -384.125978) (xy 190.044064 -384.094017)
			(xy 190.052075 -384.030599) (xy 190.067972 -383.968685) (xy 190.091504 -383.909252) (xy 190.122298 -383.853237)
			(xy 190.159871 -383.801522) (xy 190.203628 -383.754925) (xy 190.252881 -383.71418) (xy 190.306852 -383.679929)
			(xy 190.364691 -383.652712) (xy 190.425484 -383.632959) (xy 190.488274 -383.620981) (xy 190.55207 -383.616968)
			(xy 190.615866 -383.620981) (xy 190.678656 -383.632959) (xy 190.739449 -383.652712) (xy 190.797288 -383.679929)
			(xy 190.851259 -383.71418) (xy 190.900512 -383.754925) (xy 190.944269 -383.801522) (xy 190.981842 -383.853237)
			(xy 191.012636 -383.909252) (xy 191.036168 -383.968685) (xy 191.052065 -384.030599) (xy 191.060076 -384.094017)
			(xy 191.060578 -384.125978) (xy 191.060055 -384.159439) (xy 191.051279 -384.225783) (xy 191.033876 -384.290403)
			(xy 191.008147 -384.352181) (xy 190.974536 -384.410051) (xy 190.933624 -384.463011) (xy 190.886118 -384.510146)
			(xy 190.83284 -384.550643) (xy 190.804038 -384.567684) (xy 190.791195 -384.57568) (xy 190.770476 -384.597701)
			(xy 190.757102 -384.624817) (xy 190.752241 -384.65466) (xy 190.753056 -384.660648) (xy 191.979296 -384.660648)
			(xy 191.979826 -384.62721) (xy 191.98858 -384.560909) (xy 192.005957 -384.49633) (xy 192.031655 -384.434589)
			(xy 192.065231 -384.376752) (xy 192.106104 -384.32382) (xy 192.153569 -384.276708) (xy 192.206803 -384.23623)
			(xy 192.235582 -384.219196) (xy 192.246504 -384.212846) (xy 192.259712 -384.192018) (xy 192.26911 -384.08356)
			(xy 192.259458 -384.0607) (xy 192.249806 -384.052572) (xy 192.225404 -384.031853) (xy 192.181525 -383.985241)
			(xy 192.143845 -383.93349) (xy 192.11296 -383.877417) (xy 192.089358 -383.817911) (xy 192.073414 -383.755913)
			(xy 192.065378 -383.692404) (xy 192.064894 -383.660396) (xy 192.065339 -383.629875) (xy 192.072658 -383.569273)
			(xy 192.087177 -383.509983) (xy 192.108689 -383.452857) (xy 192.136883 -383.398716) (xy 192.171355 -383.348339)
			(xy 192.211609 -383.30245) (xy 192.257065 -383.261709) (xy 192.28181 -383.243836) (xy 192.291627 -383.236353)
			(xy 192.303071 -383.214511) (xy 192.303654 -383.20218) (xy 192.303654 -383.118868) (xy 192.302897 -383.106585)
			(xy 192.29148 -383.084825) (xy 192.28181 -383.077212) (xy 192.257046 -383.059364) (xy 192.211583 -383.018625)
			(xy 192.171326 -382.972735) (xy 192.136853 -382.922355) (xy 192.108661 -382.868209) (xy 192.087156 -382.811077)
			(xy 192.072647 -382.751781) (xy 192.065343 -382.691175) (xy 192.064894 -382.660652) (xy 192.065312 -382.630105)
			(xy 192.072627 -382.569451) (xy 192.087157 -382.510111) (xy 192.108694 -382.452939) (xy 192.136927 -382.398761)
			(xy 192.171448 -382.348355) (xy 192.211761 -382.30245) (xy 192.257285 -382.261707) (xy 192.282064 -382.243838)
			(xy 192.29189 -382.236365) (xy 192.303327 -382.214515) (xy 192.303908 -382.202182) (xy 192.303908 -382.11887)
			(xy 192.303168 -382.106584) (xy 192.291741 -382.084823) (xy 192.282064 -382.077214) (xy 192.255655 -382.058121)
			(xy 192.207449 -382.014269) (xy 192.16524 -381.964618) (xy 192.12972 -381.909982) (xy 192.101471 -381.851256)
			(xy 192.080955 -381.789402) (xy 192.06851 -381.725434) (xy 192.064339 -381.6604) (xy 192.06851 -381.595366)
			(xy 192.080955 -381.531398) (xy 192.101471 -381.469544) (xy 192.12972 -381.410818) (xy 192.16524 -381.356182)
			(xy 192.207449 -381.306531) (xy 192.255655 -381.262679) (xy 192.282064 -381.243586) (xy 192.291639 -381.235915)
			(xy 192.302923 -381.214175) (xy 192.303654 -381.20193) (xy 192.303654 -381.118872) (xy 192.302948 -381.106612)
			(xy 192.291686 -381.084842) (xy 192.282064 -381.077216) (xy 192.255657 -381.05812) (xy 192.207451 -381.014269)
			(xy 192.165242 -380.964618) (xy 192.129722 -380.909982) (xy 192.101473 -380.851256) (xy 192.080957 -380.789403)
			(xy 192.068512 -380.725435) (xy 192.06434 -380.660401) (xy 192.068512 -380.595368) (xy 192.080957 -380.5314)
			(xy 192.101472 -380.469546) (xy 192.129721 -380.41082) (xy 192.165241 -380.356184) (xy 192.20745 -380.306533)
			(xy 192.255656 -380.262681) (xy 192.282064 -380.243588) (xy 192.291638 -380.235916) (xy 192.302923 -380.214177)
			(xy 192.303654 -380.201932) (xy 192.303654 -380.118874) (xy 192.302947 -380.106615) (xy 192.291686 -380.084844)
			(xy 192.282064 -380.077218) (xy 192.255659 -380.058119) (xy 192.207453 -380.014268) (xy 192.165244 -379.964618)
			(xy 192.129724 -379.909983) (xy 192.101475 -379.851257) (xy 192.080959 -379.789403) (xy 192.068514 -379.725436)
			(xy 192.064342 -379.660402) (xy 192.068513 -379.595369) (xy 192.080958 -379.531401) (xy 192.101473 -379.469547)
			(xy 192.129722 -379.410821) (xy 192.165241 -379.356185) (xy 192.20745 -379.306535) (xy 192.255656 -379.262683)
			(xy 192.282064 -379.24359) (xy 192.291682 -379.235964) (xy 192.302944 -379.21419) (xy 192.303654 -379.201934)
			(xy 192.303654 -379.118876) (xy 192.302945 -379.106617) (xy 192.291685 -379.084846) (xy 192.282064 -379.07722)
			(xy 192.257287 -379.059352) (xy 192.211774 -379.018601) (xy 192.171471 -378.972691) (xy 192.136957 -378.922285)
			(xy 192.10873 -378.868107) (xy 192.087196 -378.810938) (xy 192.072665 -378.751601) (xy 192.065347 -378.690951)
			(xy 192.064894 -378.660406) (xy 192.065396 -378.628445) (xy 192.073407 -378.565027) (xy 192.089304 -378.503113)
			(xy 192.112836 -378.44368) (xy 192.14363 -378.387665) (xy 192.181203 -378.33595) (xy 192.22496 -378.289353)
			(xy 192.274213 -378.248608) (xy 192.328184 -378.214357) (xy 192.386023 -378.18714) (xy 192.446816 -378.167387)
			(xy 192.509606 -378.155409) (xy 192.573402 -378.151396) (xy 192.637198 -378.155409) (xy 192.699988 -378.167387)
			(xy 192.760781 -378.18714) (xy 192.81862 -378.214357) (xy 192.872591 -378.248608) (xy 192.921844 -378.289353)
			(xy 192.965601 -378.33595) (xy 193.003174 -378.387665) (xy 193.033968 -378.44368) (xy 193.0575 -378.503113)
			(xy 193.070952 -378.555504) (xy 204.904848 -378.555504) (xy 204.905275 -378.525288) (xy 204.912462 -378.465285)
			(xy 204.926713 -378.406557) (xy 204.947826 -378.349933) (xy 204.975503 -378.296211) (xy 205.009354 -378.246149)
			(xy 205.0288 -378.223018) (xy 205.034418 -378.215876) (xy 205.040667 -378.198825) (xy 205.040992 -378.189744)
			(xy 205.040992 -378.159264) (xy 205.040665 -378.150183) (xy 205.034419 -378.133132) (xy 205.0288 -378.12599)
			(xy 205.009372 -378.102846) (xy 204.97553 -378.052782) (xy 204.947859 -377.999061) (xy 204.926748 -377.94244)
			(xy 204.912494 -377.883717) (xy 204.905298 -377.823718) (xy 204.904848 -377.793504) (xy 204.90535 -377.761543)
			(xy 204.913361 -377.698125) (xy 204.929258 -377.636211) (xy 204.95279 -377.576778) (xy 204.983584 -377.520763)
			(xy 205.021157 -377.469048) (xy 205.064914 -377.422451) (xy 205.114167 -377.381706) (xy 205.168138 -377.347455)
			(xy 205.225977 -377.320238) (xy 205.28677 -377.300485) (xy 205.34956 -377.288507) (xy 205.413356 -377.284494)
			(xy 205.477152 -377.288507) (xy 205.539942 -377.300485) (xy 205.600735 -377.320238) (xy 205.658574 -377.347455)
			(xy 205.712545 -377.381706) (xy 205.761798 -377.422451) (xy 205.805555 -377.469048) (xy 205.843128 -377.520763)
			(xy 205.873922 -377.576778) (xy 205.897454 -377.636211) (xy 205.913351 -377.698125) (xy 205.921362 -377.761543)
			(xy 205.921864 -377.793504) (xy 205.921439 -377.82372) (xy 205.914251 -377.883723) (xy 205.899999 -377.942451)
			(xy 205.878886 -377.999075) (xy 205.851209 -378.052797) (xy 205.817358 -378.102859) (xy 205.797912 -378.12599)
			(xy 205.792292 -378.133131) (xy 205.786044 -378.150182) (xy 205.78572 -378.159264) (xy 205.78572 -378.189744)
			(xy 205.78604 -378.198826) (xy 205.792291 -378.215877) (xy 205.797912 -378.223018) (xy 205.817346 -378.246157)
			(xy 205.851186 -378.296223) (xy 205.878856 -378.349944) (xy 205.899967 -378.406566) (xy 205.914219 -378.46529)
			(xy 205.921414 -378.52529) (xy 205.921864 -378.555504) (xy 206.930752 -378.555504) (xy 206.931178 -378.525288)
			(xy 206.938365 -378.465285) (xy 206.952616 -378.406557) (xy 206.973729 -378.349933) (xy 207.001407 -378.296211)
			(xy 207.035258 -378.246149) (xy 207.054704 -378.223018) (xy 207.060323 -378.215876) (xy 207.066571 -378.198825)
			(xy 207.066896 -378.189744) (xy 207.066896 -378.159264) (xy 207.066569 -378.150183) (xy 207.060323 -378.133132)
			(xy 207.054704 -378.12599) (xy 207.035276 -378.102845) (xy 207.001435 -378.052782) (xy 206.973763 -377.999061)
			(xy 206.952652 -377.94244) (xy 206.938398 -377.883717) (xy 206.931202 -377.823718) (xy 206.930752 -377.793504)
			(xy 206.931254 -377.761543) (xy 206.939265 -377.698125) (xy 206.955162 -377.636211) (xy 206.978694 -377.576778)
			(xy 207.009488 -377.520763) (xy 207.047061 -377.469048) (xy 207.090818 -377.422451) (xy 207.140071 -377.381706)
			(xy 207.194042 -377.347455) (xy 207.251881 -377.320238) (xy 207.312674 -377.300485) (xy 207.375464 -377.288507)
			(xy 207.43926 -377.284494) (xy 207.503056 -377.288507) (xy 207.565846 -377.300485) (xy 207.626639 -377.320238)
			(xy 207.684478 -377.347455) (xy 207.738449 -377.381706) (xy 207.787702 -377.422451) (xy 207.831459 -377.469048)
			(xy 207.869032 -377.520763) (xy 207.899826 -377.576778) (xy 207.923358 -377.636211) (xy 207.939255 -377.698125)
			(xy 207.947266 -377.761543) (xy 207.947768 -377.793504) (xy 207.947342 -377.82372) (xy 207.940154 -377.883723)
			(xy 207.925903 -377.942451) (xy 207.90479 -377.999075) (xy 207.877112 -378.052797) (xy 207.843262 -378.102859)
			(xy 207.823816 -378.12599) (xy 207.818196 -378.133131) (xy 207.811948 -378.150182) (xy 207.811624 -378.159264)
			(xy 207.811624 -378.189744) (xy 207.811943 -378.198826) (xy 207.818194 -378.215877) (xy 207.823816 -378.223018)
			(xy 207.843251 -378.246157) (xy 207.877091 -378.296222) (xy 207.904761 -378.349944) (xy 207.925871 -378.406566)
			(xy 207.940123 -378.46529) (xy 207.947318 -378.52529) (xy 207.947768 -378.555504) (xy 208.968848 -378.555504)
			(xy 208.969275 -378.525288) (xy 208.976462 -378.465285) (xy 208.990713 -378.406557) (xy 209.011826 -378.349933)
			(xy 209.039503 -378.296211) (xy 209.073354 -378.246149) (xy 209.0928 -378.223018) (xy 209.098418 -378.215876)
			(xy 209.104667 -378.198825) (xy 209.104992 -378.189744) (xy 209.104992 -378.159264) (xy 209.104665 -378.150183)
			(xy 209.098419 -378.133132) (xy 209.0928 -378.12599) (xy 209.073372 -378.102846) (xy 209.03953 -378.052782)
			(xy 209.011859 -377.999061) (xy 208.990748 -377.94244) (xy 208.976494 -377.883717) (xy 208.969298 -377.823718)
			(xy 208.968848 -377.793504) (xy 208.96935 -377.761543) (xy 208.977361 -377.698125) (xy 208.993258 -377.636211)
			(xy 209.01679 -377.576778) (xy 209.047584 -377.520763) (xy 209.085157 -377.469048) (xy 209.128914 -377.422451)
			(xy 209.178167 -377.381706) (xy 209.232138 -377.347455) (xy 209.289977 -377.320238) (xy 209.35077 -377.300485)
			(xy 209.41356 -377.288507) (xy 209.477356 -377.284494) (xy 209.541152 -377.288507) (xy 209.603942 -377.300485)
			(xy 209.664735 -377.320238) (xy 209.722574 -377.347455) (xy 209.776545 -377.381706) (xy 209.825798 -377.422451)
			(xy 209.869555 -377.469048) (xy 209.907128 -377.520763) (xy 209.937922 -377.576778) (xy 209.961454 -377.636211)
			(xy 209.977351 -377.698125) (xy 209.985362 -377.761543) (xy 209.985864 -377.793504) (xy 209.985439 -377.82372)
			(xy 209.978251 -377.883723) (xy 209.963999 -377.942451) (xy 209.942886 -377.999075) (xy 209.915209 -378.052797)
			(xy 209.881358 -378.102859) (xy 209.861912 -378.12599) (xy 209.856292 -378.133131) (xy 209.850044 -378.150182)
			(xy 209.84972 -378.159264) (xy 209.84972 -378.189744) (xy 209.85004 -378.198826) (xy 209.856291 -378.215877)
			(xy 209.861912 -378.223018) (xy 209.881346 -378.246157) (xy 209.915186 -378.296223) (xy 209.942856 -378.349944)
			(xy 209.963967 -378.406566) (xy 209.978219 -378.46529) (xy 209.985414 -378.52529) (xy 209.985864 -378.555504)
			(xy 209.985362 -378.587465) (xy 209.977351 -378.650883) (xy 209.961454 -378.712797) (xy 209.937922 -378.77223)
			(xy 209.907128 -378.828245) (xy 209.869555 -378.87996) (xy 209.825798 -378.926557) (xy 209.776545 -378.967302)
			(xy 209.722574 -379.001553) (xy 209.664735 -379.02877) (xy 209.603942 -379.048523) (xy 209.541152 -379.060501)
			(xy 209.477356 -379.064515) (xy 209.41356 -379.060501) (xy 209.35077 -379.048523) (xy 209.289977 -379.02877)
			(xy 209.232138 -379.001553) (xy 209.178167 -378.967302) (xy 209.128914 -378.926557) (xy 209.085157 -378.87996)
			(xy 209.047584 -378.828245) (xy 209.01679 -378.77223) (xy 208.993258 -378.712797) (xy 208.977361 -378.650883)
			(xy 208.96935 -378.587465) (xy 208.968848 -378.555504) (xy 207.947768 -378.555504) (xy 207.947266 -378.587465)
			(xy 207.939255 -378.650883) (xy 207.923358 -378.712797) (xy 207.899826 -378.77223) (xy 207.869032 -378.828245)
			(xy 207.831459 -378.87996) (xy 207.787702 -378.926557) (xy 207.738449 -378.967302) (xy 207.684478 -379.001553)
			(xy 207.626639 -379.02877) (xy 207.565846 -379.048523) (xy 207.503056 -379.060501) (xy 207.43926 -379.064515)
			(xy 207.375464 -379.060501) (xy 207.312674 -379.048523) (xy 207.251881 -379.02877) (xy 207.194042 -379.001553)
			(xy 207.140071 -378.967302) (xy 207.090818 -378.926557) (xy 207.047061 -378.87996) (xy 207.009488 -378.828245)
			(xy 206.978694 -378.77223) (xy 206.955162 -378.712797) (xy 206.939265 -378.650883) (xy 206.931254 -378.587465)
			(xy 206.930752 -378.555504) (xy 205.921864 -378.555504) (xy 205.921362 -378.587465) (xy 205.913351 -378.650883)
			(xy 205.897454 -378.712797) (xy 205.873922 -378.77223) (xy 205.843128 -378.828245) (xy 205.805555 -378.87996)
			(xy 205.761798 -378.926557) (xy 205.712545 -378.967302) (xy 205.658574 -379.001553) (xy 205.600735 -379.02877)
			(xy 205.539942 -379.048523) (xy 205.477152 -379.060501) (xy 205.413356 -379.064515) (xy 205.34956 -379.060501)
			(xy 205.28677 -379.048523) (xy 205.225977 -379.02877) (xy 205.168138 -379.001553) (xy 205.114167 -378.967302)
			(xy 205.064914 -378.926557) (xy 205.021157 -378.87996) (xy 204.983584 -378.828245) (xy 204.95279 -378.77223)
			(xy 204.929258 -378.712797) (xy 204.913361 -378.650883) (xy 204.90535 -378.587465) (xy 204.904848 -378.555504)
			(xy 193.070952 -378.555504) (xy 193.073397 -378.565027) (xy 193.081408 -378.628445) (xy 193.08191 -378.660406)
			(xy 193.081458 -378.690952) (xy 193.074148 -378.751604) (xy 193.059623 -378.810944) (xy 193.038091 -378.868115)
			(xy 193.009863 -378.922294) (xy 192.975346 -378.9727) (xy 192.935037 -379.018606) (xy 192.889518 -379.05935)
			(xy 192.86474 -379.07722) (xy 192.855163 -379.084889) (xy 192.84388 -379.10663) (xy 192.84315 -379.118876)
			(xy 192.84315 -379.201934) (xy 192.843851 -379.214194) (xy 192.855116 -379.235965) (xy 192.86474 -379.24359)
			(xy 192.891152 -379.262678) (xy 192.939358 -379.306531) (xy 192.981567 -379.356182) (xy 193.017087 -379.410819)
			(xy 193.045336 -379.469545) (xy 193.065851 -379.5314) (xy 193.078296 -379.595368) (xy 193.082467 -379.660402)
			(xy 193.078295 -379.725436) (xy 193.06585 -379.789405) (xy 193.045334 -379.851259) (xy 193.017085 -379.909985)
			(xy 192.981564 -379.964622) (xy 192.939355 -380.014273) (xy 192.891149 -380.058124) (xy 192.86474 -380.077218)
			(xy 192.855164 -380.084888) (xy 192.84388 -380.106629) (xy 192.84315 -380.118874) (xy 192.84315 -380.201932)
			(xy 192.843852 -380.214192) (xy 192.855117 -380.235963) (xy 192.86474 -380.243588) (xy 192.89115 -380.262679)
			(xy 192.939356 -380.306531) (xy 192.981565 -380.356182) (xy 193.017085 -380.410818) (xy 193.045334 -380.469545)
			(xy 193.065849 -380.531399) (xy 193.078294 -380.595367) (xy 193.082465 -380.660401) (xy 193.078294 -380.725435)
			(xy 193.065848 -380.789403) (xy 193.045333 -380.851257) (xy 193.017084 -380.909984) (xy 192.981564 -380.96462)
			(xy 192.939355 -381.014271) (xy 192.891149 -381.058122) (xy 192.86474 -381.077216) (xy 192.855165 -381.084887)
			(xy 192.84388 -381.106627) (xy 192.84315 -381.118872) (xy 192.84315 -381.20193) (xy 192.843854 -381.21419)
			(xy 192.855117 -381.235961) (xy 192.86474 -381.243586) (xy 192.891148 -381.26268) (xy 192.939354 -381.306531)
			(xy 192.981563 -381.356182) (xy 193.017083 -381.410818) (xy 193.045332 -381.469544) (xy 193.065847 -381.531398)
			(xy 193.078292 -381.595366) (xy 193.082463 -381.6604) (xy 193.078292 -381.725434) (xy 193.065847 -381.789402)
			(xy 193.045332 -381.851256) (xy 193.017083 -381.909982) (xy 192.981563 -381.964618) (xy 192.939354 -382.014269)
			(xy 192.891148 -382.05812) (xy 192.86474 -382.077214) (xy 192.854937 -382.084711) (xy 192.843488 -382.106543)
			(xy 192.842896 -382.11887) (xy 192.842896 -382.202182) (xy 192.843663 -382.214464) (xy 192.855071 -382.236226)
			(xy 192.86474 -382.243838) (xy 192.889499 -382.261732) (xy 192.935011 -382.302479) (xy 192.975315 -382.348384)
			(xy 193.009831 -382.398787) (xy 193.03806 -382.452961) (xy 193.059597 -382.510127) (xy 193.074132 -382.569461)
			(xy 193.081455 -382.630108) (xy 193.08191 -382.660652) (xy 193.081424 -382.691172) (xy 193.074111 -382.751772)
			(xy 193.059598 -382.811061) (xy 193.038092 -382.868187) (xy 193.009904 -382.922328) (xy 192.975437 -382.972706)
			(xy 192.935189 -383.018596) (xy 192.889736 -383.059338) (xy 192.864994 -383.077212) (xy 192.855202 -383.084721)
			(xy 192.843744 -383.106544) (xy 192.84315 -383.118868) (xy 192.84315 -383.160514) (xy 198.697333 -383.160514)
			(xy 198.701502 -383.095484) (xy 198.713944 -383.031519) (xy 198.734455 -382.969668) (xy 198.762699 -382.910944)
			(xy 198.798213 -382.856309) (xy 198.840416 -382.806658) (xy 198.888615 -382.762805) (xy 198.91502 -382.74371)
			(xy 198.924622 -382.736066) (xy 198.935894 -382.714306) (xy 198.93661 -382.702054) (xy 198.93661 -382.618996)
			(xy 198.935966 -382.606728) (xy 198.924662 -382.584957) (xy 198.91502 -382.57734) (xy 198.888638 -382.558212)
			(xy 198.840437 -382.514362) (xy 198.798232 -382.464713) (xy 198.762714 -382.41008) (xy 198.734467 -382.351358)
			(xy 198.713953 -382.289508) (xy 198.701507 -382.225544) (xy 198.697335 -382.160515) (xy 198.701504 -382.095485)
			(xy 198.713945 -382.031521) (xy 198.734456 -381.96967) (xy 198.7627 -381.910946) (xy 198.798214 -381.856311)
			(xy 198.840416 -381.80666) (xy 198.888615 -381.762807) (xy 198.91502 -381.743712) (xy 198.924621 -381.736067)
			(xy 198.935894 -381.714308) (xy 198.93661 -381.702056) (xy 198.93661 -381.618998) (xy 198.935965 -381.60673)
			(xy 198.924661 -381.584959) (xy 198.91502 -381.577342) (xy 198.890243 -381.559473) (xy 198.844732 -381.518721)
			(xy 198.804431 -381.472811) (xy 198.769918 -381.422405) (xy 198.741691 -381.368227) (xy 198.720156 -381.311059)
			(xy 198.705624 -381.251722) (xy 198.698304 -381.191073) (xy 198.69785 -381.160528) (xy 198.698352 -381.128567)
			(xy 198.706363 -381.065149) (xy 198.72226 -381.003235) (xy 198.745792 -380.943802) (xy 198.776586 -380.887787)
			(xy 198.814159 -380.836072) (xy 198.857916 -380.789475) (xy 198.907169 -380.74873) (xy 198.96114 -380.714479)
			(xy 199.018979 -380.687262) (xy 199.079772 -380.667509) (xy 199.142562 -380.655531) (xy 199.206358 -380.651518)
			(xy 199.270154 -380.655531) (xy 199.332944 -380.667509) (xy 199.393737 -380.687262) (xy 199.451576 -380.714479)
			(xy 199.505547 -380.74873) (xy 199.5548 -380.789475) (xy 199.598557 -380.836072) (xy 199.63613 -380.887787)
			(xy 199.666924 -380.943802) (xy 199.690456 -381.003235) (xy 199.706353 -381.065149) (xy 199.710572 -381.098552)
			(xy 206.93761 -381.098552) (xy 206.938056 -381.067865) (xy 206.945438 -381.006938) (xy 206.960102 -380.947342)
			(xy 206.981834 -380.889945) (xy 207.010317 -380.835582) (xy 207.045138 -380.785043) (xy 207.065118 -380.761748)
			(xy 207.070921 -380.754608) (xy 207.077431 -380.737413) (xy 207.077818 -380.72822) (xy 207.078072 -380.69774)
			(xy 207.077723 -380.688573) (xy 207.07134 -380.671389) (xy 207.065626 -380.664212) (xy 207.046023 -380.641033)
			(xy 207.011887 -380.590832) (xy 206.983975 -380.536922) (xy 206.962688 -380.480069) (xy 206.948327 -380.421085)
			(xy 206.941098 -380.36081) (xy 206.940658 -380.330456) (xy 206.94116 -380.298495) (xy 206.949171 -380.235077)
			(xy 206.965068 -380.173163) (xy 206.9886 -380.11373) (xy 207.019394 -380.057715) (xy 207.056967 -380.006)
			(xy 207.100724 -379.959403) (xy 207.149977 -379.918658) (xy 207.203948 -379.884407) (xy 207.261787 -379.85719)
			(xy 207.32258 -379.837437) (xy 207.38537 -379.825459) (xy 207.449166 -379.821446) (xy 207.512962 -379.825459)
			(xy 207.575752 -379.837437) (xy 207.636545 -379.85719) (xy 207.694384 -379.884407) (xy 207.748355 -379.918658)
			(xy 207.797608 -379.959403) (xy 207.841365 -380.006) (xy 207.878938 -380.057715) (xy 207.909732 -380.11373)
			(xy 207.933264 -380.173163) (xy 207.949161 -380.235077) (xy 207.957172 -380.298495) (xy 207.957674 -380.330456)
			(xy 207.957237 -380.361143) (xy 207.949853 -380.422071) (xy 207.935188 -380.481667) (xy 207.913455 -380.539064)
			(xy 207.88497 -380.593427) (xy 207.850147 -380.643965) (xy 207.830166 -380.66726) (xy 207.824357 -380.674396)
			(xy 207.817851 -380.691594) (xy 207.817466 -380.700788) (xy 207.817212 -380.731268) (xy 207.81756 -380.740435)
			(xy 207.823944 -380.757619) (xy 207.829658 -380.764796) (xy 207.849278 -380.787961) (xy 207.88341 -380.838166)
			(xy 207.911317 -380.89208) (xy 207.932601 -380.948935) (xy 207.94696 -381.007921) (xy 207.954187 -381.068198)
			(xy 207.954582 -381.095504) (xy 208.968848 -381.095504) (xy 208.969275 -381.065288) (xy 208.976462 -381.005285)
			(xy 208.990713 -380.946557) (xy 209.011826 -380.889933) (xy 209.039503 -380.836211) (xy 209.073354 -380.786149)
			(xy 209.0928 -380.763018) (xy 209.098418 -380.755876) (xy 209.104667 -380.738825) (xy 209.104992 -380.729744)
			(xy 209.104992 -380.699264) (xy 209.104665 -380.690183) (xy 209.098419 -380.673132) (xy 209.0928 -380.66599)
			(xy 209.073372 -380.642846) (xy 209.03953 -380.592782) (xy 209.011859 -380.539061) (xy 208.990748 -380.48244)
			(xy 208.976494 -380.423717) (xy 208.969298 -380.363718) (xy 208.968848 -380.333504) (xy 208.96935 -380.301543)
			(xy 208.977361 -380.238125) (xy 208.993258 -380.176211) (xy 209.01679 -380.116778) (xy 209.047584 -380.060763)
			(xy 209.085157 -380.009048) (xy 209.128914 -379.962451) (xy 209.178167 -379.921706) (xy 209.232138 -379.887455)
			(xy 209.289977 -379.860238) (xy 209.35077 -379.840485) (xy 209.41356 -379.828507) (xy 209.477356 -379.824494)
			(xy 209.541152 -379.828507) (xy 209.603942 -379.840485) (xy 209.664735 -379.860238) (xy 209.722574 -379.887455)
			(xy 209.776545 -379.921706) (xy 209.825798 -379.962451) (xy 209.869555 -380.009048) (xy 209.907128 -380.060763)
			(xy 209.937922 -380.116778) (xy 209.961454 -380.176211) (xy 209.977351 -380.238125) (xy 209.985362 -380.301543)
			(xy 209.985864 -380.333504) (xy 209.985439 -380.36372) (xy 209.978251 -380.423723) (xy 209.963999 -380.482451)
			(xy 209.942886 -380.539075) (xy 209.915209 -380.592797) (xy 209.881358 -380.642859) (xy 209.861912 -380.66599)
			(xy 209.856292 -380.673131) (xy 209.850044 -380.690182) (xy 209.84972 -380.699264) (xy 209.84972 -380.729744)
			(xy 209.85004 -380.738826) (xy 209.856291 -380.755877) (xy 209.861912 -380.763018) (xy 209.881346 -380.786157)
			(xy 209.915186 -380.836223) (xy 209.942856 -380.889944) (xy 209.963967 -380.946566) (xy 209.978219 -381.00529)
			(xy 209.985414 -381.06529) (xy 209.985864 -381.095504) (xy 209.985362 -381.127465) (xy 209.977351 -381.190883)
			(xy 209.961454 -381.252797) (xy 209.937922 -381.31223) (xy 209.907128 -381.368245) (xy 209.869555 -381.41996)
			(xy 209.825798 -381.466557) (xy 209.776545 -381.507302) (xy 209.722574 -381.541553) (xy 209.664735 -381.56877)
			(xy 209.603942 -381.588523) (xy 209.541152 -381.600501) (xy 209.477356 -381.604515) (xy 209.41356 -381.600501)
			(xy 209.35077 -381.588523) (xy 209.289977 -381.56877) (xy 209.232138 -381.541553) (xy 209.178167 -381.507302)
			(xy 209.128914 -381.466557) (xy 209.085157 -381.41996) (xy 209.047584 -381.368245) (xy 209.01679 -381.31223)
			(xy 208.993258 -381.252797) (xy 208.977361 -381.190883) (xy 208.96935 -381.127465) (xy 208.968848 -381.095504)
			(xy 207.954582 -381.095504) (xy 207.954626 -381.098552) (xy 207.954124 -381.130513) (xy 207.946113 -381.193931)
			(xy 207.930216 -381.255845) (xy 207.906684 -381.315278) (xy 207.87589 -381.371293) (xy 207.838317 -381.423008)
			(xy 207.79456 -381.469605) (xy 207.745307 -381.51035) (xy 207.691336 -381.544601) (xy 207.633497 -381.571818)
			(xy 207.572704 -381.591571) (xy 207.509914 -381.603549) (xy 207.446118 -381.607563) (xy 207.382322 -381.603549)
			(xy 207.319532 -381.591571) (xy 207.258739 -381.571818) (xy 207.2009 -381.544601) (xy 207.146929 -381.51035)
			(xy 207.097676 -381.469605) (xy 207.053919 -381.423008) (xy 207.016346 -381.371293) (xy 206.985552 -381.315278)
			(xy 206.96202 -381.255845) (xy 206.946123 -381.193931) (xy 206.938112 -381.130513) (xy 206.93761 -381.098552)
			(xy 199.710572 -381.098552) (xy 199.714364 -381.128567) (xy 199.714866 -381.160528) (xy 199.71445 -381.191075)
			(xy 199.707136 -381.25173) (xy 199.692607 -381.311071) (xy 199.671071 -381.368243) (xy 199.642838 -381.422422)
			(xy 199.608316 -381.472827) (xy 199.568001 -381.518732) (xy 199.522476 -381.559474) (xy 199.497696 -381.577342)
			(xy 199.488119 -381.585012) (xy 199.476833 -381.606752) (xy 199.476106 -381.618998) (xy 199.476106 -381.702056)
			(xy 199.476773 -381.714321) (xy 199.48806 -381.736093) (xy 199.497696 -381.743712) (xy 199.524131 -381.762771)
			(xy 199.572342 -381.806624) (xy 199.614554 -381.856277) (xy 199.650077 -381.910916) (xy 199.678329 -381.969646)
			(xy 199.698845 -382.031504) (xy 199.71129 -382.095477) (xy 199.71546 -382.160515) (xy 199.711286 -382.225553)
			(xy 199.698837 -382.289524) (xy 199.678317 -382.351381) (xy 199.650063 -382.41011) (xy 199.614537 -382.464747)
			(xy 199.572321 -382.514398) (xy 199.524108 -382.558248) (xy 199.497696 -382.57734) (xy 199.48812 -382.585011)
			(xy 199.476833 -382.60675) (xy 199.476106 -382.618996) (xy 199.476106 -382.702054) (xy 199.476774 -382.714319)
			(xy 199.488061 -382.736091) (xy 199.497696 -382.74371) (xy 199.524129 -382.762771) (xy 199.57234 -382.806624)
			(xy 199.614552 -382.856277) (xy 199.650075 -382.910916) (xy 199.678327 -382.969646) (xy 199.698843 -383.031504)
			(xy 199.711288 -383.095476) (xy 199.715458 -383.160514) (xy 199.711284 -383.225551) (xy 199.698836 -383.289523)
			(xy 199.678316 -383.35138) (xy 199.650062 -383.410108) (xy 199.614536 -383.464745) (xy 199.597199 -383.485136)
			(xy 204.904848 -383.485136) (xy 204.905294 -383.454921) (xy 204.912478 -383.394918) (xy 204.926725 -383.336191)
			(xy 204.947834 -383.279566) (xy 204.975508 -383.225844) (xy 205.009356 -383.175782) (xy 205.0288 -383.15265)
			(xy 205.034405 -383.145498) (xy 205.040661 -383.128455) (xy 205.040992 -383.119376) (xy 205.040992 -383.088896)
			(xy 205.04065 -383.079816) (xy 205.034414 -383.062765) (xy 205.0288 -383.055622) (xy 205.00934 -383.032504)
			(xy 204.975502 -382.982434) (xy 204.947836 -382.928708) (xy 204.92673 -382.872082) (xy 204.912483 -382.813354)
			(xy 204.905294 -382.753351) (xy 204.904848 -382.723136) (xy 204.90535 -382.691175) (xy 204.913361 -382.627757)
			(xy 204.929258 -382.565843) (xy 204.95279 -382.50641) (xy 204.983584 -382.450395) (xy 205.021157 -382.39868)
			(xy 205.064914 -382.352083) (xy 205.114167 -382.311338) (xy 205.168138 -382.277087) (xy 205.225977 -382.24987)
			(xy 205.28677 -382.230117) (xy 205.34956 -382.218139) (xy 205.413356 -382.214126) (xy 205.477152 -382.218139)
			(xy 205.539942 -382.230117) (xy 205.600735 -382.24987) (xy 205.658574 -382.277087) (xy 205.712545 -382.311338)
			(xy 205.761798 -382.352083) (xy 205.805555 -382.39868) (xy 205.843128 -382.450395) (xy 205.873922 -382.50641)
			(xy 205.897454 -382.565843) (xy 205.913351 -382.627757) (xy 205.921362 -382.691175) (xy 205.921864 -382.723136)
			(xy 206.931514 -382.723136) (xy 206.932016 -382.691175) (xy 206.940027 -382.627757) (xy 206.955924 -382.565843)
			(xy 206.979456 -382.50641) (xy 207.01025 -382.450395) (xy 207.047823 -382.39868) (xy 207.09158 -382.352083)
			(xy 207.140833 -382.311338) (xy 207.194804 -382.277087) (xy 207.252643 -382.24987) (xy 207.313436 -382.230117)
			(xy 207.376226 -382.218139) (xy 207.440022 -382.214126) (xy 207.503818 -382.218139) (xy 207.566608 -382.230117)
			(xy 207.627401 -382.24987) (xy 207.68524 -382.277087) (xy 207.739211 -382.311338) (xy 207.788464 -382.352083)
			(xy 207.832221 -382.39868) (xy 207.869794 -382.450395) (xy 207.900588 -382.50641) (xy 207.92412 -382.565843)
			(xy 207.940017 -382.627757) (xy 207.948028 -382.691175) (xy 207.94853 -382.723136) (xy 207.948046 -382.753488)
			(xy 207.940813 -382.813758) (xy 207.926455 -382.872739) (xy 207.905175 -382.92959) (xy 207.877277 -382.983502)
			(xy 207.843157 -383.033709) (xy 207.823562 -383.056892) (xy 207.817825 -383.064055) (xy 207.811451 -383.081249)
			(xy 207.811116 -383.09042) (xy 207.811116 -383.120646) (xy 207.811474 -383.129812) (xy 207.817851 -383.146996)
			(xy 207.823562 -383.154174) (xy 207.843198 -383.17736) (xy 207.877373 -383.2276) (xy 207.905322 -383.281552)
			(xy 207.92665 -383.338448) (xy 207.941052 -383.397478) (xy 207.948323 -383.457803) (xy 207.948738 -383.485136)
			(xy 208.968848 -383.485136) (xy 208.969294 -383.454921) (xy 208.976478 -383.394918) (xy 208.990725 -383.336191)
			(xy 209.011834 -383.279566) (xy 209.039508 -383.225844) (xy 209.073356 -383.175782) (xy 209.0928 -383.15265)
			(xy 209.098405 -383.145498) (xy 209.104661 -383.128455) (xy 209.104992 -383.119376) (xy 209.104992 -383.088896)
			(xy 209.10465 -383.079816) (xy 209.098414 -383.062765) (xy 209.0928 -383.055622) (xy 209.07334 -383.032504)
			(xy 209.039502 -382.982434) (xy 209.011836 -382.928708) (xy 208.99073 -382.872082) (xy 208.976483 -382.813354)
			(xy 208.969294 -382.753351) (xy 208.968848 -382.723136) (xy 208.96935 -382.691175) (xy 208.977361 -382.627757)
			(xy 208.993258 -382.565843) (xy 209.01679 -382.50641) (xy 209.047584 -382.450395) (xy 209.085157 -382.39868)
			(xy 209.128914 -382.352083) (xy 209.178167 -382.311338) (xy 209.232138 -382.277087) (xy 209.289977 -382.24987)
			(xy 209.35077 -382.230117) (xy 209.41356 -382.218139) (xy 209.477356 -382.214126) (xy 209.541152 -382.218139)
			(xy 209.603942 -382.230117) (xy 209.664735 -382.24987) (xy 209.722574 -382.277087) (xy 209.776545 -382.311338)
			(xy 209.825798 -382.352083) (xy 209.869555 -382.39868) (xy 209.907128 -382.450395) (xy 209.937922 -382.50641)
			(xy 209.961454 -382.565843) (xy 209.977351 -382.627757) (xy 209.985362 -382.691175) (xy 209.985864 -382.723136)
			(xy 209.985399 -382.753351) (xy 209.978218 -382.813352) (xy 209.963975 -382.87208) (xy 209.942869 -382.928704)
			(xy 209.915199 -382.982426) (xy 209.881355 -383.03249) (xy 209.861912 -383.055622) (xy 209.856278 -383.062754)
			(xy 209.850039 -383.079812) (xy 209.84972 -383.088896) (xy 209.84972 -383.119376) (xy 209.850025 -383.12846)
			(xy 209.856286 -383.145511) (xy 209.861912 -383.15265) (xy 209.881361 -383.175777) (xy 209.9152 -383.225845)
			(xy 209.942867 -383.27957) (xy 209.963975 -383.336194) (xy 209.978225 -383.39492) (xy 209.985416 -383.454921)
			(xy 209.985864 -383.485136) (xy 209.985362 -383.517097) (xy 209.977351 -383.580515) (xy 209.961454 -383.642429)
			(xy 209.937922 -383.701862) (xy 209.907128 -383.757877) (xy 209.869555 -383.809592) (xy 209.825798 -383.856189)
			(xy 209.776545 -383.896934) (xy 209.722574 -383.931185) (xy 209.664735 -383.958402) (xy 209.603942 -383.978155)
			(xy 209.541152 -383.990133) (xy 209.477356 -383.994147) (xy 209.41356 -383.990133) (xy 209.35077 -383.978155)
			(xy 209.289977 -383.958402) (xy 209.232138 -383.931185) (xy 209.178167 -383.896934) (xy 209.128914 -383.856189)
			(xy 209.085157 -383.809592) (xy 209.047584 -383.757877) (xy 209.01679 -383.701862) (xy 208.993258 -383.642429)
			(xy 208.977361 -383.580515) (xy 208.96935 -383.517097) (xy 208.968848 -383.485136) (xy 207.948738 -383.485136)
			(xy 207.948784 -383.488184) (xy 207.948282 -383.520145) (xy 207.940271 -383.583563) (xy 207.924374 -383.645477)
			(xy 207.900842 -383.70491) (xy 207.870048 -383.760925) (xy 207.832475 -383.81264) (xy 207.788718 -383.859237)
			(xy 207.739465 -383.899982) (xy 207.685494 -383.934233) (xy 207.627655 -383.96145) (xy 207.566862 -383.981203)
			(xy 207.504072 -383.993181) (xy 207.440276 -383.997195) (xy 207.37648 -383.993181) (xy 207.31369 -383.981203)
			(xy 207.252897 -383.96145) (xy 207.195058 -383.934233) (xy 207.141087 -383.899982) (xy 207.091834 -383.859237)
			(xy 207.048077 -383.81264) (xy 207.010504 -383.760925) (xy 206.97971 -383.70491) (xy 206.956178 -383.645477)
			(xy 206.940281 -383.583563) (xy 206.93227 -383.520145) (xy 206.931768 -383.488184) (xy 206.932205 -383.457831)
			(xy 206.939447 -383.397559) (xy 206.953815 -383.338577) (xy 206.975103 -383.281726) (xy 207.00301 -383.227815)
			(xy 207.037137 -383.17761) (xy 207.056736 -383.154428) (xy 207.062464 -383.147259) (xy 207.068844 -383.13007)
			(xy 207.069182 -383.1209) (xy 207.069182 -383.090674) (xy 207.068815 -383.081509) (xy 207.062444 -383.064325)
			(xy 207.056736 -383.057146) (xy 207.037109 -383.033953) (xy 207.002933 -382.983714) (xy 206.974982 -382.929763)
			(xy 206.953653 -382.872869) (xy 206.939249 -382.81384) (xy 206.931976 -382.753516) (xy 206.931514 -382.723136)
			(xy 205.921864 -382.723136) (xy 205.921399 -382.753351) (xy 205.914218 -382.813352) (xy 205.899975 -382.87208)
			(xy 205.878869 -382.928704) (xy 205.851199 -382.982426) (xy 205.817355 -383.03249) (xy 205.797912 -383.055622)
			(xy 205.792278 -383.062754) (xy 205.786039 -383.079812) (xy 205.78572 -383.088896) (xy 205.78572 -383.119376)
			(xy 205.786025 -383.12846) (xy 205.792286 -383.145511) (xy 205.797912 -383.15265) (xy 205.817361 -383.175777)
			(xy 205.8512 -383.225845) (xy 205.878867 -383.27957) (xy 205.899975 -383.336194) (xy 205.914225 -383.39492)
			(xy 205.921416 -383.454921) (xy 205.921864 -383.485136) (xy 205.921362 -383.517097) (xy 205.913351 -383.580515)
			(xy 205.897454 -383.642429) (xy 205.873922 -383.701862) (xy 205.843128 -383.757877) (xy 205.805555 -383.809592)
			(xy 205.761798 -383.856189) (xy 205.712545 -383.896934) (xy 205.658574 -383.931185) (xy 205.600735 -383.958402)
			(xy 205.539942 -383.978155) (xy 205.477152 -383.990133) (xy 205.413356 -383.994147) (xy 205.34956 -383.990133)
			(xy 205.28677 -383.978155) (xy 205.225977 -383.958402) (xy 205.168138 -383.931185) (xy 205.114167 -383.896934)
			(xy 205.064914 -383.856189) (xy 205.021157 -383.809592) (xy 204.983584 -383.757877) (xy 204.95279 -383.701862)
			(xy 204.929258 -383.642429) (xy 204.913361 -383.580515) (xy 204.90535 -383.517097) (xy 204.904848 -383.485136)
			(xy 199.597199 -383.485136) (xy 199.572321 -383.514396) (xy 199.524108 -383.558246) (xy 199.497696 -383.577338)
			(xy 199.488121 -383.58501) (xy 199.476834 -383.606748) (xy 199.476106 -383.618994) (xy 199.476106 -383.702052)
			(xy 199.476775 -383.714317) (xy 199.488061 -383.736089) (xy 199.497696 -383.743708) (xy 199.522453 -383.761603)
			(xy 199.567963 -383.802352) (xy 199.608266 -383.848258) (xy 199.64278 -383.898661) (xy 199.67101 -383.952835)
			(xy 199.692547 -384.009999) (xy 199.707084 -384.069332) (xy 199.714409 -384.129978) (xy 199.714866 -384.160522)
			(xy 199.714364 -384.192483) (xy 199.706353 -384.255901) (xy 199.690456 -384.317815) (xy 199.666924 -384.377248)
			(xy 199.63613 -384.433263) (xy 199.598557 -384.484978) (xy 199.5548 -384.531575) (xy 199.505547 -384.57232)
			(xy 199.451576 -384.606571) (xy 199.393737 -384.633788) (xy 199.332944 -384.653541) (xy 199.270154 -384.665519)
			(xy 199.206358 -384.669533) (xy 199.142562 -384.665519) (xy 199.079772 -384.653541) (xy 199.018979 -384.633788)
			(xy 198.96114 -384.606571) (xy 198.907169 -384.57232) (xy 198.857916 -384.531575) (xy 198.814159 -384.484978)
			(xy 198.776586 -384.433263) (xy 198.745792 -384.377248) (xy 198.72226 -384.317815) (xy 198.706363 -384.255901)
			(xy 198.698352 -384.192483) (xy 198.69785 -384.160522) (xy 198.69834 -384.129977) (xy 198.705646 -384.069327)
			(xy 198.720167 -384.009989) (xy 198.741694 -383.952819) (xy 198.769917 -383.89864) (xy 198.804428 -383.848234)
			(xy 198.844731 -383.802326) (xy 198.890245 -383.761579) (xy 198.91502 -383.743708) (xy 198.924623 -383.736065)
			(xy 198.935895 -383.714305) (xy 198.93661 -383.702052) (xy 198.93661 -383.618994) (xy 198.935967 -383.606726)
			(xy 198.924662 -383.584955) (xy 198.91502 -383.577338) (xy 198.888636 -383.558212) (xy 198.840435 -383.514362)
			(xy 198.79823 -383.464713) (xy 198.762712 -383.41008) (xy 198.734465 -383.351357) (xy 198.713951 -383.289507)
			(xy 198.701506 -383.225543) (xy 198.697333 -383.160514) (xy 192.84315 -383.160514) (xy 192.84315 -383.20218)
			(xy 192.843936 -383.214459) (xy 192.855332 -383.23622) (xy 192.864994 -383.243836) (xy 192.889734 -383.261716)
			(xy 192.935198 -383.30245) (xy 192.975456 -383.348335) (xy 193.009931 -383.398711) (xy 193.038126 -383.452852)
			(xy 193.059635 -383.509979) (xy 193.074148 -383.569271) (xy 193.081458 -383.629875) (xy 193.08191 -383.660396)
			(xy 193.081412 -383.693835) (xy 193.072653 -383.760137) (xy 193.055271 -383.824717) (xy 193.029568 -383.886458)
			(xy 192.995987 -383.944295) (xy 192.95511 -383.997226) (xy 192.907642 -384.044337) (xy 192.854404 -384.084814)
			(xy 192.825624 -384.101848) (xy 192.814702 -384.108198) (xy 192.801494 -384.129026) (xy 192.792096 -384.237484)
			(xy 192.801748 -384.260344) (xy 192.8114 -384.268472) (xy 192.835776 -384.28922) (xy 192.879656 -384.335827)
			(xy 192.917338 -384.387573) (xy 192.948227 -384.443641) (xy 192.971833 -384.503142) (xy 192.987783 -384.565136)
			(xy 192.995825 -384.628642) (xy 192.996312 -384.660648) (xy 192.995767 -384.693519) (xy 192.98729 -384.758713)
			(xy 192.970482 -384.822271) (xy 192.945625 -384.883133) (xy 192.913132 -384.940285) (xy 192.873546 -384.992774)
			(xy 192.827526 -385.039724) (xy 192.802002 -385.060444) (xy 192.792096 -385.068318) (xy 192.781936 -385.090924)
			(xy 192.788286 -385.199128) (xy 192.800986 -385.220464) (xy 192.811654 -385.227068) (xy 192.839111 -385.244414)
			(xy 192.889748 -385.285084) (xy 192.934792 -385.331873) (xy 192.973507 -385.38402) (xy 193.005264 -385.440674)
			(xy 193.029544 -385.500913) (xy 193.045952 -385.563753) (xy 193.05422 -385.628172) (xy 193.054732 -385.660646)
			(xy 193.054168 -385.694584) (xy 193.045161 -385.761861) (xy 193.027285 -385.827341) (xy 193.000859 -385.889862)
			(xy 192.966351 -385.948313) (xy 192.924376 -386.001655) (xy 192.87568 -386.048939) (xy 192.848738 -386.069586)
			(xy 192.838578 -386.076952) (xy 192.827656 -386.099304) (xy 192.830704 -386.207508) (xy 192.842642 -386.229098)
			(xy 192.853056 -386.235956) (xy 192.879051 -386.253623) (xy 192.926889 -386.294392) (xy 192.969336 -386.340747)
			(xy 193.005745 -386.391981) (xy 193.035561 -386.447313) (xy 193.058329 -386.505898) (xy 193.073701 -386.566842)
			(xy 193.081444 -386.629217) (xy 193.08191 -386.660644) (xy 193.081408 -386.692605) (xy 193.073397 -386.756023)
			(xy 193.057778 -386.816854) (xy 195.809616 -386.816854) (xy 195.810086 -386.786246) (xy 195.817452 -386.725474)
			(xy 195.832059 -386.666026) (xy 195.853698 -386.608761) (xy 195.882054 -386.554507) (xy 195.916717 -386.50405)
			(xy 195.957187 -386.458119) (xy 196.002878 -386.417378) (xy 196.053129 -386.382416) (xy 196.107213 -386.353739)
			(xy 196.164349 -386.331762) (xy 196.193918 -386.32384) (xy 196.202867 -386.321114) (xy 196.218115 -386.310309)
			(xy 196.223636 -386.302758) (xy 196.240654 -386.277358) (xy 196.24552 -386.269429) (xy 196.249684 -386.251312)
			(xy 196.248782 -386.242052) (xy 196.246509 -386.224552) (xy 196.244091 -386.189341) (xy 196.243956 -386.171694)
			(xy 196.244363 -386.141115) (xy 196.251721 -386.080402) (xy 196.266304 -386.021009) (xy 196.287903 -385.963793)
			(xy 196.316206 -385.909579) (xy 196.350805 -385.859149) (xy 196.391201 -385.813232) (xy 196.436811 -385.772489)
			(xy 196.461634 -385.754626) (xy 196.472048 -385.74726) (xy 196.483478 -385.72567) (xy 196.48424 -385.61772)
			(xy 196.473064 -385.59613) (xy 196.462904 -385.588764) (xy 196.438752 -385.570794) (xy 196.394403 -385.530083)
			(xy 196.355169 -385.484423) (xy 196.321599 -385.434451) (xy 196.294161 -385.380866) (xy 196.27324 -385.324418)
			(xy 196.259127 -385.265894) (xy 196.25202 -385.206114) (xy 196.251576 -385.176014) (xy 196.252078 -385.144053)
			(xy 196.260089 -385.080635) (xy 196.275986 -385.018721) (xy 196.299518 -384.959288) (xy 196.330312 -384.903273)
			(xy 196.367885 -384.851558) (xy 196.411642 -384.804961) (xy 196.460895 -384.764216) (xy 196.514866 -384.729965)
			(xy 196.572705 -384.702748) (xy 196.633498 -384.682995) (xy 196.696288 -384.671017) (xy 196.760084 -384.667004)
			(xy 196.82388 -384.671017) (xy 196.88667 -384.682995) (xy 196.947463 -384.702748) (xy 197.005302 -384.729965)
			(xy 197.059273 -384.764216) (xy 197.108526 -384.804961) (xy 197.152283 -384.851558) (xy 197.189856 -384.903273)
			(xy 197.22065 -384.959288) (xy 197.244182 -385.018721) (xy 197.260079 -385.080635) (xy 197.26809 -385.144053)
			(xy 197.268592 -385.176014) (xy 197.268094 -385.20659) (xy 197.260749 -385.267299) (xy 197.246178 -385.326689)
			(xy 197.224591 -385.383904) (xy 197.1963 -385.438118) (xy 197.161713 -385.488549) (xy 197.12133 -385.534469)
			(xy 197.075732 -385.575216) (xy 197.050914 -385.593082) (xy 197.0405 -385.600448) (xy 197.02907 -385.622038)
			(xy 197.028308 -385.729988) (xy 197.039484 -385.751578) (xy 197.049644 -385.758944) (xy 197.073811 -385.776895)
			(xy 197.118157 -385.81761) (xy 197.157389 -385.863274) (xy 197.190957 -385.913249) (xy 197.218392 -385.966836)
			(xy 197.239312 -386.023287) (xy 197.239758 -386.025136) (xy 204.904848 -386.025136) (xy 204.905294 -385.994921)
			(xy 204.912478 -385.934918) (xy 204.926725 -385.876191) (xy 204.947834 -385.819566) (xy 204.975508 -385.765844)
			(xy 205.009356 -385.715782) (xy 205.0288 -385.69265) (xy 205.034405 -385.685498) (xy 205.040661 -385.668455)
			(xy 205.040992 -385.659376) (xy 205.040992 -385.628896) (xy 205.04065 -385.619816) (xy 205.034414 -385.602765)
			(xy 205.0288 -385.595622) (xy 205.00934 -385.572504) (xy 204.975502 -385.522434) (xy 204.947836 -385.468708)
			(xy 204.92673 -385.412082) (xy 204.912483 -385.353354) (xy 204.905294 -385.293351) (xy 204.904848 -385.263136)
			(xy 204.90535 -385.231175) (xy 204.913361 -385.167757) (xy 204.929258 -385.105843) (xy 204.95279 -385.04641)
			(xy 204.983584 -384.990395) (xy 205.021157 -384.93868) (xy 205.064914 -384.892083) (xy 205.114167 -384.851338)
			(xy 205.168138 -384.817087) (xy 205.225977 -384.78987) (xy 205.28677 -384.770117) (xy 205.34956 -384.758139)
			(xy 205.413356 -384.754126) (xy 205.477152 -384.758139) (xy 205.539942 -384.770117) (xy 205.600735 -384.78987)
			(xy 205.658574 -384.817087) (xy 205.712545 -384.851338) (xy 205.761798 -384.892083) (xy 205.805555 -384.93868)
			(xy 205.843128 -384.990395) (xy 205.873922 -385.04641) (xy 205.897454 -385.105843) (xy 205.913351 -385.167757)
			(xy 205.921362 -385.231175) (xy 205.921864 -385.263136) (xy 206.931514 -385.263136) (xy 206.932016 -385.231175)
			(xy 206.940027 -385.167757) (xy 206.955924 -385.105843) (xy 206.979456 -385.04641) (xy 207.01025 -384.990395)
			(xy 207.047823 -384.93868) (xy 207.09158 -384.892083) (xy 207.140833 -384.851338) (xy 207.194804 -384.817087)
			(xy 207.252643 -384.78987) (xy 207.313436 -384.770117) (xy 207.376226 -384.758139) (xy 207.440022 -384.754126)
			(xy 207.503818 -384.758139) (xy 207.566608 -384.770117) (xy 207.627401 -384.78987) (xy 207.68524 -384.817087)
			(xy 207.739211 -384.851338) (xy 207.788464 -384.892083) (xy 207.832221 -384.93868) (xy 207.869794 -384.990395)
			(xy 207.900588 -385.04641) (xy 207.92412 -385.105843) (xy 207.940017 -385.167757) (xy 207.948028 -385.231175)
			(xy 207.94853 -385.263136) (xy 207.948059 -385.293625) (xy 207.940764 -385.354165) (xy 207.926282 -385.413399)
			(xy 207.904822 -385.470476) (xy 207.876692 -385.524578) (xy 207.842294 -385.574928) (xy 207.822546 -385.598162)
			(xy 207.8167 -385.60535) (xy 207.810195 -385.622684) (xy 207.809846 -385.631944) (xy 207.8101 -385.662424)
			(xy 207.810596 -385.671628) (xy 207.817225 -385.688812) (xy 207.823054 -385.695952) (xy 207.843224 -385.719303)
			(xy 207.87838 -385.770015) (xy 207.907145 -385.824606) (xy 207.929097 -385.882274) (xy 207.943914 -385.942175)
			(xy 207.951379 -386.003427) (xy 207.951698 -386.025136) (xy 208.968848 -386.025136) (xy 208.969294 -385.994921)
			(xy 208.976478 -385.934918) (xy 208.990725 -385.876191) (xy 209.011834 -385.819566) (xy 209.039508 -385.765844)
			(xy 209.073356 -385.715782) (xy 209.0928 -385.69265) (xy 209.098405 -385.685498) (xy 209.104661 -385.668455)
			(xy 209.104992 -385.659376) (xy 209.104992 -385.628896) (xy 209.10465 -385.619816) (xy 209.098414 -385.602765)
			(xy 209.0928 -385.595622) (xy 209.07334 -385.572504) (xy 209.039502 -385.522434) (xy 209.011836 -385.468708)
			(xy 208.99073 -385.412082) (xy 208.976483 -385.353354) (xy 208.969294 -385.293351) (xy 208.968848 -385.263136)
			(xy 208.96935 -385.231175) (xy 208.977361 -385.167757) (xy 208.993258 -385.105843) (xy 209.01679 -385.04641)
			(xy 209.047584 -384.990395) (xy 209.085157 -384.93868) (xy 209.128914 -384.892083) (xy 209.178167 -384.851338)
			(xy 209.232138 -384.817087) (xy 209.289977 -384.78987) (xy 209.35077 -384.770117) (xy 209.41356 -384.758139)
			(xy 209.477356 -384.754126) (xy 209.541152 -384.758139) (xy 209.603942 -384.770117) (xy 209.664735 -384.78987)
			(xy 209.722574 -384.817087) (xy 209.776545 -384.851338) (xy 209.825798 -384.892083) (xy 209.869555 -384.93868)
			(xy 209.907128 -384.990395) (xy 209.937922 -385.04641) (xy 209.961454 -385.105843) (xy 209.977351 -385.167757)
			(xy 209.985362 -385.231175) (xy 209.985864 -385.263136) (xy 209.985399 -385.293351) (xy 209.978218 -385.353352)
			(xy 209.963975 -385.41208) (xy 209.942869 -385.468704) (xy 209.915199 -385.522426) (xy 209.881355 -385.57249)
			(xy 209.861912 -385.595622) (xy 209.856278 -385.602754) (xy 209.850039 -385.619812) (xy 209.84972 -385.628896)
			(xy 209.84972 -385.659376) (xy 209.850025 -385.66846) (xy 209.856286 -385.685511) (xy 209.861912 -385.69265)
			(xy 209.881361 -385.715777) (xy 209.9152 -385.765845) (xy 209.942867 -385.81957) (xy 209.963975 -385.876194)
			(xy 209.978225 -385.93492) (xy 209.985416 -385.994921) (xy 209.985864 -386.025136) (xy 209.985362 -386.057097)
			(xy 209.977351 -386.120515) (xy 209.961454 -386.182429) (xy 209.937922 -386.241862) (xy 209.907128 -386.297877)
			(xy 209.869555 -386.349592) (xy 209.825798 -386.396189) (xy 209.776545 -386.436934) (xy 209.722574 -386.471185)
			(xy 209.664735 -386.498402) (xy 209.603942 -386.518155) (xy 209.541152 -386.530133) (xy 209.477356 -386.534147)
			(xy 209.41356 -386.530133) (xy 209.35077 -386.518155) (xy 209.289977 -386.498402) (xy 209.232138 -386.471185)
			(xy 209.178167 -386.436934) (xy 209.128914 -386.396189) (xy 209.085157 -386.349592) (xy 209.047584 -386.297877)
			(xy 209.01679 -386.241862) (xy 208.993258 -386.182429) (xy 208.977361 -386.120515) (xy 208.96935 -386.057097)
			(xy 208.968848 -386.025136) (xy 207.951698 -386.025136) (xy 207.951832 -386.03428) (xy 207.95133 -386.066241)
			(xy 207.943319 -386.129659) (xy 207.927422 -386.191573) (xy 207.90389 -386.251006) (xy 207.873096 -386.307021)
			(xy 207.835523 -386.358736) (xy 207.791766 -386.405333) (xy 207.742513 -386.446078) (xy 207.688542 -386.480329)
			(xy 207.630703 -386.507546) (xy 207.56991 -386.527299) (xy 207.50712 -386.539277) (xy 207.443324 -386.543291)
			(xy 207.379528 -386.539277) (xy 207.316738 -386.527299) (xy 207.255945 -386.507546) (xy 207.198106 -386.480329)
			(xy 207.144135 -386.446078) (xy 207.094882 -386.405333) (xy 207.051125 -386.358736) (xy 207.013552 -386.307021)
			(xy 206.982758 -386.251006) (xy 206.959226 -386.191573) (xy 206.943329 -386.129659) (xy 206.935318 -386.066241)
			(xy 206.934816 -386.03428) (xy 206.935285 -386.003791) (xy 206.942579 -385.94325) (xy 206.95706 -385.884016)
			(xy 206.97852 -385.826939) (xy 207.006652 -385.772837) (xy 207.041051 -385.722487) (xy 207.0608 -385.699254)
			(xy 207.066633 -385.692056) (xy 207.073147 -385.67473) (xy 207.0735 -385.665472) (xy 207.073246 -385.634992)
			(xy 207.072755 -385.625787) (xy 207.066124 -385.608602) (xy 207.060292 -385.601464) (xy 207.040121 -385.578114)
			(xy 207.004967 -385.527401) (xy 206.976203 -385.47281) (xy 206.954251 -385.415141) (xy 206.939434 -385.355241)
			(xy 206.931968 -385.293989) (xy 206.931514 -385.263136) (xy 205.921864 -385.263136) (xy 205.921399 -385.293351)
			(xy 205.914218 -385.353352) (xy 205.899975 -385.41208) (xy 205.878869 -385.468704) (xy 205.851199 -385.522426)
			(xy 205.817355 -385.57249) (xy 205.797912 -385.595622) (xy 205.792278 -385.602754) (xy 205.786039 -385.619812)
			(xy 205.78572 -385.628896) (xy 205.78572 -385.659376) (xy 205.786025 -385.66846) (xy 205.792286 -385.685511)
			(xy 205.797912 -385.69265) (xy 205.817361 -385.715777) (xy 205.8512 -385.765845) (xy 205.878867 -385.81957)
			(xy 205.899975 -385.876194) (xy 205.914225 -385.93492) (xy 205.921416 -385.994921) (xy 205.921864 -386.025136)
			(xy 205.921362 -386.057097) (xy 205.913351 -386.120515) (xy 205.897454 -386.182429) (xy 205.873922 -386.241862)
			(xy 205.843128 -386.297877) (xy 205.805555 -386.349592) (xy 205.761798 -386.396189) (xy 205.712545 -386.436934)
			(xy 205.658574 -386.471185) (xy 205.600735 -386.498402) (xy 205.539942 -386.518155) (xy 205.477152 -386.530133)
			(xy 205.413356 -386.534147) (xy 205.34956 -386.530133) (xy 205.28677 -386.518155) (xy 205.225977 -386.498402)
			(xy 205.168138 -386.471185) (xy 205.114167 -386.436934) (xy 205.064914 -386.396189) (xy 205.021157 -386.349592)
			(xy 204.983584 -386.297877) (xy 204.95279 -386.241862) (xy 204.929258 -386.182429) (xy 204.913361 -386.120515)
			(xy 204.90535 -386.057097) (xy 204.904848 -386.025136) (xy 197.239758 -386.025136) (xy 197.253423 -386.081812)
			(xy 197.260529 -386.141593) (xy 197.260972 -386.171694) (xy 197.26048 -386.202301) (xy 197.25311 -386.263069)
			(xy 197.2385 -386.322514) (xy 197.216861 -386.379776) (xy 197.188505 -386.434026) (xy 197.153844 -386.484482)
			(xy 197.113378 -386.530412) (xy 197.067692 -386.571154) (xy 197.017446 -386.606118) (xy 196.963367 -386.634799)
			(xy 196.906236 -386.656782) (xy 196.87667 -386.664708) (xy 196.867713 -386.667413) (xy 196.852468 -386.678232)
			(xy 196.846952 -386.68579) (xy 196.829934 -386.71119) (xy 196.825092 -386.719132) (xy 196.820914 -386.737238)
			(xy 196.821806 -386.746496) (xy 196.824084 -386.763996) (xy 196.826499 -386.799207) (xy 196.826632 -386.816854)
			(xy 196.82613 -386.848815) (xy 196.818119 -386.912233) (xy 196.802222 -386.974147) (xy 196.77869 -387.03358)
			(xy 196.747896 -387.089595) (xy 196.710323 -387.14131) (xy 196.690809 -387.162091) (xy 200.244171 -387.162091)
			(xy 200.247937 -387.078693) (xy 200.259501 -386.996014) (xy 200.27876 -386.914783) (xy 200.305546 -386.835713)
			(xy 200.339622 -386.759501) (xy 200.380689 -386.686817) (xy 200.428386 -386.6183) (xy 200.482292 -386.554554)
			(xy 200.541934 -386.496139) (xy 200.606787 -386.443569) (xy 200.67628 -386.397307) (xy 200.749802 -386.357759)
			(xy 200.826706 -386.325275) (xy 200.906315 -386.300138) (xy 200.987929 -386.282571) (xy 201.07083 -386.272728)
			(xy 201.154289 -386.270696) (xy 201.237571 -386.276493) (xy 201.319943 -386.290067) (xy 201.400682 -386.311299)
			(xy 201.479075 -386.340003) (xy 201.554435 -386.375926) (xy 201.626097 -386.418751) (xy 201.693432 -386.468102)
			(xy 201.755846 -386.523546) (xy 201.812791 -386.584593) (xy 201.863765 -386.650707) (xy 201.908321 -386.721306)
			(xy 201.946066 -386.79577) (xy 201.976668 -386.873442) (xy 201.999858 -386.95364) (xy 202.015431 -387.035658)
			(xy 202.023252 -387.118774) (xy 202.023726 -387.160516) (xy 202.023274 -387.201621) (xy 202.015695 -387.283481)
			(xy 202.000595 -387.364292) (xy 201.978102 -387.443365) (xy 201.948408 -387.520025) (xy 201.911766 -387.593618)
			(xy 201.868489 -387.663515) (xy 201.818947 -387.72912) (xy 201.763563 -387.789874) (xy 201.702808 -387.845258)
			(xy 201.637202 -387.894799) (xy 201.567303 -387.938074) (xy 201.530712 -387.956806) (xy 201.523169 -387.960964)
			(xy 201.511165 -387.973297) (xy 201.503931 -387.988913) (xy 201.502772 -387.997446) (xy 201.499525 -388.025395)
			(xy 201.485926 -388.07999) (xy 201.464456 -388.131996) (xy 201.435582 -388.180285) (xy 201.399929 -388.22381)
			(xy 201.35827 -388.261627) (xy 201.311509 -388.292915) (xy 201.26066 -388.316997) (xy 201.206826 -388.33335)
			(xy 201.151174 -388.341619) (xy 201.123042 -388.342124) (xy 201.09438 -388.341622) (xy 201.037705 -388.33301)
			(xy 200.982956 -388.316019) (xy 200.931364 -388.291031) (xy 200.884089 -388.258608) (xy 200.842195 -388.219479)
			(xy 200.806624 -388.174525) (xy 200.778177 -388.124756) (xy 200.757493 -388.071293) (xy 200.745037 -388.015337)
			(xy 200.74255 -387.986778) (xy 200.741612 -387.978204) (xy 200.734769 -387.962383) (xy 200.72308 -387.949716)
			(xy 200.715626 -387.945376) (xy 200.679012 -387.925326) (xy 200.609354 -387.879312) (xy 200.544314 -387.826975)
			(xy 200.484463 -387.768773) (xy 200.430329 -387.70522) (xy 200.382388 -387.636875) (xy 200.341061 -387.564338)
			(xy 200.306713 -387.488248) (xy 200.279644 -387.409275) (xy 200.260095 -387.328113) (xy 200.248235 -387.245476)
			(xy 200.244171 -387.162091) (xy 196.690809 -387.162091) (xy 196.666566 -387.187907) (xy 196.617313 -387.228652)
			(xy 196.563342 -387.262903) (xy 196.505503 -387.29012) (xy 196.44471 -387.309873) (xy 196.38192 -387.321851)
			(xy 196.318124 -387.325865) (xy 196.254328 -387.321851) (xy 196.191538 -387.309873) (xy 196.130745 -387.29012)
			(xy 196.072906 -387.262903) (xy 196.018935 -387.228652) (xy 195.969682 -387.187907) (xy 195.925925 -387.14131)
			(xy 195.888352 -387.089595) (xy 195.857558 -387.03358) (xy 195.834026 -386.974147) (xy 195.818129 -386.912233)
			(xy 195.810118 -386.848815) (xy 195.809616 -386.816854) (xy 193.057778 -386.816854) (xy 193.0575 -386.817937)
			(xy 193.033968 -386.87737) (xy 193.003174 -386.933385) (xy 192.965601 -386.9851) (xy 192.921844 -387.031697)
			(xy 192.872591 -387.072442) (xy 192.81862 -387.106693) (xy 192.760781 -387.13391) (xy 192.699988 -387.153663)
			(xy 192.637198 -387.165641) (xy 192.573402 -387.169655) (xy 192.509606 -387.165641) (xy 192.446816 -387.153663)
			(xy 192.386023 -387.13391) (xy 192.328184 -387.106693) (xy 192.274213 -387.072442) (xy 192.22496 -387.031697)
			(xy 192.181203 -386.9851) (xy 192.14363 -386.933385) (xy 192.112836 -386.87737) (xy 192.089304 -386.817937)
			(xy 192.073407 -386.756023) (xy 192.065396 -386.692605) (xy 192.064894 -386.660644) (xy 192.06548 -386.626707)
			(xy 192.074488 -386.559432) (xy 192.092362 -386.493954) (xy 192.118785 -386.431434) (xy 192.153288 -386.372983)
			(xy 192.195258 -386.31964) (xy 192.243949 -386.272353) (xy 192.270888 -386.251704) (xy 192.281048 -386.244338)
			(xy 192.29197 -386.221986) (xy 192.288922 -386.113782) (xy 192.276984 -386.092192) (xy 192.26657 -386.085334)
			(xy 192.240554 -386.067698) (xy 192.192719 -386.026922) (xy 192.150275 -385.980561) (xy 192.11387 -385.929322)
			(xy 192.084057 -385.873986) (xy 192.061292 -385.815398) (xy 192.045922 -385.754451) (xy 192.038181 -385.692074)
			(xy 192.037716 -385.660646) (xy 192.038246 -385.627774) (xy 192.046725 -385.562579) (xy 192.063534 -385.49902)
			(xy 192.088394 -385.438158) (xy 192.120889 -385.381006) (xy 192.160478 -385.328518) (xy 192.206501 -385.28157)
			(xy 192.232026 -385.26085) (xy 192.241932 -385.252976) (xy 192.252092 -385.23037) (xy 192.245742 -385.122166)
			(xy 192.233042 -385.10083) (xy 192.222374 -385.094226) (xy 192.194921 -385.076874) (xy 192.144282 -385.036206)
			(xy 192.099238 -384.989418) (xy 192.060521 -384.937272) (xy 192.028764 -384.880619) (xy 192.004483 -384.820381)
			(xy 191.988075 -384.75754) (xy 191.979807 -384.693122) (xy 191.979296 -384.660648) (xy 190.753056 -384.660648)
			(xy 190.756318 -384.684619) (xy 190.768977 -384.712077) (xy 190.789112 -384.734633) (xy 190.801752 -384.742944)
			(xy 190.829492 -384.760275) (xy 190.88073 -384.800933) (xy 190.926332 -384.847824) (xy 190.965547 -384.900175)
			(xy 190.997725 -384.957121) (xy 191.022338 -385.017723) (xy 191.038977 -385.080981) (xy 191.047369 -385.145849)
			(xy 191.047878 -385.178554) (xy 191.047376 -385.210515) (xy 191.039365 -385.273933) (xy 191.023468 -385.335847)
			(xy 190.999936 -385.39528) (xy 190.969142 -385.451295) (xy 190.931569 -385.50301) (xy 190.887812 -385.549607)
			(xy 190.838559 -385.590352) (xy 190.784588 -385.624603) (xy 190.726749 -385.65182) (xy 190.665956 -385.671573)
			(xy 190.603166 -385.683551) (xy 190.53937 -385.687565) (xy 190.475574 -385.683551) (xy 190.412784 -385.671573)
			(xy 190.351991 -385.65182) (xy 190.294152 -385.624603) (xy 190.240181 -385.590352) (xy 190.190928 -385.549607)
			(xy 190.147171 -385.50301) (xy 190.109598 -385.451295) (xy 190.078804 -385.39528) (xy 190.055272 -385.335847)
			(xy 190.039375 -385.273933) (xy 190.031364 -385.210515) (xy 190.030862 -385.178554) (xy 189.738682 -385.178554)
			(xy 189.738762 -385.183634) (xy 189.73826 -385.215595) (xy 189.730249 -385.279013) (xy 189.714352 -385.340927)
			(xy 189.69082 -385.40036) (xy 189.660026 -385.456375) (xy 189.622453 -385.50809) (xy 189.578696 -385.554687)
			(xy 189.529443 -385.595432) (xy 189.475472 -385.629683) (xy 189.417633 -385.6569) (xy 189.35684 -385.676653)
			(xy 189.29405 -385.688631) (xy 189.230254 -385.692645) (xy 189.166458 -385.688631) (xy 189.103668 -385.676653)
			(xy 189.042875 -385.6569) (xy 188.985036 -385.629683) (xy 188.931065 -385.595432) (xy 188.881812 -385.554687)
			(xy 188.838055 -385.50809) (xy 188.800482 -385.456375) (xy 188.769688 -385.40036) (xy 188.746156 -385.340927)
			(xy 188.730259 -385.279013) (xy 188.722248 -385.215595) (xy 168.950212 -385.215595) (xy 168.950696 -385.219566)
			(xy 168.951148 -385.250436) (xy 168.950683 -385.281133) (xy 168.94328 -385.342078) (xy 168.928587 -385.401687)
			(xy 168.906816 -385.459091) (xy 168.878287 -385.513453) (xy 168.861232 -385.53898) (xy 168.855726 -385.547714)
			(xy 168.851605 -385.56793) (xy 168.85575 -385.588141) (xy 168.861232 -385.596892) (xy 168.878253 -385.622439)
			(xy 168.906767 -385.676804) (xy 168.928533 -385.734203) (xy 168.943238 -385.793805) (xy 168.950665 -385.854742)
			(xy 168.951148 -385.885436) (xy 168.950683 -385.916133) (xy 168.94328 -385.977078) (xy 168.935065 -386.010404)
			(xy 170.98848 -386.010404) (xy 170.992551 -385.954782) (xy 171.004677 -385.900345) (xy 171.0246 -385.848254)
			(xy 171.051896 -385.799619) (xy 171.085982 -385.755476) (xy 171.126131 -385.716767) (xy 171.171489 -385.684316)
			(xy 171.221089 -385.658815) (xy 171.273873 -385.640808) (xy 171.328716 -385.630678) (xy 171.38445 -385.628641)
			(xy 171.439887 -385.634741) (xy 171.493844 -385.648847) (xy 171.545173 -385.670659) (xy 171.592779 -385.699713)
			(xy 171.635647 -385.735388) (xy 171.672864 -385.776925) (xy 171.703637 -385.823438) (xy 171.727309 -385.873935)
			(xy 171.743377 -385.927342) (xy 171.751497 -385.982518) (xy 171.752006 -386.010404) (xy 171.751497 -386.03829)
			(xy 171.743377 -386.093466) (xy 171.727309 -386.146873) (xy 171.724842 -386.152136) (xy 172.518322 -386.152136)
			(xy 172.522393 -386.096514) (xy 172.534519 -386.042077) (xy 172.554442 -385.989986) (xy 172.581738 -385.941351)
			(xy 172.615824 -385.897208) (xy 172.655973 -385.858499) (xy 172.701331 -385.826048) (xy 172.750931 -385.800547)
			(xy 172.803715 -385.78254) (xy 172.858558 -385.77241) (xy 172.914292 -385.770373) (xy 172.969729 -385.776473)
			(xy 173.023686 -385.790579) (xy 173.075015 -385.812391) (xy 173.122621 -385.841445) (xy 173.165489 -385.87712)
			(xy 173.202706 -385.918657) (xy 173.233479 -385.96517) (xy 173.2398 -385.978654) (xy 174.400462 -385.978654)
			(xy 174.404533 -385.923032) (xy 174.416659 -385.868595) (xy 174.436582 -385.816504) (xy 174.463878 -385.767869)
			(xy 174.497964 -385.723726) (xy 174.538113 -385.685017) (xy 174.583471 -385.652566) (xy 174.633071 -385.627065)
			(xy 174.685855 -385.609058) (xy 174.740698 -385.598928) (xy 174.796432 -385.596891) (xy 174.851869 -385.602991)
			(xy 174.905826 -385.617097) (xy 174.957155 -385.638909) (xy 175.004761 -385.667963) (xy 175.047629 -385.703638)
			(xy 175.084846 -385.745175) (xy 175.115619 -385.791688) (xy 175.139291 -385.842185) (xy 175.155359 -385.895592)
			(xy 175.163479 -385.950768) (xy 175.163988 -385.978654) (xy 175.163479 -386.00654) (xy 175.155359 -386.061716)
			(xy 175.139291 -386.115123) (xy 175.115619 -386.16562) (xy 175.084846 -386.212133) (xy 175.047629 -386.25367)
			(xy 175.004761 -386.289345) (xy 174.957155 -386.318399) (xy 174.905826 -386.340211) (xy 174.851869 -386.354317)
			(xy 174.796432 -386.360417) (xy 174.740698 -386.35838) (xy 174.685855 -386.34825) (xy 174.633071 -386.330243)
			(xy 174.583471 -386.304742) (xy 174.538113 -386.272291) (xy 174.497964 -386.233582) (xy 174.463878 -386.189439)
			(xy 174.436582 -386.140804) (xy 174.416659 -386.088713) (xy 174.404533 -386.034276) (xy 174.400462 -385.978654)
			(xy 173.2398 -385.978654) (xy 173.257151 -386.015667) (xy 173.273219 -386.069074) (xy 173.281339 -386.12425)
			(xy 173.281848 -386.152136) (xy 173.281339 -386.180022) (xy 173.273219 -386.235198) (xy 173.257151 -386.288605)
			(xy 173.233479 -386.339102) (xy 173.202706 -386.385615) (xy 173.165489 -386.427152) (xy 173.122621 -386.462827)
			(xy 173.075015 -386.491881) (xy 173.023686 -386.513693) (xy 172.969729 -386.527799) (xy 172.914292 -386.533899)
			(xy 172.858558 -386.531862) (xy 172.803715 -386.521732) (xy 172.750931 -386.503725) (xy 172.701331 -386.478224)
			(xy 172.655973 -386.445773) (xy 172.615824 -386.407064) (xy 172.581738 -386.362921) (xy 172.554442 -386.314286)
			(xy 172.534519 -386.262195) (xy 172.522393 -386.207758) (xy 172.518322 -386.152136) (xy 171.724842 -386.152136)
			(xy 171.703637 -386.19737) (xy 171.672864 -386.243883) (xy 171.635647 -386.28542) (xy 171.592779 -386.321095)
			(xy 171.545173 -386.350149) (xy 171.493844 -386.371961) (xy 171.439887 -386.386067) (xy 171.38445 -386.392167)
			(xy 171.328716 -386.39013) (xy 171.273873 -386.38) (xy 171.221089 -386.361993) (xy 171.171489 -386.336492)
			(xy 171.126131 -386.304041) (xy 171.085982 -386.265332) (xy 171.051896 -386.221189) (xy 171.0246 -386.172554)
			(xy 171.004677 -386.120463) (xy 170.992551 -386.066026) (xy 170.98848 -386.010404) (xy 168.935065 -386.010404)
			(xy 168.928587 -386.036687) (xy 168.906816 -386.094091) (xy 168.878287 -386.148453) (xy 168.861232 -386.17398)
			(xy 168.855726 -386.182714) (xy 168.851605 -386.20293) (xy 168.85575 -386.223141) (xy 168.861232 -386.231892)
			(xy 168.878253 -386.257439) (xy 168.906767 -386.311804) (xy 168.928533 -386.369203) (xy 168.943238 -386.428805)
			(xy 168.950665 -386.489742) (xy 168.951148 -386.520436) (xy 168.950683 -386.551133) (xy 168.94328 -386.612078)
			(xy 168.928587 -386.671687) (xy 168.906816 -386.729091) (xy 168.888884 -386.76326) (xy 170.479718 -386.76326)
			(xy 170.483789 -386.707638) (xy 170.495915 -386.653201) (xy 170.515838 -386.60111) (xy 170.543134 -386.552475)
			(xy 170.57722 -386.508332) (xy 170.617369 -386.469623) (xy 170.662727 -386.437172) (xy 170.712327 -386.411671)
			(xy 170.765111 -386.393664) (xy 170.819954 -386.383534) (xy 170.875688 -386.381497) (xy 170.931125 -386.387597)
			(xy 170.985082 -386.401703) (xy 171.036411 -386.423515) (xy 171.084017 -386.452569) (xy 171.126885 -386.488244)
			(xy 171.164102 -386.529781) (xy 171.194875 -386.576294) (xy 171.218547 -386.626791) (xy 171.228808 -386.660898)
			(xy 173.271178 -386.660898) (xy 173.275249 -386.605276) (xy 173.287375 -386.550839) (xy 173.307298 -386.498748)
			(xy 173.334594 -386.450113) (xy 173.36868 -386.40597) (xy 173.408829 -386.367261) (xy 173.454187 -386.33481)
			(xy 173.503787 -386.309309) (xy 173.556571 -386.291302) (xy 173.611414 -386.281172) (xy 173.667148 -386.279135)
			(xy 173.722585 -386.285235) (xy 173.776542 -386.299341) (xy 173.827871 -386.321153) (xy 173.875477 -386.350207)
			(xy 173.918345 -386.385882) (xy 173.955562 -386.427419) (xy 173.986335 -386.473932) (xy 174.010007 -386.524429)
			(xy 174.026075 -386.577836) (xy 174.034195 -386.633012) (xy 174.034704 -386.660898) (xy 174.034195 -386.688784)
			(xy 174.026075 -386.74396) (xy 174.010007 -386.797367) (xy 173.986335 -386.847864) (xy 173.955562 -386.894377)
			(xy 173.918345 -386.935914) (xy 173.875477 -386.971589) (xy 173.827871 -387.000643) (xy 173.776542 -387.022455)
			(xy 173.722585 -387.036561) (xy 173.667148 -387.042661) (xy 173.611414 -387.040624) (xy 173.556571 -387.030494)
			(xy 173.503787 -387.012487) (xy 173.454187 -386.986986) (xy 173.408829 -386.954535) (xy 173.36868 -386.915826)
			(xy 173.334594 -386.871683) (xy 173.307298 -386.823048) (xy 173.287375 -386.770957) (xy 173.275249 -386.71652)
			(xy 173.271178 -386.660898) (xy 171.228808 -386.660898) (xy 171.234615 -386.680198) (xy 171.242735 -386.735374)
			(xy 171.243244 -386.76326) (xy 171.242735 -386.791146) (xy 171.234615 -386.846322) (xy 171.218547 -386.899729)
			(xy 171.194875 -386.950226) (xy 171.164102 -386.996739) (xy 171.126885 -387.038276) (xy 171.084017 -387.073951)
			(xy 171.036411 -387.103005) (xy 170.985082 -387.124817) (xy 170.931125 -387.138923) (xy 170.875688 -387.145023)
			(xy 170.819954 -387.142986) (xy 170.765111 -387.132856) (xy 170.712327 -387.114849) (xy 170.662727 -387.089348)
			(xy 170.617369 -387.056897) (xy 170.57722 -387.018188) (xy 170.543134 -386.974045) (xy 170.515838 -386.92541)
			(xy 170.495915 -386.873319) (xy 170.483789 -386.818882) (xy 170.479718 -386.76326) (xy 168.888884 -386.76326)
			(xy 168.878287 -386.783453) (xy 168.861232 -386.80898) (xy 168.855726 -386.817714) (xy 168.851605 -386.83793)
			(xy 168.85575 -386.858141) (xy 168.861232 -386.866892) (xy 168.878253 -386.892439) (xy 168.906767 -386.946804)
			(xy 168.928533 -387.004203) (xy 168.943238 -387.063805) (xy 168.950665 -387.124742) (xy 168.951148 -387.155436)
			(xy 168.950729 -387.185177) (xy 168.943782 -387.244253) (xy 168.929989 -387.302114) (xy 168.92016 -387.330188)
			(xy 168.915334 -387.343142) (xy 168.92016 -387.369558) (xy 168.994328 -387.458458) (xy 169.019474 -387.467602)
			(xy 169.03319 -387.465062) (xy 169.055046 -387.461463) (xy 169.099179 -387.457651) (xy 169.121328 -387.457442)
			(xy 169.152058 -387.45793) (xy 169.213069 -387.46534) (xy 169.272742 -387.48005) (xy 169.330207 -387.501845)
			(xy 169.384626 -387.530407) (xy 169.435206 -387.56532) (xy 169.48121 -387.606075) (xy 169.521966 -387.652076)
			(xy 169.556881 -387.702655) (xy 169.585446 -387.757073) (xy 169.607243 -387.814537) (xy 169.621956 -387.87421)
			(xy 169.629369 -387.93522) (xy 169.629836 -387.96595) (xy 169.629276 -387.999899) (xy 169.620246 -388.067193)
			(xy 169.60234 -388.132687) (xy 169.575875 -388.195215) (xy 169.541325 -388.253665) (xy 169.499302 -388.306995)
			(xy 169.450555 -388.354259) (xy 169.423588 -388.37489) (xy 169.414952 -388.38124) (xy 169.404792 -388.39902)
			(xy 169.393362 -388.493762) (xy 169.399204 -388.51332) (xy 169.406062 -388.521702) (xy 169.4227 -388.542376)
			(xy 169.450724 -388.587439) (xy 169.47224 -388.635948) (xy 169.486836 -388.686968) (xy 169.494229 -388.739517)
			(xy 169.494483 -388.753604) (xy 170.361102 -388.753604) (xy 170.361529 -388.723494) (xy 170.368662 -388.663698)
			(xy 170.382805 -388.605162) (xy 170.403759 -388.548705) (xy 170.431233 -388.495117) (xy 170.464841 -388.445148)
			(xy 170.504114 -388.399496) (xy 170.548502 -388.3588) (xy 170.572684 -388.340854) (xy 170.582147 -388.333226)
			(xy 170.593151 -388.311592) (xy 170.593766 -388.299452) (xy 170.593766 -388.217156) (xy 170.593091 -388.205031)
			(xy 170.582103 -388.183417) (xy 170.572684 -388.175754) (xy 170.548471 -388.157848) (xy 170.504071 -388.117157)
			(xy 170.464791 -388.071504) (xy 170.431181 -388.02153) (xy 170.403713 -387.967934) (xy 170.38277 -387.911467)
			(xy 170.368647 -387.852921) (xy 170.361541 -387.793117) (xy 170.361102 -387.763004) (xy 170.361604 -387.731043)
			(xy 170.369615 -387.667625) (xy 170.385512 -387.605711) (xy 170.409044 -387.546278) (xy 170.439838 -387.490263)
			(xy 170.477411 -387.438548) (xy 170.521168 -387.391951) (xy 170.570421 -387.351206) (xy 170.624392 -387.316955)
			(xy 170.682231 -387.289738) (xy 170.743024 -387.269985) (xy 170.805814 -387.258007) (xy 170.86961 -387.253994)
			(xy 170.933406 -387.258007) (xy 170.996196 -387.269985) (xy 171.056989 -387.289738) (xy 171.114828 -387.316955)
			(xy 171.168799 -387.351206) (xy 171.218052 -387.391951) (xy 171.261809 -387.438548) (xy 171.299382 -387.490263)
			(xy 171.330176 -387.546278) (xy 171.353708 -387.605711) (xy 171.369605 -387.667625) (xy 171.377616 -387.731043)
			(xy 171.377719 -387.737604) (xy 173.18939 -387.737604) (xy 173.193461 -387.681982) (xy 173.205587 -387.627545)
			(xy 173.22551 -387.575454) (xy 173.252806 -387.526819) (xy 173.286892 -387.482676) (xy 173.327041 -387.443967)
			(xy 173.372399 -387.411516) (xy 173.421999 -387.386015) (xy 173.474783 -387.368008) (xy 173.529626 -387.357878)
			(xy 173.58536 -387.355841) (xy 173.640797 -387.361941) (xy 173.694754 -387.376047) (xy 173.746083 -387.397859)
			(xy 173.793689 -387.426913) (xy 173.81362 -387.4435) (xy 186.296061 -387.4435) (xy 186.300075 -387.379704)
			(xy 186.312052 -387.316913) (xy 186.331805 -387.256119) (xy 186.35902 -387.198279) (xy 186.39327 -387.144307)
			(xy 186.434014 -387.095052) (xy 186.48061 -387.051293) (xy 186.532323 -387.013718) (xy 186.588337 -386.98292)
			(xy 186.64777 -386.959385) (xy 186.709683 -386.943484) (xy 186.773101 -386.935468) (xy 186.805062 -386.934964)
			(xy 186.81954 -386.935218) (xy 186.82985 -386.935068) (xy 186.849024 -386.92753) (xy 186.863702 -386.913071)
			(xy 186.868054 -386.903722) (xy 186.881222 -386.873118) (xy 186.914505 -386.815399) (xy 186.95504 -386.762522)
			(xy 187.002135 -386.715392) (xy 187.054982 -386.674817) (xy 187.112676 -386.641491) (xy 187.174227 -386.615985)
			(xy 187.238583 -386.598738) (xy 187.30464 -386.590043) (xy 187.337954 -386.589524) (xy 187.370314 -386.589997)
			(xy 187.434517 -386.598154) (xy 187.46597 -386.60578) (xy 187.475996 -386.607964) (xy 187.496284 -386.605026)
			(xy 187.513764 -386.594315) (xy 187.520072 -386.586222) (xy 187.537943 -386.561743) (xy 187.578656 -386.516842)
			(xy 187.62442 -386.4771) (xy 187.674584 -386.443081) (xy 187.728438 -386.415269) (xy 187.785216 -386.394056)
			(xy 187.844113 -386.379745) (xy 187.904294 -386.372539) (xy 187.9346 -386.3721) (xy 187.966562 -386.372586)
			(xy 188.029981 -386.380598) (xy 188.091895 -386.396495) (xy 188.15133 -386.420026) (xy 188.207346 -386.450821)
			(xy 188.259061 -386.488395) (xy 188.305659 -386.532153) (xy 188.346405 -386.581406) (xy 188.380656 -386.635378)
			(xy 188.407873 -386.693218) (xy 188.427627 -386.754012) (xy 188.439605 -386.816803) (xy 188.443619 -386.8806)
			(xy 188.439605 -386.944397) (xy 188.427627 -387.007188) (xy 188.407873 -387.067982) (xy 188.380656 -387.125822)
			(xy 188.346405 -387.179794) (xy 188.305659 -387.229047) (xy 188.259061 -387.272805) (xy 188.207346 -387.310379)
			(xy 188.15133 -387.341174) (xy 188.091895 -387.364705) (xy 188.029981 -387.380602) (xy 187.966562 -387.388614)
			(xy 187.9346 -387.389116) (xy 187.90224 -387.388635) (xy 187.838037 -387.380483) (xy 187.806584 -387.37286)
			(xy 187.796561 -387.37066) (xy 187.776273 -387.373613) (xy 187.758793 -387.384326) (xy 187.752482 -387.392418)
			(xy 187.73456 -387.416858) (xy 187.693855 -387.461763) (xy 187.6481 -387.501508) (xy 187.597944 -387.535532)
			(xy 187.544098 -387.56335) (xy 187.487326 -387.584568) (xy 187.428434 -387.598885) (xy 187.368258 -387.606098)
			(xy 187.337954 -387.60654) (xy 187.323476 -387.606286) (xy 187.313167 -387.606446) (xy 187.293992 -387.613979)
			(xy 187.279314 -387.628434) (xy 187.274962 -387.637782) (xy 187.265116 -387.660642) (xy 192.191384 -387.660642)
			(xy 192.195455 -387.60502) (xy 192.207581 -387.550583) (xy 192.227504 -387.498492) (xy 192.2548 -387.449857)
			(xy 192.288886 -387.405714) (xy 192.329035 -387.367005) (xy 192.374393 -387.334554) (xy 192.423993 -387.309053)
			(xy 192.476777 -387.291046) (xy 192.53162 -387.280916) (xy 192.587354 -387.278879) (xy 192.642791 -387.284979)
			(xy 192.696748 -387.299085) (xy 192.748077 -387.320897) (xy 192.795683 -387.349951) (xy 192.838551 -387.385626)
			(xy 192.875768 -387.427163) (xy 192.906541 -387.473676) (xy 192.930213 -387.524173) (xy 192.946281 -387.57758)
			(xy 192.954401 -387.632756) (xy 192.95491 -387.660642) (xy 192.954401 -387.688528) (xy 192.946281 -387.743704)
			(xy 192.930213 -387.797111) (xy 192.906541 -387.847608) (xy 192.875768 -387.894121) (xy 192.838551 -387.935658)
			(xy 192.795683 -387.971333) (xy 192.748077 -388.000387) (xy 192.696748 -388.022199) (xy 192.642791 -388.036305)
			(xy 192.587354 -388.042405) (xy 192.53162 -388.040368) (xy 192.476777 -388.030238) (xy 192.423993 -388.012231)
			(xy 192.374393 -387.98673) (xy 192.329035 -387.954279) (xy 192.288886 -387.91557) (xy 192.2548 -387.871427)
			(xy 192.227504 -387.822792) (xy 192.207581 -387.770701) (xy 192.195455 -387.716264) (xy 192.191384 -387.660642)
			(xy 187.265116 -387.660642) (xy 187.261783 -387.668381) (xy 187.228501 -387.726099) (xy 187.187967 -387.778976)
			(xy 187.140873 -387.826106) (xy 187.088028 -387.866682) (xy 187.030336 -387.900008) (xy 186.968785 -387.925514)
			(xy 186.904431 -387.942764) (xy 186.838375 -387.95146) (xy 186.805062 -387.95198) (xy 186.773101 -387.951532)
			(xy 186.709683 -387.943516) (xy 186.64777 -387.927615) (xy 186.588337 -387.90408) (xy 186.532323 -387.873282)
			(xy 186.48061 -387.835707) (xy 186.434014 -387.791948) (xy 186.39327 -387.742693) (xy 186.35902 -387.68872)
			(xy 186.331805 -387.630881) (xy 186.312052 -387.570087) (xy 186.300075 -387.507296) (xy 186.296061 -387.4435)
			(xy 173.81362 -387.4435) (xy 173.836557 -387.462588) (xy 173.873774 -387.504125) (xy 173.904547 -387.550638)
			(xy 173.928219 -387.601135) (xy 173.944287 -387.654542) (xy 173.952407 -387.709718) (xy 173.952916 -387.737604)
			(xy 173.952407 -387.76549) (xy 173.944287 -387.820666) (xy 173.928219 -387.874073) (xy 173.904547 -387.92457)
			(xy 173.873774 -387.971083) (xy 173.836557 -388.01262) (xy 173.793689 -388.048295) (xy 173.746083 -388.077349)
			(xy 173.694754 -388.099161) (xy 173.640797 -388.113267) (xy 173.58536 -388.119367) (xy 173.529626 -388.11733)
			(xy 173.474783 -388.1072) (xy 173.421999 -388.089193) (xy 173.372399 -388.063692) (xy 173.327041 -388.031241)
			(xy 173.286892 -387.992532) (xy 173.252806 -387.948389) (xy 173.22551 -387.899754) (xy 173.205587 -387.847663)
			(xy 173.193461 -387.793226) (xy 173.18939 -387.737604) (xy 171.377719 -387.737604) (xy 171.378118 -387.763004)
			(xy 171.377689 -387.793114) (xy 171.370555 -387.85291) (xy 171.356412 -387.911445) (xy 171.335458 -387.967902)
			(xy 171.307984 -388.021489) (xy 171.274377 -388.071459) (xy 171.235105 -388.117111) (xy 171.190718 -388.157808)
			(xy 171.166536 -388.175754) (xy 171.157102 -388.18341) (xy 171.146086 -388.205023) (xy 171.145454 -388.217156)
			(xy 171.145454 -388.299452) (xy 171.146116 -388.311579) (xy 171.157113 -388.333193) (xy 171.166536 -388.340854)
			(xy 171.190758 -388.358749) (xy 171.235156 -388.399443) (xy 171.274435 -388.445097) (xy 171.308044 -388.495073)
			(xy 171.335511 -388.548671) (xy 171.356453 -388.605139) (xy 171.370575 -388.663686) (xy 171.377679 -388.723491)
			(xy 171.378118 -388.753604) (xy 173.18939 -388.753604) (xy 173.193461 -388.697982) (xy 173.205587 -388.643545)
			(xy 173.22551 -388.591454) (xy 173.252806 -388.542819) (xy 173.286892 -388.498676) (xy 173.327041 -388.459967)
			(xy 173.372399 -388.427516) (xy 173.421999 -388.402015) (xy 173.474783 -388.384008) (xy 173.529626 -388.373878)
			(xy 173.58536 -388.371841) (xy 173.640797 -388.377941) (xy 173.694754 -388.392047) (xy 173.746083 -388.413859)
			(xy 173.793689 -388.442913) (xy 173.836557 -388.478588) (xy 173.873774 -388.520125) (xy 173.904547 -388.566638)
			(xy 173.928219 -388.617135) (xy 173.944287 -388.670542) (xy 173.952407 -388.725718) (xy 173.952916 -388.753604)
			(xy 173.952407 -388.78149) (xy 173.944287 -388.836666) (xy 173.928219 -388.890073) (xy 173.904547 -388.94057)
			(xy 173.873774 -388.987083) (xy 173.836557 -389.02862) (xy 173.793689 -389.064295) (xy 173.761793 -389.083761)
			(xy 179.082694 -389.083761) (xy 179.082694 -389.019839) (xy 179.090705 -388.956421) (xy 179.106602 -388.894507)
			(xy 179.130134 -388.835074) (xy 179.160928 -388.779059) (xy 179.198501 -388.727344) (xy 179.242258 -388.680747)
			(xy 179.291511 -388.640002) (xy 179.345482 -388.605751) (xy 179.403321 -388.578534) (xy 179.464114 -388.558781)
			(xy 179.526904 -388.546803) (xy 179.5907 -388.54279) (xy 179.654496 -388.546803) (xy 179.717286 -388.558781)
			(xy 179.778079 -388.578534) (xy 179.835918 -388.605751) (xy 179.889889 -388.640002) (xy 179.939142 -388.680747)
			(xy 179.982899 -388.727344) (xy 180.020472 -388.779059) (xy 180.051266 -388.835074) (xy 180.074798 -388.894507)
			(xy 180.090695 -388.956421) (xy 180.098706 -389.019839) (xy 180.099208 -389.0518) (xy 180.098706 -389.083761)
			(xy 180.090695 -389.147179) (xy 180.074798 -389.209093) (xy 180.051266 -389.268526) (xy 180.020472 -389.324541)
			(xy 179.982899 -389.376256) (xy 179.939142 -389.422853) (xy 179.889889 -389.463598) (xy 179.835918 -389.497849)
			(xy 179.778079 -389.525066) (xy 179.717286 -389.544819) (xy 179.654496 -389.556797) (xy 179.5907 -389.560811)
			(xy 179.526904 -389.556797) (xy 179.464114 -389.544819) (xy 179.403321 -389.525066) (xy 179.345482 -389.497849)
			(xy 179.291511 -389.463598) (xy 179.242258 -389.422853) (xy 179.198501 -389.376256) (xy 179.160928 -389.324541)
			(xy 179.130134 -389.268526) (xy 179.106602 -389.209093) (xy 179.090705 -389.147179) (xy 179.082694 -389.083761)
			(xy 173.761793 -389.083761) (xy 173.746083 -389.093349) (xy 173.694754 -389.115161) (xy 173.640797 -389.129267)
			(xy 173.58536 -389.135367) (xy 173.529626 -389.13333) (xy 173.474783 -389.1232) (xy 173.421999 -389.105193)
			(xy 173.372399 -389.079692) (xy 173.327041 -389.047241) (xy 173.286892 -389.008532) (xy 173.252806 -388.964389)
			(xy 173.22551 -388.915754) (xy 173.205587 -388.863663) (xy 173.193461 -388.809226) (xy 173.18939 -388.753604)
			(xy 171.378118 -388.753604) (xy 171.377616 -388.785565) (xy 171.369605 -388.848983) (xy 171.353708 -388.910897)
			(xy 171.330176 -388.97033) (xy 171.299382 -389.026345) (xy 171.261809 -389.07806) (xy 171.218052 -389.124657)
			(xy 171.168799 -389.165402) (xy 171.114828 -389.199653) (xy 171.056989 -389.22687) (xy 170.996196 -389.246623)
			(xy 170.933406 -389.258601) (xy 170.86961 -389.262615) (xy 170.805814 -389.258601) (xy 170.743024 -389.246623)
			(xy 170.682231 -389.22687) (xy 170.624392 -389.199653) (xy 170.570421 -389.165402) (xy 170.521168 -389.124657)
			(xy 170.477411 -389.07806) (xy 170.439838 -389.026345) (xy 170.409044 -388.97033) (xy 170.385512 -388.910897)
			(xy 170.369615 -388.848983) (xy 170.361604 -388.785565) (xy 170.361102 -388.753604) (xy 169.494483 -388.753604)
			(xy 169.494708 -388.76605) (xy 169.494222 -388.793301) (xy 169.486466 -388.847249) (xy 169.471111 -388.899544)
			(xy 169.448469 -388.949121) (xy 169.419003 -388.994971) (xy 169.383312 -389.036162) (xy 169.342121 -389.071853)
			(xy 169.296271 -389.101319) (xy 169.246694 -389.123961) (xy 169.194399 -389.139316) (xy 169.140451 -389.147072)
			(xy 169.085949 -389.147072) (xy 169.032001 -389.139316) (xy 168.979706 -389.123961) (xy 168.930129 -389.101319)
			(xy 168.884279 -389.071853) (xy 168.843088 -389.036162) (xy 168.807397 -388.994971) (xy 168.777931 -388.949121)
			(xy 168.755289 -388.899544) (xy 168.739934 -388.847249) (xy 168.732178 -388.793301) (xy 168.731692 -388.76605)
			(xy 168.732166 -388.738716) (xy 168.739974 -388.68461) (xy 168.755423 -388.632171) (xy 168.778197 -388.582473)
			(xy 168.807829 -388.536534) (xy 168.825418 -388.515606) (xy 168.832276 -388.507478) (xy 168.838626 -388.48792)
			(xy 168.829228 -388.393178) (xy 168.819322 -388.375144) (xy 168.810686 -388.36854) (xy 168.784713 -388.347859)
			(xy 168.737875 -388.300801) (xy 168.69756 -388.248048) (xy 168.664454 -388.190496) (xy 168.63912 -388.129125)
			(xy 168.62199 -388.064978) (xy 168.613355 -387.999147) (xy 168.61282 -387.96595) (xy 168.613231 -387.936208)
			(xy 168.62018 -387.877132) (xy 168.633977 -387.819271) (xy 168.643808 -387.791198) (xy 168.648634 -387.778244)
			(xy 168.643808 -387.751828) (xy 168.56964 -387.662928) (xy 168.544494 -387.653784) (xy 168.530778 -387.656324)
			(xy 168.508921 -387.659915) (xy 168.464789 -387.663732) (xy 168.44264 -387.663944) (xy 168.41191 -387.663425)
			(xy 168.350898 -387.656021) (xy 168.291223 -387.641318) (xy 168.233756 -387.619528) (xy 168.179333 -387.590971)
			(xy 168.12875 -387.556061) (xy 168.082744 -387.51531) (xy 168.041985 -387.469309) (xy 168.007069 -387.418732)
			(xy 167.978503 -387.364314) (xy 167.956705 -387.30685) (xy 167.941992 -387.247177) (xy 167.93458 -387.186166)
			(xy 167.934132 -387.155436) (xy 167.934586 -387.124739) (xy 167.941992 -387.063793) (xy 167.956688 -387.004184)
			(xy 167.978461 -386.94678) (xy 168.006992 -386.892419) (xy 168.024048 -386.866892) (xy 168.029485 -386.858122)
			(xy 168.03362 -386.83793) (xy 168.029509 -386.817733) (xy 168.024048 -386.80898) (xy 168.007012 -386.783443)
			(xy 167.978502 -386.729075) (xy 167.956738 -386.671673) (xy 167.942037 -386.612069) (xy 167.934613 -386.55113)
			(xy 167.934132 -386.520436) (xy 167.93464 -386.499354) (xy 167.935148 -386.488432) (xy 167.927528 -386.468874)
			(xy 167.859202 -386.400548) (xy 167.839644 -386.392928) (xy 167.828722 -386.393436) (xy 167.80764 -386.393944)
			(xy 167.77691 -386.393425) (xy 167.715898 -386.386021) (xy 167.656223 -386.371318) (xy 167.598756 -386.349528)
			(xy 167.544333 -386.320971) (xy 167.49375 -386.286061) (xy 167.447744 -386.24531) (xy 167.406985 -386.199309)
			(xy 167.372069 -386.148732) (xy 167.343503 -386.094314) (xy 167.321705 -386.03685) (xy 167.306992 -385.977177)
			(xy 167.29958 -385.916166) (xy 167.299132 -385.885436) (xy 167.299527 -385.857224) (xy 167.305796 -385.801149)
			(xy 167.318219 -385.74611) (xy 167.327072 -385.71932) (xy 167.330374 -385.709414) (xy 167.329104 -385.68884)
			(xy 167.285416 -385.604766) (xy 167.269668 -385.591558) (xy 167.259508 -385.588764) (xy 167.23136 -385.580059)
			(xy 167.177391 -385.556417) (xy 167.126901 -385.526046) (xy 167.080724 -385.489449) (xy 167.039625 -385.44723)
			(xy 167.004281 -385.400088) (xy 166.975277 -385.348801) (xy 166.953093 -385.294216) (xy 166.938094 -385.237237)
			(xy 166.93053 -385.178804) (xy 166.93007 -385.149344) (xy 165.847072 -385.149344) (xy 165.853266 -385.164449)
			(xy 165.868502 -385.221828) (xy 165.876193 -385.280696) (xy 165.876732 -385.31038) (xy 165.876212 -385.341443)
			(xy 165.867797 -385.402997) (xy 165.859968 -385.433062) (xy 165.857174 -385.443222) (xy 165.859714 -385.463034)
			(xy 165.907212 -385.54533) (xy 165.923214 -385.557522) (xy 165.933374 -385.560062) (xy 165.962481 -385.568067)
			(xy 166.018448 -385.590697) (xy 166.070954 -385.620488) (xy 166.119086 -385.656924) (xy 166.16201 -385.699373)
			(xy 166.198981 -385.747096) (xy 166.229356 -385.799266) (xy 166.252607 -385.854977) (xy 166.268332 -385.913262)
			(xy 166.276258 -385.973108) (xy 166.276782 -386.003292) (xy 166.27668 -386.017042) (xy 166.275028 -386.044493)
			(xy 166.27348 -386.058156) (xy 166.272744 -386.066845) (xy 166.276522 -386.083856) (xy 166.280846 -386.09143)
			(xy 166.296848 -386.11683) (xy 166.301632 -386.123853) (xy 166.314869 -386.134494) (xy 166.322756 -386.137658)
			(xy 166.346509 -386.146635) (xy 166.391153 -386.170824) (xy 166.431576 -386.201553) (xy 166.466826 -386.2381)
			(xy 166.496077 -386.279605) (xy 166.51864 -386.325093) (xy 166.533985 -386.373495) (xy 166.541752 -386.423674)
			(xy 166.542212 -386.449062) (xy 166.541732 -386.475053) (xy 166.533605 -386.526397) (xy 166.517546 -386.575837)
			(xy 166.493951 -386.622155) (xy 166.463399 -386.664212) (xy 166.426644 -386.700972) (xy 166.384591 -386.731529)
			(xy 166.338275 -386.75513) (xy 166.288838 -386.771195) (xy 166.237495 -386.779328) (xy 166.211504 -386.77977)
			(xy 166.186599 -386.779313) (xy 166.137354 -386.771832) (xy 166.089787 -386.757054) (xy 166.044972 -386.735313)
			(xy 166.003922 -386.7071) (xy 165.967565 -386.673053) (xy 165.936723 -386.63394) (xy 165.912092 -386.590647)
			(xy 165.894228 -386.54415) (xy 165.888416 -386.519928) (xy 165.886329 -386.511677) (xy 165.877502 -386.497138)
			(xy 165.871144 -386.49148) (xy 165.847776 -386.47243) (xy 165.840868 -386.467261) (xy 165.824644 -386.461423)
			(xy 165.816026 -386.461) (xy 165.785821 -386.460338) (xy 165.725978 -386.452032) (xy 165.667749 -386.435919)
			(xy 165.61215 -386.412278) (xy 165.560147 -386.381522) (xy 165.536118 -386.36321) (xy 165.524434 -386.354066)
			(xy 165.495986 -386.350764) (xy 165.400482 -386.397246) (xy 165.39208 -386.401744) (xy 165.379137 -386.415715)
			(xy 165.37218 -386.433444) (xy 165.37178 -386.442966) (xy 165.37178 -386.791962) (xy 165.372021 -386.799757)
			(xy 165.376679 -386.81463) (xy 165.380924 -386.821172) (xy 165.396679 -386.844341) (xy 165.423038 -386.893784)
			(xy 165.443159 -386.946076) (xy 165.456741 -387.000436) (xy 165.463579 -387.056047) (xy 165.463982 -387.084062)
			(xy 165.463378 -387.117382) (xy 165.453709 -387.183317) (xy 165.434584 -387.247153) (xy 165.421056 -387.27761)
			(xy 165.416794 -387.288079) (xy 165.416869 -387.310653) (xy 165.426623 -387.331012) (xy 165.435026 -387.33857)
			(xy 165.457273 -387.357244) (xy 165.497338 -387.3993) (xy 165.53176 -387.446086) (xy 165.559987 -387.49685)
			(xy 165.581565 -387.550778) (xy 165.596147 -387.607002) (xy 165.6035 -387.66462) (xy 165.603936 -387.693662)
			(xy 165.603485 -387.722666) (xy 165.596155 -387.78021) (xy 165.581619 -387.836368) (xy 165.56011 -387.890241)
			(xy 165.531973 -387.940969) (xy 165.497657 -387.987738) (xy 165.457712 -388.029802) (xy 165.435534 -388.0485)
			(xy 165.428422 -388.054088) (xy 165.419278 -388.069328) (xy 165.404038 -388.152132) (xy 165.406832 -388.169404)
			(xy 165.411404 -388.177532) (xy 165.423997 -388.200711) (xy 165.441884 -388.250331) (xy 165.450966 -388.302289)
			(xy 165.451536 -388.328662) (xy 165.451464 -388.33802) (xy 165.450318 -388.356702) (xy 165.44925 -388.366)
			(xy 165.448234 -388.37489) (xy 165.452044 -388.391654) (xy 165.495986 -388.461504) (xy 165.509702 -388.471918)
			(xy 165.518084 -388.474712) (xy 165.542121 -388.483164) (xy 165.587306 -388.506707) (xy 165.628122 -388.537203)
			(xy 165.663509 -388.573859) (xy 165.692549 -388.615723) (xy 165.714486 -388.661708) (xy 165.722046 -388.68604)
			(xy 165.72357 -388.691882) (xy 166.043864 -389.245602) (xy 166.047928 -389.24992) (xy 166.064144 -389.267619)
			(xy 166.091574 -389.307009) (xy 166.112719 -389.3501) (xy 166.127091 -389.395898) (xy 166.134357 -389.443344)
			(xy 166.134796 -389.467344) (xy 166.134331 -389.492147) (xy 166.126561 -389.54114) (xy 166.11122 -389.588314)
			(xy 166.088686 -389.632506) (xy 166.059513 -389.672627) (xy 166.024422 -389.707689) (xy 165.984276 -389.736827)
			(xy 165.940064 -389.759323) (xy 165.892877 -389.774624) (xy 165.843877 -389.782352) (xy 165.819074 -389.782812)
			(xy 165.793681 -389.782302) (xy 165.743552 -389.774168) (xy 165.695371 -389.758115) (xy 165.650381 -389.734555)
			(xy 165.609743 -389.704098) (xy 165.574504 -389.667528) (xy 165.545574 -389.625788) (xy 165.523698 -389.579956)
			(xy 165.516052 -389.555736) (xy 165.514528 -389.549894) (xy 165.466522 -389.46709) (xy 165.460457 -389.457739)
			(xy 165.442207 -389.444992) (xy 165.420277 -389.441157) (xy 165.409372 -389.443468) (xy 165.392608 -389.44804)
			(xy 165.37178 -389.475218) (xy 165.37178 -390.185989) (xy 166.04285 -390.185989) (xy 166.04285 -390.134015)
			(xy 166.05098 -390.08268) (xy 166.067041 -390.03325) (xy 166.090637 -389.98694) (xy 166.121187 -389.944892)
			(xy 166.157938 -389.908141) (xy 166.199986 -389.877591) (xy 166.246296 -389.853995) (xy 166.295726 -389.837934)
			(xy 166.347061 -389.829804) (xy 166.399035 -389.829804) (xy 166.45037 -389.837934) (xy 166.4998 -389.853995)
			(xy 166.54611 -389.877591) (xy 166.588158 -389.908141) (xy 166.624909 -389.944892) (xy 166.655459 -389.98694)
			(xy 166.679055 -390.03325) (xy 166.695116 -390.08268) (xy 166.703246 -390.134015) (xy 166.703756 -390.160002)
			(xy 166.703246 -390.185989) (xy 166.695116 -390.237324) (xy 166.679055 -390.286754) (xy 166.655459 -390.333064)
			(xy 166.624909 -390.375112) (xy 166.588158 -390.411863) (xy 166.54611 -390.442413) (xy 166.4998 -390.466009)
			(xy 166.45037 -390.48207) (xy 166.399035 -390.4902) (xy 166.347061 -390.4902) (xy 166.295726 -390.48207)
			(xy 166.246296 -390.466009) (xy 166.199986 -390.442413) (xy 166.157938 -390.411863) (xy 166.121187 -390.375112)
			(xy 166.090637 -390.333064) (xy 166.067041 -390.286754) (xy 166.05098 -390.237324) (xy 166.04285 -390.185989)
			(xy 165.37178 -390.185989) (xy 165.37178 -390.96315) (xy 165.372212 -390.973217) (xy 165.379937 -390.99181)
			(xy 165.386766 -390.999218) (xy 166.575486 -392.187938) (xy 166.582886 -392.194778) (xy 166.601485 -392.20249)
			(xy 166.611554 -392.202924) (xy 167.354758 -392.202924) (xy 167.36365 -392.20259) (xy 167.380359 -392.196505)
			(xy 167.393968 -392.18506) (xy 167.3987 -392.177524) (xy 167.4495 -392.089386) (xy 167.4495 -392.061954)
			(xy 167.442642 -392.05027) (xy 167.426249 -392.021031) (xy 167.400432 -391.959169) (xy 167.382952 -391.894455)
			(xy 167.374109 -391.828008) (xy 167.373554 -391.794492) (xy 167.374033 -391.763797) (xy 167.381455 -391.702857)
			(xy 167.396153 -391.643252) (xy 167.417915 -391.585848) (xy 167.446424 -391.531479) (xy 167.46347 -391.505948)
			(xy 167.468943 -391.497197) (xy 167.473071 -391.476993) (xy 167.468938 -391.456791) (xy 167.46347 -391.448036)
			(xy 167.446019 -391.421924) (xy 167.416988 -391.366229) (xy 167.395038 -391.307383) (xy 167.380504 -391.246281)
			(xy 167.376602 -391.215118) (xy 167.375253 -391.206193) (xy 167.367182 -391.19006) (xy 167.360854 -391.183622)
			(xy 167.338756 -391.162794) (xy 167.332098 -391.157057) (xy 167.315995 -391.150048) (xy 167.30726 -391.149078)
			(xy 167.282414 -391.147033) (xy 167.233705 -391.136417) (xy 167.187141 -391.11861) (xy 167.143777 -391.094018)
			(xy 167.104595 -391.063196) (xy 167.070482 -391.026843) (xy 167.042211 -390.985782) (xy 167.020422 -390.940943)
			(xy 167.00561 -390.893343) (xy 166.998108 -390.844058) (xy 166.997634 -390.819132) (xy 166.998042 -390.795393)
			(xy 167.004827 -390.748403) (xy 167.018264 -390.702867) (xy 167.038075 -390.65972) (xy 167.063853 -390.61985)
			(xy 167.079168 -390.601708) (xy 167.085915 -390.593325) (xy 167.092285 -390.572791) (xy 167.089678 -390.55145)
			(xy 167.084502 -390.542018) (xy 167.069029 -390.515232) (xy 167.044635 -390.458387) (xy 167.028105 -390.398779)
			(xy 167.01974 -390.337489) (xy 167.019224 -390.30656) (xy 167.019776 -390.274961) (xy 167.028503 -390.212369)
			(xy 167.045744 -390.151568) (xy 167.071173 -390.093711) (xy 167.087296 -390.06653) (xy 167.091842 -390.058314)
			(xy 167.095256 -390.039866) (xy 167.091817 -390.021422) (xy 167.087296 -390.01319) (xy 167.071155 -389.986016)
			(xy 167.045692 -389.928168) (xy 167.028444 -389.867363) (xy 167.01974 -389.804762) (xy 167.019224 -389.77316)
			(xy 167.01982 -389.739928) (xy 167.029436 -389.674163) (xy 167.048458 -389.610479) (xy 167.076489 -389.550215)
			(xy 167.112938 -389.494636) (xy 167.13454 -389.469376) (xy 167.14089 -389.462264) (xy 167.147494 -389.444992)
			(xy 167.147494 -389.358886) (xy 167.14089 -389.341614) (xy 167.13454 -389.334502) (xy 167.112982 -389.309252)
			(xy 167.07662 -389.253702) (xy 167.048657 -389.193486) (xy 167.02968 -389.129863) (xy 167.020086 -389.064168)
			(xy 167.019478 -389.030972) (xy 167.020027 -388.999148) (xy 167.02885 -388.936113) (xy 167.04632 -388.874909)
			(xy 167.072103 -388.816716) (xy 167.105699 -388.762656) (xy 167.12565 -388.737856) (xy 167.131492 -388.730744)
			(xy 167.137588 -388.713218) (xy 167.135048 -388.627112) (xy 167.127936 -388.610094) (xy 167.121586 -388.603236)
			(xy 167.102106 -388.581958) (xy 167.068098 -388.535357) (xy 167.04022 -388.484849) (xy 167.018915 -388.431236)
			(xy 167.004521 -388.37537) (xy 166.997267 -388.318137) (xy 166.996872 -388.289292) (xy 166.997363 -388.259324)
			(xy 167.005186 -388.199901) (xy 167.020699 -388.142008) (xy 167.043636 -388.086635) (xy 167.073603 -388.034729)
			(xy 167.11009 -387.987179) (xy 167.15247 -387.944797) (xy 167.200019 -387.90831) (xy 167.251924 -387.878341)
			(xy 167.307297 -387.855403) (xy 167.36519 -387.839889) (xy 167.424612 -387.832063) (xy 167.45458 -387.831584)
			(xy 167.484579 -387.832054) (xy 167.544062 -387.839892) (xy 167.602011 -387.855436) (xy 167.657432 -387.87842)
			(xy 167.709374 -387.908449) (xy 167.756946 -387.945008) (xy 167.799333 -387.987471) (xy 167.835807 -388.035109)
			(xy 167.865743 -388.087105) (xy 167.888627 -388.142566) (xy 167.896794 -388.171436) (xy 167.899716 -388.180765)
			(xy 167.911412 -388.196408) (xy 167.928117 -388.206529) (xy 167.937688 -388.20852) (xy 167.96649 -388.213769)
			(xy 168.022553 -388.230637) (xy 168.076007 -388.254517) (xy 168.125979 -388.285019) (xy 168.171653 -388.321646)
			(xy 168.212283 -388.363798) (xy 168.247205 -388.410788) (xy 168.275849 -388.461848) (xy 168.297747 -388.516144)
			(xy 168.312542 -388.572789) (xy 168.319992 -388.630859) (xy 168.320466 -388.660132) (xy 168.319942 -388.691246)
			(xy 168.31151 -388.752899) (xy 168.294805 -388.812843) (xy 168.270136 -388.869972) (xy 168.237957 -388.923233)
			(xy 168.19886 -388.971645) (xy 168.153568 -389.014316) (xy 168.102913 -389.05046) (xy 168.04783 -389.079411)
			(xy 167.989334 -389.100634) (xy 167.959024 -389.10768) (xy 167.949955 -389.110127) (xy 167.934312 -389.120496)
			(xy 167.923426 -389.135784) (xy 167.92067 -389.144764) (xy 167.912758 -389.173637) (xy 167.890445 -389.229192)
			(xy 167.86108 -389.281364) (xy 167.825164 -389.329261) (xy 167.804592 -389.351012) (xy 167.798034 -389.358335)
			(xy 167.790564 -389.376499) (xy 167.790114 -389.386318) (xy 167.78986 -389.417814) (xy 167.790318 -389.427692)
			(xy 167.797756 -389.445995) (xy 167.804338 -389.453374) (xy 167.80637 -389.455406) (xy 167.860218 -389.45312)
			(xy 167.870388 -389.452259) (xy 167.888863 -389.443621) (xy 167.896032 -389.436356) (xy 167.917838 -389.412718)
			(xy 167.966934 -389.371178) (xy 168.021359 -389.336917) (xy 168.080043 -389.310608) (xy 168.141831 -389.292769)
			(xy 168.205507 -389.283752) (xy 168.237662 -389.283194) (xy 168.267633 -389.283661) (xy 168.327061 -389.29148)
			(xy 168.384961 -389.30699) (xy 168.44034 -389.329925) (xy 168.492253 -389.359892) (xy 168.539809 -389.39638)
			(xy 168.582195 -389.438763) (xy 168.618686 -389.486316) (xy 168.648658 -389.538225) (xy 168.671598 -389.593603)
			(xy 168.687113 -389.651501) (xy 168.694937 -389.71093) (xy 168.694937 -389.77087) (xy 168.687113 -389.830299)
			(xy 168.671598 -389.888197) (xy 168.648658 -389.943575) (xy 168.639848 -389.958834) (xy 170.971462 -389.958834)
			(xy 170.975533 -389.903212) (xy 170.987659 -389.848775) (xy 171.007582 -389.796684) (xy 171.034878 -389.748049)
			(xy 171.068964 -389.703906) (xy 171.109113 -389.665197) (xy 171.154471 -389.632746) (xy 171.204071 -389.607245)
			(xy 171.256855 -389.589238) (xy 171.311698 -389.579108) (xy 171.367432 -389.577071) (xy 171.422869 -389.583171)
			(xy 171.476826 -389.597277) (xy 171.528155 -389.619089) (xy 171.575761 -389.648143) (xy 171.618629 -389.683818)
			(xy 171.655846 -389.725355) (xy 171.686619 -389.771868) (xy 171.710291 -389.822365) (xy 171.726359 -389.875772)
			(xy 171.734479 -389.930948) (xy 171.734988 -389.958834) (xy 171.734479 -389.98672) (xy 171.726359 -390.041896)
			(xy 171.710291 -390.095303) (xy 171.686619 -390.1458) (xy 171.655846 -390.192313) (xy 171.618629 -390.23385)
			(xy 171.611887 -390.239461) (xy 179.616094 -390.239461) (xy 179.616094 -390.175539) (xy 179.624105 -390.112121)
			(xy 179.640002 -390.050207) (xy 179.663534 -389.990774) (xy 179.694328 -389.934759) (xy 179.731901 -389.883044)
			(xy 179.775658 -389.836447) (xy 179.824911 -389.795702) (xy 179.878882 -389.761451) (xy 179.936721 -389.734234)
			(xy 179.997514 -389.714481) (xy 180.060304 -389.702503) (xy 180.1241 -389.69849) (xy 180.187896 -389.702503)
			(xy 180.250686 -389.714481) (xy 180.311479 -389.734234) (xy 180.369318 -389.761451) (xy 180.423289 -389.795702)
			(xy 180.472542 -389.836447) (xy 180.516299 -389.883044) (xy 180.553872 -389.934759) (xy 180.558869 -389.943848)
			(xy 180.81117 -389.943848) (xy 180.811701 -389.915232) (xy 180.820257 -389.858644) (xy 180.83717 -389.803969)
			(xy 180.86206 -389.752434) (xy 180.894368 -389.705194) (xy 180.93337 -389.66331) (xy 180.978191 -389.627722)
			(xy 181.027825 -389.599228) (xy 181.081158 -389.578468) (xy 181.136994 -389.565906) (xy 181.1655 -389.563356)
			(xy 181.174898 -389.562594) (xy 181.191662 -389.55472) (xy 181.252114 -389.491982) (xy 181.25948 -389.474964)
			(xy 181.259734 -389.465312) (xy 181.261058 -389.438542) (xy 181.270285 -389.385743) (xy 181.286816 -389.334758)
			(xy 181.310325 -389.28659) (xy 181.340348 -389.242189) (xy 181.376293 -389.20243) (xy 181.417453 -389.168098)
			(xy 181.463015 -389.139869) (xy 181.512082 -389.118299) (xy 181.563686 -389.103814) (xy 181.590188 -389.099806)
			(xy 181.599332 -389.098536) (xy 181.615842 -389.0899) (xy 181.671976 -389.024368) (xy 181.678326 -389.006842)
			(xy 181.678072 -388.997444) (xy 181.678072 -388.990586) (xy 181.678558 -388.963335) (xy 181.686314 -388.909387)
			(xy 181.701669 -388.857092) (xy 181.724311 -388.807515) (xy 181.753777 -388.761665) (xy 181.789468 -388.720474)
			(xy 181.830659 -388.684783) (xy 181.876509 -388.655317) (xy 181.926086 -388.632675) (xy 181.978381 -388.61732)
			(xy 182.032329 -388.609564) (xy 182.086831 -388.609564) (xy 182.140779 -388.61732) (xy 182.193074 -388.632675)
			(xy 182.242651 -388.655317) (xy 182.288501 -388.684783) (xy 182.329692 -388.720474) (xy 182.365383 -388.761665)
			(xy 182.394849 -388.807515) (xy 182.417491 -388.857092) (xy 182.432846 -388.909387) (xy 182.440602 -388.963335)
			(xy 182.441088 -388.990586) (xy 182.440613 -389.018022) (xy 182.43278 -389.07233) (xy 182.417244 -389.124955)
			(xy 182.394328 -389.174811) (xy 182.364502 -389.220868) (xy 182.328384 -389.262175) (xy 182.286719 -389.29788)
			(xy 182.240368 -389.327244) (xy 182.190286 -389.349663) (xy 182.137509 -389.364674) (xy 182.11038 -389.368792)
			(xy 182.101236 -389.370062) (xy 182.084726 -389.378698) (xy 182.028592 -389.44423) (xy 182.022242 -389.461756)
			(xy 182.022496 -389.471154) (xy 182.022496 -389.478012) (xy 182.02196 -389.506626) (xy 182.013397 -389.563211)
			(xy 181.996479 -389.617882) (xy 181.971587 -389.669414) (xy 181.939279 -389.71665) (xy 181.900278 -389.758532)
			(xy 181.855461 -389.79412) (xy 181.805831 -389.822616) (xy 181.752502 -389.843381) (xy 181.696671 -389.855949)
			(xy 181.668166 -389.858504) (xy 181.658768 -389.859266) (xy 181.642004 -389.86714) (xy 181.581552 -389.929878)
			(xy 181.574186 -389.946896) (xy 181.573932 -389.956548) (xy 181.572616 -389.983193) (xy 181.563436 -390.035746)
			(xy 181.547022 -390.086506) (xy 181.523695 -390.134485) (xy 181.493912 -390.178745) (xy 181.458251 -390.218423)
			(xy 181.41741 -390.252746) (xy 181.372185 -390.281043) (xy 181.323458 -390.302763) (xy 181.272181 -390.317482)
			(xy 181.219352 -390.324912) (xy 181.192678 -390.325356) (xy 181.165428 -390.324843) (xy 181.111484 -390.317085)
			(xy 181.059193 -390.301729) (xy 181.009619 -390.279089) (xy 180.963771 -390.249625) (xy 180.922582 -390.213936)
			(xy 180.886891 -390.17275) (xy 180.857424 -390.126904) (xy 180.83478 -390.077332) (xy 180.819421 -390.025041)
			(xy 180.811659 -389.971098) (xy 180.81117 -389.943848) (xy 180.558869 -389.943848) (xy 180.584666 -389.990774)
			(xy 180.608198 -390.050207) (xy 180.624095 -390.112121) (xy 180.632106 -390.175539) (xy 180.632608 -390.2075)
			(xy 180.632106 -390.239461) (xy 180.624095 -390.302879) (xy 180.608198 -390.364793) (xy 180.584666 -390.424226)
			(xy 180.553872 -390.480241) (xy 180.516299 -390.531956) (xy 180.472542 -390.578553) (xy 180.423289 -390.619298)
			(xy 180.369318 -390.653549) (xy 180.311479 -390.680766) (xy 180.250686 -390.700519) (xy 180.187896 -390.712497)
			(xy 180.1241 -390.716511) (xy 180.060304 -390.712497) (xy 179.997514 -390.700519) (xy 179.936721 -390.680766)
			(xy 179.878882 -390.653549) (xy 179.824911 -390.619298) (xy 179.775658 -390.578553) (xy 179.731901 -390.531956)
			(xy 179.694328 -390.480241) (xy 179.663534 -390.424226) (xy 179.640002 -390.364793) (xy 179.624105 -390.302879)
			(xy 179.616094 -390.239461) (xy 171.611887 -390.239461) (xy 171.575761 -390.269525) (xy 171.528155 -390.298579)
			(xy 171.476826 -390.320391) (xy 171.422869 -390.334497) (xy 171.367432 -390.340597) (xy 171.311698 -390.33856)
			(xy 171.256855 -390.32843) (xy 171.204071 -390.310423) (xy 171.154471 -390.284922) (xy 171.109113 -390.252471)
			(xy 171.068964 -390.213762) (xy 171.034878 -390.169619) (xy 171.007582 -390.120984) (xy 170.987659 -390.068893)
			(xy 170.975533 -390.014456) (xy 170.971462 -389.958834) (xy 168.639848 -389.958834) (xy 168.618686 -389.995484)
			(xy 168.582195 -390.043037) (xy 168.539809 -390.08542) (xy 168.492253 -390.121908) (xy 168.44034 -390.151875)
			(xy 168.384961 -390.17481) (xy 168.327061 -390.19032) (xy 168.267633 -390.198139) (xy 168.237662 -390.19861)
			(xy 168.209275 -390.198202) (xy 168.152933 -390.191211) (xy 168.097891 -390.177292) (xy 168.071292 -390.167368)
			(xy 168.0591 -390.162542) (xy 168.033192 -390.166098) (xy 167.943022 -390.233154) (xy 167.9321 -390.25703)
			(xy 167.933116 -390.269984) (xy 167.93464 -390.30656) (xy 167.934101 -390.338305) (xy 167.925334 -390.401187)
			(xy 167.907963 -390.462255) (xy 167.88232 -390.520336) (xy 167.86606 -390.547606) (xy 167.861762 -390.555179)
			(xy 167.858038 -390.572178) (xy 167.86021 -390.589443) (xy 167.863774 -390.59739) (xy 167.877744 -390.624568)
			(xy 167.882011 -390.632209) (xy 167.894699 -390.644243) (xy 167.910702 -390.651295) (xy 167.9194 -390.652254)
			(xy 167.92575 -390.652762) (xy 167.936088 -390.653148) (xy 167.955704 -390.646637) (xy 167.971182 -390.632939)
			(xy 167.976042 -390.623806) (xy 167.990128 -390.595162) (xy 168.024406 -390.541316) (xy 168.065153 -390.492181)
			(xy 168.111727 -390.448532) (xy 168.163397 -390.411053) (xy 168.219351 -390.380335) (xy 168.278709 -390.356859)
			(xy 168.340538 -390.340996) (xy 168.403866 -390.332994) (xy 168.435782 -390.332468) (xy 168.466514 -390.332931)
			(xy 168.527531 -390.340338) (xy 168.58721 -390.355045) (xy 168.644681 -390.376838) (xy 168.699106 -390.4054)
			(xy 168.749692 -390.440314) (xy 168.7957 -390.48107) (xy 168.83646 -390.527075) (xy 168.871378 -390.577658)
			(xy 168.899945 -390.632081) (xy 168.921743 -390.68955) (xy 168.927201 -390.71169) (xy 170.4627 -390.71169)
			(xy 170.466771 -390.656068) (xy 170.478897 -390.601631) (xy 170.49882 -390.54954) (xy 170.526116 -390.500905)
			(xy 170.560202 -390.456762) (xy 170.600351 -390.418053) (xy 170.645709 -390.385602) (xy 170.695309 -390.360101)
			(xy 170.748093 -390.342094) (xy 170.802936 -390.331964) (xy 170.85867 -390.329927) (xy 170.914107 -390.336027)
			(xy 170.968064 -390.350133) (xy 171.019393 -390.371945) (xy 171.066999 -390.400999) (xy 171.109867 -390.436674)
			(xy 171.147084 -390.478211) (xy 171.177857 -390.524724) (xy 171.201529 -390.575221) (xy 171.217597 -390.628628)
			(xy 171.225717 -390.683804) (xy 171.226226 -390.71169) (xy 171.225717 -390.739576) (xy 171.217597 -390.794752)
			(xy 171.201529 -390.848159) (xy 171.177857 -390.898656) (xy 171.161739 -390.923018) (xy 172.850046 -390.923018)
			(xy 172.854117 -390.867396) (xy 172.866243 -390.812959) (xy 172.886166 -390.760868) (xy 172.913462 -390.712233)
			(xy 172.947548 -390.66809) (xy 172.987697 -390.629381) (xy 173.033055 -390.59693) (xy 173.082655 -390.571429)
			(xy 173.135439 -390.553422) (xy 173.190282 -390.543292) (xy 173.246016 -390.541255) (xy 173.301453 -390.547355)
			(xy 173.35541 -390.561461) (xy 173.406739 -390.583273) (xy 173.454345 -390.612327) (xy 173.497213 -390.648002)
			(xy 173.53443 -390.689539) (xy 173.565203 -390.736052) (xy 173.588875 -390.786549) (xy 173.604943 -390.839956)
			(xy 173.613063 -390.895132) (xy 173.613572 -390.923018) (xy 173.613063 -390.950904) (xy 173.604943 -391.00608)
			(xy 173.588875 -391.059487) (xy 173.565203 -391.109984) (xy 173.53443 -391.156497) (xy 173.497213 -391.198034)
			(xy 173.454345 -391.233709) (xy 173.406739 -391.262763) (xy 173.35541 -391.284575) (xy 173.301453 -391.298681)
			(xy 173.246016 -391.304781) (xy 173.190282 -391.302744) (xy 173.135439 -391.292614) (xy 173.082655 -391.274607)
			(xy 173.033055 -391.249106) (xy 172.987697 -391.216655) (xy 172.947548 -391.177946) (xy 172.913462 -391.133803)
			(xy 172.886166 -391.085168) (xy 172.866243 -391.033077) (xy 172.854117 -390.97864) (xy 172.850046 -390.923018)
			(xy 171.161739 -390.923018) (xy 171.147084 -390.945169) (xy 171.109867 -390.986706) (xy 171.066999 -391.022381)
			(xy 171.019393 -391.051435) (xy 170.968064 -391.073247) (xy 170.914107 -391.087353) (xy 170.85867 -391.093453)
			(xy 170.802936 -391.091416) (xy 170.748093 -391.081286) (xy 170.695309 -391.063279) (xy 170.645709 -391.037778)
			(xy 170.600351 -391.005327) (xy 170.560202 -390.966618) (xy 170.526116 -390.922475) (xy 170.49882 -390.87384)
			(xy 170.478897 -390.821749) (xy 170.466771 -390.767312) (xy 170.4627 -390.71169) (xy 168.927201 -390.71169)
			(xy 168.936455 -390.749228) (xy 168.943866 -390.810244) (xy 168.94429 -390.840976) (xy 168.943813 -390.871672)
			(xy 168.936395 -390.932614) (xy 168.921701 -390.992221) (xy 168.899943 -391.049628) (xy 168.871439 -391.104001)
			(xy 168.854374 -391.12952) (xy 168.848899 -391.138273) (xy 168.844764 -391.15848) (xy 168.848883 -391.178691)
			(xy 168.854374 -391.187432) (xy 168.871427 -391.212959) (xy 168.899953 -391.267322) (xy 168.92172 -391.324726)
			(xy 168.936411 -391.384335) (xy 168.943812 -391.44528) (xy 168.94429 -391.475976) (xy 168.943813 -391.506672)
			(xy 168.936395 -391.567614) (xy 168.921701 -391.627221) (xy 168.899943 -391.684628) (xy 168.892016 -391.69975)
			(xy 170.971462 -391.69975) (xy 170.975533 -391.644128) (xy 170.987659 -391.589691) (xy 171.007582 -391.5376)
			(xy 171.034878 -391.488965) (xy 171.068964 -391.444822) (xy 171.109113 -391.406113) (xy 171.154471 -391.373662)
			(xy 171.204071 -391.348161) (xy 171.256855 -391.330154) (xy 171.311698 -391.320024) (xy 171.367432 -391.317987)
			(xy 171.422869 -391.324087) (xy 171.476826 -391.338193) (xy 171.528155 -391.360005) (xy 171.575761 -391.389059)
			(xy 171.618629 -391.424734) (xy 171.655846 -391.466271) (xy 171.686619 -391.512784) (xy 171.710291 -391.563281)
			(xy 171.726359 -391.616688) (xy 171.731138 -391.649161) (xy 179.082694 -391.649161) (xy 179.082694 -391.585239)
			(xy 179.090705 -391.521821) (xy 179.106602 -391.459907) (xy 179.130134 -391.400474) (xy 179.160928 -391.344459)
			(xy 179.198501 -391.292744) (xy 179.242258 -391.246147) (xy 179.291511 -391.205402) (xy 179.345482 -391.171151)
			(xy 179.403321 -391.143934) (xy 179.464114 -391.124181) (xy 179.526904 -391.112203) (xy 179.5907 -391.10819)
			(xy 179.654496 -391.112203) (xy 179.717286 -391.124181) (xy 179.778079 -391.143934) (xy 179.835918 -391.171151)
			(xy 179.889889 -391.205402) (xy 179.939142 -391.246147) (xy 179.982899 -391.292744) (xy 180.020472 -391.344459)
			(xy 180.047112 -391.392918) (xy 180.837078 -391.392918) (xy 180.837574 -391.364301) (xy 180.846134 -391.307711)
			(xy 180.863052 -391.253035) (xy 180.887946 -391.201499) (xy 180.920258 -391.154259) (xy 180.959264 -391.112376)
			(xy 181.004089 -391.076788) (xy 181.053726 -391.048295) (xy 181.107062 -391.027536) (xy 181.1629 -391.014976)
			(xy 181.191408 -391.012426) (xy 181.200806 -391.011664) (xy 181.21757 -391.00379) (xy 181.278022 -390.941052)
			(xy 181.285388 -390.924034) (xy 181.285642 -390.914382) (xy 181.287056 -390.886434) (xy 181.297072 -390.83138)
			(xy 181.315023 -390.778379) (xy 181.340525 -390.728569) (xy 181.37303 -390.683019) (xy 181.41184 -390.642707)
			(xy 181.456123 -390.608496) (xy 181.504929 -390.581122) (xy 181.55721 -390.561172) (xy 181.611845 -390.549073)
			(xy 181.639718 -390.54659) (xy 181.649116 -390.545828) (xy 181.66588 -390.537954) (xy 181.726332 -390.475216)
			(xy 181.733698 -390.458198) (xy 181.733952 -390.448546) (xy 181.735278 -390.421902) (xy 181.744459 -390.36935)
			(xy 181.760873 -390.318591) (xy 181.784199 -390.270614) (xy 181.813982 -390.226354) (xy 181.849641 -390.186676)
			(xy 181.890481 -390.152353) (xy 181.935704 -390.124056) (xy 181.984429 -390.102335) (xy 182.035705 -390.087615)
			(xy 182.088532 -390.080183) (xy 182.115206 -390.079738) (xy 182.142461 -390.08015) (xy 182.196416 -390.087909)
			(xy 182.248718 -390.103268) (xy 182.298301 -390.125915) (xy 182.344156 -390.155387) (xy 182.38535 -390.191087)
			(xy 182.421044 -390.232285) (xy 182.45051 -390.278145) (xy 182.47315 -390.327731) (xy 182.488502 -390.380035)
			(xy 182.496254 -390.433991) (xy 182.496714 -390.461246) (xy 182.496193 -390.489862) (xy 182.487637 -390.546451)
			(xy 182.470724 -390.601128) (xy 182.445833 -390.652664) (xy 182.413524 -390.699904) (xy 182.37452 -390.741788)
			(xy 182.329698 -390.777376) (xy 182.280063 -390.80587) (xy 182.226728 -390.826629) (xy 182.170891 -390.839189)
			(xy 182.142384 -390.841738) (xy 182.132986 -390.8425) (xy 182.116222 -390.850374) (xy 182.05577 -390.913112)
			(xy 182.048404 -390.93013) (xy 182.04815 -390.939782) (xy 182.046711 -390.967728) (xy 182.0367 -391.022783)
			(xy 182.018753 -391.075784) (xy 181.993255 -391.125594) (xy 181.960753 -391.171144) (xy 181.921945 -391.211457)
			(xy 181.877664 -391.245668) (xy 181.82886 -391.273043) (xy 181.77658 -391.292993) (xy 181.721947 -391.305091)
			(xy 181.694074 -391.307574) (xy 181.684676 -391.308336) (xy 181.667912 -391.31621) (xy 181.60746 -391.378948)
			(xy 181.600094 -391.395966) (xy 181.59984 -391.405618) (xy 181.59849 -391.432261) (xy 181.589313 -391.484812)
			(xy 181.572903 -391.535572) (xy 181.549581 -391.583549) (xy 181.519801 -391.62781) (xy 181.484144 -391.667488)
			(xy 181.443306 -391.701812) (xy 181.398084 -391.73011) (xy 181.34936 -391.75183) (xy 181.298085 -391.76655)
			(xy 181.245259 -391.773981) (xy 181.218586 -391.774426) (xy 181.191335 -391.773935) (xy 181.137389 -391.766177)
			(xy 181.085095 -391.750821) (xy 181.035519 -391.72818) (xy 180.98967 -391.698714) (xy 180.94848 -391.663023)
			(xy 180.912789 -391.621834) (xy 180.883322 -391.575985) (xy 180.86068 -391.526409) (xy 180.845324 -391.474115)
			(xy 180.837565 -391.420169) (xy 180.837078 -391.392918) (xy 180.047112 -391.392918) (xy 180.051266 -391.400474)
			(xy 180.074798 -391.459907) (xy 180.090695 -391.521821) (xy 180.098706 -391.585239) (xy 180.099208 -391.6172)
			(xy 180.098706 -391.649161) (xy 180.090695 -391.712579) (xy 180.074798 -391.774493) (xy 180.051266 -391.833926)
			(xy 180.020472 -391.889941) (xy 179.982899 -391.941656) (xy 179.939142 -391.988253) (xy 179.889889 -392.028998)
			(xy 179.835918 -392.063249) (xy 179.778079 -392.090466) (xy 179.717286 -392.110219) (xy 179.654496 -392.122197)
			(xy 179.5907 -392.126211) (xy 179.526904 -392.122197) (xy 179.464114 -392.110219) (xy 179.403321 -392.090466)
			(xy 179.345482 -392.063249) (xy 179.291511 -392.028998) (xy 179.242258 -391.988253) (xy 179.198501 -391.941656)
			(xy 179.160928 -391.889941) (xy 179.130134 -391.833926) (xy 179.106602 -391.774493) (xy 179.090705 -391.712579)
			(xy 179.082694 -391.649161) (xy 171.731138 -391.649161) (xy 171.734479 -391.671864) (xy 171.734988 -391.69975)
			(xy 171.734479 -391.727636) (xy 171.726359 -391.782812) (xy 171.710291 -391.836219) (xy 171.686619 -391.886716)
			(xy 171.655846 -391.933229) (xy 171.618629 -391.974766) (xy 171.575761 -392.010441) (xy 171.528155 -392.039495)
			(xy 171.476826 -392.061307) (xy 171.422869 -392.075413) (xy 171.367432 -392.081513) (xy 171.311698 -392.079476)
			(xy 171.256855 -392.069346) (xy 171.204071 -392.051339) (xy 171.154471 -392.025838) (xy 171.109113 -391.993387)
			(xy 171.068964 -391.954678) (xy 171.034878 -391.910535) (xy 171.007582 -391.8619) (xy 170.987659 -391.809809)
			(xy 170.975533 -391.755372) (xy 170.971462 -391.69975) (xy 168.892016 -391.69975) (xy 168.871439 -391.739001)
			(xy 168.854374 -391.76452) (xy 168.848899 -391.773273) (xy 168.844764 -391.79348) (xy 168.848883 -391.813691)
			(xy 168.854374 -391.822432) (xy 168.87099 -391.847275) (xy 168.898933 -391.900111) (xy 168.920494 -391.955856)
			(xy 168.935377 -392.013743) (xy 168.943375 -392.072974) (xy 168.94429 -392.102848) (xy 168.94429 -392.113008)
			(xy 168.952164 -392.131296) (xy 169.010076 -392.188446) (xy 169.017512 -392.195061) (xy 169.035946 -392.202505)
			(xy 169.04589 -392.202924) (xy 170.533822 -392.202924) (xy 170.544069 -392.202462) (xy 170.562943 -392.194475)
			(xy 170.570398 -392.18743) (xy 170.590112 -392.167763) (xy 170.634222 -392.133778) (xy 170.682804 -392.106566)
			(xy 170.734826 -392.086705) (xy 170.789182 -392.074617) (xy 170.844718 -392.070559) (xy 170.900254 -392.074617)
			(xy 170.95461 -392.086705) (xy 171.006632 -392.106566) (xy 171.055214 -392.133778) (xy 171.099324 -392.167763)
			(xy 171.119038 -392.18743) (xy 171.126489 -392.194484) (xy 171.145363 -392.202484) (xy 171.155614 -392.202924)
			(xy 172.59681 -392.202924) (xy 172.606879 -392.203349) (xy 172.625478 -392.211069) (xy 172.632878 -392.21791)
			(xy 172.902329 -392.487361) (xy 178.127654 -392.487361) (xy 178.127654 -392.423439) (xy 178.135665 -392.360021)
			(xy 178.151562 -392.298107) (xy 178.175094 -392.238674) (xy 178.205888 -392.182659) (xy 178.243461 -392.130944)
			(xy 178.287218 -392.084347) (xy 178.336471 -392.043602) (xy 178.390442 -392.009351) (xy 178.448281 -391.982134)
			(xy 178.509074 -391.962381) (xy 178.571864 -391.950403) (xy 178.63566 -391.94639) (xy 178.699456 -391.950403)
			(xy 178.762246 -391.962381) (xy 178.823039 -391.982134) (xy 178.880878 -392.009351) (xy 178.934849 -392.043602)
			(xy 178.984102 -392.084347) (xy 179.027859 -392.130944) (xy 179.065432 -392.182659) (xy 179.096226 -392.238674)
			(xy 179.119758 -392.298107) (xy 179.135655 -392.360021) (xy 179.143666 -392.423439) (xy 179.144168 -392.4554)
			(xy 179.143666 -392.487361) (xy 179.135655 -392.550779) (xy 179.119758 -392.612693) (xy 179.096226 -392.672126)
			(xy 179.065432 -392.728141) (xy 179.027859 -392.779856) (xy 178.984102 -392.826453) (xy 178.934849 -392.867198)
			(xy 178.880878 -392.901449) (xy 178.823039 -392.928666) (xy 178.762246 -392.948419) (xy 178.699456 -392.960397)
			(xy 178.63566 -392.964411) (xy 178.571864 -392.960397) (xy 178.509074 -392.948419) (xy 178.448281 -392.928666)
			(xy 178.390442 -392.901449) (xy 178.336471 -392.867198) (xy 178.287218 -392.826453) (xy 178.243461 -392.779856)
			(xy 178.205888 -392.728141) (xy 178.175094 -392.672126) (xy 178.151562 -392.612693) (xy 178.135665 -392.550779)
			(xy 178.127654 -392.487361) (xy 172.902329 -392.487361) (xy 174.124874 -393.709906) (xy 174.131722 -393.717304)
			(xy 174.139459 -393.735902) (xy 174.13986 -393.745974) (xy 174.13986 -394.1318) (xy 178.126689 -394.1318)
			(xy 178.130703 -394.068007) (xy 178.142679 -394.00522) (xy 178.16243 -393.94443) (xy 178.189645 -393.886594)
			(xy 178.223892 -393.832624) (xy 178.264634 -393.783372) (xy 178.311227 -393.739615) (xy 178.362937 -393.702042)
			(xy 178.418948 -393.671246) (xy 178.478377 -393.647712) (xy 178.540286 -393.631812) (xy 178.603701 -393.623796)
			(xy 178.63566 -393.623292) (xy 178.667258 -393.623793) (xy 178.729966 -393.631619) (xy 178.791222 -393.647156)
			(xy 178.85008 -393.670164) (xy 178.905634 -393.700288) (xy 178.957026 -393.737064) (xy 179.003465 -393.779925)
			(xy 179.044234 -393.828211) (xy 179.061872 -393.854432) (xy 179.067206 -393.86256) (xy 179.082192 -393.873482)
			(xy 179.16652 -393.895834) (xy 179.184808 -393.893802) (xy 179.193444 -393.889484) (xy 179.205851 -393.883279)
			(xy 179.231403 -393.872473) (xy 179.244498 -393.867894) (xy 179.257706 -393.863322) (xy 179.27574 -393.84224)
			(xy 179.295552 -393.726416) (xy 179.2859 -393.700762) (xy 179.274724 -393.692126) (xy 179.24941 -393.671389)
			(xy 179.203784 -393.624479) (xy 179.16455 -393.572106) (xy 179.132356 -393.515134) (xy 179.107734 -393.454505)
			(xy 179.09109 -393.391218) (xy 179.082698 -393.326319) (xy 179.082192 -393.2936) (xy 179.082694 -393.261639)
			(xy 179.090705 -393.198221) (xy 179.106602 -393.136307) (xy 179.130134 -393.076874) (xy 179.160928 -393.020859)
			(xy 179.198501 -392.969144) (xy 179.242258 -392.922547) (xy 179.291511 -392.881802) (xy 179.345482 -392.847551)
			(xy 179.403321 -392.820334) (xy 179.464114 -392.800581) (xy 179.526904 -392.788603) (xy 179.5907 -392.78459)
			(xy 179.654496 -392.788603) (xy 179.717286 -392.800581) (xy 179.778079 -392.820334) (xy 179.835918 -392.847551)
			(xy 179.889889 -392.881802) (xy 179.939142 -392.922547) (xy 179.982899 -392.969144) (xy 180.020472 -393.020859)
			(xy 180.051266 -393.076874) (xy 180.074798 -393.136307) (xy 180.090695 -393.198221) (xy 180.098706 -393.261639)
			(xy 180.099208 -393.2936) (xy 180.098683 -393.32524) (xy 180.090819 -393.388031) (xy 180.075227 -393.449361)
			(xy 180.052145 -393.508282) (xy 180.021932 -393.563885) (xy 179.985054 -393.615309) (xy 179.942081 -393.661762)
			(xy 179.893677 -393.702523) (xy 179.84059 -393.736965) (xy 179.783639 -393.764554) (xy 179.723706 -393.784864)
			(xy 179.692808 -393.791694) (xy 179.679092 -393.794488) (xy 179.658772 -393.81303) (xy 179.624228 -393.925298)
			(xy 179.630832 -393.952222) (xy 179.640484 -393.962128) (xy 179.660757 -393.983632) (xy 179.695059 -394.031758)
			(xy 179.721529 -394.084597) (xy 179.739534 -394.140886) (xy 179.748644 -394.199279) (xy 179.749196 -394.228828)
			(xy 179.748748 -394.25608) (xy 179.740988 -394.31003) (xy 179.725628 -394.362326) (xy 179.702983 -394.411905)
			(xy 179.673513 -394.457755) (xy 179.637817 -394.498946) (xy 179.596623 -394.534637) (xy 179.550769 -394.564102)
			(xy 179.501189 -394.586742) (xy 179.448891 -394.602096) (xy 179.394941 -394.609851) (xy 179.367688 -394.610336)
			(xy 179.33953 -394.609835) (xy 179.283828 -394.601534) (xy 179.229954 -394.585129) (xy 179.179079 -394.560977)
			(xy 179.13231 -394.529604) (xy 179.111148 -394.511022) (xy 179.104036 -394.504672) (xy 179.086764 -394.497814)
			(xy 178.999388 -394.49756) (xy 178.982116 -394.504164) (xy 178.975004 -394.510514) (xy 178.951648 -394.53086)
			(xy 178.900833 -394.566284) (xy 178.846092 -394.595273) (xy 178.788234 -394.617398) (xy 178.728117 -394.632331)
			(xy 178.666632 -394.63985) (xy 178.63566 -394.640308) (xy 178.603701 -394.639804) (xy 178.540286 -394.631788)
			(xy 178.478377 -394.615888) (xy 178.418948 -394.592354) (xy 178.362937 -394.561558) (xy 178.311227 -394.523985)
			(xy 178.264634 -394.480228) (xy 178.223892 -394.430976) (xy 178.189645 -394.377006) (xy 178.16243 -394.31917)
			(xy 178.142679 -394.25838) (xy 178.130703 -394.195593) (xy 178.126689 -394.1318) (xy 174.13986 -394.1318)
			(xy 174.13986 -400.078702) (xy 174.140207 -400.087393) (xy 174.146053 -400.103761) (xy 174.15129 -400.110706)
			(xy 174.170768 -400.135479) (xy 174.204108 -400.188957) (xy 174.230584 -400.246145) (xy 174.249791 -400.306167)
			(xy 174.261434 -400.368101) (xy 174.265335 -400.431) (xy 174.261434 -400.493899) (xy 174.249791 -400.555833)
			(xy 174.230584 -400.615855) (xy 174.204108 -400.673043) (xy 174.170768 -400.726521) (xy 174.15129 -400.751294)
			(xy 174.14608 -400.758254) (xy 174.140223 -400.774612) (xy 174.13986 -400.783298) (xy 174.13986 -401.0025)
			(xy 174.140285 -401.012569) (xy 174.148006 -401.031168) (xy 174.154846 -401.038568) (xy 175.161956 -402.045678)
			(xy 175.168795 -402.053079) (xy 175.176508 -402.071677) (xy 175.176942 -402.081746) (xy 175.176942 -403.937724)
			(xy 175.177958 -403.942804) (xy 175.194589 -404.026738) (xy 175.221938 -404.195667) (xy 175.242495 -404.365557)
			(xy 175.25623 -404.536133) (xy 175.263119 -404.707124) (xy 175.263556 -404.792688) (xy 175.263123 -404.878253)
			(xy 175.256244 -405.049244) (xy 175.242515 -405.219821) (xy 175.221955 -405.389711) (xy 175.1946 -405.55864)
			(xy 175.177958 -405.642572) (xy 175.176942 -405.647652) (xy 175.176942 -407.039318) (xy 175.176514 -407.049385)
			(xy 175.168789 -407.06798) (xy 175.161956 -407.075386) (xy 174.154846 -408.082496) (xy 174.147994 -408.089892)
			(xy 174.140251 -408.108491) (xy 174.13986 -408.118564) (xy 174.13986 -409.904184) (xy 174.13942 -409.914246)
			(xy 174.13168 -409.932825) (xy 174.124874 -409.940252) (xy 172.182536 -411.88259) (xy 172.17644 -411.912054)
			(xy 172.181774 -411.926278) (xy 172.191863 -411.953768) (xy 172.202731 -412.011302) (xy 172.203364 -412.040578)
			(xy 172.203364 -413.99333) (xy 172.203906 -414.003316) (xy 172.211623 -414.021743) (xy 172.21835 -414.029144)
			(xy 173.242986 -415.05378) (xy 173.260059 -415.071483) (xy 173.28898 -415.11126) (xy 173.311314 -415.155076)
			(xy 173.326511 -415.201848) (xy 173.334196 -415.250424) (xy 173.33468 -415.275014) (xy 173.33468 -415.951627)
			(xy 173.628806 -415.951627) (xy 173.628806 -415.887705) (xy 173.636817 -415.824287) (xy 173.652714 -415.762373)
			(xy 173.676246 -415.70294) (xy 173.70704 -415.646925) (xy 173.744613 -415.59521) (xy 173.78837 -415.548613)
			(xy 173.837623 -415.507868) (xy 173.891594 -415.473617) (xy 173.949433 -415.4464) (xy 174.010226 -415.426647)
			(xy 174.073016 -415.414669) (xy 174.136812 -415.410656) (xy 174.200608 -415.414669) (xy 174.263398 -415.426647)
			(xy 174.324191 -415.4464) (xy 174.38203 -415.473617) (xy 174.436001 -415.507868) (xy 174.485254 -415.548613)
			(xy 174.529011 -415.59521) (xy 174.566584 -415.646925) (xy 174.597378 -415.70294) (xy 174.62091 -415.762373)
			(xy 174.636807 -415.824287) (xy 174.644818 -415.887705) (xy 174.64532 -415.919666) (xy 174.644818 -415.951627)
			(xy 174.636807 -416.015045) (xy 174.62091 -416.076959) (xy 174.597378 -416.136392) (xy 174.566584 -416.192407)
			(xy 174.529011 -416.244122) (xy 174.485254 -416.290719) (xy 174.436001 -416.331464) (xy 174.38203 -416.365715)
			(xy 174.324191 -416.392932) (xy 174.263398 -416.412685) (xy 174.200608 -416.424663) (xy 174.136812 -416.428677)
			(xy 174.073016 -416.424663) (xy 174.010226 -416.412685) (xy 173.949433 -416.392932) (xy 173.891594 -416.365715)
			(xy 173.837623 -416.331464) (xy 173.78837 -416.290719) (xy 173.744613 -416.244122) (xy 173.70704 -416.192407)
			(xy 173.676246 -416.136392) (xy 173.652714 -416.076959) (xy 173.636817 -416.015045) (xy 173.628806 -415.951627)
			(xy 173.33468 -415.951627) (xy 173.33468 -416.399726) (xy 173.335144 -416.410383) (xy 173.343831 -416.429845)
			(xy 173.351444 -416.437318) (xy 173.415452 -416.49523) (xy 173.435772 -416.501834) (xy 173.446694 -416.500818)
			(xy 173.459737 -416.499524) (xy 173.485912 -416.498127) (xy 173.499018 -416.498024) (xy 173.530161 -416.498495)
			(xy 173.59198 -416.506102) (xy 173.652408 -416.521201) (xy 173.71054 -416.543565) (xy 173.765507 -416.572859)
			(xy 173.816485 -416.608646) (xy 173.862712 -416.65039) (xy 173.903497 -416.697466) (xy 173.938228 -416.749169)
			(xy 173.941863 -416.756342) (xy 175.678082 -416.756342) (xy 175.682153 -416.70072) (xy 175.694279 -416.646283)
			(xy 175.714202 -416.594192) (xy 175.741498 -416.545557) (xy 175.775584 -416.501414) (xy 175.815733 -416.462705)
			(xy 175.861091 -416.430254) (xy 175.910691 -416.404753) (xy 175.963475 -416.386746) (xy 176.018318 -416.376616)
			(xy 176.074052 -416.374579) (xy 176.129489 -416.380679) (xy 176.183446 -416.394785) (xy 176.234775 -416.416597)
			(xy 176.282381 -416.445651) (xy 176.325249 -416.481326) (xy 176.362466 -416.522863) (xy 176.393239 -416.569376)
			(xy 176.416911 -416.619873) (xy 176.432979 -416.67328) (xy 176.433908 -416.679591) (xy 177.57495 -416.679591)
			(xy 177.57495 -416.615669) (xy 177.582961 -416.552251) (xy 177.598858 -416.490337) (xy 177.62239 -416.430904)
			(xy 177.653184 -416.374889) (xy 177.690757 -416.323174) (xy 177.734514 -416.276577) (xy 177.783767 -416.235832)
			(xy 177.837738 -416.201581) (xy 177.895577 -416.174364) (xy 177.95637 -416.154611) (xy 178.01916 -416.142633)
			(xy 178.082956 -416.13862) (xy 178.146752 -416.142633) (xy 178.209542 -416.154611) (xy 178.270335 -416.174364)
			(xy 178.328174 -416.201581) (xy 178.382145 -416.235832) (xy 178.431398 -416.276577) (xy 178.475155 -416.323174)
			(xy 178.512728 -416.374889) (xy 178.543522 -416.430904) (xy 178.567054 -416.490337) (xy 178.582951 -416.552251)
			(xy 178.590962 -416.615669) (xy 178.591464 -416.64763) (xy 178.590962 -416.679591) (xy 178.582951 -416.743009)
			(xy 178.567054 -416.804923) (xy 178.543522 -416.864356) (xy 178.512728 -416.920371) (xy 178.475155 -416.972086)
			(xy 178.431398 -417.018683) (xy 178.382145 -417.059428) (xy 178.328174 -417.093679) (xy 178.270335 -417.120896)
			(xy 178.209542 -417.140649) (xy 178.146752 -417.152627) (xy 178.082956 -417.156641) (xy 178.01916 -417.152627)
			(xy 177.95637 -417.140649) (xy 177.895577 -417.120896) (xy 177.837738 -417.093679) (xy 177.783767 -417.059428)
			(xy 177.734514 -417.018683) (xy 177.690757 -416.972086) (xy 177.653184 -416.920371) (xy 177.62239 -416.864356)
			(xy 177.598858 -416.804923) (xy 177.582961 -416.743009) (xy 177.57495 -416.679591) (xy 176.433908 -416.679591)
			(xy 176.441099 -416.728456) (xy 176.441608 -416.756342) (xy 176.441099 -416.784228) (xy 176.432979 -416.839404)
			(xy 176.416911 -416.892811) (xy 176.393239 -416.943308) (xy 176.362466 -416.989821) (xy 176.325249 -417.031358)
			(xy 176.282381 -417.067033) (xy 176.234775 -417.096087) (xy 176.183446 -417.117899) (xy 176.129489 -417.132005)
			(xy 176.074052 -417.138105) (xy 176.018318 -417.136068) (xy 175.963475 -417.125938) (xy 175.910691 -417.107931)
			(xy 175.861091 -417.08243) (xy 175.815733 -417.049979) (xy 175.775584 -417.01127) (xy 175.741498 -416.967127)
			(xy 175.714202 -416.918492) (xy 175.694279 -416.866401) (xy 175.682153 -416.811964) (xy 175.678082 -416.756342)
			(xy 173.941863 -416.756342) (xy 173.966386 -416.804726) (xy 173.98755 -416.863306) (xy 174.001403 -416.924031)
			(xy 174.004986 -416.95497) (xy 174.006256 -416.968432) (xy 174.02175 -416.990022) (xy 174.125382 -417.038536)
			(xy 174.151798 -417.03625) (xy 174.163228 -417.02863) (xy 174.188602 -417.011906) (xy 174.242565 -416.983954)
			(xy 174.29947 -416.962623) (xy 174.358511 -416.948216) (xy 174.418846 -416.940939) (xy 174.449232 -416.940492)
			(xy 174.481192 -416.940996) (xy 174.544607 -416.949011) (xy 174.606517 -416.96491) (xy 174.665947 -416.988443)
			(xy 174.721959 -417.019239) (xy 174.773669 -417.056812) (xy 174.820263 -417.10057) (xy 174.861006 -417.149821)
			(xy 174.895254 -417.203791) (xy 174.922469 -417.261628) (xy 174.94222 -417.322419) (xy 174.954197 -417.385207)
			(xy 174.958211 -417.449) (xy 174.954197 -417.512793) (xy 174.94222 -417.575581) (xy 174.922469 -417.636372)
			(xy 174.895254 -417.694209) (xy 174.861006 -417.748179) (xy 174.820263 -417.79743) (xy 174.773669 -417.841188)
			(xy 174.721959 -417.878761) (xy 174.665947 -417.909557) (xy 174.606517 -417.93309) (xy 174.544607 -417.948989)
			(xy 174.481192 -417.957004) (xy 174.449232 -417.957508) (xy 174.418091 -417.957034) (xy 174.356274 -417.949422)
			(xy 174.29585 -417.934319) (xy 174.237722 -417.911953) (xy 174.182759 -417.882657) (xy 174.131784 -417.846869)
			(xy 174.085559 -417.805126) (xy 174.044777 -417.758052) (xy 174.010047 -417.706351) (xy 173.981889 -417.650797)
			(xy 173.960724 -417.59222) (xy 173.946869 -417.531497) (xy 173.943264 -417.500562) (xy 173.941994 -417.4871)
			(xy 173.9265 -417.46551) (xy 173.822868 -417.416996) (xy 173.796452 -417.419282) (xy 173.785022 -417.426902)
			(xy 173.756887 -417.445388) (xy 173.696716 -417.47558) (xy 173.633085 -417.497561) (xy 173.567108 -417.510946)
			(xy 173.533562 -417.51377) (xy 173.518322 -417.514786) (xy 173.4947 -417.532566) (xy 173.456854 -417.633404)
			(xy 173.453843 -417.642638) (xy 173.454285 -417.662039) (xy 173.461944 -417.679869) (xy 173.468538 -417.686998)
			(xy 174.001938 -418.220398) (xy 174.009884 -418.227705) (xy 174.030006 -418.235473) (xy 174.0408 -418.235384)
			(xy 174.127668 -418.23005) (xy 174.146972 -418.21989) (xy 174.153576 -418.211508) (xy 174.171768 -418.189199)
			(xy 174.213725 -418.149788) (xy 174.261126 -418.117128) (xy 174.312896 -418.091959) (xy 174.367859 -418.074853)
			(xy 174.424768 -418.066198) (xy 174.45355 -418.065712) (xy 174.480805 -418.066172) (xy 174.53476 -418.073923)
			(xy 174.587063 -418.089275) (xy 174.636648 -418.111915) (xy 174.682506 -418.141382) (xy 174.723703 -418.177076)
			(xy 174.7594 -418.21827) (xy 174.788871 -418.264126) (xy 174.811514 -418.313709) (xy 174.82687 -418.366011)
			(xy 174.834626 -418.419965) (xy 174.835058 -418.44722) (xy 174.834532 -418.475999) (xy 174.825882 -418.532904)
			(xy 174.80878 -418.587863) (xy 174.783615 -418.639629) (xy 174.750958 -418.687027) (xy 174.711551 -418.72898)
			(xy 174.689262 -418.747194) (xy 174.68088 -418.753798) (xy 174.67072 -418.773102) (xy 174.665386 -418.85997)
			(xy 174.66528 -418.870769) (xy 174.673046 -418.890897) (xy 174.680372 -418.898832) (xy 176.083468 -420.301928)
			(xy 176.100512 -420.319643) (xy 176.129376 -420.359435) (xy 176.151656 -420.403255) (xy 176.166801 -420.450021)
			(xy 176.17444 -420.498582) (xy 176.174908 -420.523162) (xy 176.174908 -423.817796) (xy 176.173892 -423.843958)
			(xy 176.17313 -423.85361) (xy 176.178464 -423.871898) (xy 176.23282 -423.941494) (xy 176.249076 -423.951146)
			(xy 176.258728 -423.95267) (xy 176.290782 -423.95845) (xy 176.353185 -423.977106) (xy 176.412695 -424.00358)
			(xy 176.468337 -424.037437) (xy 176.519199 -424.078123) (xy 176.564448 -424.124971) (xy 176.603344 -424.177215)
			(xy 176.635248 -424.233998) (xy 176.65964 -424.294391) (xy 176.676119 -424.357405) (xy 176.684415 -424.422007)
			(xy 176.68494 -424.454574) (xy 176.684496 -424.485005) (xy 176.677234 -424.545434) (xy 176.662812 -424.604563)
			(xy 176.641436 -424.661548) (xy 176.61341 -424.715575) (xy 176.579137 -424.76587) (xy 176.559464 -424.789092)
			(xy 176.554084 -424.795801) (xy 176.547714 -424.811764) (xy 176.547018 -424.820334) (xy 176.545748 -424.849798)
			(xy 176.545681 -424.85835) (xy 176.550614 -424.874714) (xy 176.5554 -424.881802) (xy 176.573771 -424.907965)
			(xy 176.604546 -424.963998) (xy 176.628061 -425.023445) (xy 176.643943 -425.085369) (xy 176.651944 -425.148796)
			(xy 176.652428 -425.18076) (xy 176.651926 -425.212721) (xy 176.643915 -425.276139) (xy 176.628018 -425.338053)
			(xy 176.604486 -425.397486) (xy 176.573692 -425.453501) (xy 176.536119 -425.505216) (xy 176.492362 -425.551813)
			(xy 176.443109 -425.592558) (xy 176.389138 -425.626809) (xy 176.331299 -425.654026) (xy 176.270506 -425.673779)
			(xy 176.207716 -425.685757) (xy 176.14392 -425.689771) (xy 176.080124 -425.685757) (xy 176.017334 -425.673779)
			(xy 175.956541 -425.654026) (xy 175.898702 -425.626809) (xy 175.844731 -425.592558) (xy 175.795478 -425.551813)
			(xy 175.751721 -425.505216) (xy 175.714148 -425.453501) (xy 175.683354 -425.397486) (xy 175.659822 -425.338053)
			(xy 175.643925 -425.276139) (xy 175.635914 -425.212721) (xy 175.635412 -425.18076) (xy 175.635854 -425.150328)
			(xy 175.643111 -425.089897) (xy 175.657529 -425.030765) (xy 175.678901 -424.973776) (xy 175.706922 -424.919745)
			(xy 175.741191 -424.869444) (xy 175.760888 -424.846242) (xy 175.766254 -424.839528) (xy 175.772598 -424.823565)
			(xy 175.773334 -424.815) (xy 175.774604 -424.785536) (xy 175.774677 -424.776981) (xy 175.769758 -424.760608)
			(xy 175.764952 -424.753532) (xy 175.744519 -424.724393) (xy 175.711125 -424.661548) (xy 175.698404 -424.62831)
			(xy 175.694086 -424.615864) (xy 175.674528 -424.598846) (xy 175.578008 -424.57751) (xy 175.569644 -424.57599)
			(xy 175.552773 -424.57799) (xy 175.537505 -424.585444) (xy 175.531272 -424.591226) (xy 174.665132 -425.457366)
			(xy 174.657512 -425.478194) (xy 174.658274 -425.48937) (xy 174.659798 -425.52874) (xy 174.659296 -425.560701)
			(xy 174.651285 -425.624119) (xy 174.635388 -425.686033) (xy 174.611856 -425.745466) (xy 174.581062 -425.801481)
			(xy 174.543489 -425.853196) (xy 174.499732 -425.899793) (xy 174.450479 -425.940538) (xy 174.396508 -425.974789)
			(xy 174.338669 -426.002006) (xy 174.277876 -426.021759) (xy 174.215086 -426.033737) (xy 174.15129 -426.037751)
			(xy 174.087494 -426.033737) (xy 174.024704 -426.021759) (xy 173.963911 -426.002006) (xy 173.906072 -425.974789)
			(xy 173.852101 -425.940538) (xy 173.802848 -425.899793) (xy 173.759091 -425.853196) (xy 173.721518 -425.801481)
			(xy 173.690724 -425.745466) (xy 173.667192 -425.686033) (xy 173.651295 -425.624119) (xy 173.643284 -425.560701)
			(xy 173.642782 -425.52874) (xy 173.643233 -425.49828) (xy 173.650517 -425.437797) (xy 173.664973 -425.378618)
			(xy 173.686396 -425.321589) (xy 173.714477 -425.267527) (xy 173.748814 -425.217207) (xy 173.768512 -425.193968)
			(xy 173.773991 -425.187097) (xy 173.780365 -425.170732) (xy 173.780958 -425.161964) (xy 173.781974 -425.132246)
			(xy 173.781858 -425.123431) (xy 173.776391 -425.106683) (xy 173.771306 -425.09948) (xy 173.751079 -425.072609)
			(xy 173.717126 -425.014552) (xy 173.691125 -424.952524) (xy 173.673529 -424.88761) (xy 173.664646 -424.820942)
			(xy 173.664118 -424.787314) (xy 173.664604 -424.755594) (xy 173.672496 -424.692647) (xy 173.688158 -424.63117)
			(xy 173.711348 -424.57212) (xy 173.741705 -424.516415) (xy 173.778757 -424.464919) (xy 173.800008 -424.441366)
			(xy 173.806124 -424.434216) (xy 173.813036 -424.416729) (xy 173.81347 -424.40733) (xy 173.813724 -424.376342)
			(xy 173.813454 -424.366919) (xy 173.806804 -424.349294) (xy 173.80077 -424.342052) (xy 173.780476 -424.318689)
			(xy 173.745107 -424.267907) (xy 173.716164 -424.213206) (xy 173.694075 -424.155397) (xy 173.679166 -424.095334)
			(xy 173.671658 -424.033905) (xy 173.67123 -424.002962) (xy 173.671696 -423.972233) (xy 173.679109 -423.911225)
			(xy 173.693821 -423.851554) (xy 173.715618 -423.794092) (xy 173.744183 -423.739676) (xy 173.779099 -423.689101)
			(xy 173.819856 -423.643102) (xy 173.86586 -423.602352) (xy 173.916441 -423.567444) (xy 173.970861 -423.538887)
			(xy 174.028327 -423.517098) (xy 174.087999 -423.502395) (xy 174.149009 -423.494992) (xy 174.179738 -423.494454)
			(xy 174.219108 -423.495978) (xy 174.230284 -423.49674) (xy 174.251112 -423.48912) (xy 174.45101 -423.289222)
			(xy 174.457807 -423.281872) (xy 174.46551 -423.263409) (xy 174.465996 -423.253408) (xy 174.465996 -421.500554)
			(xy 174.465433 -421.489446) (xy 174.456082 -421.469293) (xy 174.447962 -421.461692) (xy 174.37989 -421.404288)
			(xy 174.358554 -421.398446) (xy 174.347378 -421.400224) (xy 174.326454 -421.403544) (xy 174.284235 -421.407104)
			(xy 174.26305 -421.407336) (xy 174.22988 -421.406802) (xy 174.164104 -421.398177) (xy 174.100009 -421.381067)
			(xy 174.038685 -421.355763) (xy 173.981175 -421.322695) (xy 173.928456 -421.282426) (xy 173.881425 -421.235639)
			(xy 173.860714 -421.209724) (xy 173.85411 -421.201088) (xy 173.836076 -421.191182) (xy 173.74108 -421.181784)
			(xy 173.721522 -421.188134) (xy 173.713394 -421.195246) (xy 173.692467 -421.212836) (xy 173.646528 -421.242472)
			(xy 173.596831 -421.265248) (xy 173.544391 -421.280698) (xy 173.490284 -421.288507) (xy 173.46295 -421.288972)
			(xy 173.435704 -421.288482) (xy 173.381767 -421.280721) (xy 173.329483 -421.265363) (xy 173.279917 -421.242721)
			(xy 173.234077 -421.213256) (xy 173.192896 -421.177568) (xy 173.157214 -421.136383) (xy 173.127755 -421.090539)
			(xy 173.10512 -421.04097) (xy 173.089769 -420.988685) (xy 173.082014 -420.934746) (xy 173.082014 -420.880254)
			(xy 173.089769 -420.826315) (xy 173.10512 -420.77403) (xy 173.127755 -420.724461) (xy 173.157214 -420.678617)
			(xy 173.192897 -420.637432) (xy 173.234077 -420.601744) (xy 173.279917 -420.572279) (xy 173.329483 -420.549637)
			(xy 173.381767 -420.534279) (xy 173.435704 -420.526518) (xy 173.46295 -420.525956) (xy 173.489478 -420.52639)
			(xy 173.542026 -420.533704) (xy 173.593051 -420.548239) (xy 173.641565 -420.569714) (xy 173.68663 -420.597713)
			(xy 173.707298 -420.614348) (xy 173.715426 -420.621206) (xy 173.735238 -420.627048) (xy 173.82998 -420.615618)
			(xy 173.847506 -420.605458) (xy 173.85411 -420.596822) (xy 173.871708 -420.573637) (xy 173.911381 -420.531042)
			(xy 173.95566 -420.493257) (xy 173.979586 -420.47668) (xy 173.989238 -420.470076) (xy 174.000668 -420.450772)
			(xy 174.009558 -420.361364) (xy 174.010025 -420.350082) (xy 174.002377 -420.328867) (xy 173.994826 -420.32047)
			(xy 171.91609 -418.241734) (xy 171.898488 -418.223442) (xy 171.868869 -418.182217) (xy 171.857162 -418.159692)
			(xy 171.852336 -418.149786) (xy 171.835572 -418.13607) (xy 171.740322 -418.110924) (xy 171.718986 -418.11448)
			(xy 171.709588 -418.120576) (xy 171.695071 -418.130166) (xy 171.664945 -418.147578) (xy 171.64939 -418.155374)
			(xy 171.638722 -418.160454) (xy 171.624498 -418.178488) (xy 171.6024 -418.279326) (xy 171.607734 -418.301678)
			(xy 171.6151 -418.310822) (xy 171.631273 -418.331319) (xy 171.658453 -418.375898) (xy 171.679294 -418.42377)
			(xy 171.693405 -418.474038) (xy 171.700522 -418.525762) (xy 171.700952 -418.551868) (xy 171.700466 -418.579119)
			(xy 171.69271 -418.633067) (xy 171.677355 -418.685362) (xy 171.654713 -418.734939) (xy 171.625247 -418.780789)
			(xy 171.589556 -418.82198) (xy 171.548365 -418.857671) (xy 171.502515 -418.887137) (xy 171.452938 -418.909779)
			(xy 171.400643 -418.925134) (xy 171.346695 -418.93289) (xy 171.292193 -418.93289) (xy 171.238245 -418.925134)
			(xy 171.18595 -418.909779) (xy 171.136373 -418.887137) (xy 171.090523 -418.857671) (xy 171.049332 -418.82198)
			(xy 171.013641 -418.780789) (xy 170.984175 -418.734939) (xy 170.961533 -418.685362) (xy 170.946178 -418.633067)
			(xy 170.938422 -418.579119) (xy 170.937936 -418.551868) (xy 170.938499 -418.522166) (xy 170.947707 -418.463481)
			(xy 170.965909 -418.406935) (xy 170.992666 -418.353899) (xy 171.027328 -418.305657) (xy 171.069057 -418.263378)
			(xy 171.092622 -418.24529) (xy 171.10202 -418.238178) (xy 171.112688 -418.217858) (xy 171.11599 -418.114734)
			(xy 171.106846 -418.093652) (xy 171.097702 -418.086032) (xy 171.07398 -418.065275) (xy 171.03133 -418.018859)
			(xy 170.994738 -417.967532) (xy 170.964764 -417.912079) (xy 170.941867 -417.853349) (xy 170.926398 -417.792242)
			(xy 170.918593 -417.729691) (xy 170.918124 -417.698174) (xy 170.918571 -417.667444) (xy 170.925983 -417.606431)
			(xy 170.940694 -417.546757) (xy 170.962492 -417.489292) (xy 170.991057 -417.434872) (xy 171.025973 -417.384293)
			(xy 171.066732 -417.338291) (xy 171.112739 -417.297538) (xy 171.163322 -417.262627) (xy 171.217744 -417.234068)
			(xy 171.275213 -417.212277) (xy 171.334888 -417.197572) (xy 171.395902 -417.190168) (xy 171.426632 -417.189666)
			(xy 171.45887 -417.190162) (xy 171.522827 -417.198314) (xy 171.585239 -417.214497) (xy 171.6451 -417.238448)
			(xy 171.67352 -417.253674) (xy 171.685458 -417.260278) (xy 171.712382 -417.260024) (xy 171.799504 -417.208716)
			(xy 171.806912 -417.203889) (xy 171.818147 -417.190253) (xy 171.824077 -417.17361) (xy 171.824396 -417.164774)
			(xy 171.824396 -416.746436) (xy 171.82391 -416.736474) (xy 171.816323 -416.718049) (xy 171.809664 -416.710622)
			(xy 171.668948 -416.569906) (xy 171.660516 -416.562292) (xy 171.639151 -416.55466) (xy 171.6278 -416.555174)
			(xy 171.53763 -416.564826) (xy 171.518072 -416.576764) (xy 171.511722 -416.586416) (xy 171.496577 -416.608986)
			(xy 171.46091 -416.649998) (xy 171.419781 -416.68553) (xy 171.374023 -416.714861) (xy 171.324563 -416.737396)
			(xy 171.272404 -416.75268) (xy 171.218604 -416.760403) (xy 171.191428 -416.760914) (xy 171.164174 -416.760453)
			(xy 171.110219 -416.752699) (xy 171.057918 -416.737345) (xy 171.008334 -416.714705) (xy 170.962477 -416.685237)
			(xy 170.92128 -416.649544) (xy 170.885583 -416.60835) (xy 170.856112 -416.562496) (xy 170.833467 -416.512914)
			(xy 170.818108 -416.460614) (xy 170.81035 -416.40666) (xy 170.80992 -416.379406) (xy 170.810401 -416.352228)
			(xy 170.818122 -416.298425) (xy 170.833407 -416.246263) (xy 170.855947 -416.196802) (xy 170.885284 -416.151044)
			(xy 170.920824 -416.109918) (xy 170.961846 -416.074257) (xy 170.984418 -416.059112) (xy 170.99407 -416.052762)
			(xy 171.006008 -416.033204) (xy 171.01566 -415.943034) (xy 171.016176 -415.931688) (xy 171.008517 -415.910339)
			(xy 171.000928 -415.901886) (xy 169.618152 -414.518856) (xy 169.610705 -414.512168) (xy 169.592209 -414.504572)
			(xy 169.572213 -414.504572) (xy 169.553717 -414.512168) (xy 169.54627 -414.518856) (xy 168.13911 -415.926016)
			(xy 168.13276 -415.954464) (xy 168.137586 -415.968434) (xy 168.147652 -415.999084) (xy 168.158509 -416.062672)
			(xy 168.159176 -416.094926) (xy 168.158658 -416.123602) (xy 168.150074 -416.180307) (xy 168.133102 -416.235089)
			(xy 168.108124 -416.286715) (xy 168.075704 -416.334024) (xy 168.03657 -416.375949) (xy 168.014396 -416.394138)
			(xy 168.006522 -416.400234) (xy 167.99687 -416.416998) (xy 167.984424 -416.506406) (xy 167.988996 -416.524948)
			(xy 167.994838 -416.533076) (xy 168.009682 -416.554656) (xy 168.032711 -416.601696) (xy 168.047566 -416.65192)
			(xy 168.051226 -416.677856) (xy 168.052496 -416.686238) (xy 168.059862 -416.701478) (xy 168.594024 -417.23564)
			(xy 168.601437 -417.242316) (xy 168.619872 -417.249883) (xy 168.629838 -417.250372) (xy 168.70426 -417.250372)
			(xy 168.728849 -417.250834) (xy 168.777421 -417.258538) (xy 168.824189 -417.273748) (xy 168.868001 -417.296087)
			(xy 168.907778 -417.325007) (xy 168.925494 -417.342066) (xy 169.197528 -417.6141) (xy 169.214576 -417.631814)
			(xy 169.243447 -417.671604) (xy 169.265733 -417.715423) (xy 169.280885 -417.76219) (xy 169.288529 -417.810753)
			(xy 169.288968 -417.835334) (xy 169.288968 -417.909756) (xy 169.289497 -417.919748) (xy 169.297195 -417.938194)
			(xy 169.303954 -417.94557) (xy 169.369994 -418.011864) (xy 169.378728 -418.019706) (xy 169.400972 -418.027112)
			(xy 169.412666 -418.026088) (xy 169.50436 -418.013896) (xy 169.524172 -418.000688) (xy 169.530014 -417.990528)
			(xy 169.547075 -417.961808) (xy 169.587585 -417.908689) (xy 169.634699 -417.861329) (xy 169.687607 -417.820544)
			(xy 169.745398 -417.787035) (xy 169.807078 -417.761379) (xy 169.871586 -417.744018) (xy 169.937811 -417.735249)
			(xy 169.971212 -417.73475) (xy 170.001943 -417.735214) (xy 170.062958 -417.742624) (xy 170.122635 -417.757333)
			(xy 170.180104 -417.779128) (xy 170.234527 -417.807691) (xy 170.285111 -417.842605) (xy 170.331117 -417.883361)
			(xy 170.371876 -417.929366) (xy 170.406793 -417.979947) (xy 170.435359 -418.034369) (xy 170.457158 -418.091836)
			(xy 170.471871 -418.151512) (xy 170.479284 -418.212527) (xy 170.47972 -418.243258) (xy 170.479189 -418.276364)
			(xy 170.470596 -418.342017) (xy 170.453549 -418.405997) (xy 170.428338 -418.467222) (xy 170.395389 -418.524654)
			(xy 170.35526 -418.577321) (xy 170.308632 -418.62433) (xy 170.256293 -418.664886) (xy 170.199131 -418.698301)
			(xy 170.168824 -418.711634) (xy 170.15968 -418.715698) (xy 170.152822 -418.722556) (xy 170.145978 -418.72992)
			(xy 170.13823 -418.748454) (xy 170.138229 -418.768542) (xy 170.145976 -418.787076) (xy 170.152822 -418.794438)
			(xy 170.201336 -418.842952) (xy 170.231816 -418.848794) (xy 170.246548 -418.842444) (xy 170.278942 -418.828822)
			(xy 170.346539 -418.809611) (xy 170.416136 -418.799876) (xy 170.451272 -418.799264) (xy 170.482005 -418.799726)
			(xy 170.543022 -418.807132) (xy 170.602702 -418.821838) (xy 170.660175 -418.843631) (xy 170.714601 -418.872192)
			(xy 170.765188 -418.907106) (xy 170.811198 -418.947862) (xy 170.85196 -418.993868) (xy 170.886879 -419.044451)
			(xy 170.915446 -419.098874) (xy 170.937245 -419.156344) (xy 170.951958 -419.216023) (xy 170.95937 -419.277039)
			(xy 170.95978 -419.307772) (xy 170.959308 -419.338968) (xy 170.951675 -419.400892) (xy 170.936522 -419.461416)
			(xy 170.914076 -419.519631) (xy 170.884675 -419.574661) (xy 170.848759 -419.625679) (xy 170.80687 -419.671919)
			(xy 170.759637 -419.712684) (xy 170.733974 -419.730428) (xy 170.724068 -419.737032) (xy 170.712384 -419.757352)
			(xy 170.705018 -419.861238) (xy 170.713908 -419.882828) (xy 170.722798 -419.890702) (xy 170.745298 -419.911415)
			(xy 170.785687 -419.957339) (xy 170.785945 -419.957715) (xy 172.062896 -419.957715) (xy 172.062896 -419.893793)
			(xy 172.070907 -419.830375) (xy 172.086804 -419.768461) (xy 172.110336 -419.709028) (xy 172.14113 -419.653013)
			(xy 172.178703 -419.601298) (xy 172.22246 -419.554701) (xy 172.271713 -419.513956) (xy 172.325684 -419.479705)
			(xy 172.383523 -419.452488) (xy 172.444316 -419.432735) (xy 172.507106 -419.420757) (xy 172.570902 -419.416744)
			(xy 172.634698 -419.420757) (xy 172.697488 -419.432735) (xy 172.758281 -419.452488) (xy 172.81612 -419.479705)
			(xy 172.870091 -419.513956) (xy 172.919344 -419.554701) (xy 172.963101 -419.601298) (xy 173.000674 -419.653013)
			(xy 173.031468 -419.709028) (xy 173.055 -419.768461) (xy 173.070897 -419.830375) (xy 173.078908 -419.893793)
			(xy 173.07941 -419.925754) (xy 173.078908 -419.957715) (xy 173.070897 -420.021133) (xy 173.055 -420.083047)
			(xy 173.031468 -420.14248) (xy 173.000674 -420.198495) (xy 172.963101 -420.25021) (xy 172.919344 -420.296807)
			(xy 172.870091 -420.337552) (xy 172.81612 -420.371803) (xy 172.758281 -420.39902) (xy 172.697488 -420.418773)
			(xy 172.634698 -420.430751) (xy 172.570902 -420.434765) (xy 172.507106 -420.430751) (xy 172.444316 -420.418773)
			(xy 172.383523 -420.39902) (xy 172.325684 -420.371803) (xy 172.271713 -420.337552) (xy 172.22246 -420.296807)
			(xy 172.178703 -420.25021) (xy 172.14113 -420.198495) (xy 172.110336 -420.14248) (xy 172.086804 -420.083047)
			(xy 172.070907 -420.021133) (xy 172.062896 -419.957715) (xy 170.785945 -419.957715) (xy 170.820274 -420.007777)
			(xy 170.84856 -420.062001) (xy 170.870137 -420.119226) (xy 170.884691 -420.178627) (xy 170.892014 -420.239345)
			(xy 170.89247 -420.269924) (xy 170.892023 -420.300654) (xy 170.884612 -420.361667) (xy 170.8699 -420.421341)
			(xy 170.848103 -420.478806) (xy 170.819538 -420.533225) (xy 170.784621 -420.583804) (xy 170.743862 -420.629806)
			(xy 170.697856 -420.670559) (xy 170.647272 -420.70547) (xy 170.59285 -420.734028) (xy 170.535381 -420.755819)
			(xy 170.475706 -420.770523) (xy 170.414692 -420.777927) (xy 170.383962 -420.778432) (xy 170.351252 -420.777923)
			(xy 170.286373 -420.769529) (xy 170.223107 -420.752884) (xy 170.162497 -420.728263) (xy 170.105545 -420.696072)
			(xy 170.053192 -420.656844) (xy 170.029378 -420.634414) (xy 170.022763 -420.628413) (xy 170.0065 -420.621062)
			(xy 169.9887 -420.61975) (xy 169.971534 -420.624637) (xy 169.9641 -420.629588) (xy 169.937925 -420.648062)
			(xy 169.881819 -420.678991) (xy 169.822271 -420.702629) (xy 169.760227 -420.7186) (xy 169.696668 -420.726651)
			(xy 169.664634 -420.727124) (xy 169.6339 -420.72668) (xy 169.57288 -420.719275) (xy 169.513198 -420.704569)
			(xy 169.455724 -420.682775) (xy 169.401295 -420.654213) (xy 169.350707 -420.619298) (xy 169.304695 -420.57854)
			(xy 169.263933 -420.532533) (xy 169.229013 -420.481948) (xy 169.200445 -420.427522) (xy 169.178646 -420.37005)
			(xy 169.163934 -420.310369) (xy 169.156523 -420.24935) (xy 169.156126 -420.218616) (xy 169.15765 -420.18077)
			(xy 169.158158 -420.170864) (xy 169.152316 -420.152576) (xy 169.095166 -420.08298) (xy 169.078148 -420.073582)
			(xy 169.068242 -420.072312) (xy 169.040808 -420.068515) (xy 168.987357 -420.054022) (xy 168.936562 -420.031953)
			(xy 168.889492 -420.002773) (xy 168.847135 -419.967094) (xy 168.810382 -419.925666) (xy 168.780004 -419.87936)
			(xy 168.75664 -419.829148) (xy 168.740781 -419.776086) (xy 168.73276 -419.721289) (xy 168.7322 -419.693598)
			(xy 168.732852 -419.661544) (xy 168.743571 -419.59834) (xy 168.753536 -419.567868) (xy 168.75594 -419.560063)
			(xy 168.756199 -419.543742) (xy 168.754044 -419.535864) (xy 168.7449 -419.50767) (xy 168.742121 -419.500097)
			(xy 168.732675 -419.487033) (xy 168.726358 -419.482016) (xy 168.716417 -419.474675) (xy 168.6976 -419.458654)
			(xy 168.688766 -419.450012) (xy 168.26738 -419.028372) (xy 168.258419 -419.020394) (xy 168.235633 -419.012978)
			(xy 168.223692 -419.014148) (xy 168.130728 -419.028372) (xy 168.11117 -419.042342) (xy 168.105328 -419.053264)
			(xy 168.090686 -419.080344) (xy 168.055815 -419.131078) (xy 168.015071 -419.177229) (xy 167.96905 -419.218119)
			(xy 167.918427 -419.253151) (xy 167.863942 -419.281811) (xy 167.806394 -419.30368) (xy 167.746626 -419.318437)
			(xy 167.685513 -419.325865) (xy 167.654732 -419.326314) (xy 167.623998 -419.32587) (xy 167.562979 -419.318465)
			(xy 167.503298 -419.303758) (xy 167.445824 -419.281965) (xy 167.391396 -419.253402) (xy 167.340808 -419.218487)
			(xy 167.294798 -419.177729) (xy 167.254036 -419.131721) (xy 167.219118 -419.081136) (xy 167.190551 -419.026711)
			(xy 167.168753 -418.969239) (xy 167.154042 -418.909558) (xy 167.146632 -418.848539) (xy 167.146224 -418.817806)
			(xy 167.146673 -418.787024) (xy 167.154106 -418.725912) (xy 167.168866 -418.666144) (xy 167.190735 -418.608596)
			(xy 167.219393 -418.55411) (xy 167.254422 -418.503484) (xy 167.295307 -418.457458) (xy 167.341452 -418.416707)
			(xy 167.392181 -418.381826) (xy 167.419274 -418.36721) (xy 167.430196 -418.361368) (xy 167.444166 -418.34181)
			(xy 167.45839 -418.248846) (xy 167.459618 -418.236897) (xy 167.452203 -418.214084) (xy 167.444166 -418.205158)
			(xy 166.688008 -417.449) (xy 166.680561 -417.442312) (xy 166.662065 -417.434716) (xy 166.642069 -417.434716)
			(xy 166.623573 -417.442312) (xy 166.616126 -417.449) (xy 165.884606 -418.18052) (xy 165.877598 -418.188157)
			(xy 165.869847 -418.20736) (xy 165.870304 -418.228063) (xy 165.874192 -418.23767) (xy 165.92042 -418.338762)
			(xy 165.947598 -418.355018) (xy 165.9636 -418.353748) (xy 165.999668 -418.352478) (xy 166.031633 -418.352957)
			(xy 166.095058 -418.360966) (xy 166.156979 -418.376861) (xy 166.21642 -418.400392) (xy 166.272443 -418.431188)
			(xy 166.324164 -418.468762) (xy 166.370768 -418.512523) (xy 166.411519 -418.56178) (xy 166.445775 -418.615756)
			(xy 166.472996 -418.673601) (xy 166.492752 -418.734401) (xy 166.504731 -418.797197) (xy 166.508746 -418.861)
			(xy 166.504731 -418.924803) (xy 166.492752 -418.987599) (xy 166.472996 -419.048399) (xy 166.445775 -419.106244)
			(xy 166.411519 -419.16022) (xy 166.370768 -419.209477) (xy 166.324164 -419.253238) (xy 166.272443 -419.290812)
			(xy 166.21642 -419.321608) (xy 166.156979 -419.345139) (xy 166.095058 -419.361034) (xy 166.031633 -419.369043)
			(xy 165.999668 -419.369494) (xy 165.966258 -419.36897) (xy 165.900012 -419.360229) (xy 165.835482 -419.342888)
			(xy 165.773778 -419.317246) (xy 165.715963 -419.283744) (xy 165.663033 -419.24296) (xy 165.6159 -419.195596)
			(xy 165.575375 -419.142467) (xy 165.542156 -419.084489) (xy 165.529006 -419.053772) (xy 165.52545 -419.045136)
			(xy 165.513766 -419.032182) (xy 165.438836 -418.99332) (xy 165.42131 -418.991034) (xy 165.41242 -418.993066)
			(xy 165.381178 -418.998908) (xy 165.371526 -419.000178) (xy 165.355016 -419.009576) (xy 165.299136 -419.07841)
			(xy 165.293548 -419.096444) (xy 165.29431 -419.10635) (xy 165.295072 -419.132004) (xy 165.294608 -419.159256)
			(xy 165.286851 -419.213204) (xy 165.271494 -419.2655) (xy 165.248851 -419.315077) (xy 165.219382 -419.360927)
			(xy 165.183688 -419.402116) (xy 165.142495 -419.437806) (xy 165.096642 -419.46727) (xy 165.047062 -419.489908)
			(xy 164.994765 -419.505259) (xy 164.940816 -419.513011) (xy 164.913564 -419.513512) (xy 164.886171 -419.513038)
			(xy 164.831949 -419.505205) (xy 164.779402 -419.489704) (xy 164.754306 -419.478714) (xy 164.742368 -419.473126)
			(xy 164.71646 -419.474904) (xy 164.633656 -419.528244) (xy 164.6267 -419.5331) (xy 164.616218 -419.546427)
			(xy 164.610643 -419.56244) (xy 164.610288 -419.570916) (xy 164.610288 -420.270135) (xy 167.2308 -420.270135)
			(xy 167.2308 -420.206213) (xy 167.238811 -420.142795) (xy 167.254708 -420.080881) (xy 167.27824 -420.021448)
			(xy 167.309034 -419.965433) (xy 167.346607 -419.913718) (xy 167.390364 -419.867121) (xy 167.439617 -419.826376)
			(xy 167.493588 -419.792125) (xy 167.551427 -419.764908) (xy 167.61222 -419.745155) (xy 167.67501 -419.733177)
			(xy 167.738806 -419.729164) (xy 167.802602 -419.733177) (xy 167.865392 -419.745155) (xy 167.926185 -419.764908)
			(xy 167.984024 -419.792125) (xy 168.037995 -419.826376) (xy 168.087248 -419.867121) (xy 168.131005 -419.913718)
			(xy 168.168578 -419.965433) (xy 168.199372 -420.021448) (xy 168.222904 -420.080881) (xy 168.238801 -420.142795)
			(xy 168.246812 -420.206213) (xy 168.247314 -420.238174) (xy 168.246812 -420.270135) (xy 168.238801 -420.333553)
			(xy 168.222904 -420.395467) (xy 168.199372 -420.4549) (xy 168.168578 -420.510915) (xy 168.131005 -420.56263)
			(xy 168.087248 -420.609227) (xy 168.037995 -420.649972) (xy 167.984024 -420.684223) (xy 167.926185 -420.71144)
			(xy 167.865392 -420.731193) (xy 167.802602 -420.743171) (xy 167.738806 -420.747185) (xy 167.67501 -420.743171)
			(xy 167.61222 -420.731193) (xy 167.551427 -420.71144) (xy 167.493588 -420.684223) (xy 167.439617 -420.649972)
			(xy 167.390364 -420.609227) (xy 167.346607 -420.56263) (xy 167.309034 -420.510915) (xy 167.27824 -420.4549)
			(xy 167.254708 -420.395467) (xy 167.238811 -420.333553) (xy 167.2308 -420.270135) (xy 164.610288 -420.270135)
			(xy 164.610288 -420.41572) (xy 164.609829 -420.44031) (xy 164.602129 -420.488884) (xy 164.586923 -420.535655)
			(xy 164.564585 -420.57947) (xy 164.535665 -420.619249) (xy 164.518594 -420.636954) (xy 162.859212 -422.296336)
			(xy 162.853102 -422.302877) (xy 162.84551 -422.319074) (xy 162.843974 -422.336895) (xy 162.846004 -422.345612)
			(xy 162.866523 -422.421769) (xy 163.946834 -422.421769) (xy 163.946834 -422.357847) (xy 163.954845 -422.294429)
			(xy 163.970742 -422.232515) (xy 163.994274 -422.173082) (xy 164.025068 -422.117067) (xy 164.062641 -422.065352)
			(xy 164.106398 -422.018755) (xy 164.155651 -421.97801) (xy 164.209622 -421.943759) (xy 164.267461 -421.916542)
			(xy 164.328254 -421.896789) (xy 164.391044 -421.884811) (xy 164.45484 -421.880798) (xy 164.518636 -421.884811)
			(xy 164.581426 -421.896789) (xy 164.642219 -421.916542) (xy 164.700058 -421.943759) (xy 164.754029 -421.97801)
			(xy 164.803282 -422.018755) (xy 164.847039 -422.065352) (xy 164.884612 -422.117067) (xy 164.915406 -422.173082)
			(xy 164.938938 -422.232515) (xy 164.954835 -422.294429) (xy 164.962846 -422.357847) (xy 164.963348 -422.389808)
			(xy 164.962846 -422.421769) (xy 164.954835 -422.485187) (xy 164.938938 -422.547101) (xy 164.915406 -422.606534)
			(xy 164.884612 -422.662549) (xy 164.850282 -422.7098) (xy 166.034537 -422.7098) (xy 166.038551 -422.646012)
			(xy 166.050527 -422.583229) (xy 166.070277 -422.522442) (xy 166.09749 -422.46461) (xy 166.131736 -422.410645)
			(xy 166.172476 -422.361397) (xy 166.219067 -422.317644) (xy 166.270775 -422.280075) (xy 166.326783 -422.249282)
			(xy 166.386208 -422.225752) (xy 166.448114 -422.209856) (xy 166.511525 -422.201843) (xy 166.543482 -422.20134)
			(xy 166.578507 -422.201918) (xy 166.647894 -422.211532) (xy 166.715304 -422.230579) (xy 166.779462 -422.2587)
			(xy 166.839152 -422.295362) (xy 166.86657 -422.317164) (xy 166.873719 -422.322563) (xy 166.890633 -422.328426)
			(xy 166.89959 -422.328594) (xy 166.929562 -422.32834) (xy 166.938552 -422.327813) (xy 166.955335 -422.321313)
			(xy 166.962328 -422.31564) (xy 166.985537 -422.295997) (xy 167.035811 -422.261797) (xy 167.089803 -422.233832)
			(xy 167.146743 -422.212502) (xy 167.205819 -422.19811) (xy 167.26619 -422.190862) (xy 167.296592 -422.190418)
			(xy 167.328556 -422.190847) (xy 167.391981 -422.198858) (xy 167.453901 -422.214756) (xy 167.513341 -422.238289)
			(xy 167.569362 -422.269086) (xy 167.621082 -422.306662) (xy 167.632807 -422.317672) (xy 170.681902 -422.317672)
			(xy 170.685973 -422.26205) (xy 170.698099 -422.207613) (xy 170.718022 -422.155522) (xy 170.745318 -422.106887)
			(xy 170.779404 -422.062744) (xy 170.819553 -422.024035) (xy 170.864911 -421.991584) (xy 170.914511 -421.966083)
			(xy 170.967295 -421.948076) (xy 171.022138 -421.937946) (xy 171.077872 -421.935909) (xy 171.133309 -421.942009)
			(xy 171.187266 -421.956115) (xy 171.238595 -421.977927) (xy 171.286201 -422.006981) (xy 171.329069 -422.042656)
			(xy 171.366286 -422.084193) (xy 171.397059 -422.130706) (xy 171.420731 -422.181203) (xy 171.436799 -422.23461)
			(xy 171.444919 -422.289786) (xy 171.445428 -422.317672) (xy 171.444919 -422.345558) (xy 171.436799 -422.400734)
			(xy 171.420731 -422.454141) (xy 171.397059 -422.504638) (xy 171.366286 -422.551151) (xy 171.329069 -422.592688)
			(xy 171.286201 -422.628363) (xy 171.238595 -422.657417) (xy 171.187266 -422.679229) (xy 171.133309 -422.693335)
			(xy 171.077872 -422.699435) (xy 171.022138 -422.697398) (xy 170.967295 -422.687268) (xy 170.914511 -422.669261)
			(xy 170.864911 -422.64376) (xy 170.819553 -422.611309) (xy 170.779404 -422.5726) (xy 170.745318 -422.528457)
			(xy 170.718022 -422.479822) (xy 170.698099 -422.427731) (xy 170.685973 -422.373294) (xy 170.681902 -422.317672)
			(xy 167.632807 -422.317672) (xy 167.667684 -422.350423) (xy 167.708434 -422.399681) (xy 167.742689 -422.453657)
			(xy 167.769909 -422.511502) (xy 167.789664 -422.572301) (xy 167.801643 -422.635098) (xy 167.805658 -422.6989)
			(xy 167.801643 -422.762702) (xy 167.789664 -422.825499) (xy 167.769909 -422.886298) (xy 167.742689 -422.944143)
			(xy 167.708434 -422.998119) (xy 167.667684 -423.047377) (xy 167.621082 -423.091138) (xy 167.569362 -423.128714)
			(xy 167.513341 -423.159511) (xy 167.453901 -423.183044) (xy 167.391981 -423.198942) (xy 167.328556 -423.206953)
			(xy 167.296592 -423.207434) (xy 167.261566 -423.206876) (xy 167.192178 -423.197259) (xy 167.124767 -423.178207)
			(xy 167.06061 -423.150081) (xy 167.000921 -423.113415) (xy 166.973504 -423.09161) (xy 166.966364 -423.086197)
			(xy 166.949443 -423.080343) (xy 166.940484 -423.08018) (xy 166.910512 -423.080434) (xy 166.901521 -423.080955)
			(xy 166.884739 -423.08746) (xy 166.877746 -423.093134) (xy 166.854544 -423.112785) (xy 166.804269 -423.146985)
			(xy 166.750275 -423.174949) (xy 166.693334 -423.196278) (xy 166.634256 -423.210668) (xy 166.573885 -423.217914)
			(xy 166.543482 -423.218356) (xy 166.511525 -423.217757) (xy 166.448114 -423.209744) (xy 166.386208 -423.193848)
			(xy 166.326783 -423.170318) (xy 166.270775 -423.139525) (xy 166.219067 -423.101956) (xy 166.172476 -423.058203)
			(xy 166.131736 -423.008955) (xy 166.09749 -422.95499) (xy 166.070277 -422.897158) (xy 166.050527 -422.836371)
			(xy 166.038551 -422.773588) (xy 166.034537 -422.7098) (xy 164.850282 -422.7098) (xy 164.847039 -422.714264)
			(xy 164.803282 -422.760861) (xy 164.754029 -422.801606) (xy 164.700058 -422.835857) (xy 164.642219 -422.863074)
			(xy 164.581426 -422.882827) (xy 164.518636 -422.894805) (xy 164.45484 -422.898819) (xy 164.391044 -422.894805)
			(xy 164.328254 -422.882827) (xy 164.267461 -422.863074) (xy 164.209622 -422.835857) (xy 164.155651 -422.801606)
			(xy 164.106398 -422.760861) (xy 164.062641 -422.714264) (xy 164.025068 -422.662549) (xy 163.994274 -422.606534)
			(xy 163.970742 -422.547101) (xy 163.954845 -422.485187) (xy 163.946834 -422.421769) (xy 162.866523 -422.421769)
			(xy 162.87242 -422.443656) (xy 162.891724 -422.46296) (xy 162.904932 -422.466516) (xy 162.937068 -422.475541)
			(xy 162.998825 -422.500876) (xy 163.056732 -422.53408) (xy 163.109793 -422.57458) (xy 163.157093 -422.62168)
			(xy 163.197819 -422.674568) (xy 163.231268 -422.732333) (xy 163.256866 -422.793981) (xy 163.274171 -422.85845)
			(xy 163.282885 -422.92463) (xy 163.283392 -422.958006) (xy 163.28292 -422.989571) (xy 163.275114 -423.052215)
			(xy 163.25961 -423.113411) (xy 163.236648 -423.172216) (xy 163.20658 -423.227724) (xy 163.169869 -423.279082)
			(xy 163.127081 -423.325498) (xy 163.078874 -423.366258) (xy 163.025991 -423.400735) (xy 162.969245 -423.428397)
			(xy 162.909511 -423.44882) (xy 162.847707 -423.461687) (xy 162.816286 -423.464736) (xy 162.807125 -423.465916)
			(xy 162.790467 -423.473863) (xy 162.783774 -423.48023) (xy 162.762946 -423.502074) (xy 162.756556 -423.509393)
			(xy 162.749355 -423.527419) (xy 162.748976 -423.537126) (xy 162.748976 -423.860976) (xy 166.220138 -423.860976)
			(xy 166.224209 -423.805354) (xy 166.236335 -423.750917) (xy 166.256258 -423.698826) (xy 166.283554 -423.650191)
			(xy 166.31764 -423.606048) (xy 166.357789 -423.567339) (xy 166.403147 -423.534888) (xy 166.452747 -423.509387)
			(xy 166.505531 -423.49138) (xy 166.560374 -423.48125) (xy 166.616108 -423.479213) (xy 166.671545 -423.485313)
			(xy 166.725502 -423.499419) (xy 166.776831 -423.521231) (xy 166.824437 -423.550285) (xy 166.867305 -423.58596)
			(xy 166.904522 -423.627497) (xy 166.935295 -423.67401) (xy 166.958967 -423.724507) (xy 166.975035 -423.777914)
			(xy 166.983155 -423.83309) (xy 166.983664 -423.860976) (xy 166.983155 -423.888862) (xy 166.975035 -423.944038)
			(xy 166.958967 -423.997445) (xy 166.935295 -424.047942) (xy 166.904522 -424.094455) (xy 166.901649 -424.097661)
			(xy 170.573186 -424.097661) (xy 170.573186 -424.033739) (xy 170.581197 -423.970321) (xy 170.597094 -423.908407)
			(xy 170.620626 -423.848974) (xy 170.65142 -423.792959) (xy 170.688993 -423.741244) (xy 170.73275 -423.694647)
			(xy 170.782003 -423.653902) (xy 170.835974 -423.619651) (xy 170.893813 -423.592434) (xy 170.954606 -423.572681)
			(xy 171.017396 -423.560703) (xy 171.081192 -423.55669) (xy 171.144988 -423.560703) (xy 171.207778 -423.572681)
			(xy 171.268571 -423.592434) (xy 171.32641 -423.619651) (xy 171.380381 -423.653902) (xy 171.429634 -423.694647)
			(xy 171.473391 -423.741244) (xy 171.510964 -423.792959) (xy 171.541758 -423.848974) (xy 171.56529 -423.908407)
			(xy 171.581187 -423.970321) (xy 171.589198 -424.033739) (xy 171.5897 -424.0657) (xy 171.589198 -424.097661)
			(xy 171.581187 -424.161079) (xy 171.56529 -424.222993) (xy 171.541758 -424.282426) (xy 171.510964 -424.338441)
			(xy 171.473391 -424.390156) (xy 171.429634 -424.436753) (xy 171.380381 -424.477498) (xy 171.32641 -424.511749)
			(xy 171.268571 -424.538966) (xy 171.207778 -424.558719) (xy 171.144988 -424.570697) (xy 171.081192 -424.574711)
			(xy 171.017396 -424.570697) (xy 170.954606 -424.558719) (xy 170.893813 -424.538966) (xy 170.835974 -424.511749)
			(xy 170.782003 -424.477498) (xy 170.73275 -424.436753) (xy 170.688993 -424.390156) (xy 170.65142 -424.338441)
			(xy 170.620626 -424.282426) (xy 170.597094 -424.222993) (xy 170.581197 -424.161079) (xy 170.573186 -424.097661)
			(xy 166.901649 -424.097661) (xy 166.867305 -424.135992) (xy 166.824437 -424.171667) (xy 166.776831 -424.200721)
			(xy 166.725502 -424.222533) (xy 166.671545 -424.236639) (xy 166.616108 -424.242739) (xy 166.560374 -424.240702)
			(xy 166.505531 -424.230572) (xy 166.452747 -424.212565) (xy 166.403147 -424.187064) (xy 166.357789 -424.154613)
			(xy 166.31764 -424.115904) (xy 166.283554 -424.071761) (xy 166.256258 -424.023126) (xy 166.236335 -423.971035)
			(xy 166.224209 -423.916598) (xy 166.220138 -423.860976) (xy 162.748976 -423.860976) (xy 162.748976 -423.98188)
			(xy 162.749509 -423.99187) (xy 162.757215 -424.010309) (xy 162.763962 -424.017694) (xy 162.834828 -424.08856)
			(xy 162.842199 -424.095302) (xy 162.860661 -424.102891) (xy 162.870642 -424.103292) (xy 164.16655 -424.103292)
			(xy 164.19114 -424.103753) (xy 164.239712 -424.111457) (xy 164.28648 -424.126665) (xy 164.330292 -424.149005)
			(xy 164.370069 -424.177926) (xy 164.387784 -424.194986) (xy 165.079426 -424.886628) (xy 165.100254 -424.894248)
			(xy 165.11143 -424.893486) (xy 165.1508 -424.891962) (xy 165.182763 -424.892464) (xy 165.246185 -424.900476)
			(xy 165.308102 -424.916374) (xy 165.367539 -424.939906) (xy 165.423558 -424.970703) (xy 165.475275 -425.008278)
			(xy 165.521875 -425.052038) (xy 165.562622 -425.101294) (xy 165.596876 -425.155268) (xy 165.624094 -425.21311)
			(xy 165.643848 -425.273907) (xy 165.655827 -425.3367) (xy 165.659841 -425.4005) (xy 165.658885 -425.4157)
			(xy 167.519078 -425.4157) (xy 167.523092 -425.351902) (xy 167.535071 -425.28911) (xy 167.554825 -425.228314)
			(xy 167.582043 -425.170474) (xy 167.616296 -425.116501) (xy 167.657043 -425.067247) (xy 167.703643 -425.023488)
			(xy 167.755359 -424.985915) (xy 167.811377 -424.95512) (xy 167.870813 -424.931589) (xy 167.932729 -424.915693)
			(xy 167.99615 -424.907682) (xy 168.028112 -424.907202) (xy 168.060271 -424.907691) (xy 168.124075 -424.915813)
			(xy 168.186347 -424.931912) (xy 168.246092 -424.955733) (xy 168.302358 -424.986895) (xy 168.328594 -425.0055)
			(xy 168.337683 -425.011549) (xy 168.359036 -425.016005) (xy 168.380309 -425.011187) (xy 168.3893 -425.004992)
			(xy 168.415911 -424.985504) (xy 168.473206 -424.952824) (xy 168.534243 -424.927822) (xy 168.598 -424.910917)
			(xy 168.663406 -424.902392) (xy 168.696386 -424.901868) (xy 168.728347 -424.902396) (xy 168.791766 -424.910406)
			(xy 168.853681 -424.926302) (xy 168.913116 -424.949832) (xy 168.969132 -424.980626) (xy 169.020848 -425.018198)
			(xy 169.067446 -425.061955) (xy 169.108192 -425.111208) (xy 169.142445 -425.16518) (xy 169.169662 -425.223019)
			(xy 169.189416 -425.283813) (xy 169.198579 -425.331847) (xy 170.52518 -425.331847) (xy 170.52518 -425.267925)
			(xy 170.533191 -425.204507) (xy 170.549088 -425.142593) (xy 170.57262 -425.08316) (xy 170.603414 -425.027145)
			(xy 170.640987 -424.97543) (xy 170.684744 -424.928833) (xy 170.733997 -424.888088) (xy 170.787968 -424.853837)
			(xy 170.845807 -424.82662) (xy 170.9066 -424.806867) (xy 170.96939 -424.794889) (xy 171.033186 -424.790876)
			(xy 171.096982 -424.794889) (xy 171.159772 -424.806867) (xy 171.220565 -424.82662) (xy 171.278404 -424.853837)
			(xy 171.332375 -424.888088) (xy 171.381628 -424.928833) (xy 171.425385 -424.97543) (xy 171.462958 -425.027145)
			(xy 171.493752 -425.08316) (xy 171.517284 -425.142593) (xy 171.533181 -425.204507) (xy 171.541192 -425.267925)
			(xy 171.541694 -425.299886) (xy 171.541192 -425.331847) (xy 171.533181 -425.395265) (xy 171.517284 -425.457179)
			(xy 171.493752 -425.516612) (xy 171.462958 -425.572627) (xy 171.425385 -425.624342) (xy 171.381628 -425.670939)
			(xy 171.332375 -425.711684) (xy 171.278404 -425.745935) (xy 171.220565 -425.773152) (xy 171.159772 -425.792905)
			(xy 171.096982 -425.804883) (xy 171.033186 -425.808897) (xy 170.96939 -425.804883) (xy 170.9066 -425.792905)
			(xy 170.845807 -425.773152) (xy 170.787968 -425.745935) (xy 170.733997 -425.711684) (xy 170.684744 -425.670939)
			(xy 170.640987 -425.624342) (xy 170.603414 -425.572627) (xy 170.57262 -425.516612) (xy 170.549088 -425.457179)
			(xy 170.533191 -425.395265) (xy 170.52518 -425.331847) (xy 169.198579 -425.331847) (xy 169.201394 -425.346603)
			(xy 169.205408 -425.4104) (xy 169.201394 -425.474197) (xy 169.189416 -425.536987) (xy 169.169662 -425.597781)
			(xy 169.142445 -425.65562) (xy 169.108192 -425.709592) (xy 169.067446 -425.758845) (xy 169.020848 -425.802602)
			(xy 168.969132 -425.840174) (xy 168.913116 -425.870968) (xy 168.853681 -425.894498) (xy 168.791766 -425.910394)
			(xy 168.728347 -425.918404) (xy 168.696386 -425.918884) (xy 168.664226 -425.918399) (xy 168.600422 -425.910277)
			(xy 168.538151 -425.894176) (xy 168.478405 -425.870355) (xy 168.42214 -425.839192) (xy 168.395904 -425.820586)
			(xy 168.386815 -425.814537) (xy 168.365463 -425.810083) (xy 168.344189 -425.8149) (xy 168.335198 -425.821094)
			(xy 168.308586 -425.840581) (xy 168.251292 -425.873262) (xy 168.190254 -425.898264) (xy 168.126498 -425.915169)
			(xy 168.061092 -425.923694) (xy 168.028112 -425.924218) (xy 167.99615 -425.923718) (xy 167.932729 -425.915707)
			(xy 167.870813 -425.899811) (xy 167.811377 -425.87628) (xy 167.755359 -425.845485) (xy 167.703643 -425.807912)
			(xy 167.657043 -425.764153) (xy 167.616296 -425.714899) (xy 167.582043 -425.660926) (xy 167.554825 -425.603086)
			(xy 167.535071 -425.54229) (xy 167.523092 -425.479498) (xy 167.519078 -425.4157) (xy 165.658885 -425.4157)
			(xy 165.655827 -425.4643) (xy 165.643848 -425.527093) (xy 165.624094 -425.58789) (xy 165.596876 -425.645732)
			(xy 165.562622 -425.699706) (xy 165.521875 -425.748962) (xy 165.475275 -425.792722) (xy 165.423558 -425.830297)
			(xy 165.367539 -425.861094) (xy 165.308102 -425.884626) (xy 165.246185 -425.900524) (xy 165.182763 -425.908536)
			(xy 165.1508 -425.908978) (xy 165.117241 -425.90844) (xy 165.050704 -425.899613) (xy 164.985907 -425.882112)
			(xy 164.923974 -425.856242) (xy 164.865982 -425.822451) (xy 164.839142 -425.802298) (xy 164.829887 -425.795845)
			(xy 164.8079 -425.790917) (xy 164.785913 -425.795845) (xy 164.776658 -425.802298) (xy 164.74981 -425.82244)
			(xy 164.691823 -425.856237) (xy 164.629892 -425.88211) (xy 164.565095 -425.899609) (xy 164.498559 -425.908428)
			(xy 164.465 -425.908978) (xy 164.431179 -425.908422) (xy 164.364136 -425.899452) (xy 164.298873 -425.881671)
			(xy 164.236545 -425.855392) (xy 164.178253 -425.82108) (xy 164.125025 -425.77934) (xy 164.077803 -425.730911)
			(xy 164.03742 -425.676648) (xy 164.0205 -425.647358) (xy 164.0158 -425.639615) (xy 164.002076 -425.627812)
			(xy 163.985101 -425.621527) (xy 163.97605 -425.621196) (xy 163.88715 -425.621196) (xy 163.878107 -425.621567)
			(xy 163.861147 -425.627856) (xy 163.847421 -425.639635) (xy 163.8427 -425.647358) (xy 163.825788 -425.676649)
			(xy 163.78539 -425.730894) (xy 163.738158 -425.779307) (xy 163.684927 -425.821033) (xy 163.626635 -425.855336)
			(xy 163.564312 -425.88161) (xy 163.499055 -425.899393) (xy 163.432018 -425.90837) (xy 163.3982 -425.908978)
			(xy 163.364641 -425.90844) (xy 163.298104 -425.899613) (xy 163.233307 -425.882112) (xy 163.171374 -425.856242)
			(xy 163.113382 -425.822451) (xy 163.086542 -425.802298) (xy 163.077287 -425.795845) (xy 163.0553 -425.790917)
			(xy 163.033313 -425.795845) (xy 163.024058 -425.802298) (xy 162.998501 -425.821496) (xy 162.943466 -425.85401)
			(xy 162.88479 -425.879369) (xy 162.823398 -425.897174) (xy 162.791902 -425.902628) (xy 162.77336 -425.905676)
			(xy 162.748976 -425.934124) (xy 162.748976 -427.07814) (xy 162.749492 -427.08868) (xy 162.757947 -427.107989)
			(xy 162.773454 -427.122267) (xy 162.783266 -427.126146) (xy 162.889692 -427.162722) (xy 162.92068 -427.153324)
			(xy 162.93084 -427.14037) (xy 162.951552 -427.114573) (xy 162.998569 -427.068032) (xy 163.051224 -427.02798)
			(xy 163.108627 -426.995093) (xy 163.16981 -426.969927) (xy 163.233739 -426.952905) (xy 163.299336 -426.944317)
			(xy 163.332414 -426.943774) (xy 163.363145 -426.944239) (xy 163.424158 -426.951649) (xy 163.483834 -426.966358)
			(xy 163.541301 -426.988154) (xy 163.595723 -427.016717) (xy 163.646304 -427.051631) (xy 163.692309 -427.092388)
			(xy 163.733066 -427.138392) (xy 163.767981 -427.188974) (xy 163.796545 -427.243395) (xy 163.81834 -427.300862)
			(xy 163.833051 -427.360538) (xy 163.840461 -427.421551) (xy 163.840796 -427.4439) (xy 164.082982 -427.4439)
			(xy 164.087053 -427.388278) (xy 164.099179 -427.333841) (xy 164.119102 -427.28175) (xy 164.146398 -427.233115)
			(xy 164.180484 -427.188972) (xy 164.220633 -427.150263) (xy 164.265991 -427.117812) (xy 164.315591 -427.092311)
			(xy 164.368375 -427.074304) (xy 164.423218 -427.064174) (xy 164.478952 -427.062137) (xy 164.534389 -427.068237)
			(xy 164.588346 -427.082343) (xy 164.639675 -427.104155) (xy 164.687281 -427.133209) (xy 164.730149 -427.168884)
			(xy 164.767366 -427.210421) (xy 164.798139 -427.256934) (xy 164.821811 -427.307431) (xy 164.837879 -427.360838)
			(xy 164.845999 -427.416014) (xy 164.846508 -427.4439) (xy 164.845999 -427.471786) (xy 164.837879 -427.526962)
			(xy 164.821811 -427.580369) (xy 164.821388 -427.581271) (xy 165.39311 -427.581271) (xy 165.39311 -427.517349)
			(xy 165.401121 -427.453931) (xy 165.417018 -427.392017) (xy 165.44055 -427.332584) (xy 165.471344 -427.276569)
			(xy 165.508917 -427.224854) (xy 165.552674 -427.178257) (xy 165.601927 -427.137512) (xy 165.655898 -427.103261)
			(xy 165.713737 -427.076044) (xy 165.77453 -427.056291) (xy 165.83732 -427.044313) (xy 165.901116 -427.0403)
			(xy 165.964912 -427.044313) (xy 166.027702 -427.056291) (xy 166.088495 -427.076044) (xy 166.146334 -427.103261)
			(xy 166.200305 -427.137512) (xy 166.249558 -427.178257) (xy 166.293315 -427.224854) (xy 166.330888 -427.276569)
			(xy 166.340353 -427.293786) (xy 173.731172 -427.293786) (xy 173.735243 -427.238164) (xy 173.747369 -427.183727)
			(xy 173.767292 -427.131636) (xy 173.794588 -427.083001) (xy 173.828674 -427.038858) (xy 173.868823 -427.000149)
			(xy 173.914181 -426.967698) (xy 173.963781 -426.942197) (xy 174.016565 -426.92419) (xy 174.071408 -426.91406)
			(xy 174.127142 -426.912023) (xy 174.182579 -426.918123) (xy 174.236536 -426.932229) (xy 174.287865 -426.954041)
			(xy 174.335471 -426.983095) (xy 174.378339 -427.01877) (xy 174.415556 -427.060307) (xy 174.446329 -427.10682)
			(xy 174.470001 -427.157317) (xy 174.486069 -427.210724) (xy 174.494189 -427.2659) (xy 174.494298 -427.271899)
			(xy 175.148234 -427.271899) (xy 175.148234 -427.207977) (xy 175.156245 -427.144559) (xy 175.172142 -427.082645)
			(xy 175.195674 -427.023212) (xy 175.226468 -426.967197) (xy 175.264041 -426.915482) (xy 175.307798 -426.868885)
			(xy 175.357051 -426.82814) (xy 175.411022 -426.793889) (xy 175.468861 -426.766672) (xy 175.529654 -426.746919)
			(xy 175.592444 -426.734941) (xy 175.65624 -426.730928) (xy 175.720036 -426.734941) (xy 175.782826 -426.746919)
			(xy 175.843619 -426.766672) (xy 175.901458 -426.793889) (xy 175.955429 -426.82814) (xy 176.004682 -426.868885)
			(xy 176.048439 -426.915482) (xy 176.086012 -426.967197) (xy 176.116806 -427.023212) (xy 176.140338 -427.082645)
			(xy 176.156235 -427.144559) (xy 176.164246 -427.207977) (xy 176.164748 -427.239938) (xy 176.164246 -427.271899)
			(xy 176.156235 -427.335317) (xy 176.140338 -427.397231) (xy 176.116806 -427.456664) (xy 176.086012 -427.512679)
			(xy 176.048439 -427.564394) (xy 176.004682 -427.610991) (xy 175.955429 -427.651736) (xy 175.901458 -427.685987)
			(xy 175.843619 -427.713204) (xy 175.782826 -427.732957) (xy 175.720036 -427.744935) (xy 175.65624 -427.748949)
			(xy 175.592444 -427.744935) (xy 175.529654 -427.732957) (xy 175.468861 -427.713204) (xy 175.411022 -427.685987)
			(xy 175.357051 -427.651736) (xy 175.307798 -427.610991) (xy 175.264041 -427.564394) (xy 175.226468 -427.512679)
			(xy 175.195674 -427.456664) (xy 175.172142 -427.397231) (xy 175.156245 -427.335317) (xy 175.148234 -427.271899)
			(xy 174.494298 -427.271899) (xy 174.494698 -427.293786) (xy 174.494189 -427.321672) (xy 174.486069 -427.376848)
			(xy 174.470001 -427.430255) (xy 174.446329 -427.480752) (xy 174.415556 -427.527265) (xy 174.378339 -427.568802)
			(xy 174.335471 -427.604477) (xy 174.287865 -427.633531) (xy 174.236536 -427.655343) (xy 174.182579 -427.669449)
			(xy 174.127142 -427.675549) (xy 174.071408 -427.673512) (xy 174.016565 -427.663382) (xy 173.963781 -427.645375)
			(xy 173.914181 -427.619874) (xy 173.868823 -427.587423) (xy 173.828674 -427.548714) (xy 173.794588 -427.504571)
			(xy 173.767292 -427.455936) (xy 173.747369 -427.403845) (xy 173.735243 -427.349408) (xy 173.731172 -427.293786)
			(xy 166.340353 -427.293786) (xy 166.361682 -427.332584) (xy 166.385214 -427.392017) (xy 166.401111 -427.453931)
			(xy 166.409122 -427.517349) (xy 166.409624 -427.54931) (xy 166.409122 -427.581271) (xy 166.401111 -427.644689)
			(xy 166.385214 -427.706603) (xy 166.361682 -427.766036) (xy 166.330888 -427.822051) (xy 166.293315 -427.873766)
			(xy 166.249558 -427.920363) (xy 166.200305 -427.961108) (xy 166.146334 -427.995359) (xy 166.088495 -428.022576)
			(xy 166.027702 -428.042329) (xy 165.964912 -428.054307) (xy 165.901116 -428.058321) (xy 165.83732 -428.054307)
			(xy 165.77453 -428.042329) (xy 165.713737 -428.022576) (xy 165.655898 -427.995359) (xy 165.601927 -427.961108)
			(xy 165.552674 -427.920363) (xy 165.508917 -427.873766) (xy 165.471344 -427.822051) (xy 165.44055 -427.766036)
			(xy 165.417018 -427.706603) (xy 165.401121 -427.644689) (xy 165.39311 -427.581271) (xy 164.821388 -427.581271)
			(xy 164.798139 -427.630866) (xy 164.767366 -427.677379) (xy 164.730149 -427.718916) (xy 164.687281 -427.754591)
			(xy 164.639675 -427.783645) (xy 164.588346 -427.805457) (xy 164.534389 -427.819563) (xy 164.478952 -427.825663)
			(xy 164.423218 -427.823626) (xy 164.368375 -427.813496) (xy 164.315591 -427.795489) (xy 164.265991 -427.769988)
			(xy 164.220633 -427.737537) (xy 164.180484 -427.698828) (xy 164.146398 -427.654685) (xy 164.119102 -427.60605)
			(xy 164.099179 -427.553959) (xy 164.087053 -427.499522) (xy 164.082982 -427.4439) (xy 163.840796 -427.4439)
			(xy 163.840922 -427.452282) (xy 163.840403 -427.484848) (xy 163.832086 -427.549446) (xy 163.815585 -427.612453)
			(xy 163.791171 -427.672836) (xy 163.759244 -427.729606) (xy 163.720327 -427.781832) (xy 163.675058 -427.828659)
			(xy 163.624178 -427.869321) (xy 163.56852 -427.90315) (xy 163.508998 -427.929592) (xy 163.477956 -427.939454)
			(xy 163.464748 -427.943518) (xy 163.44646 -427.962568) (xy 163.421822 -428.060358) (xy 163.420031 -428.068922)
			(xy 163.421702 -428.086327) (xy 163.429131 -428.102155) (xy 163.43503 -428.108618) (xy 163.737036 -428.410624)
			(xy 163.744433 -428.417473) (xy 163.763032 -428.425206) (xy 163.773104 -428.42561) (xy 164.624258 -428.42561)
		)
		(stroke
			(width 0)
			(type solid)
		)
		(fill yes)
		(layer "In13.Cu")
		(net "P1V8_CPU1_RT_1D")
	)
	(gr_poly
		(pts
			(xy 435.376574 -374.328182) (xy 435.386761 -374.326034) (xy 435.404328 -374.314894) (xy 435.41061 -374.306592)
			(xy 435.41061 -374.306084) (xy 435.41315 -374.302274) (xy 435.455822 -374.224042) (xy 435.458761 -374.218378)
			(xy 435.461983 -374.206036) (xy 435.462172 -374.199658) (xy 435.457092 -374.182386) (xy 435.454806 -374.176036)
			(xy 435.450488 -374.166638) (xy 435.432181 -374.136232) (xy 435.403312 -374.071395) (xy 435.383752 -374.003169)
			(xy 435.373883 -373.932885) (xy 435.373272 -373.897398) (xy 435.373774 -373.865437) (xy 435.381785 -373.802019)
			(xy 435.397682 -373.740105) (xy 435.421214 -373.680672) (xy 435.452008 -373.624657) (xy 435.489581 -373.572942)
			(xy 435.533338 -373.526345) (xy 435.582591 -373.4856) (xy 435.636562 -373.451349) (xy 435.694401 -373.424132)
			(xy 435.755194 -373.404379) (xy 435.817984 -373.392401) (xy 435.88178 -373.388388) (xy 435.945576 -373.392401)
			(xy 436.008366 -373.404379) (xy 436.069159 -373.424132) (xy 436.126998 -373.451349) (xy 436.180969 -373.4856)
			(xy 436.230222 -373.526345) (xy 436.273979 -373.572942) (xy 436.311552 -373.624657) (xy 436.342346 -373.680672)
			(xy 436.365878 -373.740105) (xy 436.381775 -373.802019) (xy 436.389786 -373.865437) (xy 436.390288 -373.897398)
			(xy 436.389704 -373.932472) (xy 436.380066 -374.001955) (xy 436.36096 -374.06945) (xy 436.332748 -374.133675)
			(xy 436.31485 -374.163844) (xy 436.311802 -374.169686) (xy 436.307484 -374.179084) (xy 436.301388 -374.199658)
			(xy 436.301615 -374.206032) (xy 436.30482 -374.218372) (xy 436.307738 -374.224042) (xy 436.35041 -374.302274)
			(xy 436.35295 -374.306084) (xy 436.35295 -374.306592) (xy 436.359209 -374.314919) (xy 436.376786 -374.326059)
			(xy 436.386986 -374.328182) (xy 436.39359 -374.32869) (xy 455.079862 -374.32869) (xy 455.085871 -374.328521)
			(xy 455.097552 -374.325694) (xy 455.102976 -374.323102) (xy 455.106452 -374.321265) (xy 455.112835 -374.316675)
			(xy 455.115676 -374.313958) (xy 456.909932 -372.519702) (xy 456.912639 -372.516852) (xy 456.917235 -372.510475)
			(xy 456.919076 -372.507002) (xy 456.921665 -372.501576) (xy 456.9245 -372.489897) (xy 456.924664 -372.483888)
			(xy 456.924664 -367.631472) (xy 456.922886 -367.618264) (xy 456.921108 -367.612168) (xy 456.91933 -367.60912)
			(xy 456.914896 -367.602432) (xy 456.909983 -367.587167) (xy 456.909678 -367.579148) (xy 456.909678 -364.55477)
			(xy 456.909678 -364.551214) (xy 456.909075 -364.545023) (xy 456.905231 -364.533196) (xy 456.902058 -364.527846)
			(xy 456.900026 -364.525052) (xy 456.834803 -364.434404) (xy 456.709955 -364.249213) (xy 456.591643 -364.059779)
			(xy 456.480012 -363.866333) (xy 456.375197 -363.66911) (xy 456.277326 -363.468351) (xy 456.186518 -363.2643)
			(xy 456.102884 -363.057205) (xy 456.026525 -362.847319) (xy 455.957535 -362.634896) (xy 455.895998 -362.420196)
			(xy 455.841988 -362.20348) (xy 455.795571 -361.985012) (xy 455.756803 -361.765057) (xy 455.725733 -361.543884)
			(xy 455.702397 -361.321762) (xy 455.686824 -361.09896) (xy 455.679033 -360.875751) (xy 455.679034 -360.652407)
			(xy 455.686826 -360.429198) (xy 455.702401 -360.206396) (xy 455.725738 -359.984274) (xy 455.75681 -359.763101)
			(xy 455.795579 -359.543147) (xy 455.841997 -359.324679) (xy 455.896009 -359.107963) (xy 455.957548 -358.893263)
			(xy 456.026539 -358.680841) (xy 456.102899 -358.470955) (xy 456.186534 -358.263861) (xy 456.277344 -358.059811)
			(xy 456.375216 -357.859052) (xy 456.480032 -357.66183) (xy 456.591665 -357.468385) (xy 456.709978 -357.278952)
			(xy 456.834827 -357.093761) (xy 456.900026 -357.003096) (xy 456.902058 -357.000302) (xy 456.90518 -356.994928)
			(xy 456.909034 -356.983116) (xy 456.909678 -356.976934) (xy 456.909678 -350.380046) (xy 456.908154 -350.368108)
			(xy 456.905868 -350.358202) (xy 456.90409 -350.35236) (xy 456.90028 -350.344486) (xy 456.847299 -350.252055)
			(xy 456.747947 -350.06356) (xy 456.656293 -349.871205) (xy 456.572488 -349.675303) (xy 456.496667 -349.476174)
			(xy 456.428954 -349.274144) (xy 456.369461 -349.069543) (xy 456.318285 -348.862705) (xy 456.275508 -348.653968)
			(xy 456.241202 -348.443673) (xy 456.215421 -348.232163) (xy 456.198209 -348.019784) (xy 456.189592 -347.806884)
			(xy 456.18908 -347.700346) (xy 456.18908 -347.699838) (xy 456.189587 -347.596337) (xy 456.197713 -347.389494)
			(xy 456.213952 -347.183129) (xy 456.238281 -346.977561) (xy 456.270661 -346.773107) (xy 456.311043 -346.570081)
			(xy 456.359364 -346.368797) (xy 456.41555 -346.169566) (xy 456.479515 -345.972694) (xy 456.551159 -345.778485)
			(xy 456.630373 -345.587238) (xy 456.717033 -345.399248) (xy 456.811007 -345.214806) (xy 456.91215 -345.034195)
			(xy 457.020305 -344.857695) (xy 457.135306 -344.685576) (xy 457.256976 -344.518105) (xy 457.385127 -344.355539)
			(xy 457.519561 -344.19813) (xy 457.660071 -344.04612) (xy 457.80644 -343.899744) (xy 457.958443 -343.759227)
			(xy 458.115846 -343.624785) (xy 458.278405 -343.496627) (xy 458.445871 -343.374949) (xy 458.617984 -343.25994)
			(xy 458.79448 -343.151776) (xy 458.975086 -343.050625) (xy 459.159523 -342.956642) (xy 459.347509 -342.869973)
			(xy 459.538752 -342.79075) (xy 459.732957 -342.719097) (xy 459.929826 -342.655123) (xy 460.129055 -342.598927)
			(xy 460.330337 -342.550596) (xy 460.53336 -342.510205) (xy 460.737813 -342.477815) (xy 460.94338 -342.453477)
			(xy 461.149744 -342.437227) (xy 461.356587 -342.429092) (xy 461.460088 -342.428576) (xy 461.564065 -342.429093)
			(xy 461.771857 -342.437305) (xy 461.979163 -342.453705) (xy 462.185661 -342.478267) (xy 462.39103 -342.510954)
			(xy 462.594951 -342.551715) (xy 462.797105 -342.600485) (xy 462.997179 -342.657189) (xy 463.194861 -342.72174)
			(xy 463.389843 -342.794035) (xy 463.581823 -342.873964) (xy 463.770501 -342.961402) (xy 463.955585 -343.056212)
			(xy 464.136786 -343.158247) (xy 464.313822 -343.267348) (xy 464.400392 -343.324942) (xy 464.406996 -343.32926)
			(xy 464.4136 -343.331292) (xy 464.417258 -343.332343) (xy 464.424781 -343.333486) (xy 464.428586 -343.333578)
			(xy 464.463638 -343.333578) (xy 464.473036 -343.332562) (xy 464.473544 -343.332562) (xy 464.478773 -343.331368)
			(xy 464.488627 -343.327137) (xy 464.493102 -343.32418) (xy 464.499452 -343.318846) (xy 464.5025 -343.315798)
			(xy 464.521042 -343.308178) (xy 464.53552 -343.308178) (xy 466.674708 -341.16899) (xy 466.677412 -341.166137)
			(xy 466.682 -341.159757) (xy 466.683852 -341.15629) (xy 466.686441 -341.150864) (xy 466.689275 -341.139185)
			(xy 466.68944 -341.133176) (xy 466.68944 -192.70218) (xy 466.689276 -192.696169) (xy 466.686461 -192.684483)
			(xy 466.683852 -192.679066) (xy 466.68201 -192.675594) (xy 466.677412 -192.669219) (xy 466.674708 -192.666366)
			(xy 455.919078 -181.910736) (xy 455.912233 -181.903338) (xy 455.90451 -181.884739) (xy 455.904092 -181.874668)
			(xy 455.904092 -174.072042) (xy 455.903838 -174.067978) (xy 455.903076 -174.063152) (xy 455.903076 -174.062644)
			(xy 455.901337 -174.05496) (xy 455.893828 -174.041122) (xy 455.888344 -174.035466) (xy 455.880216 -174.02937)
			(xy 455.873866 -174.026068) (xy 455.80173 -173.99381) (xy 455.788014 -173.987714) (xy 455.781521 -173.985244)
			(xy 455.767734 -173.983579) (xy 455.760836 -173.984412) (xy 455.75347 -173.985682) (xy 455.740516 -173.991778)
			(xy 455.734674 -173.996858) (xy 455.711301 -174.017183) (xy 455.66049 -174.052609) (xy 455.605752 -174.081602)
			(xy 455.547897 -174.103731) (xy 455.487784 -174.11867) (xy 455.426301 -174.126197) (xy 455.39533 -174.126652)
			(xy 455.363364 -174.126173) (xy 455.299935 -174.118163) (xy 455.23801 -174.102267) (xy 455.178566 -174.078734)
			(xy 455.12254 -174.047937) (xy 455.070816 -174.01036) (xy 455.02421 -173.966597) (xy 454.983456 -173.917337)
			(xy 454.949198 -173.863357) (xy 454.921976 -173.80551) (xy 454.902219 -173.744707) (xy 454.890239 -173.681906)
			(xy 454.886224 -173.6181) (xy 454.890239 -173.554294) (xy 454.902219 -173.491493) (xy 454.921976 -173.43069)
			(xy 454.949198 -173.372843) (xy 454.983456 -173.318863) (xy 455.02421 -173.269603) (xy 455.070816 -173.22584)
			(xy 455.12254 -173.188263) (xy 455.178566 -173.157466) (xy 455.23801 -173.133933) (xy 455.299935 -173.118037)
			(xy 455.363364 -173.110027) (xy 455.39533 -173.109636) (xy 455.4263 -173.110098) (xy 455.487781 -173.117626)
			(xy 455.547892 -173.132567) (xy 455.605743 -173.154699) (xy 455.660478 -173.183695) (xy 455.711284 -173.219125)
			(xy 455.734674 -173.23943) (xy 455.737468 -173.24197) (xy 455.742631 -173.245693) (xy 455.754323 -173.250716)
			(xy 455.760582 -173.251876) (xy 455.760836 -173.251876) (xy 455.767948 -173.252892) (xy 455.782426 -173.251114)
			(xy 455.78649 -173.249336) (xy 455.789792 -173.247812) (xy 455.873866 -173.21022) (xy 455.880216 -173.206918)
			(xy 455.888344 -173.200822) (xy 455.893805 -173.195149) (xy 455.901318 -173.181319) (xy 455.903076 -173.173644)
			(xy 455.903076 -173.173136) (xy 455.903838 -173.16831) (xy 455.904092 -173.164246) (xy 455.904092 -159.07004)
			(xy 455.904526 -159.059974) (xy 455.912254 -159.041385) (xy 455.919078 -159.033972) (xy 456.67549 -158.27756)
			(xy 456.679808 -158.27248) (xy 456.688444 -158.260288) (xy 456.690222 -158.256224) (xy 456.733754 -158.164821)
			(xy 456.826917 -157.985048) (xy 456.926914 -157.808985) (xy 457.033598 -157.636892) (xy 457.146812 -157.469023)
			(xy 457.266389 -157.305625) (xy 457.392153 -157.14694) (xy 457.523917 -156.993201) (xy 457.661488 -156.844635)
			(xy 457.804662 -156.701462) (xy 457.953229 -156.563892) (xy 458.106969 -156.432129) (xy 458.265655 -156.306367)
			(xy 458.429054 -156.186791) (xy 458.596924 -156.073578) (xy 458.769017 -155.966895) (xy 458.945081 -155.866899)
			(xy 459.124854 -155.773737) (xy 459.216252 -155.730194) (xy 459.220316 -155.728416) (xy 459.232508 -155.71978)
			(xy 459.237588 -155.715462) (xy 466.674708 -148.278342) (xy 466.677414 -148.275491) (xy 466.682008 -148.269113)
			(xy 466.683852 -148.265642) (xy 466.686436 -148.260215) (xy 466.689259 -148.248536) (xy 466.68944 -148.242528)
			(xy 466.68944 -66.664586) (xy 466.689277 -66.658575) (xy 466.686463 -66.646888) (xy 466.683852 -66.641472)
			(xy 466.68201 -66.637999) (xy 466.677413 -66.631624) (xy 466.674708 -66.628772) (xy 458.51699 -58.471054)
			(xy 458.510141 -58.463658) (xy 458.502409 -58.445058) (xy 458.502004 -58.434986) (xy 458.502004 -53.496972)
			(xy 458.501496 -53.490368) (xy 458.500384 -53.484336) (xy 458.495628 -53.473032) (xy 458.492098 -53.468016)
			(xy 458.491844 -53.467508) (xy 458.488542 -53.463952) (xy 458.485902 -53.461088) (xy 458.479905 -53.456115)
			(xy 458.476604 -53.454046) (xy 458.469746 -53.450236) (xy 458.460348 -53.448458) (xy 458.434643 -53.44326)
			(xy 458.384865 -53.426753) (xy 458.337813 -53.403594) (xy 458.294369 -53.374218) (xy 458.25535 -53.339178)
			(xy 458.238098 -53.319426) (xy 458.237844 -53.318918) (xy 458.23406 -53.314808) (xy 458.225089 -53.308153)
			(xy 458.220064 -53.30571) (xy 458.214939 -53.303528) (xy 458.204044 -53.301215) (xy 458.198474 -53.301138)
			(xy 458.186028 -53.301392) (xy 458.117194 -53.302916) (xy 458.112672 -53.303318) (xy 458.103857 -53.305485)
			(xy 458.099668 -53.307234) (xy 458.092302 -53.31079) (xy 458.083412 -53.317902) (xy 458.079856 -53.322728)
			(xy 458.06167 -53.345351) (xy 458.019612 -53.38535) (xy 457.971981 -53.418518) (xy 457.919875 -53.444087)
			(xy 457.864497 -53.461469) (xy 457.807125 -53.470261) (xy 457.778104 -53.47081) (xy 457.749246 -53.470273)
			(xy 457.692189 -53.461564) (xy 457.637095 -53.444361) (xy 457.585222 -53.419055) (xy 457.537752 -53.386223)
			(xy 457.495769 -53.346616) (xy 457.460232 -53.301137) (xy 457.445618 -53.276246) (xy 457.442062 -53.269896)
			(xy 457.432664 -53.260752) (xy 457.4286 -53.258212) (xy 457.424028 -53.255672) (xy 457.419646 -53.253575)
			(xy 457.410312 -53.250891) (xy 457.405486 -53.250338) (xy 457.359766 -53.250846) (xy 457.356972 -53.250846)
			(xy 457.31176 -53.251354) (xy 457.304874 -53.251621) (xy 457.291616 -53.255362) (xy 457.285598 -53.25872)
			(xy 457.28509 -53.258974) (xy 457.28001 -53.262022) (xy 457.27112 -53.27142) (xy 457.267564 -53.278024)
			(xy 457.253155 -53.303621) (xy 457.217697 -53.350449) (xy 457.175484 -53.391294) (xy 457.127513 -53.42519)
			(xy 457.074917 -53.45134) (xy 457.018936 -53.469124) (xy 456.960891 -53.478124) (xy 456.931522 -53.478684)
			(xy 456.903015 -53.478155) (xy 456.846635 -53.46967) (xy 456.792147 -53.452887) (xy 456.740764 -53.42818)
			(xy 456.693632 -53.396099) (xy 456.651801 -53.357358) (xy 456.63358 -53.335428) (xy 456.633326 -53.335174)
			(xy 456.629598 -53.330854) (xy 456.620623 -53.323811) (xy 456.615546 -53.321204) (xy 456.615292 -53.321204)
			(xy 456.609704 -53.318664) (xy 456.598782 -53.316378) (xy 456.54976 -53.317648) (xy 456.51166 -53.318664)
			(xy 456.505688 -53.318978) (xy 456.494136 -53.32206) (xy 456.4888 -53.32476) (xy 456.487276 -53.325522)
			(xy 456.483974 -53.3273) (xy 456.483466 -53.327554) (xy 456.475338 -53.33492) (xy 456.471528 -53.34)
			(xy 456.456115 -53.360864) (xy 456.420553 -53.398629) (xy 456.380203 -53.431227) (xy 456.335807 -53.458058)
			(xy 456.288186 -53.478625) (xy 456.238217 -53.492551) (xy 456.186823 -53.499578) (xy 456.160886 -53.50002)
			(xy 456.133635 -53.499533) (xy 456.079687 -53.491775) (xy 456.027392 -53.476418) (xy 455.977815 -53.453775)
			(xy 455.931965 -53.424308) (xy 455.890775 -53.388615) (xy 455.855084 -53.347424) (xy 455.825618 -53.301573)
			(xy 455.802977 -53.251995) (xy 455.787622 -53.1997) (xy 455.779866 -53.145751) (xy 455.779866 -53.091249)
			(xy 455.787622 -53.0373) (xy 455.802977 -52.985005) (xy 455.825618 -52.935427) (xy 455.855084 -52.889576)
			(xy 455.890775 -52.848385) (xy 455.931965 -52.812692) (xy 455.977815 -52.783225) (xy 456.027392 -52.760582)
			(xy 456.079687 -52.745225) (xy 456.133635 -52.737467) (xy 456.160886 -52.737004) (xy 456.189393 -52.737534)
			(xy 456.245772 -52.746019) (xy 456.30026 -52.762802) (xy 456.351642 -52.78751) (xy 456.398774 -52.819591)
			(xy 456.440605 -52.858331) (xy 456.458828 -52.88026) (xy 456.459082 -52.880514) (xy 456.46281 -52.884835)
			(xy 456.471785 -52.891878) (xy 456.476862 -52.894484) (xy 456.477116 -52.894484) (xy 456.482704 -52.897024)
			(xy 456.493626 -52.89931) (xy 456.542648 -52.89804) (xy 456.580748 -52.897024) (xy 456.58672 -52.896709)
			(xy 456.59827 -52.893624) (xy 456.603608 -52.890928) (xy 456.605132 -52.890166) (xy 456.608434 -52.888388)
			(xy 456.608942 -52.888134) (xy 456.61707 -52.880768) (xy 456.62088 -52.875688) (xy 456.636291 -52.85482)
			(xy 456.671849 -52.817048) (xy 456.712197 -52.784443) (xy 456.756593 -52.757607) (xy 456.804215 -52.737035)
			(xy 456.854186 -52.723107) (xy 456.905584 -52.71608) (xy 456.931522 -52.715668) (xy 456.960382 -52.7162)
			(xy 457.017443 -52.724901) (xy 457.072542 -52.742099) (xy 457.12442 -52.767403) (xy 457.171894 -52.800234)
			(xy 457.213879 -52.839844) (xy 457.249416 -52.885327) (xy 457.264008 -52.910232) (xy 457.267564 -52.916582)
			(xy 457.2762 -52.925472) (xy 457.285598 -52.930806) (xy 457.28998 -52.932902) (xy 457.299315 -52.935582)
			(xy 457.30414 -52.93614) (xy 457.34986 -52.935632) (xy 457.352654 -52.935632) (xy 457.397866 -52.935124)
			(xy 457.404752 -52.934854) (xy 457.418008 -52.931113) (xy 457.424028 -52.927758) (xy 457.424536 -52.927504)
			(xy 457.429616 -52.924456) (xy 457.438506 -52.915058) (xy 457.442062 -52.908454) (xy 457.45647 -52.882854)
			(xy 457.491928 -52.836021) (xy 457.534139 -52.795171) (xy 457.582109 -52.761267) (xy 457.634705 -52.73511)
			(xy 457.690687 -52.717316) (xy 457.748733 -52.708305) (xy 457.778104 -52.707794) (xy 457.805782 -52.708289)
			(xy 457.860554 -52.716296) (xy 457.913593 -52.732141) (xy 457.963783 -52.75549) (xy 458.010068 -52.785853)
			(xy 458.051474 -52.822591) (xy 458.069696 -52.84343) (xy 458.06995 -52.843684) (xy 458.073734 -52.847794)
			(xy 458.082705 -52.85445) (xy 458.08773 -52.856892) (xy 458.09027 -52.858162) (xy 458.093318 -52.859432)
			(xy 458.103986 -52.861464) (xy 458.149198 -52.860448) (xy 458.187806 -52.859686) (xy 458.191108 -52.859686)
			(xy 458.195148 -52.859338) (xy 458.203058 -52.857552) (xy 458.206856 -52.85613) (xy 458.215492 -52.851812)
			(xy 458.224382 -52.8447) (xy 458.227938 -52.839874) (xy 458.245378 -52.818157) (xy 458.285498 -52.779527)
			(xy 458.330808 -52.747138) (xy 458.380344 -52.721679) (xy 458.433054 -52.70369) (xy 458.460348 -52.698142)
			(xy 458.463396 -52.697634) (xy 458.47043 -52.695629) (xy 458.483063 -52.688274) (xy 458.488288 -52.683156)
			(xy 458.489304 -52.68214) (xy 458.493876 -52.676298) (xy 458.495908 -52.673758) (xy 458.498956 -52.665884)
			(xy 458.501242 -52.657756) (xy 458.502004 -52.648612) (xy 458.502004 -52.404772) (xy 458.501496 -52.398168)
			(xy 458.500384 -52.392136) (xy 458.495628 -52.380832) (xy 458.492098 -52.375816) (xy 458.491844 -52.375308)
			(xy 458.488542 -52.371752) (xy 458.485902 -52.368888) (xy 458.479905 -52.363915) (xy 458.476604 -52.361846)
			(xy 458.469746 -52.358036) (xy 458.460348 -52.356258) (xy 458.434643 -52.35106) (xy 458.384865 -52.334553)
			(xy 458.337813 -52.311394) (xy 458.294369 -52.282018) (xy 458.25535 -52.246978) (xy 458.238098 -52.227226)
			(xy 458.237844 -52.226718) (xy 458.23406 -52.222608) (xy 458.225089 -52.215953) (xy 458.220064 -52.21351)
			(xy 458.214939 -52.211328) (xy 458.204044 -52.209015) (xy 458.198474 -52.208938) (xy 458.186028 -52.209192)
			(xy 458.117194 -52.210716) (xy 458.112672 -52.211118) (xy 458.103857 -52.213285) (xy 458.099668 -52.215034)
			(xy 458.092302 -52.21859) (xy 458.083412 -52.225702) (xy 458.079856 -52.230528) (xy 458.06167 -52.253151)
			(xy 458.019612 -52.29315) (xy 457.971981 -52.326318) (xy 457.919875 -52.351887) (xy 457.864497 -52.369269)
			(xy 457.807125 -52.378061) (xy 457.778104 -52.37861) (xy 457.749246 -52.378073) (xy 457.692189 -52.369364)
			(xy 457.637095 -52.352161) (xy 457.585222 -52.326855) (xy 457.537752 -52.294023) (xy 457.495769 -52.254416)
			(xy 457.460232 -52.208937) (xy 457.445618 -52.184046) (xy 457.442062 -52.177696) (xy 457.432664 -52.168552)
			(xy 457.4286 -52.166012) (xy 457.424028 -52.163472) (xy 457.419646 -52.161375) (xy 457.410312 -52.158691)
			(xy 457.405486 -52.158138) (xy 457.359766 -52.158646) (xy 457.356972 -52.158646) (xy 457.31176 -52.159154)
			(xy 457.304874 -52.159421) (xy 457.291616 -52.163162) (xy 457.285598 -52.16652) (xy 457.28509 -52.166774)
			(xy 457.28001 -52.169822) (xy 457.27112 -52.17922) (xy 457.267564 -52.185824) (xy 457.253155 -52.211421)
			(xy 457.217697 -52.258249) (xy 457.175484 -52.299094) (xy 457.127513 -52.33299) (xy 457.074917 -52.35914)
			(xy 457.018936 -52.376924) (xy 456.960891 -52.385924) (xy 456.931522 -52.386484) (xy 456.905451 -52.386061)
			(xy 456.853794 -52.378962) (xy 456.803585 -52.364894) (xy 456.75576 -52.344119) (xy 456.711211 -52.317023)
			(xy 456.69073 -52.300886) (xy 456.690476 -52.300632) (xy 456.687174 -52.297838) (xy 456.683568 -52.295573)
			(xy 456.675782 -52.292124) (xy 456.67168 -52.29098) (xy 456.6666 -52.28971) (xy 456.66165 -52.289065)
			(xy 456.651676 -52.289456) (xy 456.646788 -52.290472) (xy 456.607672 -52.301394) (xy 456.607164 -52.301394)
			(xy 456.562714 -52.314094) (xy 456.558027 -52.315693) (xy 456.549332 -52.320428) (xy 456.545442 -52.323492)
			(xy 456.539092 -52.329588) (xy 456.532742 -52.33924) (xy 456.530456 -52.345336) (xy 456.520119 -52.372773)
			(xy 456.492235 -52.424347) (xy 456.456789 -52.471047) (xy 456.414614 -52.511774) (xy 456.366704 -52.545568)
			(xy 456.314187 -52.571633) (xy 456.258301 -52.589355) (xy 456.200361 -52.598318) (xy 456.171046 -52.598828)
			(xy 456.14379 -52.598368) (xy 456.089831 -52.590616) (xy 456.037525 -52.575263) (xy 455.987936 -52.552622)
			(xy 455.942075 -52.523154) (xy 455.900874 -52.487458) (xy 455.865174 -52.446262) (xy 455.8357 -52.400404)
			(xy 455.813053 -52.350819) (xy 455.797694 -52.298514) (xy 455.789935 -52.244556) (xy 455.789935 -52.190044)
			(xy 455.797694 -52.136086) (xy 455.813053 -52.083781) (xy 455.8357 -52.034196) (xy 455.865174 -51.988338)
			(xy 455.900874 -51.947142) (xy 455.942075 -51.911446) (xy 455.987936 -51.881978) (xy 456.037525 -51.859337)
			(xy 456.089831 -51.843984) (xy 456.14379 -51.836232) (xy 456.171046 -51.835812) (xy 456.197118 -51.836233)
			(xy 456.248777 -51.843328) (xy 456.298988 -51.857392) (xy 456.346816 -51.878165) (xy 456.391369 -51.905257)
			(xy 456.411838 -51.92141) (xy 456.412092 -51.921664) (xy 456.415394 -51.924458) (xy 456.418999 -51.926726)
			(xy 456.426784 -51.930179) (xy 456.430888 -51.931316) (xy 456.435968 -51.932586) (xy 456.440918 -51.933234)
			(xy 456.450894 -51.932849) (xy 456.45578 -51.931824) (xy 456.494896 -51.920902) (xy 456.495404 -51.920902)
			(xy 456.539854 -51.908202) (xy 456.544542 -51.906606) (xy 456.55324 -51.901874) (xy 456.557126 -51.898804)
			(xy 456.563476 -51.892708) (xy 456.569826 -51.883056) (xy 456.572112 -51.87696) (xy 456.581789 -51.851234)
			(xy 456.607472 -51.802641) (xy 456.639856 -51.758231) (xy 456.67827 -51.718922) (xy 456.721922 -51.685524)
			(xy 456.769911 -51.658728) (xy 456.821244 -51.639087) (xy 456.847956 -51.632612) (xy 456.856592 -51.630834)
			(xy 456.860402 -51.629818) (xy 456.863958 -51.62677) (xy 456.869546 -51.622198) (xy 456.871324 -51.620674)
			(xy 456.875267 -51.616798) (xy 456.881555 -51.607706) (xy 456.88377 -51.60264) (xy 456.91806 -51.519074)
			(xy 456.920346 -51.51374) (xy 456.919076 -51.501548) (xy 456.916536 -51.48961) (xy 456.914504 -51.483768)
			(xy 456.911202 -51.478688) (xy 456.89675 -51.455449) (xy 456.873937 -51.405706) (xy 456.858483 -51.35321)
			(xy 456.850706 -51.299041) (xy 456.850242 -51.271678) (xy 456.850753 -51.242807) (xy 456.859419 -51.185719)
			(xy 456.876594 -51.13059) (xy 456.901886 -51.078682) (xy 456.934716 -51.031181) (xy 456.954128 -51.009804)
			(xy 456.954382 -51.00955) (xy 456.957866 -51.005685) (xy 456.963361 -50.996852) (xy 456.965304 -50.992024)
			(xy 456.966574 -50.987452) (xy 456.967705 -50.982385) (xy 456.968098 -50.972013) (xy 456.967336 -50.966878)
			(xy 456.960732 -50.927) (xy 456.953874 -50.886614) (xy 456.953016 -50.88221) (xy 456.949946 -50.873779)
			(xy 456.947778 -50.86985) (xy 456.947778 -50.869342) (xy 456.945238 -50.865532) (xy 456.94219 -50.861214)
			(xy 456.9333 -50.85334) (xy 456.927712 -50.850292) (xy 456.901799 -50.836005) (xy 456.854343 -50.800662)
			(xy 456.81292 -50.758409) (xy 456.778524 -50.710262) (xy 456.751981 -50.657379) (xy 456.73393 -50.601028)
			(xy 456.724804 -50.542566) (xy 456.724258 -50.51298) (xy 456.724744 -50.485729) (xy 456.7325 -50.431781)
			(xy 456.747855 -50.379486) (xy 456.770497 -50.329909) (xy 456.799963 -50.284059) (xy 456.835654 -50.242868)
			(xy 456.876845 -50.207177) (xy 456.922695 -50.177711) (xy 456.972272 -50.155069) (xy 457.024567 -50.139714)
			(xy 457.078515 -50.131958) (xy 457.133017 -50.131958) (xy 457.186965 -50.139714) (xy 457.23926 -50.155069)
			(xy 457.288837 -50.177711) (xy 457.334687 -50.207177) (xy 457.375878 -50.242868) (xy 457.411569 -50.284059)
			(xy 457.441035 -50.329909) (xy 457.463677 -50.379486) (xy 457.479032 -50.431781) (xy 457.486788 -50.485729)
			(xy 457.487274 -50.51298) (xy 457.487274 -50.513234) (xy 457.486749 -50.542081) (xy 457.478066 -50.599118)
			(xy 457.46089 -50.654195) (xy 457.435611 -50.706056) (xy 457.402807 -50.753516) (xy 457.383388 -50.774854)
			(xy 457.383134 -50.775108) (xy 457.379646 -50.778971) (xy 457.374143 -50.787801) (xy 457.372212 -50.792634)
			(xy 457.370942 -50.797206) (xy 457.369817 -50.802273) (xy 457.369435 -50.812643) (xy 457.37018 -50.81778)
			(xy 457.376784 -50.857658) (xy 457.383642 -50.898044) (xy 457.384497 -50.90245) (xy 457.387562 -50.910883)
			(xy 457.389738 -50.914808) (xy 457.389738 -50.915316) (xy 457.392278 -50.919126) (xy 457.395326 -50.923444)
			(xy 457.404216 -50.931318) (xy 457.409804 -50.934366) (xy 457.435713 -50.948655) (xy 457.483161 -50.984001)
			(xy 457.524577 -51.026256) (xy 457.558964 -51.074403) (xy 457.585497 -51.127286) (xy 457.603539 -51.183635)
			(xy 457.612656 -51.242095) (xy 457.613258 -51.271678) (xy 457.612747 -51.300309) (xy 457.604193 -51.356929)
			(xy 457.587275 -51.411635) (xy 457.562372 -51.463198) (xy 457.530043 -51.510461) (xy 457.491014 -51.552362)
			(xy 457.446163 -51.587961) (xy 457.396495 -51.616458) (xy 457.343126 -51.637213) (xy 457.315316 -51.644042)
			(xy 457.30668 -51.64582) (xy 457.30287 -51.646836) (xy 457.299314 -51.649884) (xy 457.293726 -51.654456)
			(xy 457.291948 -51.65598) (xy 457.28801 -51.65986) (xy 457.281735 -51.668957) (xy 457.279502 -51.674014)
			(xy 457.245212 -51.75758) (xy 457.242926 -51.762914) (xy 457.244196 -51.775106) (xy 457.246736 -51.787044)
			(xy 457.248768 -51.792886) (xy 457.25207 -51.797966) (xy 457.264008 -51.817778) (xy 457.264008 -51.818032)
			(xy 457.267564 -51.824382) (xy 457.2762 -51.833272) (xy 457.285598 -51.838606) (xy 457.28998 -51.840702)
			(xy 457.299315 -51.843382) (xy 457.30414 -51.84394) (xy 457.34986 -51.843432) (xy 457.352654 -51.843432)
			(xy 457.397866 -51.842924) (xy 457.404752 -51.842654) (xy 457.418008 -51.838913) (xy 457.424028 -51.835558)
			(xy 457.424536 -51.835304) (xy 457.429616 -51.832256) (xy 457.438506 -51.822858) (xy 457.442062 -51.816254)
			(xy 457.45647 -51.790654) (xy 457.491928 -51.743821) (xy 457.534139 -51.702971) (xy 457.582109 -51.669067)
			(xy 457.634705 -51.64291) (xy 457.690687 -51.625116) (xy 457.748733 -51.616105) (xy 457.778104 -51.615594)
			(xy 457.805782 -51.616089) (xy 457.860554 -51.624096) (xy 457.913593 -51.639941) (xy 457.963783 -51.66329)
			(xy 458.010068 -51.693653) (xy 458.051474 -51.730391) (xy 458.069696 -51.75123) (xy 458.06995 -51.751484)
			(xy 458.073734 -51.755594) (xy 458.082705 -51.76225) (xy 458.08773 -51.764692) (xy 458.09027 -51.765962)
			(xy 458.093318 -51.767232) (xy 458.103986 -51.769264) (xy 458.149198 -51.768248) (xy 458.187806 -51.767486)
			(xy 458.191108 -51.767486) (xy 458.195148 -51.767138) (xy 458.203058 -51.765352) (xy 458.206856 -51.76393)
			(xy 458.215492 -51.759612) (xy 458.224382 -51.7525) (xy 458.227938 -51.747674) (xy 458.245378 -51.725957)
			(xy 458.285498 -51.687327) (xy 458.330808 -51.654938) (xy 458.380344 -51.629479) (xy 458.433054 -51.61149)
			(xy 458.460348 -51.605942) (xy 458.463396 -51.605434) (xy 458.47043 -51.603429) (xy 458.483063 -51.596074)
			(xy 458.488288 -51.590956) (xy 458.489304 -51.58994) (xy 458.493876 -51.584098) (xy 458.495908 -51.581558)
			(xy 458.498956 -51.573684) (xy 458.501242 -51.565556) (xy 458.502004 -51.556412) (xy 458.502004 -49.330864)
			(xy 458.502434 -49.320797) (xy 458.510158 -49.302202) (xy 458.51699 -49.294796) (xy 460.272384 -47.539402)
			(xy 460.279787 -47.532569) (xy 460.298385 -47.524865) (xy 460.308452 -47.524416) (xy 465.473034 -47.524416)
			(xy 465.482432 -47.5234) (xy 465.48294 -47.5234) (xy 465.488168 -47.522205) (xy 465.49802 -47.517971)
			(xy 465.502498 -47.515018) (xy 465.508848 -47.509684) (xy 465.511896 -47.506636) (xy 465.530438 -47.499016)
			(xy 465.544916 -47.499016) (xy 466.365844 -46.678088) (xy 466.371178 -46.671738) (xy 466.374185 -46.66729)
			(xy 466.378413 -46.657425) (xy 466.37956 -46.65218) (xy 466.37956 -46.651672) (xy 466.380576 -46.642274)
			(xy 466.380576 -42.121074) (xy 466.380068 -42.114216) (xy 466.377528 -42.103802) (xy 466.368892 -42.08018)
			(xy 466.365844 -42.07637) (xy 466.346219 -42.05141) (xy 466.312661 -41.997508) (xy 466.286072 -41.939848)
			(xy 466.266868 -41.879326) (xy 466.255346 -41.816886) (xy 466.251686 -41.753496) (xy 466.255944 -41.690144)
			(xy 466.268055 -41.627815) (xy 466.28783 -41.567478) (xy 466.314962 -41.510071) (xy 466.349028 -41.456488)
			(xy 466.368892 -41.431718) (xy 466.37448 -41.42486) (xy 466.378544 -41.413684) (xy 466.380576 -41.399968)
			(xy 466.380576 -41.257728) (xy 466.380322 -41.253918) (xy 466.380322 -41.25341) (xy 466.379855 -41.24859)
			(xy 466.377294 -41.239254) (xy 466.375242 -41.234868) (xy 466.368384 -41.224708) (xy 466.365844 -41.221914)
			(xy 466.311234 -41.167558) (xy 466.304391 -41.160159) (xy 466.296666 -41.14156) (xy 466.296248 -41.13149)
			(xy 466.296248 -38.32987) (xy 466.296084 -38.32386) (xy 466.293267 -38.312174) (xy 466.29066 -38.306756)
			(xy 466.288818 -38.303284) (xy 466.284219 -38.29691) (xy 466.281516 -38.294056) (xy 465.048092 -37.060632)
			(xy 465.045241 -37.057927) (xy 465.038862 -37.053335) (xy 465.035392 -37.051488) (xy 465.029966 -37.048902)
			(xy 465.018286 -37.046071) (xy 465.012278 -37.0459) (xy 459.071472 -37.0459) (xy 459.060297 -37.046523)
			(xy 459.040119 -37.056143) (xy 459.03261 -37.064442) (xy 459.026006 -37.07257) (xy 459.022196 -37.07765)
			(xy 459.022196 -37.077904) (xy 458.985874 -37.124386) (xy 458.982318 -37.128958) (xy 458.978992 -37.133598)
			(xy 458.974248 -37.14398) (xy 458.97292 -37.149532) (xy 458.97038 -37.160962) (xy 458.973174 -37.172392)
			(xy 458.978633 -37.195374) (xy 458.98449 -37.242246) (xy 458.984858 -37.265864) (xy 458.984372 -37.293115)
			(xy 458.976616 -37.347063) (xy 458.961261 -37.399358) (xy 458.938619 -37.448935) (xy 458.909153 -37.494785)
			(xy 458.873462 -37.535976) (xy 458.832271 -37.571667) (xy 458.786421 -37.601133) (xy 458.736844 -37.623775)
			(xy 458.684549 -37.63913) (xy 458.630601 -37.646886) (xy 458.576099 -37.646886) (xy 458.522151 -37.63913)
			(xy 458.469856 -37.623775) (xy 458.420279 -37.601133) (xy 458.374429 -37.571667) (xy 458.333238 -37.535976)
			(xy 458.297547 -37.494785) (xy 458.268081 -37.448935) (xy 458.245439 -37.399358) (xy 458.230084 -37.347063)
			(xy 458.222328 -37.293115) (xy 458.221842 -37.265864) (xy 458.222422 -37.236666) (xy 458.231364 -37.178957)
			(xy 458.248989 -37.123283) (xy 458.274885 -37.070942) (xy 458.308449 -37.023153) (xy 458.328268 -37.001704)
			(xy 458.335126 -36.994338) (xy 458.338682 -36.985448) (xy 458.340431 -36.980753) (xy 458.342229 -36.970899)
			(xy 458.342238 -36.96589) (xy 458.341476 -36.89477) (xy 458.340924 -36.884935) (xy 458.33335 -36.866771)
			(xy 458.326744 -36.859464) (xy 453.534272 -32.066992) (xy 453.531419 -32.064289) (xy 453.525037 -32.059703)
			(xy 453.521572 -32.057848) (xy 453.516146 -32.055261) (xy 453.504466 -32.052431) (xy 453.498458 -32.05226)
			(xy 453.039988 -32.05226) (xy 453.031382 -32.052587) (xy 453.015144 -32.058292) (xy 453.008238 -32.063436)
			(xy 453.007222 -32.064198) (xy 453.00138 -32.069024) (xy 452.992744 -32.08274) (xy 452.990712 -32.091376)
			(xy 452.983051 -32.121375) (xy 452.959364 -32.178576) (xy 452.926765 -32.23121) (xy 452.906892 -32.254952)
			(xy 452.900796 -32.262064) (xy 452.897748 -32.270446) (xy 452.896231 -32.274735) (xy 452.894576 -32.283679)
			(xy 452.894446 -32.288226) (xy 452.894446 -32.355282) (xy 452.894571 -32.359829) (xy 452.896235 -32.368772)
			(xy 452.897748 -32.373062) (xy 452.900796 -32.381444) (xy 452.906892 -32.388556) (xy 452.924531 -32.409488)
			(xy 452.954251 -32.455456) (xy 452.977087 -32.505203) (xy 452.99257 -32.557706) (xy 453.000381 -32.611885)
			(xy 453.000872 -32.639254) (xy 453.000386 -32.666505) (xy 452.99263 -32.720453) (xy 452.977275 -32.772748)
			(xy 452.954633 -32.822325) (xy 452.925167 -32.868175) (xy 452.889476 -32.909366) (xy 452.848285 -32.945057)
			(xy 452.802435 -32.974523) (xy 452.752858 -32.997165) (xy 452.700563 -33.01252) (xy 452.646615 -33.020276)
			(xy 452.592113 -33.020276) (xy 452.538165 -33.01252) (xy 452.48587 -32.997165) (xy 452.436293 -32.974523)
			(xy 452.390443 -32.945057) (xy 452.349252 -32.909366) (xy 452.313561 -32.868175) (xy 452.284095 -32.822325)
			(xy 452.261453 -32.772748) (xy 452.246098 -32.720453) (xy 452.238342 -32.666505) (xy 452.237856 -32.639254)
			(xy 452.238331 -32.611885) (xy 452.246162 -32.557711) (xy 452.261656 -32.505213) (xy 452.284495 -32.455468)
			(xy 452.31421 -32.409498) (xy 452.331836 -32.388556) (xy 452.337932 -32.381444) (xy 452.34098 -32.373062)
			(xy 452.342497 -32.368773) (xy 452.344152 -32.359829) (xy 452.344282 -32.355282) (xy 452.344282 -32.288226)
			(xy 452.344158 -32.283678) (xy 452.342496 -32.274735) (xy 452.34098 -32.270446) (xy 452.337932 -32.262064)
			(xy 452.331836 -32.254952) (xy 452.311946 -32.231222) (xy 452.279339 -32.178591) (xy 452.255677 -32.121377)
			(xy 452.248016 -32.091376) (xy 452.247 -32.087566) (xy 452.244497 -32.080566) (xy 452.236108 -32.068303)
			(xy 452.23049 -32.063436) (xy 452.230236 -32.063182) (xy 452.223378 -32.057848) (xy 452.215758 -32.055308)
			(xy 452.2117 -32.053937) (xy 452.203274 -32.052408) (xy 452.198994 -32.05226) (xy 450.474334 -32.05226)
			(xy 450.469762 -32.052514) (xy 450.462689 -32.053391) (xy 450.449408 -32.058544) (xy 450.4436 -32.062674)
			(xy 450.436996 -32.067754) (xy 450.428106 -32.080962) (xy 450.425566 -32.089598) (xy 450.417482 -32.116982)
			(xy 450.394318 -32.169167) (xy 450.363649 -32.217326) (xy 450.345302 -32.239204) (xy 450.339206 -32.246316)
			(xy 450.336158 -32.254698) (xy 450.334636 -32.258986) (xy 450.332973 -32.26793) (xy 450.332856 -32.272478)
			(xy 450.332856 -32.339534) (xy 450.332977 -32.344082) (xy 450.334633 -32.353028) (xy 450.336158 -32.357314)
			(xy 450.339206 -32.365696) (xy 450.345302 -32.372808) (xy 450.362943 -32.39374) (xy 450.392668 -32.439706)
			(xy 450.41551 -32.489453) (xy 450.430999 -32.541956) (xy 450.438817 -32.596136) (xy 450.439282 -32.623506)
			(xy 450.438796 -32.650757) (xy 450.43104 -32.704705) (xy 450.415685 -32.757) (xy 450.393043 -32.806577)
			(xy 450.363577 -32.852427) (xy 450.327886 -32.893618) (xy 450.286695 -32.929309) (xy 450.240845 -32.958775)
			(xy 450.191268 -32.981417) (xy 450.138973 -32.996772) (xy 450.085025 -33.004528) (xy 450.030523 -33.004528)
			(xy 449.976575 -32.996772) (xy 449.92428 -32.981417) (xy 449.874703 -32.958775) (xy 449.828853 -32.929309)
			(xy 449.787662 -32.893618) (xy 449.751971 -32.852427) (xy 449.722505 -32.806577) (xy 449.699863 -32.757)
			(xy 449.684508 -32.704705) (xy 449.676752 -32.650757) (xy 449.676266 -32.623506) (xy 449.676737 -32.596136)
			(xy 449.684562 -32.541959) (xy 449.70005 -32.489456) (xy 449.722885 -32.439706) (xy 449.752597 -32.393732)
			(xy 449.770246 -32.372808) (xy 449.776342 -32.365696) (xy 449.77939 -32.357314) (xy 449.780911 -32.353026)
			(xy 449.782575 -32.344082) (xy 449.782692 -32.339534) (xy 449.782692 -32.272478) (xy 449.782572 -32.267929)
			(xy 449.78092 -32.258983) (xy 449.77939 -32.254698) (xy 449.776342 -32.246316) (xy 449.770246 -32.239204)
			(xy 449.751911 -32.217366) (xy 449.721249 -32.169292) (xy 449.698074 -32.117194) (xy 449.689982 -32.089852)
			(xy 449.689982 -32.089598) (xy 449.689728 -32.08909) (xy 449.689728 -32.088836) (xy 449.687229 -32.081163)
			(xy 449.678162 -32.067824) (xy 449.671948 -32.062674) (xy 449.66509 -32.057594) (xy 449.657724 -32.055054)
			(xy 449.653717 -32.053771) (xy 449.64542 -32.052367) (xy 449.641214 -32.05226) (xy 447.513456 -32.05226)
			(xy 447.508222 -32.052419) (xy 447.497983 -32.054597) (xy 447.493136 -32.056578) (xy 447.48553 -32.06017)
			(xy 447.473072 -32.071459) (xy 447.468752 -32.078676) (xy 447.46672 -32.082994) (xy 447.42989 -32.168846)
			(xy 447.428006 -32.173647) (xy 447.425969 -32.183756) (xy 447.425826 -32.188912) (xy 447.434462 -32.210502)
			(xy 447.43878 -32.219138) (xy 447.44386 -32.227012) (xy 447.44894 -32.233616) (xy 447.469445 -32.257027)
			(xy 447.505203 -32.307964) (xy 447.534477 -32.362885) (xy 447.55683 -32.420968) (xy 447.571927 -32.481345)
			(xy 447.579543 -32.543112) (xy 447.580004 -32.57423) (xy 447.580004 -32.574484) (xy 447.579502 -32.606445)
			(xy 447.571491 -32.669863) (xy 447.555594 -32.731777) (xy 447.532062 -32.79121) (xy 447.501268 -32.847225)
			(xy 447.463695 -32.89894) (xy 447.419938 -32.945537) (xy 447.370685 -32.986282) (xy 447.316714 -33.020533)
			(xy 447.258875 -33.04775) (xy 447.198082 -33.067503) (xy 447.135292 -33.079481) (xy 447.071496 -33.083495)
			(xy 447.0077 -33.079481) (xy 446.94491 -33.067503) (xy 446.884117 -33.04775) (xy 446.826278 -33.020533)
			(xy 446.772307 -32.986282) (xy 446.723054 -32.945537) (xy 446.679297 -32.89894) (xy 446.641724 -32.847225)
			(xy 446.61093 -32.79121) (xy 446.587398 -32.731777) (xy 446.571501 -32.669863) (xy 446.56349 -32.606445)
			(xy 446.562988 -32.574484) (xy 446.562988 -32.57423) (xy 446.563457 -32.543112) (xy 446.571056 -32.481341)
			(xy 446.586145 -32.420961) (xy 446.608497 -32.362877) (xy 446.637777 -32.307958) (xy 446.673547 -32.257028)
			(xy 446.694052 -32.233616) (xy 446.699132 -32.227012) (xy 446.704212 -32.219138) (xy 446.70853 -32.210502)
			(xy 446.717166 -32.188912) (xy 446.717069 -32.183752) (xy 446.715014 -32.17364) (xy 446.713102 -32.168846)
			(xy 446.676272 -32.082994) (xy 446.67424 -32.078676) (xy 446.669864 -32.071506) (xy 446.657416 -32.060242)
			(xy 446.649856 -32.056578) (xy 446.645016 -32.054576) (xy 446.634772 -32.052399) (xy 446.629536 -32.05226)
			(xy 446.044828 -32.05226) (xy 446.03516 -32.052733) (xy 446.01723 -32.059985) (xy 446.003255 -32.073357)
			(xy 445.998854 -32.081978) (xy 445.961516 -32.1691) (xy 445.95883 -32.176005) (xy 445.957164 -32.190721)
			(xy 445.958214 -32.198056) (xy 445.959484 -32.205168) (xy 445.965834 -32.217868) (xy 445.971168 -32.22371)
			(xy 445.992939 -32.247381) (xy 446.030956 -32.299253) (xy 446.062124 -32.355508) (xy 446.085944 -32.415246)
			(xy 446.102036 -32.477513) (xy 446.110143 -32.541312) (xy 446.110614 -32.573468) (xy 446.110112 -32.605429)
			(xy 446.102101 -32.668847) (xy 446.086204 -32.730761) (xy 446.062672 -32.790194) (xy 446.031878 -32.846209)
			(xy 445.994305 -32.897924) (xy 445.950548 -32.944521) (xy 445.901295 -32.985266) (xy 445.847324 -33.019517)
			(xy 445.789485 -33.046734) (xy 445.728692 -33.066487) (xy 445.665902 -33.078465) (xy 445.602106 -33.082479)
			(xy 445.53831 -33.078465) (xy 445.47552 -33.066487) (xy 445.414727 -33.046734) (xy 445.356888 -33.019517)
			(xy 445.302917 -32.985266) (xy 445.253664 -32.944521) (xy 445.209907 -32.897924) (xy 445.172334 -32.846209)
			(xy 445.14154 -32.790194) (xy 445.118008 -32.730761) (xy 445.102111 -32.668847) (xy 445.0941 -32.605429)
			(xy 445.093598 -32.573468) (xy 445.094085 -32.541342) (xy 445.102174 -32.477601) (xy 445.118231 -32.415387)
			(xy 445.142001 -32.355693) (xy 445.173104 -32.299471) (xy 445.211044 -32.247616) (xy 445.23279 -32.223964)
			(xy 445.233044 -32.22371) (xy 445.233806 -32.222694) (xy 445.238334 -32.21731) (xy 445.244519 -32.20468)
			(xy 445.245998 -32.197802) (xy 445.246252 -32.196278) (xy 445.247522 -32.189928) (xy 445.24676 -32.18307)
			(xy 445.246235 -32.179536) (xy 445.244318 -32.172654) (xy 445.24295 -32.169354) (xy 445.205358 -32.081978)
			(xy 445.200963 -32.073353) (xy 445.18699 -32.059978) (xy 445.169053 -32.05274) (xy 445.159384 -32.05226)
			(xy 441.280042 -32.05226) (xy 441.269977 -32.051825) (xy 441.251392 -32.044091) (xy 441.243974 -32.037274)
			(xy 439.596022 -30.389322) (xy 439.58877 -30.38275) (xy 439.57074 -30.375179) (xy 439.56097 -30.37459)
			(xy 439.560208 -30.37459) (xy 439.5343 -30.38475) (xy 439.530074 -30.386546) (xy 439.52228 -30.3914)
			(xy 439.518806 -30.394402) (xy 439.495368 -30.414952) (xy 439.444363 -30.450788) (xy 439.389363 -30.480126)
			(xy 439.331191 -30.502525) (xy 439.270719 -30.51765) (xy 439.208852 -30.525275) (xy 439.177684 -30.52572)
			(xy 439.146953 -30.525255) (xy 439.08594 -30.517845) (xy 439.026265 -30.503135) (xy 438.968799 -30.481339)
			(xy 438.914378 -30.452776) (xy 438.863796 -30.417862) (xy 438.817792 -30.377105) (xy 438.777036 -30.3311)
			(xy 438.742122 -30.280519) (xy 438.713559 -30.226098) (xy 438.691764 -30.168631) (xy 438.677054 -30.108956)
			(xy 438.669645 -30.047943) (xy 438.669176 -30.017212) (xy 438.669646 -29.986045) (xy 438.677261 -29.924177)
			(xy 438.692379 -29.863703) (xy 438.714772 -29.80553) (xy 438.744105 -29.750528) (xy 438.779939 -29.699523)
			(xy 438.800494 -29.67609) (xy 438.803517 -29.672631) (xy 438.808371 -29.664833) (xy 438.810146 -29.660596)
			(xy 438.820306 -29.634688) (xy 438.820306 -29.633926) (xy 438.81972 -29.624155) (xy 438.812155 -29.606119)
			(xy 438.805574 -29.598874) (xy 437.547512 -28.340812) (xy 437.544661 -28.338107) (xy 437.538282 -28.333514)
			(xy 437.534812 -28.331668) (xy 437.529384 -28.329091) (xy 437.517704 -28.326279) (xy 437.511698 -28.32608)
			(xy 435.632352 -28.32608) (xy 435.625748 -28.326588) (xy 435.62524 -28.326588) (xy 435.618128 -28.328112)
			(xy 435.607968 -28.332176) (xy 435.60365 -28.33497) (xy 435.603142 -28.335478) (xy 435.596538 -28.340812)
			(xy 435.544214 -28.392882) (xy 435.541246 -28.396241) (xy 435.536394 -28.403777) (xy 435.534562 -28.407868)
			(xy 435.530752 -28.416758) (xy 435.530752 -28.427172) (xy 435.530097 -28.459029) (xy 435.521821 -28.522209)
			(xy 435.505715 -28.58386) (xy 435.482034 -28.643016) (xy 435.451147 -28.698749) (xy 435.413539 -28.750187)
			(xy 435.369799 -28.796524) (xy 435.320613 -28.837032) (xy 435.266751 -28.871078) (xy 435.209058 -28.898128)
			(xy 435.148437 -28.917758) (xy 435.085839 -28.929661) (xy 435.022244 -28.933649) (xy 434.958649 -28.929661)
			(xy 434.896051 -28.917758) (xy 434.83543 -28.898128) (xy 434.777737 -28.871078) (xy 434.723875 -28.837032)
			(xy 434.674689 -28.796524) (xy 434.630949 -28.750187) (xy 434.593341 -28.698749) (xy 434.562454 -28.643016)
			(xy 434.538773 -28.58386) (xy 434.522667 -28.522209) (xy 434.514391 -28.459029) (xy 434.513736 -28.427172)
			(xy 434.513736 -28.416758) (xy 434.509926 -28.407868) (xy 434.508128 -28.403758) (xy 434.50328 -28.396211)
			(xy 434.500274 -28.392882) (xy 434.44795 -28.340812) (xy 434.441346 -28.335478) (xy 434.440838 -28.33497)
			(xy 434.43652 -28.332176) (xy 434.42636 -28.328112) (xy 434.419248 -28.326588) (xy 434.41874 -28.326588)
			(xy 434.412136 -28.32608) (xy 376.603768 -28.32608) (xy 376.593701 -28.325651) (xy 376.575107 -28.317926)
			(xy 376.5677 -28.311094) (xy 375.217944 -26.961338) (xy 375.211103 -26.953938) (xy 375.203384 -26.93534)
			(xy 375.202958 -26.92527) (xy 375.202958 -19.48815) (xy 375.198894 -19.484086) (xy 375.198894 -14.308836)
			(xy 375.198725 -14.302827) (xy 375.195898 -14.291146) (xy 375.193306 -14.285722) (xy 375.191469 -14.282246)
			(xy 375.186879 -14.275863) (xy 375.184162 -14.273022) (xy 374.230392 -13.319252) (xy 374.227541 -13.316546)
			(xy 374.221163 -13.311952) (xy 374.217692 -13.310108) (xy 374.212266 -13.307521) (xy 374.200586 -13.304689)
			(xy 374.194578 -13.30452) (xy 366.54359 -13.30452) (xy 366.535045 -13.304849) (xy 366.51891 -13.310479)
			(xy 366.505528 -13.321108) (xy 366.500664 -13.328142) (xy 366.45469 -13.400532) (xy 366.451402 -13.406122)
			(xy 366.447413 -13.418458) (xy 366.446816 -13.424916) (xy 366.446054 -13.437616) (xy 366.449102 -13.443966)
			(xy 366.463346 -13.474493) (xy 366.483483 -13.538774) (xy 366.493687 -13.605358) (xy 366.494314 -13.639038)
			(xy 366.494314 -13.639546) (xy 366.493835 -13.668647) (xy 366.486233 -13.726351) (xy 366.471165 -13.782569)
			(xy 366.448888 -13.83634) (xy 366.419783 -13.886743) (xy 366.38435 -13.932917) (xy 366.343193 -13.974071)
			(xy 366.297017 -14.009501) (xy 366.246611 -14.038602) (xy 366.192839 -14.060875) (xy 366.13662 -14.075939)
			(xy 366.078915 -14.083537) (xy 366.049814 -14.084046) (xy 366.020451 -14.083575) (xy 365.962235 -14.075844)
			(xy 365.905545 -14.060516) (xy 365.851366 -14.037856) (xy 365.800642 -14.00826) (xy 365.754257 -13.972243)
			(xy 365.713018 -13.930433) (xy 365.694976 -13.907262) (xy 365.694722 -13.906754) (xy 365.689388 -13.899642)
			(xy 365.682022 -13.894816) (xy 365.678115 -13.892516) (xy 365.669685 -13.889187) (xy 365.665258 -13.888212)
			(xy 365.599218 -13.874242) (xy 365.59488 -13.873456) (xy 365.586069 -13.873203) (xy 365.581692 -13.873734)
			(xy 365.572802 -13.875004) (xy 365.564674 -13.879576) (xy 365.536322 -13.894691) (xy 365.476625 -13.918451)
			(xy 365.414413 -13.934507) (xy 365.350674 -13.942602) (xy 365.318548 -13.943076) (xy 365.287815 -13.942633)
			(xy 365.226796 -13.935229) (xy 365.167114 -13.920523) (xy 365.109641 -13.898731) (xy 365.055214 -13.870168)
			(xy 365.004627 -13.835253) (xy 364.958617 -13.794494) (xy 364.917857 -13.748486) (xy 364.88294 -13.6979)
			(xy 364.854376 -13.643474) (xy 364.832581 -13.586001) (xy 364.817874 -13.52632) (xy 364.810468 -13.465301)
			(xy 364.81004 -13.434568) (xy 364.810548 -13.4112) (xy 364.810548 -13.410692) (xy 364.810632 -13.40193)
			(xy 364.805572 -13.385169) (xy 364.800642 -13.377926) (xy 364.796578 -13.373354) (xy 364.745778 -13.320268)
			(xy 364.738355 -13.313145) (xy 364.719478 -13.305017) (xy 364.709202 -13.30452) (xy 364.130336 -13.30452)
			(xy 364.12932 -13.30452) (xy 364.12277 -13.304853) (xy 364.110164 -13.308453) (xy 364.104428 -13.311632)
			(xy 364.094268 -13.319506) (xy 364.090204 -13.324332) (xy 364.041182 -13.388086) (xy 364.036263 -13.39487)
			(xy 364.030799 -13.4107) (xy 364.030514 -13.419074) (xy 364.032292 -13.432028) (xy 364.040143 -13.463835)
			(xy 364.048549 -13.52881) (xy 364.049056 -13.561568) (xy 364.048554 -13.593529) (xy 364.040543 -13.656947)
			(xy 364.024646 -13.718861) (xy 364.001114 -13.778294) (xy 363.97032 -13.834309) (xy 363.932747 -13.886024)
			(xy 363.88899 -13.932621) (xy 363.839737 -13.973366) (xy 363.785766 -14.007617) (xy 363.727927 -14.034834)
			(xy 363.667134 -14.054587) (xy 363.604344 -14.066565) (xy 363.540548 -14.070579) (xy 363.476752 -14.066565)
			(xy 363.413962 -14.054587) (xy 363.353169 -14.034834) (xy 363.29533 -14.007617) (xy 363.241359 -13.973366)
			(xy 363.192106 -13.932621) (xy 363.148349 -13.886024) (xy 363.110776 -13.834309) (xy 363.079982 -13.778294)
			(xy 363.05645 -13.718861) (xy 363.040553 -13.656947) (xy 363.032542 -13.593529) (xy 363.03204 -13.561568)
			(xy 363.03255 -13.52881) (xy 363.040958 -13.463836) (xy 363.048804 -13.432028) (xy 363.050582 -13.419074)
			(xy 363.050204 -13.410715) (xy 363.044769 -13.3949) (xy 363.039914 -13.388086) (xy 362.990892 -13.324332)
			(xy 362.986828 -13.319506) (xy 362.976668 -13.311632) (xy 362.970928 -13.308461) (xy 362.958325 -13.304849)
			(xy 362.951776 -13.30452) (xy 298.177966 -13.30452) (xy 298.171956 -13.304686) (xy 298.160272 -13.307507)
			(xy 298.154852 -13.310108) (xy 298.151379 -13.311949) (xy 298.145003 -13.316546) (xy 298.142152 -13.319252)
			(xy 297.828716 -13.632688) (xy 297.820334 -13.64361) (xy 297.820334 -13.644118) (xy 297.817915 -13.64863)
			(xy 297.814717 -13.658355) (xy 297.813984 -13.663422) (xy 297.813984 -14.48181) (xy 304.086258 -14.48181)
			(xy 304.090329 -14.426188) (xy 304.102455 -14.371751) (xy 304.122378 -14.31966) (xy 304.149674 -14.271025)
			(xy 304.18376 -14.226882) (xy 304.223909 -14.188173) (xy 304.269267 -14.155722) (xy 304.318867 -14.130221)
			(xy 304.371651 -14.112214) (xy 304.426494 -14.102084) (xy 304.482228 -14.100047) (xy 304.537665 -14.106147)
			(xy 304.591622 -14.120253) (xy 304.642951 -14.142065) (xy 304.690557 -14.171119) (xy 304.733425 -14.206794)
			(xy 304.770642 -14.248331) (xy 304.789638 -14.277043) (xy 373.41276 -14.277043) (xy 373.41276 -14.213121)
			(xy 373.420771 -14.149703) (xy 373.436668 -14.087789) (xy 373.4602 -14.028356) (xy 373.490994 -13.972341)
			(xy 373.528567 -13.920626) (xy 373.572324 -13.874029) (xy 373.621577 -13.833284) (xy 373.675548 -13.799033)
			(xy 373.733387 -13.771816) (xy 373.79418 -13.752063) (xy 373.85697 -13.740085) (xy 373.920766 -13.736072)
			(xy 373.984562 -13.740085) (xy 374.047352 -13.752063) (xy 374.108145 -13.771816) (xy 374.165984 -13.799033)
			(xy 374.219955 -13.833284) (xy 374.269208 -13.874029) (xy 374.312965 -13.920626) (xy 374.350538 -13.972341)
			(xy 374.381332 -14.028356) (xy 374.404864 -14.087789) (xy 374.420761 -14.149703) (xy 374.428772 -14.213121)
			(xy 374.429274 -14.245082) (xy 374.428772 -14.277043) (xy 374.420761 -14.340461) (xy 374.404864 -14.402375)
			(xy 374.381332 -14.461808) (xy 374.350538 -14.517823) (xy 374.312965 -14.569538) (xy 374.269208 -14.616135)
			(xy 374.219955 -14.65688) (xy 374.165984 -14.691131) (xy 374.108145 -14.718348) (xy 374.047352 -14.738101)
			(xy 373.984562 -14.750079) (xy 373.920766 -14.754093) (xy 373.85697 -14.750079) (xy 373.79418 -14.738101)
			(xy 373.733387 -14.718348) (xy 373.675548 -14.691131) (xy 373.621577 -14.65688) (xy 373.572324 -14.616135)
			(xy 373.528567 -14.569538) (xy 373.490994 -14.517823) (xy 373.4602 -14.461808) (xy 373.436668 -14.402375)
			(xy 373.420771 -14.340461) (xy 373.41276 -14.277043) (xy 304.789638 -14.277043) (xy 304.801415 -14.294844)
			(xy 304.825087 -14.345341) (xy 304.841155 -14.398748) (xy 304.849275 -14.453924) (xy 304.849784 -14.48181)
			(xy 304.849275 -14.509696) (xy 304.841155 -14.564872) (xy 304.825087 -14.618279) (xy 304.801415 -14.668776)
			(xy 304.770642 -14.715289) (xy 304.733425 -14.756826) (xy 304.690557 -14.792501) (xy 304.642951 -14.821555)
			(xy 304.591622 -14.843367) (xy 304.537665 -14.857473) (xy 304.482228 -14.863573) (xy 304.426494 -14.861536)
			(xy 304.371651 -14.851406) (xy 304.318867 -14.833399) (xy 304.269267 -14.807898) (xy 304.223909 -14.775447)
			(xy 304.18376 -14.736738) (xy 304.149674 -14.692595) (xy 304.122378 -14.64396) (xy 304.102455 -14.591869)
			(xy 304.090329 -14.537432) (xy 304.086258 -14.48181) (xy 297.813984 -14.48181) (xy 297.813984 -17.126712)
			(xy 310.265572 -17.126712) (xy 310.265572 -17.126458) (xy 310.266036 -17.082231) (xy 310.27389 -16.994125)
			(xy 310.289523 -16.907062) (xy 310.312813 -16.821729) (xy 310.343575 -16.738795) (xy 310.381568 -16.658915)
			(xy 310.426493 -16.582718) (xy 310.477995 -16.510803) (xy 310.53567 -16.443736) (xy 310.599063 -16.382046)
			(xy 310.667674 -16.326219) (xy 310.740965 -16.276694) (xy 310.818358 -16.233861) (xy 310.899242 -16.198057)
			(xy 310.940958 -16.183356) (xy 310.950254 -16.179674) (xy 310.965267 -16.166498) (xy 310.974104 -16.148585)
			(xy 310.975248 -16.138652) (xy 310.982868 -16.02994) (xy 310.967628 -16.00327) (xy 310.953912 -15.996412)
			(xy 310.920982 -15.979417) (xy 310.858427 -15.939679) (xy 310.800174 -15.893865) (xy 310.746812 -15.842438)
			(xy 310.698878 -15.785917) (xy 310.656857 -15.724873) (xy 310.621172 -15.65992) (xy 310.592183 -15.591716)
			(xy 310.570183 -15.520946) (xy 310.555395 -15.448327) (xy 310.547966 -15.374591) (xy 310.547512 -15.337536)
			(xy 310.548017 -15.298932) (xy 310.556087 -15.222148) (xy 310.57214 -15.146627) (xy 310.595998 -15.073199)
			(xy 310.627401 -15.002666) (xy 310.666005 -14.935803) (xy 310.711386 -14.87334) (xy 310.763048 -14.815964)
			(xy 310.820424 -14.764302) (xy 310.882887 -14.718921) (xy 310.94975 -14.680317) (xy 311.020283 -14.648914)
			(xy 311.093711 -14.625056) (xy 311.169232 -14.609003) (xy 311.246016 -14.600933) (xy 311.323224 -14.600933)
			(xy 311.400008 -14.609003) (xy 311.475529 -14.625056) (xy 311.548957 -14.648914) (xy 311.61949 -14.680317)
			(xy 311.686353 -14.718921) (xy 311.748816 -14.764302) (xy 311.806192 -14.815964) (xy 311.857854 -14.87334)
			(xy 311.903235 -14.935803) (xy 311.941839 -15.002666) (xy 311.973242 -15.073199) (xy 311.9971 -15.146627)
			(xy 312.013153 -15.222148) (xy 312.021223 -15.298932) (xy 312.021728 -15.337536) (xy 312.420003 -15.337536)
			(xy 312.424039 -15.254089) (xy 312.436111 -15.171421) (xy 312.456104 -15.090304) (xy 312.483833 -15.011495)
			(xy 312.519039 -14.93573) (xy 312.561393 -14.863717) (xy 312.610499 -14.796128) (xy 312.6659 -14.733594)
			(xy 312.727077 -14.676699) (xy 312.79346 -14.625973) (xy 312.864428 -14.581892) (xy 312.93932 -14.544866)
			(xy 313.017436 -14.51524) (xy 313.098046 -14.493292) (xy 313.180398 -14.479227) (xy 313.263724 -14.473175)
			(xy 313.347244 -14.475194) (xy 313.43018 -14.485264) (xy 313.511756 -14.503292) (xy 313.591212 -14.529109)
			(xy 313.667805 -14.562474) (xy 313.740821 -14.603075) (xy 313.809577 -14.650534) (xy 313.873431 -14.704407)
			(xy 313.931788 -14.764192) (xy 313.984103 -14.829329) (xy 314.029886 -14.899212) (xy 314.068711 -14.973187)
			(xy 314.100216 -15.050564) (xy 314.124105 -15.130621) (xy 314.140156 -15.212609) (xy 314.148219 -15.295764)
			(xy 314.148724 -15.337536) (xy 314.419999 -15.337536) (xy 314.424035 -15.254089) (xy 314.436107 -15.171421)
			(xy 314.4561 -15.090304) (xy 314.483829 -15.011495) (xy 314.519035 -14.93573) (xy 314.561389 -14.863717)
			(xy 314.610495 -14.796128) (xy 314.665896 -14.733594) (xy 314.727073 -14.676699) (xy 314.793456 -14.625973)
			(xy 314.864424 -14.581892) (xy 314.939316 -14.544866) (xy 315.017432 -14.51524) (xy 315.098042 -14.493292)
			(xy 315.180394 -14.479227) (xy 315.26372 -14.473175) (xy 315.34724 -14.475194) (xy 315.430176 -14.485264)
			(xy 315.511752 -14.503292) (xy 315.591208 -14.529109) (xy 315.667801 -14.562474) (xy 315.740817 -14.603075)
			(xy 315.809573 -14.650534) (xy 315.873427 -14.704407) (xy 315.931784 -14.764192) (xy 315.984099 -14.829329)
			(xy 316.029882 -14.899212) (xy 316.068707 -14.973187) (xy 316.100212 -15.050564) (xy 316.124101 -15.130621)
			(xy 316.140152 -15.212609) (xy 316.148215 -15.295764) (xy 316.14872 -15.337536) (xy 316.419995 -15.337536)
			(xy 316.424031 -15.254089) (xy 316.436103 -15.171421) (xy 316.456096 -15.090304) (xy 316.483825 -15.011495)
			(xy 316.519031 -14.93573) (xy 316.561385 -14.863717) (xy 316.610491 -14.796128) (xy 316.665892 -14.733594)
			(xy 316.727069 -14.676699) (xy 316.793452 -14.625973) (xy 316.86442 -14.581892) (xy 316.939312 -14.544866)
			(xy 317.017428 -14.51524) (xy 317.098038 -14.493292) (xy 317.18039 -14.479227) (xy 317.263716 -14.473175)
			(xy 317.347236 -14.475194) (xy 317.430172 -14.485264) (xy 317.511748 -14.503292) (xy 317.591204 -14.529109)
			(xy 317.667797 -14.562474) (xy 317.740813 -14.603075) (xy 317.809569 -14.650534) (xy 317.873423 -14.704407)
			(xy 317.93178 -14.764192) (xy 317.984095 -14.829329) (xy 318.029878 -14.899212) (xy 318.068703 -14.973187)
			(xy 318.100208 -15.050564) (xy 318.124097 -15.130621) (xy 318.140148 -15.212609) (xy 318.148211 -15.295764)
			(xy 318.148716 -15.337536) (xy 318.14831 -15.371156) (xy 362.324041 -15.371156) (xy 362.324041 -15.316644)
			(xy 362.331799 -15.262688) (xy 362.347158 -15.210384) (xy 362.369805 -15.1608) (xy 362.399278 -15.114943)
			(xy 362.434977 -15.073747) (xy 362.476176 -15.038052) (xy 362.522036 -15.008584) (xy 362.571624 -14.985943)
			(xy 362.623929 -14.97059) (xy 362.677886 -14.962838) (xy 362.705142 -14.962378) (xy 362.731862 -14.962888)
			(xy 362.784778 -14.97035) (xy 362.836135 -14.985123) (xy 362.884928 -15.006918) (xy 362.930203 -15.035307)
			(xy 362.971074 -15.069737) (xy 363.006741 -15.109532) (xy 363.036506 -15.153914) (xy 363.04855 -15.17777)
			(xy 363.05363 -15.188438) (xy 363.072426 -15.202916) (xy 363.163104 -15.221458) (xy 363.174688 -15.22319)
			(xy 363.197314 -15.217245) (xy 363.206538 -15.210028) (xy 363.206792 -15.210028) (xy 363.229957 -15.190408)
			(xy 363.280162 -15.156276) (xy 363.334076 -15.128369) (xy 363.390931 -15.107085) (xy 363.449917 -15.092727)
			(xy 363.510194 -15.085499) (xy 363.540548 -15.08506) (xy 363.572505 -15.085629) (xy 363.635915 -15.093645)
			(xy 363.69782 -15.109545) (xy 363.757244 -15.133077) (xy 363.81325 -15.163872) (xy 363.864956 -15.201442)
			(xy 363.911545 -15.245197) (xy 363.952284 -15.294445) (xy 363.986529 -15.348411) (xy 364.01374 -15.406243)
			(xy 364.03349 -15.46703) (xy 364.045466 -15.529812) (xy 364.049479 -15.5936) (xy 364.046749 -15.637002)
			(xy 371.068852 -15.637002) (xy 371.072923 -15.58138) (xy 371.085049 -15.526943) (xy 371.104972 -15.474852)
			(xy 371.132268 -15.426217) (xy 371.166354 -15.382074) (xy 371.206503 -15.343365) (xy 371.251861 -15.310914)
			(xy 371.301461 -15.285413) (xy 371.354245 -15.267406) (xy 371.409088 -15.257276) (xy 371.464822 -15.255239)
			(xy 371.520259 -15.261339) (xy 371.574216 -15.275445) (xy 371.625545 -15.297257) (xy 371.673151 -15.326311)
			(xy 371.716019 -15.361986) (xy 371.753236 -15.403523) (xy 371.784009 -15.450036) (xy 371.807681 -15.500533)
			(xy 371.823749 -15.55394) (xy 371.831869 -15.609116) (xy 371.832378 -15.637002) (xy 371.831869 -15.664888)
			(xy 371.823749 -15.720064) (xy 371.807681 -15.773471) (xy 371.784009 -15.823968) (xy 371.753236 -15.870481)
			(xy 371.716019 -15.912018) (xy 371.673151 -15.947693) (xy 371.625545 -15.976747) (xy 371.574216 -15.998559)
			(xy 371.520259 -16.012665) (xy 371.464822 -16.018765) (xy 371.409088 -16.016728) (xy 371.354245 -16.006598)
			(xy 371.301461 -15.988591) (xy 371.251861 -15.96309) (xy 371.206503 -15.930639) (xy 371.166354 -15.89193)
			(xy 371.132268 -15.847787) (xy 371.104972 -15.799152) (xy 371.085049 -15.747061) (xy 371.072923 -15.692624)
			(xy 371.068852 -15.637002) (xy 364.046749 -15.637002) (xy 364.045466 -15.657388) (xy 364.03349 -15.72017)
			(xy 364.01374 -15.780957) (xy 363.986529 -15.838789) (xy 363.952284 -15.892755) (xy 363.911545 -15.942003)
			(xy 363.864956 -15.985758) (xy 363.81325 -16.023328) (xy 363.757244 -16.054123) (xy 363.69782 -16.077655)
			(xy 363.635915 -16.093555) (xy 363.572505 -16.101571) (xy 363.540548 -16.102076) (xy 363.507558 -16.101533)
			(xy 363.442132 -16.093013) (xy 363.378359 -16.076096) (xy 363.317311 -16.051067) (xy 363.260017 -16.018347)
			(xy 363.207439 -15.978487) (xy 363.160463 -15.932157) (xy 363.119878 -15.880137) (xy 363.086368 -15.823301)
			(xy 363.060496 -15.762607) (xy 363.05109 -15.730982) (xy 363.047411 -15.719885) (xy 363.031764 -15.702545)
			(xy 363.021118 -15.697708) (xy 362.945934 -15.667736) (xy 362.934801 -15.663915) (xy 362.911365 -15.66576)
			(xy 362.900976 -15.671292) (xy 362.878703 -15.684156) (xy 362.831411 -15.704384) (xy 362.781831 -15.718073)
			(xy 362.73086 -15.724977) (xy 362.705142 -15.725394) (xy 362.677886 -15.724962) (xy 362.623929 -15.71721)
			(xy 362.571624 -15.701857) (xy 362.522036 -15.679216) (xy 362.476176 -15.649748) (xy 362.434977 -15.614053)
			(xy 362.399278 -15.572857) (xy 362.369805 -15.527) (xy 362.347158 -15.477416) (xy 362.331799 -15.425112)
			(xy 362.324041 -15.371156) (xy 318.14831 -15.371156) (xy 318.148211 -15.379308) (xy 318.140148 -15.462463)
			(xy 318.124097 -15.544451) (xy 318.100208 -15.624508) (xy 318.068703 -15.701885) (xy 318.029878 -15.77586)
			(xy 317.984095 -15.845743) (xy 317.93178 -15.91088) (xy 317.873423 -15.970665) (xy 317.809569 -16.024538)
			(xy 317.740813 -16.071997) (xy 317.667797 -16.112598) (xy 317.591204 -16.145963) (xy 317.511748 -16.17178)
			(xy 317.430172 -16.189808) (xy 317.347236 -16.199878) (xy 317.263716 -16.201897) (xy 317.18039 -16.195845)
			(xy 317.098038 -16.18178) (xy 317.017428 -16.159832) (xy 316.939312 -16.130206) (xy 316.86442 -16.09318)
			(xy 316.793452 -16.049099) (xy 316.727069 -15.998373) (xy 316.665892 -15.941478) (xy 316.610491 -15.878944)
			(xy 316.561385 -15.811355) (xy 316.519031 -15.739342) (xy 316.483825 -15.663577) (xy 316.456096 -15.584768)
			(xy 316.436103 -15.503651) (xy 316.424031 -15.420983) (xy 316.419995 -15.337536) (xy 316.14872 -15.337536)
			(xy 316.148215 -15.379308) (xy 316.140152 -15.462463) (xy 316.124101 -15.544451) (xy 316.100212 -15.624508)
			(xy 316.068707 -15.701885) (xy 316.029882 -15.77586) (xy 315.984099 -15.845743) (xy 315.931784 -15.91088)
			(xy 315.873427 -15.970665) (xy 315.809573 -16.024538) (xy 315.740817 -16.071997) (xy 315.667801 -16.112598)
			(xy 315.591208 -16.145963) (xy 315.511752 -16.17178) (xy 315.430176 -16.189808) (xy 315.34724 -16.199878)
			(xy 315.26372 -16.201897) (xy 315.180394 -16.195845) (xy 315.098042 -16.18178) (xy 315.017432 -16.159832)
			(xy 314.939316 -16.130206) (xy 314.864424 -16.09318) (xy 314.793456 -16.049099) (xy 314.727073 -15.998373)
			(xy 314.665896 -15.941478) (xy 314.610495 -15.878944) (xy 314.561389 -15.811355) (xy 314.519035 -15.739342)
			(xy 314.483829 -15.663577) (xy 314.4561 -15.584768) (xy 314.436107 -15.503651) (xy 314.424035 -15.420983)
			(xy 314.419999 -15.337536) (xy 314.148724 -15.337536) (xy 314.148219 -15.379308) (xy 314.140156 -15.462463)
			(xy 314.124105 -15.544451) (xy 314.100216 -15.624508) (xy 314.068711 -15.701885) (xy 314.029886 -15.77586)
			(xy 313.984103 -15.845743) (xy 313.931788 -15.91088) (xy 313.873431 -15.970665) (xy 313.809577 -16.024538)
			(xy 313.740821 -16.071997) (xy 313.667805 -16.112598) (xy 313.591212 -16.145963) (xy 313.511756 -16.17178)
			(xy 313.43018 -16.189808) (xy 313.347244 -16.199878) (xy 313.263724 -16.201897) (xy 313.180398 -16.195845)
			(xy 313.098046 -16.18178) (xy 313.017436 -16.159832) (xy 312.93932 -16.130206) (xy 312.864428 -16.09318)
			(xy 312.79346 -16.049099) (xy 312.727077 -15.998373) (xy 312.6659 -15.941478) (xy 312.610499 -15.878944)
			(xy 312.561393 -15.811355) (xy 312.519039 -15.739342) (xy 312.483833 -15.663577) (xy 312.456104 -15.584768)
			(xy 312.436111 -15.503651) (xy 312.424039 -15.420983) (xy 312.420003 -15.337536) (xy 312.021728 -15.337536)
			(xy 312.021276 -15.374909) (xy 312.013717 -15.449272) (xy 311.99867 -15.522489) (xy 311.976289 -15.593806)
			(xy 311.946805 -15.662491) (xy 311.910519 -15.727839) (xy 311.867806 -15.78918) (xy 311.819103 -15.845881)
			(xy 311.764912 -15.897362) (xy 311.705787 -15.943093) (xy 311.642338 -15.982605) (xy 311.608978 -15.99946)
			(xy 311.608724 -15.99946) (xy 311.599915 -16.004228) (xy 311.586699 -16.019258) (xy 311.580276 -16.038215)
			(xy 311.58053 -16.048228) (xy 311.586118 -16.1417) (xy 311.587186 -16.151648) (xy 311.595941 -16.169619)
			(xy 311.610877 -16.182906) (xy 311.620154 -16.186658) (xy 311.662032 -16.20173) (xy 311.74316 -16.238354)
			(xy 311.820746 -16.281983) (xy 311.894187 -16.332278) (xy 311.962911 -16.388848) (xy 312.026383 -16.451253)
			(xy 312.084111 -16.519006) (xy 312.135646 -16.591583) (xy 312.180586 -16.668417) (xy 312.218582 -16.748912)
			(xy 312.249338 -16.832441) (xy 312.272616 -16.918355) (xy 312.288234 -17.005986) (xy 312.289561 -17.021005)
			(xy 343.852494 -17.021005) (xy 343.852494 -16.957083) (xy 343.860505 -16.893665) (xy 343.876402 -16.831751)
			(xy 343.899934 -16.772318) (xy 343.930728 -16.716303) (xy 343.968301 -16.664588) (xy 344.012058 -16.617991)
			(xy 344.061311 -16.577246) (xy 344.115282 -16.542995) (xy 344.173121 -16.515778) (xy 344.233914 -16.496025)
			(xy 344.296704 -16.484047) (xy 344.3605 -16.480034) (xy 344.424296 -16.484047) (xy 344.487086 -16.496025)
			(xy 344.547879 -16.515778) (xy 344.605718 -16.542995) (xy 344.659689 -16.577246) (xy 344.708942 -16.617991)
			(xy 344.752699 -16.664588) (xy 344.790272 -16.716303) (xy 344.821066 -16.772318) (xy 344.844598 -16.831751)
			(xy 344.860495 -16.893665) (xy 344.868506 -16.957083) (xy 344.869008 -16.989044) (xy 344.868506 -17.021005)
			(xy 344.860495 -17.084423) (xy 344.860332 -17.085056) (xy 345.451682 -17.085056) (xy 345.455753 -17.029434)
			(xy 345.467879 -16.974997) (xy 345.487802 -16.922906) (xy 345.515098 -16.874271) (xy 345.549184 -16.830128)
			(xy 345.589333 -16.791419) (xy 345.634691 -16.758968) (xy 345.684291 -16.733467) (xy 345.737075 -16.71546)
			(xy 345.791918 -16.70533) (xy 345.847652 -16.703293) (xy 345.903089 -16.709393) (xy 345.957046 -16.723499)
			(xy 346.008375 -16.745311) (xy 346.055981 -16.774365) (xy 346.098849 -16.81004) (xy 346.136066 -16.851577)
			(xy 346.166839 -16.89809) (xy 346.190511 -16.948587) (xy 346.206579 -17.001994) (xy 346.209377 -17.021005)
			(xy 346.951294 -17.021005) (xy 346.951294 -16.957083) (xy 346.959305 -16.893665) (xy 346.975202 -16.831751)
			(xy 346.998734 -16.772318) (xy 347.029528 -16.716303) (xy 347.067101 -16.664588) (xy 347.110858 -16.617991)
			(xy 347.160111 -16.577246) (xy 347.214082 -16.542995) (xy 347.271921 -16.515778) (xy 347.332714 -16.496025)
			(xy 347.395504 -16.484047) (xy 347.4593 -16.480034) (xy 347.523096 -16.484047) (xy 347.585886 -16.496025)
			(xy 347.646679 -16.515778) (xy 347.704518 -16.542995) (xy 347.758489 -16.577246) (xy 347.807742 -16.617991)
			(xy 347.851499 -16.664588) (xy 347.889072 -16.716303) (xy 347.919866 -16.772318) (xy 347.943398 -16.831751)
			(xy 347.959295 -16.893665) (xy 347.967306 -16.957083) (xy 347.967808 -16.989044) (xy 347.967306 -17.021005)
			(xy 347.959295 -17.084423) (xy 347.943398 -17.146337) (xy 347.919866 -17.20577) (xy 347.889072 -17.261785)
			(xy 347.851499 -17.3135) (xy 347.807742 -17.360097) (xy 347.758489 -17.400842) (xy 347.704518 -17.435093)
			(xy 347.646679 -17.46231) (xy 347.585886 -17.482063) (xy 347.523096 -17.494041) (xy 347.4593 -17.498055)
			(xy 347.395504 -17.494041) (xy 347.332714 -17.482063) (xy 347.271921 -17.46231) (xy 347.214082 -17.435093)
			(xy 347.160111 -17.400842) (xy 347.110858 -17.360097) (xy 347.067101 -17.3135) (xy 347.029528 -17.261785)
			(xy 346.998734 -17.20577) (xy 346.975202 -17.146337) (xy 346.959305 -17.084423) (xy 346.951294 -17.021005)
			(xy 346.209377 -17.021005) (xy 346.214699 -17.05717) (xy 346.215208 -17.085056) (xy 346.214699 -17.112942)
			(xy 346.206579 -17.168118) (xy 346.190511 -17.221525) (xy 346.166839 -17.272022) (xy 346.136066 -17.318535)
			(xy 346.098849 -17.360072) (xy 346.055981 -17.395747) (xy 346.008375 -17.424801) (xy 345.957046 -17.446613)
			(xy 345.903089 -17.460719) (xy 345.847652 -17.466819) (xy 345.791918 -17.464782) (xy 345.737075 -17.454652)
			(xy 345.684291 -17.436645) (xy 345.634691 -17.411144) (xy 345.589333 -17.378693) (xy 345.549184 -17.339984)
			(xy 345.515098 -17.295841) (xy 345.487802 -17.247206) (xy 345.467879 -17.195115) (xy 345.455753 -17.140678)
			(xy 345.451682 -17.085056) (xy 344.860332 -17.085056) (xy 344.844598 -17.146337) (xy 344.821066 -17.20577)
			(xy 344.790272 -17.261785) (xy 344.752699 -17.3135) (xy 344.708942 -17.360097) (xy 344.659689 -17.400842)
			(xy 344.605718 -17.435093) (xy 344.547879 -17.46231) (xy 344.487086 -17.482063) (xy 344.424296 -17.494041)
			(xy 344.3605 -17.498055) (xy 344.296704 -17.494041) (xy 344.233914 -17.482063) (xy 344.173121 -17.46231)
			(xy 344.115282 -17.435093) (xy 344.061311 -17.400842) (xy 344.012058 -17.360097) (xy 343.968301 -17.3135)
			(xy 343.930728 -17.261785) (xy 343.899934 -17.20577) (xy 343.876402 -17.146337) (xy 343.860505 -17.084423)
			(xy 343.852494 -17.021005) (xy 312.289561 -17.021005) (xy 312.296071 -17.094652) (xy 312.296556 -17.139158)
			(xy 312.296035 -17.183197) (xy 312.288362 -17.270939) (xy 312.273071 -17.357679) (xy 312.250278 -17.442756)
			(xy 312.220157 -17.525523) (xy 312.182937 -17.605349) (xy 312.138901 -17.681628) (xy 312.088384 -17.753778)
			(xy 312.031771 -17.821251) (xy 311.969492 -17.883533) (xy 311.902023 -17.94015) (xy 311.829875 -17.99067)
			(xy 311.753599 -18.034711) (xy 311.673774 -18.071936) (xy 311.591009 -18.102062) (xy 311.505934 -18.124859)
			(xy 311.419195 -18.140155) (xy 311.331453 -18.147833) (xy 311.287414 -18.1483) (xy 311.28716 -18.1483)
			(xy 311.24258 -18.147832) (xy 311.15376 -18.140042) (xy 311.065958 -18.124543) (xy 310.979839 -18.101453)
			(xy 310.89606 -18.070947) (xy 310.815257 -18.033257) (xy 310.738046 -17.98867) (xy 310.665013 -17.937525)
			(xy 310.596715 -17.880211) (xy 310.53367 -17.817165) (xy 310.476358 -17.748864) (xy 310.425215 -17.67583)
			(xy 310.38063 -17.598618) (xy 310.342942 -17.517814) (xy 310.312439 -17.434034) (xy 310.289351 -17.347915)
			(xy 310.273854 -17.260112) (xy 310.266067 -17.171292) (xy 310.265572 -17.126712) (xy 297.813984 -17.126712)
			(xy 297.813984 -17.864328) (xy 297.813491 -17.874331) (xy 297.805826 -17.89281) (xy 297.791673 -17.906951)
			(xy 297.773187 -17.9146) (xy 297.763184 -17.915128) (xy 293.031418 -17.915128) (xy 293.022901 -17.91604)
			(xy 293.007175 -17.922799) (xy 292.994588 -17.9344) (xy 292.99027 -17.941798) (xy 292.946582 -18.022824)
			(xy 292.943026 -18.033492) (xy 292.941502 -18.039588) (xy 292.94201 -18.050256) (xy 292.942724 -18.055181)
			(xy 292.94579 -18.064647) (xy 292.948106 -18.069052) (xy 292.950392 -18.072608) (xy 292.966478 -18.097662)
			(xy 292.993336 -18.1508) (xy 293.013807 -18.20671) (xy 293.02761 -18.264628) (xy 293.034557 -18.323762)
			(xy 293.034974 -18.353532) (xy 293.034472 -18.385493) (xy 293.026461 -18.448911) (xy 293.010564 -18.510825)
			(xy 292.987032 -18.570258) (xy 292.956238 -18.626273) (xy 292.918665 -18.677988) (xy 292.874908 -18.724585)
			(xy 292.825655 -18.76533) (xy 292.801741 -18.780506) (xy 293.13454 -18.780506) (xy 293.138611 -18.724884)
			(xy 293.150737 -18.670447) (xy 293.17066 -18.618356) (xy 293.197956 -18.569721) (xy 293.232042 -18.525578)
			(xy 293.272191 -18.486869) (xy 293.317549 -18.454418) (xy 293.367149 -18.428917) (xy 293.419933 -18.41091)
			(xy 293.474776 -18.40078) (xy 293.53051 -18.398743) (xy 293.585947 -18.404843) (xy 293.639904 -18.418949)
			(xy 293.691233 -18.440761) (xy 293.738839 -18.469815) (xy 293.781707 -18.50549) (xy 293.818924 -18.547027)
			(xy 293.849697 -18.59354) (xy 293.873369 -18.644037) (xy 293.889437 -18.697444) (xy 293.897557 -18.75262)
			(xy 293.898066 -18.780506) (xy 293.897557 -18.808392) (xy 293.89183 -18.847308) (xy 296.46448 -18.847308)
			(xy 296.468551 -18.791686) (xy 296.480677 -18.737249) (xy 296.5006 -18.685158) (xy 296.527896 -18.636523)
			(xy 296.561982 -18.59238) (xy 296.602131 -18.553671) (xy 296.647489 -18.52122) (xy 296.697089 -18.495719)
			(xy 296.749873 -18.477712) (xy 296.804716 -18.467582) (xy 296.86045 -18.465545) (xy 296.915887 -18.471645)
			(xy 296.969844 -18.485751) (xy 297.021173 -18.507563) (xy 297.03385 -18.5153) (xy 316.775598 -18.5153)
			(xy 316.779612 -18.451505) (xy 316.79159 -18.388715) (xy 316.811343 -18.327922) (xy 316.83856 -18.270084)
			(xy 316.872811 -18.216114) (xy 316.913557 -18.166862) (xy 316.960154 -18.123105) (xy 317.011868 -18.085533)
			(xy 317.067883 -18.054739) (xy 317.127316 -18.031209) (xy 317.18923 -18.015313) (xy 317.252647 -18.007302)
			(xy 317.284608 -18.006822) (xy 317.31865 -18.00736) (xy 317.386126 -18.016434) (xy 317.451787 -18.034434)
			(xy 317.514459 -18.061036) (xy 317.573019 -18.095764) (xy 317.626421 -18.137998) (xy 317.673707 -18.186981)
			(xy 317.69431 -18.214086) (xy 317.701422 -18.223738) (xy 317.721996 -18.234406) (xy 317.814198 -18.236946)
			(xy 317.825867 -18.236622) (xy 317.847031 -18.226829) (xy 317.854838 -18.21815) (xy 317.873067 -18.196636)
			(xy 317.914784 -18.158698) (xy 317.961627 -18.127307) (xy 318.012576 -18.103146) (xy 318.066525 -18.086741)
			(xy 318.1223 -18.078448) (xy 318.150494 -18.077942) (xy 318.177751 -18.078305) (xy 318.231709 -18.086062)
			(xy 318.284015 -18.101419) (xy 318.333602 -18.124065) (xy 318.379462 -18.153536) (xy 318.420661 -18.189235)
			(xy 318.45636 -18.230433) (xy 318.485833 -18.276292) (xy 318.508478 -18.325879) (xy 318.523837 -18.378185)
			(xy 318.531595 -18.432143) (xy 318.531595 -18.486657) (xy 318.523837 -18.540615) (xy 318.508478 -18.592921)
			(xy 318.485833 -18.642508) (xy 318.45636 -18.688367) (xy 318.420661 -18.729565) (xy 318.379462 -18.765264)
			(xy 318.333602 -18.794735) (xy 318.284015 -18.817381) (xy 318.231709 -18.832738) (xy 318.177751 -18.840495)
			(xy 318.150494 -18.840958) (xy 318.121575 -18.840462) (xy 318.064401 -18.831724) (xy 318.009204 -18.814449)
			(xy 317.957249 -18.789034) (xy 317.909731 -18.756061) (xy 317.888366 -18.736564) (xy 317.87973 -18.728436)
			(xy 317.857632 -18.721578) (xy 317.754254 -18.73758) (xy 317.735458 -18.750788) (xy 317.729616 -18.760948)
			(xy 317.729616 -18.761456) (xy 317.712749 -18.790844) (xy 317.672359 -18.845252) (xy 317.625103 -18.893815)
			(xy 317.571817 -18.935674) (xy 317.513445 -18.970086) (xy 317.451021 -18.996444) (xy 317.385649 -19.01428)
			(xy 317.318488 -19.023278) (xy 317.284608 -19.023838) (xy 317.252647 -19.023298) (xy 317.18923 -19.015287)
			(xy 317.127316 -18.999391) (xy 317.067883 -18.975861) (xy 317.011868 -18.945067) (xy 316.960154 -18.907495)
			(xy 316.913557 -18.863738) (xy 316.872811 -18.814486) (xy 316.83856 -18.760516) (xy 316.811343 -18.702678)
			(xy 316.79159 -18.641885) (xy 316.779612 -18.579095) (xy 316.775598 -18.5153) (xy 297.03385 -18.5153)
			(xy 297.068779 -18.536617) (xy 297.111647 -18.572292) (xy 297.148864 -18.613829) (xy 297.179637 -18.660342)
			(xy 297.203309 -18.710839) (xy 297.219377 -18.764246) (xy 297.227497 -18.819422) (xy 297.228006 -18.847308)
			(xy 297.227497 -18.875194) (xy 297.219377 -18.93037) (xy 297.203309 -18.983777) (xy 297.179637 -19.034274)
			(xy 297.148864 -19.080787) (xy 297.111647 -19.122324) (xy 297.076409 -19.151649) (xy 313.4477 -19.151649)
			(xy 313.4477 -19.097151) (xy 313.455456 -19.043208) (xy 313.470809 -18.990918) (xy 313.493448 -18.941344)
			(xy 313.522911 -18.895497) (xy 313.558599 -18.85431) (xy 313.599785 -18.818621) (xy 313.64563 -18.789156)
			(xy 313.695203 -18.766515) (xy 313.747492 -18.751159) (xy 313.801435 -18.743401) (xy 313.828684 -18.742914)
			(xy 313.857113 -18.743463) (xy 313.91334 -18.751905) (xy 313.967691 -18.768603) (xy 314.018959 -18.793187)
			(xy 314.066007 -18.825113) (xy 314.087256 -18.844006) (xy 314.08751 -18.84426) (xy 314.09569 -18.851002)
			(xy 314.115781 -18.857692) (xy 314.126372 -18.857214) (xy 314.212732 -18.848832) (xy 314.231274 -18.838418)
			(xy 314.237878 -18.829528) (xy 314.258496 -18.802484) (xy 314.3058 -18.753627) (xy 314.35919 -18.711507)
			(xy 314.417715 -18.676873) (xy 314.480332 -18.650344) (xy 314.545924 -18.632392) (xy 314.613324 -18.623337)
			(xy 314.647326 -18.622772) (xy 314.679285 -18.623315) (xy 314.742698 -18.631329) (xy 314.804607 -18.647228)
			(xy 314.864035 -18.67076) (xy 314.920045 -18.701554) (xy 314.971754 -18.739125) (xy 315.018347 -18.782881)
			(xy 315.059088 -18.832131) (xy 315.093336 -18.886099) (xy 315.12055 -18.943934) (xy 315.140301 -19.004723)
			(xy 315.152277 -19.067509) (xy 315.156291 -19.1313) (xy 315.152277 -19.195091) (xy 315.140301 -19.257877)
			(xy 315.12055 -19.318666) (xy 315.093336 -19.376501) (xy 315.085374 -19.389047) (xy 329.487778 -19.389047)
			(xy 329.487778 -19.325125) (xy 329.495789 -19.261707) (xy 329.511686 -19.199793) (xy 329.535218 -19.14036)
			(xy 329.566012 -19.084345) (xy 329.603585 -19.03263) (xy 329.647342 -18.986033) (xy 329.696595 -18.945288)
			(xy 329.750566 -18.911037) (xy 329.808405 -18.88382) (xy 329.869198 -18.864067) (xy 329.931988 -18.852089)
			(xy 329.995784 -18.848076) (xy 330.05958 -18.852089) (xy 330.12237 -18.864067) (xy 330.183163 -18.88382)
			(xy 330.241002 -18.911037) (xy 330.294973 -18.945288) (xy 330.344186 -18.986) (xy 331.134981 -18.986)
			(xy 331.138995 -18.922204) (xy 331.150973 -18.859414) (xy 331.170726 -18.79862) (xy 331.197942 -18.740781)
			(xy 331.232193 -18.68681) (xy 331.272938 -18.637556) (xy 331.319535 -18.593798) (xy 331.371249 -18.556225)
			(xy 331.427264 -18.525429) (xy 331.486697 -18.501897) (xy 331.548611 -18.485999) (xy 331.612029 -18.477987)
			(xy 331.64399 -18.477484) (xy 331.676698 -18.477934) (xy 331.741574 -18.486322) (xy 331.804839 -18.502962)
			(xy 331.813402 -18.50644) (xy 339.937342 -18.50644) (xy 339.941413 -18.450818) (xy 339.953539 -18.396381)
			(xy 339.973462 -18.34429) (xy 340.000758 -18.295655) (xy 340.034844 -18.251512) (xy 340.074993 -18.212803)
			(xy 340.120351 -18.180352) (xy 340.169951 -18.154851) (xy 340.222735 -18.136844) (xy 340.277578 -18.126714)
			(xy 340.333312 -18.124677) (xy 340.388749 -18.130777) (xy 340.442706 -18.144883) (xy 340.494035 -18.166695)
			(xy 340.541641 -18.195749) (xy 340.584509 -18.231424) (xy 340.621726 -18.272961) (xy 340.652499 -18.319474)
			(xy 340.676171 -18.369971) (xy 340.692239 -18.423378) (xy 340.700359 -18.478554) (xy 340.70071 -18.497804)
			(xy 342.962482 -18.497804) (xy 342.966553 -18.442182) (xy 342.978679 -18.387745) (xy 342.998602 -18.335654)
			(xy 343.025898 -18.287019) (xy 343.059984 -18.242876) (xy 343.100133 -18.204167) (xy 343.145491 -18.171716)
			(xy 343.195091 -18.146215) (xy 343.247875 -18.128208) (xy 343.302718 -18.118078) (xy 343.358452 -18.116041)
			(xy 343.413889 -18.122141) (xy 343.467846 -18.136247) (xy 343.519175 -18.158059) (xy 343.566781 -18.187113)
			(xy 343.609649 -18.222788) (xy 343.646866 -18.264325) (xy 343.677639 -18.310838) (xy 343.701311 -18.361335)
			(xy 343.717379 -18.414742) (xy 343.725499 -18.469918) (xy 343.726008 -18.497804) (xy 343.725499 -18.52569)
			(xy 343.717379 -18.580866) (xy 343.701311 -18.634273) (xy 343.677639 -18.68477) (xy 343.646866 -18.731283)
			(xy 343.609649 -18.77282) (xy 343.566781 -18.808495) (xy 343.519175 -18.837549) (xy 343.467846 -18.859361)
			(xy 343.413889 -18.873467) (xy 343.358452 -18.879567) (xy 343.302718 -18.87753) (xy 343.247875 -18.8674)
			(xy 343.195091 -18.849393) (xy 343.145491 -18.823892) (xy 343.100133 -18.791441) (xy 343.059984 -18.752732)
			(xy 343.025898 -18.708589) (xy 342.998602 -18.659954) (xy 342.978679 -18.607863) (xy 342.966553 -18.553426)
			(xy 342.962482 -18.497804) (xy 340.70071 -18.497804) (xy 340.700868 -18.50644) (xy 340.700359 -18.534326)
			(xy 340.692239 -18.589502) (xy 340.676171 -18.642909) (xy 340.652499 -18.693406) (xy 340.621726 -18.739919)
			(xy 340.584509 -18.781456) (xy 340.541641 -18.817131) (xy 340.494035 -18.846185) (xy 340.442706 -18.867997)
			(xy 340.388749 -18.882103) (xy 340.333312 -18.888203) (xy 340.277578 -18.886166) (xy 340.222735 -18.876036)
			(xy 340.169951 -18.858029) (xy 340.120351 -18.832528) (xy 340.074993 -18.800077) (xy 340.034844 -18.761368)
			(xy 340.000758 -18.717225) (xy 339.973462 -18.66859) (xy 339.953539 -18.616499) (xy 339.941413 -18.562062)
			(xy 339.937342 -18.50644) (xy 331.813402 -18.50644) (xy 331.865447 -18.527578) (xy 331.922398 -18.559763)
			(xy 331.974751 -18.598986) (xy 332.021641 -18.6446) (xy 332.062294 -18.695851) (xy 332.0796 -18.72361)
			(xy 332.086378 -18.733571) (xy 332.106788 -18.746305) (xy 332.118716 -18.747994) (xy 332.200758 -18.754852)
			(xy 332.21288 -18.755232) (xy 332.235299 -18.746086) (xy 332.243684 -18.737326) (xy 332.261899 -18.71688)
			(xy 332.303156 -18.680876) (xy 332.349138 -18.651143) (xy 332.398899 -18.628291) (xy 332.451417 -18.612789)
			(xy 332.505611 -18.604957) (xy 332.53299 -18.604484) (xy 332.560243 -18.604963) (xy 332.614194 -18.612718)
			(xy 332.666492 -18.628073) (xy 332.716072 -18.650715) (xy 332.761925 -18.680182) (xy 332.803118 -18.715875)
			(xy 332.838812 -18.757067) (xy 332.868281 -18.802919) (xy 332.890923 -18.852499) (xy 332.90628 -18.904797)
			(xy 332.914037 -18.958747) (xy 332.914037 -19.013253) (xy 332.90628 -19.067203) (xy 332.890923 -19.119501)
			(xy 332.868281 -19.169081) (xy 332.838812 -19.214933) (xy 332.803118 -19.256125) (xy 332.761925 -19.291818)
			(xy 332.716072 -19.321285) (xy 332.666492 -19.343927) (xy 332.614194 -19.359282) (xy 332.560243 -19.367037)
			(xy 332.53299 -19.3675) (xy 332.50561 -19.367051) (xy 332.451415 -19.359209) (xy 332.398898 -19.343701)
			(xy 332.349136 -19.320847) (xy 332.303151 -19.291114) (xy 332.261889 -19.255114) (xy 332.243684 -19.234658)
			(xy 332.235261 -19.225948) (xy 332.212868 -19.216792) (xy 332.200758 -19.217132) (xy 332.118716 -19.22399)
			(xy 332.106791 -19.225693) (xy 332.086377 -19.238416) (xy 332.0796 -19.248374) (xy 332.062315 -19.276144)
			(xy 332.02165 -19.327381) (xy 331.974752 -19.372982) (xy 331.922394 -19.412193) (xy 331.865441 -19.444368)
			(xy 331.804833 -19.468975) (xy 331.74157 -19.485609) (xy 331.676697 -19.493995) (xy 331.64399 -19.4945)
			(xy 331.612029 -19.494013) (xy 331.548611 -19.486001) (xy 331.486697 -19.470103) (xy 331.427264 -19.446571)
			(xy 331.371249 -19.415775) (xy 331.319535 -19.378202) (xy 331.272938 -19.334444) (xy 331.232193 -19.28519)
			(xy 331.197942 -19.231219) (xy 331.170726 -19.17338) (xy 331.150973 -19.112586) (xy 331.138995 -19.049796)
			(xy 331.134981 -18.986) (xy 330.344186 -18.986) (xy 330.344226 -18.986033) (xy 330.387983 -19.03263)
			(xy 330.425556 -19.084345) (xy 330.45635 -19.14036) (xy 330.479882 -19.199793) (xy 330.495779 -19.261707)
			(xy 330.50379 -19.325125) (xy 330.504292 -19.357086) (xy 330.50379 -19.389047) (xy 330.495779 -19.452465)
			(xy 330.479882 -19.514379) (xy 330.45635 -19.573812) (xy 330.425556 -19.629827) (xy 330.387983 -19.681542)
			(xy 330.344226 -19.728139) (xy 330.294973 -19.768884) (xy 330.241002 -19.803135) (xy 330.183163 -19.830352)
			(xy 330.12237 -19.850105) (xy 330.05958 -19.862083) (xy 329.995784 -19.866097) (xy 329.931988 -19.862083)
			(xy 329.869198 -19.850105) (xy 329.808405 -19.830352) (xy 329.750566 -19.803135) (xy 329.696595 -19.768884)
			(xy 329.647342 -19.728139) (xy 329.603585 -19.681542) (xy 329.566012 -19.629827) (xy 329.535218 -19.573812)
			(xy 329.511686 -19.514379) (xy 329.495789 -19.452465) (xy 329.487778 -19.389047) (xy 315.085374 -19.389047)
			(xy 315.059088 -19.430469) (xy 315.018347 -19.479719) (xy 314.971754 -19.523475) (xy 314.920045 -19.561046)
			(xy 314.864035 -19.59184) (xy 314.804607 -19.615372) (xy 314.742698 -19.631271) (xy 314.679285 -19.639285)
			(xy 314.647326 -19.639788) (xy 314.617054 -19.639345) (xy 314.556939 -19.632159) (xy 314.498103 -19.617885)
			(xy 314.441378 -19.596725) (xy 314.387567 -19.56898) (xy 314.337431 -19.53504) (xy 314.291681 -19.495387)
			(xy 314.250962 -19.450582) (xy 314.233052 -19.426174) (xy 314.22642 -19.417685) (xy 314.20788 -19.406757)
			(xy 314.197238 -19.405092) (xy 314.111132 -19.39544) (xy 314.090812 -19.402044) (xy 314.082684 -19.409156)
			(xy 314.061603 -19.427291) (xy 314.015162 -19.457876) (xy 313.964775 -19.4814) (xy 313.911508 -19.497363)
			(xy 313.856488 -19.505429) (xy 313.828684 -19.50593) (xy 313.801435 -19.505399) (xy 313.747492 -19.497641)
			(xy 313.695203 -19.482285) (xy 313.64563 -19.459644) (xy 313.599785 -19.430179) (xy 313.558599 -19.39449)
			(xy 313.522911 -19.353303) (xy 313.493448 -19.307456) (xy 313.470809 -19.257882) (xy 313.455456 -19.205592)
			(xy 313.4477 -19.151649) (xy 297.076409 -19.151649) (xy 297.068779 -19.157999) (xy 297.021173 -19.187053)
			(xy 296.969844 -19.208865) (xy 296.915887 -19.222971) (xy 296.86045 -19.229071) (xy 296.804716 -19.227034)
			(xy 296.749873 -19.216904) (xy 296.697089 -19.198897) (xy 296.647489 -19.173396) (xy 296.602131 -19.140945)
			(xy 296.561982 -19.102236) (xy 296.527896 -19.058093) (xy 296.5006 -19.009458) (xy 296.480677 -18.957367)
			(xy 296.468551 -18.90293) (xy 296.46448 -18.847308) (xy 293.89183 -18.847308) (xy 293.889437 -18.863568)
			(xy 293.873369 -18.916975) (xy 293.849697 -18.967472) (xy 293.818924 -19.013985) (xy 293.781707 -19.055522)
			(xy 293.738839 -19.091197) (xy 293.691233 -19.120251) (xy 293.639904 -19.142063) (xy 293.585947 -19.156169)
			(xy 293.53051 -19.162269) (xy 293.474776 -19.160232) (xy 293.419933 -19.150102) (xy 293.367149 -19.132095)
			(xy 293.317549 -19.106594) (xy 293.272191 -19.074143) (xy 293.232042 -19.035434) (xy 293.197956 -18.991291)
			(xy 293.17066 -18.942656) (xy 293.150737 -18.890565) (xy 293.138611 -18.836128) (xy 293.13454 -18.780506)
			(xy 292.801741 -18.780506) (xy 292.771684 -18.799581) (xy 292.713845 -18.826798) (xy 292.653052 -18.846551)
			(xy 292.590262 -18.858529) (xy 292.526466 -18.862543) (xy 292.46267 -18.858529) (xy 292.39988 -18.846551)
			(xy 292.339087 -18.826798) (xy 292.281248 -18.799581) (xy 292.227277 -18.76533) (xy 292.178024 -18.724585)
			(xy 292.134267 -18.677988) (xy 292.096694 -18.626273) (xy 292.0659 -18.570258) (xy 292.042368 -18.510825)
			(xy 292.026471 -18.448911) (xy 292.01846 -18.385493) (xy 292.017958 -18.353532) (xy 292.018379 -18.323762)
			(xy 292.025325 -18.264627) (xy 292.039124 -18.206708) (xy 292.059589 -18.150795) (xy 292.086439 -18.097652)
			(xy 292.10254 -18.072608) (xy 292.104826 -18.069052) (xy 292.10716 -18.064655) (xy 292.110228 -18.055186)
			(xy 292.110922 -18.050256) (xy 292.111176 -18.043398) (xy 292.110913 -18.038138) (xy 292.108481 -18.027894)
			(xy 292.10635 -18.023078) (xy 292.062662 -17.941798) (xy 292.058303 -17.934442) (xy 292.045691 -17.922911)
			(xy 292.030007 -17.916123) (xy 292.021514 -17.915128) (xy 290.94303 -17.915128) (xy 290.936114 -17.914776)
			(xy 290.924133 -17.907864) (xy 290.917223 -17.895882) (xy 290.916868 -17.888966) (xy 290.916868 -13.69822)
			(xy 290.916451 -13.688198) (xy 290.908784 -13.66968) (xy 290.89461 -13.655509) (xy 290.87609 -13.647846)
			(xy 290.866068 -13.64742) (xy 290.666678 -13.64742) (xy 290.662106 -13.647674) (xy 290.660074 -13.647928)
			(xy 290.648383 -13.650351) (xy 290.628923 -13.664132) (xy 290.622736 -13.674344) (xy 290.621974 -13.675868)
			(xy 290.621974 -13.676122) (xy 290.609872 -13.699896) (xy 290.58006 -13.744132) (xy 290.544381 -13.78379)
			(xy 290.503532 -13.818097) (xy 290.458306 -13.846386) (xy 290.409584 -13.868108) (xy 290.358314 -13.882838)
			(xy 290.305492 -13.890292) (xy 290.27882 -13.890752) (xy 290.250785 -13.890259) (xy 290.19532 -13.882056)
			(xy 290.141652 -13.865824) (xy 290.090937 -13.841913) (xy 290.044267 -13.810837) (xy 290.002648 -13.773266)
			(xy 289.966976 -13.730008) (xy 289.938018 -13.681996) (xy 289.926776 -13.65631) (xy 289.922966 -13.647166)
			(xy 289.783012 -13.507212) (xy 289.780161 -13.504507) (xy 289.773782 -13.499914) (xy 289.770312 -13.498068)
			(xy 289.764884 -13.495491) (xy 289.753204 -13.492679) (xy 289.747198 -13.49248) (xy 278.397462 -13.49248)
			(xy 278.391452 -13.492646) (xy 278.379768 -13.495466) (xy 278.374348 -13.498068) (xy 278.370874 -13.499908)
			(xy 278.364497 -13.504503) (xy 278.361648 -13.507212) (xy 277.408429 -14.460431) (xy 285.19983 -14.460431)
			(xy 285.19983 -14.396509) (xy 285.207841 -14.333091) (xy 285.223738 -14.271177) (xy 285.24727 -14.211744)
			(xy 285.278064 -14.155729) (xy 285.315637 -14.104014) (xy 285.359394 -14.057417) (xy 285.408647 -14.016672)
			(xy 285.462618 -13.982421) (xy 285.520457 -13.955204) (xy 285.58125 -13.935451) (xy 285.64404 -13.923473)
			(xy 285.707836 -13.91946) (xy 285.771632 -13.923473) (xy 285.834422 -13.935451) (xy 285.895215 -13.955204)
			(xy 285.953054 -13.982421) (xy 286.007025 -14.016672) (xy 286.056278 -14.057417) (xy 286.100035 -14.104014)
			(xy 286.137608 -14.155729) (xy 286.168402 -14.211744) (xy 286.191934 -14.271177) (xy 286.207831 -14.333091)
			(xy 286.215842 -14.396509) (xy 286.216344 -14.42847) (xy 286.215842 -14.460431) (xy 286.207831 -14.523849)
			(xy 286.191934 -14.585763) (xy 286.168402 -14.645196) (xy 286.137608 -14.701211) (xy 286.100035 -14.752926)
			(xy 286.056278 -14.799523) (xy 286.007025 -14.840268) (xy 285.953054 -14.874519) (xy 285.895215 -14.901736)
			(xy 285.834422 -14.921489) (xy 285.771632 -14.933467) (xy 285.707836 -14.937481) (xy 285.64404 -14.933467)
			(xy 285.58125 -14.921489) (xy 285.520457 -14.901736) (xy 285.462618 -14.874519) (xy 285.408647 -14.840268)
			(xy 285.359394 -14.799523) (xy 285.315637 -14.752926) (xy 285.278064 -14.701211) (xy 285.24727 -14.645196)
			(xy 285.223738 -14.585763) (xy 285.207841 -14.523849) (xy 285.19983 -14.460431) (xy 277.408429 -14.460431)
			(xy 276.392429 -15.476431) (xy 285.725102 -15.476431) (xy 285.725102 -15.412509) (xy 285.733113 -15.349091)
			(xy 285.74901 -15.287177) (xy 285.772542 -15.227744) (xy 285.803336 -15.171729) (xy 285.840909 -15.120014)
			(xy 285.884666 -15.073417) (xy 285.933919 -15.032672) (xy 285.98789 -14.998421) (xy 286.045729 -14.971204)
			(xy 286.106522 -14.951451) (xy 286.169312 -14.939473) (xy 286.233108 -14.93546) (xy 286.296904 -14.939473)
			(xy 286.359694 -14.951451) (xy 286.420487 -14.971204) (xy 286.478326 -14.998421) (xy 286.532297 -15.032672)
			(xy 286.58155 -15.073417) (xy 286.625307 -15.120014) (xy 286.66288 -15.171729) (xy 286.693674 -15.227744)
			(xy 286.717206 -15.287177) (xy 286.733103 -15.349091) (xy 286.741114 -15.412509) (xy 286.741616 -15.44447)
			(xy 286.741114 -15.476431) (xy 286.733103 -15.539849) (xy 286.717206 -15.601763) (xy 286.693674 -15.661196)
			(xy 286.66288 -15.717211) (xy 286.625307 -15.768926) (xy 286.58155 -15.815523) (xy 286.532297 -15.856268)
			(xy 286.478326 -15.890519) (xy 286.420487 -15.917736) (xy 286.359694 -15.937489) (xy 286.296904 -15.949467)
			(xy 286.233108 -15.953481) (xy 286.169312 -15.949467) (xy 286.106522 -15.937489) (xy 286.045729 -15.917736)
			(xy 285.98789 -15.890519) (xy 285.933919 -15.856268) (xy 285.884666 -15.815523) (xy 285.840909 -15.768926)
			(xy 285.803336 -15.717211) (xy 285.772542 -15.661196) (xy 285.74901 -15.601763) (xy 285.733113 -15.539849)
			(xy 285.725102 -15.476431) (xy 276.392429 -15.476431) (xy 275.787655 -16.081205) (xy 289.59657 -16.081205)
			(xy 289.59657 -16.017283) (xy 289.604581 -15.953865) (xy 289.620478 -15.891951) (xy 289.64401 -15.832518)
			(xy 289.674804 -15.776503) (xy 289.712377 -15.724788) (xy 289.756134 -15.678191) (xy 289.805387 -15.637446)
			(xy 289.859358 -15.603195) (xy 289.917197 -15.575978) (xy 289.97799 -15.556225) (xy 290.04078 -15.544247)
			(xy 290.104576 -15.540234) (xy 290.168372 -15.544247) (xy 290.231162 -15.556225) (xy 290.291955 -15.575978)
			(xy 290.349794 -15.603195) (xy 290.403765 -15.637446) (xy 290.453018 -15.678191) (xy 290.496775 -15.724788)
			(xy 290.534348 -15.776503) (xy 290.565142 -15.832518) (xy 290.588674 -15.891951) (xy 290.604571 -15.953865)
			(xy 290.612582 -16.017283) (xy 290.613084 -16.049244) (xy 290.612582 -16.081205) (xy 290.604571 -16.144623)
			(xy 290.588674 -16.206537) (xy 290.565142 -16.26597) (xy 290.534348 -16.321985) (xy 290.496775 -16.3737)
			(xy 290.453018 -16.420297) (xy 290.403765 -16.461042) (xy 290.349794 -16.495293) (xy 290.291955 -16.52251)
			(xy 290.231162 -16.542263) (xy 290.168372 -16.554241) (xy 290.104576 -16.558255) (xy 290.04078 -16.554241)
			(xy 289.97799 -16.542263) (xy 289.917197 -16.52251) (xy 289.859358 -16.495293) (xy 289.805387 -16.461042)
			(xy 289.756134 -16.420297) (xy 289.712377 -16.3737) (xy 289.674804 -16.321985) (xy 289.64401 -16.26597)
			(xy 289.620478 -16.206537) (xy 289.604581 -16.144623) (xy 289.59657 -16.081205) (xy 275.787655 -16.081205)
			(xy 275.109432 -16.759428) (xy 275.106728 -16.76228) (xy 275.102138 -16.76866) (xy 275.100288 -16.772128)
			(xy 275.097704 -16.777555) (xy 275.094877 -16.789234) (xy 275.0947 -16.795242) (xy 275.0947 -19.015413)
			(xy 289.723316 -19.015413) (xy 289.723316 -18.951491) (xy 289.731327 -18.888073) (xy 289.747224 -18.826159)
			(xy 289.770756 -18.766726) (xy 289.80155 -18.710711) (xy 289.839123 -18.658996) (xy 289.88288 -18.612399)
			(xy 289.932133 -18.571654) (xy 289.986104 -18.537403) (xy 290.043943 -18.510186) (xy 290.104736 -18.490433)
			(xy 290.167526 -18.478455) (xy 290.231322 -18.474442) (xy 290.295118 -18.478455) (xy 290.357908 -18.490433)
			(xy 290.418701 -18.510186) (xy 290.47654 -18.537403) (xy 290.530511 -18.571654) (xy 290.579764 -18.612399)
			(xy 290.623521 -18.658996) (xy 290.661094 -18.710711) (xy 290.691888 -18.766726) (xy 290.71542 -18.826159)
			(xy 290.731317 -18.888073) (xy 290.739328 -18.951491) (xy 290.73983 -18.983452) (xy 290.739328 -19.015413)
			(xy 290.731317 -19.078831) (xy 290.71542 -19.140745) (xy 290.691888 -19.200178) (xy 290.661094 -19.256193)
			(xy 290.623521 -19.307908) (xy 290.579764 -19.354505) (xy 290.530511 -19.39525) (xy 290.47654 -19.429501)
			(xy 290.418701 -19.456718) (xy 290.357908 -19.476471) (xy 290.295118 -19.488449) (xy 290.231322 -19.492463)
			(xy 290.167526 -19.488449) (xy 290.104736 -19.476471) (xy 290.043943 -19.456718) (xy 289.986104 -19.429501)
			(xy 289.932133 -19.39525) (xy 289.88288 -19.354505) (xy 289.839123 -19.307908) (xy 289.80155 -19.256193)
			(xy 289.770756 -19.200178) (xy 289.747224 -19.140745) (xy 289.731327 -19.078831) (xy 289.723316 -19.015413)
			(xy 275.0947 -19.015413) (xy 275.0947 -19.73199) (xy 300.189898 -19.73199) (xy 300.193969 -19.676368)
			(xy 300.206095 -19.621931) (xy 300.226018 -19.56984) (xy 300.253314 -19.521205) (xy 300.2874 -19.477062)
			(xy 300.327549 -19.438353) (xy 300.372907 -19.405902) (xy 300.422507 -19.380401) (xy 300.475291 -19.362394)
			(xy 300.530134 -19.352264) (xy 300.585868 -19.350227) (xy 300.641305 -19.356327) (xy 300.695262 -19.370433)
			(xy 300.746591 -19.392245) (xy 300.794197 -19.421299) (xy 300.837065 -19.456974) (xy 300.874282 -19.498511)
			(xy 300.905055 -19.545024) (xy 300.928727 -19.595521) (xy 300.944795 -19.648928) (xy 300.952915 -19.704104)
			(xy 300.953424 -19.73199) (xy 300.952915 -19.759876) (xy 300.944795 -19.815052) (xy 300.928727 -19.868459)
			(xy 300.905055 -19.918956) (xy 300.874282 -19.965469) (xy 300.837065 -20.007006) (xy 300.794197 -20.042681)
			(xy 300.746591 -20.071735) (xy 300.695262 -20.093547) (xy 300.641305 -20.107653) (xy 300.585868 -20.113753)
			(xy 300.530134 -20.111716) (xy 300.475291 -20.101586) (xy 300.422507 -20.083579) (xy 300.372907 -20.058078)
			(xy 300.327549 -20.025627) (xy 300.2874 -19.986918) (xy 300.253314 -19.942775) (xy 300.226018 -19.89414)
			(xy 300.206095 -19.842049) (xy 300.193969 -19.787612) (xy 300.189898 -19.73199) (xy 275.0947 -19.73199)
			(xy 275.0947 -20.36191) (xy 301.48987 -20.36191) (xy 301.493941 -20.306288) (xy 301.506067 -20.251851)
			(xy 301.52599 -20.19976) (xy 301.553286 -20.151125) (xy 301.587372 -20.106982) (xy 301.627521 -20.068273)
			(xy 301.672879 -20.035822) (xy 301.722479 -20.010321) (xy 301.775263 -19.992314) (xy 301.830106 -19.982184)
			(xy 301.88584 -19.980147) (xy 301.941277 -19.986247) (xy 301.995234 -20.000353) (xy 302.046563 -20.022165)
			(xy 302.094169 -20.051219) (xy 302.137037 -20.086894) (xy 302.174254 -20.128431) (xy 302.205027 -20.174944)
			(xy 302.228699 -20.225441) (xy 302.242399 -20.270978) (xy 331.013052 -20.270978) (xy 331.017123 -20.215356)
			(xy 331.029249 -20.160919) (xy 331.049172 -20.108828) (xy 331.076468 -20.060193) (xy 331.110554 -20.01605)
			(xy 331.150703 -19.977341) (xy 331.196061 -19.94489) (xy 331.245661 -19.919389) (xy 331.298445 -19.901382)
			(xy 331.353288 -19.891252) (xy 331.409022 -19.889215) (xy 331.464459 -19.895315) (xy 331.518416 -19.909421)
			(xy 331.569745 -19.931233) (xy 331.617351 -19.960287) (xy 331.660219 -19.995962) (xy 331.697436 -20.037499)
			(xy 331.728209 -20.084012) (xy 331.751881 -20.134509) (xy 331.767949 -20.187916) (xy 331.776069 -20.243092)
			(xy 331.776578 -20.270978) (xy 331.776069 -20.298864) (xy 331.767949 -20.35404) (xy 331.752284 -20.406106)
			(xy 368.506756 -20.406106) (xy 368.507244 -20.362074) (xy 368.514917 -20.274345) (xy 368.530207 -20.187619)
			(xy 368.552995 -20.102555) (xy 368.58311 -20.0198) (xy 368.620321 -19.939984) (xy 368.664346 -19.863715)
			(xy 368.71485 -19.791572) (xy 368.771449 -19.724104) (xy 368.833711 -19.661826) (xy 368.901164 -19.60521)
			(xy 368.973294 -19.554687) (xy 369.049552 -19.510642) (xy 369.129358 -19.47341) (xy 369.212105 -19.443274)
			(xy 369.297163 -19.420463) (xy 369.383885 -19.405152) (xy 369.471612 -19.397455) (xy 369.515644 -19.396964)
			(xy 369.560233 -19.397442) (xy 369.649072 -19.405219) (xy 369.736895 -19.420711) (xy 369.823033 -19.443798)
			(xy 369.906831 -19.474305) (xy 369.987651 -19.512001) (xy 370.064878 -19.556597) (xy 370.137923 -19.607756)
			(xy 370.206232 -19.665086) (xy 370.269283 -19.728153) (xy 370.326597 -19.796475) (xy 370.377737 -19.869533)
			(xy 370.422315 -19.946771) (xy 370.444246 -19.993821) (xy 372.028968 -19.993821) (xy 372.028968 -19.929899)
			(xy 372.036979 -19.866481) (xy 372.052876 -19.804567) (xy 372.076408 -19.745134) (xy 372.107202 -19.689119)
			(xy 372.144775 -19.637404) (xy 372.188532 -19.590807) (xy 372.237785 -19.550062) (xy 372.291756 -19.515811)
			(xy 372.349595 -19.488594) (xy 372.410388 -19.468841) (xy 372.473178 -19.456863) (xy 372.536974 -19.45285)
			(xy 372.60077 -19.456863) (xy 372.66356 -19.468841) (xy 372.724353 -19.488594) (xy 372.782192 -19.515811)
			(xy 372.836163 -19.550062) (xy 372.885416 -19.590807) (xy 372.929173 -19.637404) (xy 372.966746 -19.689119)
			(xy 372.99754 -19.745134) (xy 373.021072 -19.804567) (xy 373.036969 -19.866481) (xy 373.04498 -19.929899)
			(xy 373.045482 -19.96186) (xy 373.04498 -19.993821) (xy 373.036969 -20.057239) (xy 373.021072 -20.119153)
			(xy 372.99754 -20.178586) (xy 372.966746 -20.234601) (xy 372.929173 -20.286316) (xy 372.885416 -20.332913)
			(xy 372.836163 -20.373658) (xy 372.782192 -20.407909) (xy 372.724353 -20.435126) (xy 372.66356 -20.454879)
			(xy 372.60077 -20.466857) (xy 372.536974 -20.470871) (xy 372.473178 -20.466857) (xy 372.410388 -20.454879)
			(xy 372.349595 -20.435126) (xy 372.291756 -20.407909) (xy 372.237785 -20.373658) (xy 372.188532 -20.332913)
			(xy 372.144775 -20.286316) (xy 372.107202 -20.234601) (xy 372.076408 -20.178586) (xy 372.052876 -20.119153)
			(xy 372.036979 -20.057239) (xy 372.028968 -19.993821) (xy 370.444246 -19.993821) (xy 370.459991 -20.0276)
			(xy 370.490478 -20.111405) (xy 370.513544 -20.197549) (xy 370.529013 -20.285376) (xy 370.536768 -20.374217)
			(xy 370.537232 -20.418806) (xy 370.536747 -20.463028) (xy 370.528922 -20.551126) (xy 370.513317 -20.638183)
			(xy 370.490054 -20.723514) (xy 370.459317 -20.806445) (xy 370.421348 -20.886325) (xy 370.376445 -20.962524)
			(xy 370.324963 -21.034441) (xy 370.267308 -21.10151) (xy 370.203932 -21.163203) (xy 370.135337 -21.219034)
			(xy 370.062061 -21.268563) (xy 369.984682 -21.311399) (xy 369.90381 -21.347206) (xy 369.8621 -21.361908)
			(xy 369.852758 -21.365511) (xy 369.837719 -21.378707) (xy 369.828877 -21.396656) (xy 369.82781 -21.406612)
			(xy 369.82019 -21.515324) (xy 369.83543 -21.541994) (xy 369.849146 -21.548852) (xy 369.882051 -21.565894)
			(xy 369.944607 -21.605626) (xy 370.00286 -21.651434) (xy 370.056224 -21.702856) (xy 370.10416 -21.759371)
			(xy 370.146183 -21.820411) (xy 370.181871 -21.885359) (xy 370.210863 -21.95356) (xy 370.232865 -22.024325)
			(xy 370.247658 -22.096941) (xy 370.25509 -22.170674) (xy 370.255546 -22.207728) (xy 370.255041 -22.246332)
			(xy 370.246971 -22.323116) (xy 370.230918 -22.398637) (xy 370.20706 -22.472065) (xy 370.175657 -22.542598)
			(xy 370.137053 -22.609461) (xy 370.091672 -22.671924) (xy 370.04001 -22.7293) (xy 369.982634 -22.780962)
			(xy 369.920171 -22.826343) (xy 369.853308 -22.864947) (xy 369.782775 -22.89635) (xy 369.709347 -22.920208)
			(xy 369.633826 -22.936261) (xy 369.557042 -22.944331) (xy 369.479834 -22.944331) (xy 369.40305 -22.936261)
			(xy 369.327529 -22.920208) (xy 369.254101 -22.89635) (xy 369.183568 -22.864947) (xy 369.116705 -22.826343)
			(xy 369.054242 -22.780962) (xy 368.996866 -22.7293) (xy 368.945204 -22.671924) (xy 368.899823 -22.609461)
			(xy 368.861219 -22.542598) (xy 368.829816 -22.472065) (xy 368.805958 -22.398637) (xy 368.789905 -22.323116)
			(xy 368.781835 -22.246332) (xy 368.78133 -22.207728) (xy 368.781775 -22.170355) (xy 368.789337 -22.095992)
			(xy 368.804387 -22.022777) (xy 368.826769 -21.95146) (xy 368.856255 -21.882775) (xy 368.892541 -21.817428)
			(xy 368.935255 -21.756088) (xy 368.983957 -21.699386) (xy 369.038149 -21.647905) (xy 369.097272 -21.602173)
			(xy 369.160721 -21.56266) (xy 369.19408 -21.545804) (xy 369.194334 -21.545804) (xy 369.203124 -21.54101)
			(xy 369.216337 -21.525988) (xy 369.222771 -21.507045) (xy 369.222528 -21.497036) (xy 369.21694 -21.403564)
			(xy 369.215853 -21.393618) (xy 369.207112 -21.375643) (xy 369.19218 -21.362357) (xy 369.182904 -21.358606)
			(xy 369.141045 -21.343504) (xy 369.059945 -21.306857) (xy 368.982387 -21.263211) (xy 368.908975 -21.212903)
			(xy 368.840279 -21.156326) (xy 368.776832 -21.093918) (xy 368.719128 -21.026165) (xy 368.667615 -20.953594)
			(xy 368.622693 -20.876768) (xy 368.584712 -20.796284) (xy 368.553967 -20.712768) (xy 368.530696 -20.626868)
			(xy 368.515081 -20.539253) (xy 368.507243 -20.450604) (xy 368.506756 -20.406106) (xy 331.752284 -20.406106)
			(xy 331.751881 -20.407447) (xy 331.728209 -20.457944) (xy 331.697436 -20.504457) (xy 331.660219 -20.545994)
			(xy 331.617351 -20.581669) (xy 331.569745 -20.610723) (xy 331.518416 -20.632535) (xy 331.464459 -20.646641)
			(xy 331.409022 -20.652741) (xy 331.353288 -20.650704) (xy 331.298445 -20.640574) (xy 331.245661 -20.622567)
			(xy 331.196061 -20.597066) (xy 331.150703 -20.564615) (xy 331.110554 -20.525906) (xy 331.076468 -20.481763)
			(xy 331.049172 -20.433128) (xy 331.029249 -20.381037) (xy 331.017123 -20.3266) (xy 331.013052 -20.270978)
			(xy 302.242399 -20.270978) (xy 302.244767 -20.278848) (xy 302.252887 -20.334024) (xy 302.253396 -20.36191)
			(xy 302.252887 -20.389796) (xy 302.244767 -20.444972) (xy 302.228699 -20.498379) (xy 302.205027 -20.548876)
			(xy 302.174254 -20.595389) (xy 302.137037 -20.636926) (xy 302.094169 -20.672601) (xy 302.046563 -20.701655)
			(xy 301.995234 -20.723467) (xy 301.941277 -20.737573) (xy 301.88584 -20.743673) (xy 301.830106 -20.741636)
			(xy 301.775263 -20.731506) (xy 301.722479 -20.713499) (xy 301.672879 -20.687998) (xy 301.627521 -20.655547)
			(xy 301.587372 -20.616838) (xy 301.553286 -20.572695) (xy 301.52599 -20.52406) (xy 301.506067 -20.471969)
			(xy 301.493941 -20.417532) (xy 301.48987 -20.36191) (xy 275.0947 -20.36191) (xy 275.0947 -22.044152)
			(xy 298.56938 -22.044152) (xy 298.569866 -22.016901) (xy 298.577622 -21.962953) (xy 298.592977 -21.910658)
			(xy 298.615619 -21.861081) (xy 298.645085 -21.815231) (xy 298.680776 -21.77404) (xy 298.721967 -21.738349)
			(xy 298.767817 -21.708883) (xy 298.817394 -21.686241) (xy 298.869689 -21.670886) (xy 298.923637 -21.66313)
			(xy 298.978139 -21.66313) (xy 299.032087 -21.670886) (xy 299.084382 -21.686241) (xy 299.133959 -21.708883)
			(xy 299.179809 -21.738349) (xy 299.221 -21.77404) (xy 299.256691 -21.815231) (xy 299.286157 -21.861081)
			(xy 299.308799 -21.910658) (xy 299.324154 -21.962953) (xy 299.33191 -22.016901) (xy 299.332396 -22.044152)
			(xy 299.331981 -22.06957) (xy 299.325225 -22.119956) (xy 299.322552 -22.12975) (xy 302.255934 -22.12975)
			(xy 302.260005 -22.074128) (xy 302.272131 -22.019691) (xy 302.292054 -21.9676) (xy 302.31935 -21.918965)
			(xy 302.353436 -21.874822) (xy 302.393585 -21.836113) (xy 302.438943 -21.803662) (xy 302.488543 -21.778161)
			(xy 302.541327 -21.760154) (xy 302.59617 -21.750024) (xy 302.651904 -21.747987) (xy 302.707341 -21.754087)
			(xy 302.761298 -21.768193) (xy 302.812627 -21.790005) (xy 302.860233 -21.819059) (xy 302.903101 -21.854734)
			(xy 302.940318 -21.896271) (xy 302.971091 -21.942784) (xy 302.994763 -21.993281) (xy 303.010831 -22.046688)
			(xy 303.018951 -22.101864) (xy 303.01946 -22.12975) (xy 303.018951 -22.157636) (xy 303.010831 -22.212812)
			(xy 302.994763 -22.266219) (xy 302.983308 -22.290654) (xy 305.107532 -22.290654) (xy 305.107532 -22.236146)
			(xy 305.115289 -22.182192) (xy 305.130646 -22.129891) (xy 305.153289 -22.080309) (xy 305.182759 -22.034453)
			(xy 305.218454 -21.993258) (xy 305.259648 -21.957562) (xy 305.305503 -21.928092) (xy 305.355086 -21.905448)
			(xy 305.407386 -21.89009) (xy 305.46134 -21.882332) (xy 305.488594 -21.881846) (xy 305.51424 -21.882245)
			(xy 305.565067 -21.889132) (xy 305.614512 -21.902769) (xy 305.661683 -21.922911) (xy 305.68392 -21.935694)
			(xy 305.693711 -21.940853) (xy 305.715707 -21.943089) (xy 305.726338 -21.940012) (xy 305.81092 -21.910548)
			(xy 305.826668 -21.895054) (xy 305.830732 -21.884386) (xy 305.842064 -21.855859) (xy 305.870687 -21.801557)
			(xy 305.905636 -21.751093) (xy 305.946403 -21.705201) (xy 305.992397 -21.664548) (xy 306.042949 -21.629726)
			(xy 306.097323 -21.60124) (xy 306.15473 -21.579504) (xy 306.214336 -21.564834) (xy 306.275274 -21.557443)
			(xy 306.305966 -21.55698) (xy 306.337929 -21.557483) (xy 306.401351 -21.565491) (xy 306.46327 -21.581385)
			(xy 306.522708 -21.604915) (xy 306.578728 -21.635709) (xy 306.599662 -21.650917) (xy 323.591168 -21.650917)
			(xy 323.591168 -21.586995) (xy 323.599179 -21.523577) (xy 323.615076 -21.461663) (xy 323.638608 -21.40223)
			(xy 323.669402 -21.346215) (xy 323.706975 -21.2945) (xy 323.750732 -21.247903) (xy 323.799985 -21.207158)
			(xy 323.853956 -21.172907) (xy 323.911795 -21.14569) (xy 323.972588 -21.125937) (xy 324.035378 -21.113959)
			(xy 324.099174 -21.109946) (xy 324.16297 -21.113959) (xy 324.22576 -21.125937) (xy 324.286553 -21.14569)
			(xy 324.344392 -21.172907) (xy 324.398363 -21.207158) (xy 324.447616 -21.247903) (xy 324.491373 -21.2945)
			(xy 324.528946 -21.346215) (xy 324.55974 -21.40223) (xy 324.583272 -21.461663) (xy 324.599169 -21.523577)
			(xy 324.60718 -21.586995) (xy 324.607682 -21.618956) (xy 324.60718 -21.650917) (xy 324.603388 -21.680932)
			(xy 341.237314 -21.680932) (xy 341.241385 -21.62531) (xy 341.253511 -21.570873) (xy 341.273434 -21.518782)
			(xy 341.30073 -21.470147) (xy 341.334816 -21.426004) (xy 341.374965 -21.387295) (xy 341.420323 -21.354844)
			(xy 341.469923 -21.329343) (xy 341.522707 -21.311336) (xy 341.57755 -21.301206) (xy 341.633284 -21.299169)
			(xy 341.688721 -21.305269) (xy 341.742678 -21.319375) (xy 341.794007 -21.341187) (xy 341.841613 -21.370241)
			(xy 341.884481 -21.405916) (xy 341.921698 -21.447453) (xy 341.952471 -21.493966) (xy 341.976143 -21.544463)
			(xy 341.992211 -21.59787) (xy 342.000331 -21.653046) (xy 342.000682 -21.672296) (xy 344.262454 -21.672296)
			(xy 344.266525 -21.616674) (xy 344.278651 -21.562237) (xy 344.298574 -21.510146) (xy 344.32587 -21.461511)
			(xy 344.359956 -21.417368) (xy 344.400105 -21.378659) (xy 344.445463 -21.346208) (xy 344.495063 -21.320707)
			(xy 344.547847 -21.3027) (xy 344.60269 -21.29257) (xy 344.658424 -21.290533) (xy 344.713861 -21.296633)
			(xy 344.767818 -21.310739) (xy 344.819147 -21.332551) (xy 344.866753 -21.361605) (xy 344.909621 -21.39728)
			(xy 344.946838 -21.438817) (xy 344.977611 -21.48533) (xy 345.001283 -21.535827) (xy 345.017351 -21.589234)
			(xy 345.025471 -21.64441) (xy 345.02598 -21.672296) (xy 345.025471 -21.700182) (xy 345.017351 -21.755358)
			(xy 345.001283 -21.808765) (xy 344.977611 -21.859262) (xy 344.946838 -21.905775) (xy 344.909621 -21.947312)
			(xy 344.866753 -21.982987) (xy 344.819147 -22.012041) (xy 344.767818 -22.033853) (xy 344.713861 -22.047959)
			(xy 344.658424 -22.054059) (xy 344.60269 -22.052022) (xy 344.547847 -22.041892) (xy 344.495063 -22.023885)
			(xy 344.445463 -21.998384) (xy 344.400105 -21.965933) (xy 344.359956 -21.927224) (xy 344.32587 -21.883081)
			(xy 344.298574 -21.834446) (xy 344.278651 -21.782355) (xy 344.266525 -21.727918) (xy 344.262454 -21.672296)
			(xy 342.000682 -21.672296) (xy 342.00084 -21.680932) (xy 342.000331 -21.708818) (xy 341.992211 -21.763994)
			(xy 341.976143 -21.817401) (xy 341.952471 -21.867898) (xy 341.921698 -21.914411) (xy 341.884481 -21.955948)
			(xy 341.841613 -21.991623) (xy 341.794007 -22.020677) (xy 341.742678 -22.042489) (xy 341.688721 -22.056595)
			(xy 341.633284 -22.062695) (xy 341.57755 -22.060658) (xy 341.522707 -22.050528) (xy 341.469923 -22.032521)
			(xy 341.420323 -22.00702) (xy 341.374965 -21.974569) (xy 341.334816 -21.93586) (xy 341.30073 -21.891717)
			(xy 341.273434 -21.843082) (xy 341.253511 -21.790991) (xy 341.241385 -21.736554) (xy 341.237314 -21.680932)
			(xy 324.603388 -21.680932) (xy 324.599169 -21.714335) (xy 324.583272 -21.776249) (xy 324.55974 -21.835682)
			(xy 324.528946 -21.891697) (xy 324.491373 -21.943412) (xy 324.447616 -21.990009) (xy 324.398363 -22.030754)
			(xy 324.344392 -22.065005) (xy 324.286553 -22.092222) (xy 324.22576 -22.111975) (xy 324.16297 -22.123953)
			(xy 324.099174 -22.127967) (xy 324.035378 -22.123953) (xy 323.972588 -22.111975) (xy 323.911795 -22.092222)
			(xy 323.853956 -22.065005) (xy 323.799985 -22.030754) (xy 323.750732 -21.990009) (xy 323.706975 -21.943412)
			(xy 323.669402 -21.891697) (xy 323.638608 -21.835682) (xy 323.615076 -21.776249) (xy 323.599179 -21.714335)
			(xy 323.591168 -21.650917) (xy 306.599662 -21.650917) (xy 306.630447 -21.673282) (xy 306.677048 -21.71704)
			(xy 306.717797 -21.766295) (xy 306.752052 -21.820268) (xy 306.779271 -21.87811) (xy 306.799026 -21.938907)
			(xy 306.811005 -22.0017) (xy 306.81502 -22.0655) (xy 306.811005 -22.1293) (xy 306.799026 -22.192093)
			(xy 306.779271 -22.25289) (xy 306.752052 -22.310732) (xy 306.717797 -22.364705) (xy 306.677048 -22.41396)
			(xy 306.630447 -22.457718) (xy 306.578728 -22.495291) (xy 306.522708 -22.526085) (xy 306.486154 -22.540556)
			(xy 312.118145 -22.540556) (xy 312.118145 -22.486044) (xy 312.125903 -22.432088) (xy 312.141262 -22.379784)
			(xy 312.163909 -22.3302) (xy 312.193382 -22.284343) (xy 312.229082 -22.243148) (xy 312.270282 -22.207453)
			(xy 312.316142 -22.177986) (xy 312.36573 -22.155346) (xy 312.418035 -22.139993) (xy 312.471992 -22.132242)
			(xy 312.499248 -22.131782) (xy 312.526618 -22.132259) (xy 312.580798 -22.140071) (xy 312.633301 -22.155556)
			(xy 312.683048 -22.178396) (xy 312.729015 -22.20812) (xy 312.749946 -22.225762) (xy 312.7502 -22.226016)
			(xy 312.757281 -22.23161) (xy 312.774202 -22.237852) (xy 312.78322 -22.238208) (xy 312.850276 -22.238208)
			(xy 312.859292 -22.237838) (xy 312.876208 -22.231599) (xy 312.883296 -22.226016) (xy 312.883296 -22.225762)
			(xy 312.88355 -22.225762) (xy 312.904485 -22.208127) (xy 312.950458 -22.178415) (xy 313.000204 -22.155579)
			(xy 313.052704 -22.140087) (xy 313.106879 -22.132257) (xy 313.134248 -22.131782) (xy 313.161496 -22.132292)
			(xy 313.215437 -22.140053) (xy 313.267725 -22.155412) (xy 313.317295 -22.178055) (xy 313.363138 -22.207522)
			(xy 313.404321 -22.243213) (xy 313.407687 -22.247098) (xy 334.8134 -22.247098) (xy 334.817471 -22.191476)
			(xy 334.829597 -22.137039) (xy 334.84952 -22.084948) (xy 334.876816 -22.036313) (xy 334.910902 -21.99217)
			(xy 334.951051 -21.953461) (xy 334.996409 -21.92101) (xy 335.046009 -21.895509) (xy 335.098793 -21.877502)
			(xy 335.153636 -21.867372) (xy 335.20937 -21.865335) (xy 335.264807 -21.871435) (xy 335.318764 -21.885541)
			(xy 335.370093 -21.907353) (xy 335.417699 -21.936407) (xy 335.460567 -21.972082) (xy 335.497784 -22.013619)
			(xy 335.528557 -22.060132) (xy 335.552229 -22.110629) (xy 335.568297 -22.164036) (xy 335.576417 -22.219212)
			(xy 335.576926 -22.247098) (xy 347.549214 -22.247098) (xy 347.553285 -22.191476) (xy 347.565411 -22.137039)
			(xy 347.585334 -22.084948) (xy 347.61263 -22.036313) (xy 347.646716 -21.99217) (xy 347.686865 -21.953461)
			(xy 347.732223 -21.92101) (xy 347.781823 -21.895509) (xy 347.834607 -21.877502) (xy 347.88945 -21.867372)
			(xy 347.945184 -21.865335) (xy 348.000621 -21.871435) (xy 348.054578 -21.885541) (xy 348.105907 -21.907353)
			(xy 348.153513 -21.936407) (xy 348.196381 -21.972082) (xy 348.233598 -22.013619) (xy 348.264371 -22.060132)
			(xy 348.288043 -22.110629) (xy 348.304111 -22.164036) (xy 348.312231 -22.219212) (xy 348.31274 -22.247098)
			(xy 348.312231 -22.274984) (xy 348.311631 -22.279059) (xy 349.423222 -22.279059) (xy 349.423222 -22.215137)
			(xy 349.431233 -22.151719) (xy 349.44713 -22.089805) (xy 349.470662 -22.030372) (xy 349.501456 -21.974357)
			(xy 349.539029 -21.922642) (xy 349.582786 -21.876045) (xy 349.632039 -21.8353) (xy 349.68601 -21.801049)
			(xy 349.743849 -21.773832) (xy 349.804642 -21.754079) (xy 349.867432 -21.742101) (xy 349.931228 -21.738088)
			(xy 349.995024 -21.742101) (xy 350.057814 -21.754079) (xy 350.118607 -21.773832) (xy 350.176446 -21.801049)
			(xy 350.230417 -21.8353) (xy 350.27967 -21.876045) (xy 350.323427 -21.922642) (xy 350.361 -21.974357)
			(xy 350.391794 -22.030372) (xy 350.415326 -22.089805) (xy 350.431223 -22.151719) (xy 350.438298 -22.207728)
			(xy 362.653837 -22.207728) (xy 362.657873 -22.124281) (xy 362.669945 -22.041613) (xy 362.689938 -21.960496)
			(xy 362.717667 -21.881687) (xy 362.752873 -21.805922) (xy 362.795227 -21.733909) (xy 362.844333 -21.66632)
			(xy 362.899734 -21.603786) (xy 362.960911 -21.546891) (xy 363.027294 -21.496165) (xy 363.098262 -21.452084)
			(xy 363.173154 -21.415058) (xy 363.25127 -21.385432) (xy 363.33188 -21.363484) (xy 363.414232 -21.349419)
			(xy 363.497558 -21.343367) (xy 363.581078 -21.345386) (xy 363.664014 -21.355456) (xy 363.74559 -21.373484)
			(xy 363.825046 -21.399301) (xy 363.901639 -21.432666) (xy 363.974655 -21.473267) (xy 364.043411 -21.520726)
			(xy 364.107265 -21.574599) (xy 364.165622 -21.634384) (xy 364.217937 -21.699521) (xy 364.26372 -21.769404)
			(xy 364.302545 -21.843379) (xy 364.33405 -21.920756) (xy 364.357939 -22.000813) (xy 364.37399 -22.082801)
			(xy 364.382053 -22.165956) (xy 364.382558 -22.207728) (xy 364.653833 -22.207728) (xy 364.657869 -22.124281)
			(xy 364.669941 -22.041613) (xy 364.689934 -21.960496) (xy 364.717663 -21.881687) (xy 364.752869 -21.805922)
			(xy 364.795223 -21.733909) (xy 364.844329 -21.66632) (xy 364.89973 -21.603786) (xy 364.960907 -21.546891)
			(xy 365.02729 -21.496165) (xy 365.098258 -21.452084) (xy 365.17315 -21.415058) (xy 365.251266 -21.385432)
			(xy 365.331876 -21.363484) (xy 365.414228 -21.349419) (xy 365.497554 -21.343367) (xy 365.581074 -21.345386)
			(xy 365.66401 -21.355456) (xy 365.745586 -21.373484) (xy 365.825042 -21.399301) (xy 365.901635 -21.432666)
			(xy 365.974651 -21.473267) (xy 366.043407 -21.520726) (xy 366.107261 -21.574599) (xy 366.165618 -21.634384)
			(xy 366.217933 -21.699521) (xy 366.263716 -21.769404) (xy 366.302541 -21.843379) (xy 366.334046 -21.920756)
			(xy 366.357935 -22.000813) (xy 366.373986 -22.082801) (xy 366.382049 -22.165956) (xy 366.382554 -22.207728)
			(xy 366.653829 -22.207728) (xy 366.657865 -22.124281) (xy 366.669937 -22.041613) (xy 366.68993 -21.960496)
			(xy 366.717659 -21.881687) (xy 366.752865 -21.805922) (xy 366.795219 -21.733909) (xy 366.844325 -21.66632)
			(xy 366.899726 -21.603786) (xy 366.960903 -21.546891) (xy 367.027286 -21.496165) (xy 367.098254 -21.452084)
			(xy 367.173146 -21.415058) (xy 367.251262 -21.385432) (xy 367.331872 -21.363484) (xy 367.414224 -21.349419)
			(xy 367.49755 -21.343367) (xy 367.58107 -21.345386) (xy 367.664006 -21.355456) (xy 367.745582 -21.373484)
			(xy 367.825038 -21.399301) (xy 367.901631 -21.432666) (xy 367.974647 -21.473267) (xy 368.043403 -21.520726)
			(xy 368.107257 -21.574599) (xy 368.165614 -21.634384) (xy 368.217929 -21.699521) (xy 368.263712 -21.769404)
			(xy 368.302537 -21.843379) (xy 368.334042 -21.920756) (xy 368.357931 -22.000813) (xy 368.373982 -22.082801)
			(xy 368.382045 -22.165956) (xy 368.38255 -22.207728) (xy 368.382045 -22.2495) (xy 368.373982 -22.332655)
			(xy 368.357931 -22.414643) (xy 368.334042 -22.4947) (xy 368.302537 -22.572077) (xy 368.263712 -22.646052)
			(xy 368.217929 -22.715935) (xy 368.165614 -22.781072) (xy 368.107257 -22.840857) (xy 368.043403 -22.89473)
			(xy 367.974647 -22.942189) (xy 367.901631 -22.98279) (xy 367.825038 -23.016155) (xy 367.745582 -23.041972)
			(xy 367.664006 -23.06) (xy 367.58107 -23.07007) (xy 367.49755 -23.072089) (xy 367.414224 -23.066037)
			(xy 367.331872 -23.051972) (xy 367.251262 -23.030024) (xy 367.173146 -23.000398) (xy 367.098254 -22.963372)
			(xy 367.027286 -22.919291) (xy 366.960903 -22.868565) (xy 366.899726 -22.81167) (xy 366.844325 -22.749136)
			(xy 366.795219 -22.681547) (xy 366.752865 -22.609534) (xy 366.717659 -22.533769) (xy 366.68993 -22.45496)
			(xy 366.669937 -22.373843) (xy 366.657865 -22.291175) (xy 366.653829 -22.207728) (xy 366.382554 -22.207728)
			(xy 366.382049 -22.2495) (xy 366.373986 -22.332655) (xy 366.357935 -22.414643) (xy 366.334046 -22.4947)
			(xy 366.302541 -22.572077) (xy 366.263716 -22.646052) (xy 366.217933 -22.715935) (xy 366.165618 -22.781072)
			(xy 366.107261 -22.840857) (xy 366.043407 -22.89473) (xy 365.974651 -22.942189) (xy 365.901635 -22.98279)
			(xy 365.825042 -23.016155) (xy 365.745586 -23.041972) (xy 365.66401 -23.06) (xy 365.581074 -23.07007)
			(xy 365.497554 -23.072089) (xy 365.414228 -23.066037) (xy 365.331876 -23.051972) (xy 365.251266 -23.030024)
			(xy 365.17315 -23.000398) (xy 365.098258 -22.963372) (xy 365.02729 -22.919291) (xy 364.960907 -22.868565)
			(xy 364.89973 -22.81167) (xy 364.844329 -22.749136) (xy 364.795223 -22.681547) (xy 364.752869 -22.609534)
			(xy 364.717663 -22.533769) (xy 364.689934 -22.45496) (xy 364.669941 -22.373843) (xy 364.657869 -22.291175)
			(xy 364.653833 -22.207728) (xy 364.382558 -22.207728) (xy 364.382053 -22.2495) (xy 364.37399 -22.332655)
			(xy 364.357939 -22.414643) (xy 364.33405 -22.4947) (xy 364.302545 -22.572077) (xy 364.26372 -22.646052)
			(xy 364.217937 -22.715935) (xy 364.165622 -22.781072) (xy 364.107265 -22.840857) (xy 364.043411 -22.89473)
			(xy 363.974655 -22.942189) (xy 363.901639 -22.98279) (xy 363.825046 -23.016155) (xy 363.74559 -23.041972)
			(xy 363.664014 -23.06) (xy 363.581078 -23.07007) (xy 363.497558 -23.072089) (xy 363.414232 -23.066037)
			(xy 363.33188 -23.051972) (xy 363.25127 -23.030024) (xy 363.173154 -23.000398) (xy 363.098262 -22.963372)
			(xy 363.027294 -22.919291) (xy 362.960911 -22.868565) (xy 362.899734 -22.81167) (xy 362.844333 -22.749136)
			(xy 362.795227 -22.681547) (xy 362.752873 -22.609534) (xy 362.717667 -22.533769) (xy 362.689938 -22.45496)
			(xy 362.669945 -22.373843) (xy 362.657873 -22.291175) (xy 362.653837 -22.207728) (xy 350.438298 -22.207728)
			(xy 350.439234 -22.215137) (xy 350.439736 -22.247098) (xy 350.439234 -22.279059) (xy 350.431223 -22.342477)
			(xy 350.415326 -22.404391) (xy 350.391794 -22.463824) (xy 350.361 -22.519839) (xy 350.323427 -22.571554)
			(xy 350.27967 -22.618151) (xy 350.230417 -22.658896) (xy 350.176446 -22.693147) (xy 350.118607 -22.720364)
			(xy 350.057814 -22.740117) (xy 349.995024 -22.752095) (xy 349.931228 -22.756109) (xy 349.867432 -22.752095)
			(xy 349.804642 -22.740117) (xy 349.743849 -22.720364) (xy 349.68601 -22.693147) (xy 349.632039 -22.658896)
			(xy 349.582786 -22.618151) (xy 349.539029 -22.571554) (xy 349.501456 -22.519839) (xy 349.470662 -22.463824)
			(xy 349.44713 -22.404391) (xy 349.431233 -22.342477) (xy 349.423222 -22.279059) (xy 348.311631 -22.279059)
			(xy 348.304111 -22.33016) (xy 348.288043 -22.383567) (xy 348.264371 -22.434064) (xy 348.233598 -22.480577)
			(xy 348.196381 -22.522114) (xy 348.153513 -22.557789) (xy 348.105907 -22.586843) (xy 348.054578 -22.608655)
			(xy 348.000621 -22.622761) (xy 347.945184 -22.628861) (xy 347.88945 -22.626824) (xy 347.834607 -22.616694)
			(xy 347.781823 -22.598687) (xy 347.732223 -22.573186) (xy 347.686865 -22.540735) (xy 347.646716 -22.502026)
			(xy 347.61263 -22.457883) (xy 347.585334 -22.409248) (xy 347.565411 -22.357157) (xy 347.553285 -22.30272)
			(xy 347.549214 -22.247098) (xy 335.576926 -22.247098) (xy 335.576417 -22.274984) (xy 335.568297 -22.33016)
			(xy 335.552229 -22.383567) (xy 335.528557 -22.434064) (xy 335.497784 -22.480577) (xy 335.460567 -22.522114)
			(xy 335.417699 -22.557789) (xy 335.370093 -22.586843) (xy 335.318764 -22.608655) (xy 335.264807 -22.622761)
			(xy 335.20937 -22.628861) (xy 335.153636 -22.626824) (xy 335.098793 -22.616694) (xy 335.046009 -22.598687)
			(xy 334.996409 -22.573186) (xy 334.951051 -22.540735) (xy 334.910902 -22.502026) (xy 334.876816 -22.457883)
			(xy 334.84952 -22.409248) (xy 334.829597 -22.357157) (xy 334.817471 -22.30272) (xy 334.8134 -22.247098)
			(xy 313.407687 -22.247098) (xy 313.440007 -22.284401) (xy 313.469468 -22.330247) (xy 313.492105 -22.37982)
			(xy 313.507457 -22.43211) (xy 313.515212 -22.486052) (xy 313.515212 -22.540548) (xy 313.507457 -22.59449)
			(xy 313.492105 -22.64678) (xy 313.469468 -22.696353) (xy 313.440007 -22.742199) (xy 313.404321 -22.783387)
			(xy 313.363138 -22.819078) (xy 313.317295 -22.848545) (xy 313.267725 -22.871188) (xy 313.215437 -22.886547)
			(xy 313.161496 -22.894308) (xy 313.134248 -22.894798) (xy 313.106879 -22.894304) (xy 313.052701 -22.886493)
			(xy 313.000198 -22.871011) (xy 312.950451 -22.848175) (xy 312.904483 -22.818456) (xy 312.88355 -22.800818)
			(xy 312.883296 -22.800564) (xy 312.876218 -22.794966) (xy 312.859294 -22.788727) (xy 312.850276 -22.788372)
			(xy 312.78322 -22.788372) (xy 312.774205 -22.788745) (xy 312.757288 -22.794982) (xy 312.7502 -22.800564)
			(xy 312.7502 -22.800818) (xy 312.749946 -22.800818) (xy 312.72901 -22.818452) (xy 312.683038 -22.848164)
			(xy 312.633291 -22.871) (xy 312.580792 -22.886493) (xy 312.526617 -22.894323) (xy 312.499248 -22.894798)
			(xy 312.471992 -22.894358) (xy 312.418035 -22.886607) (xy 312.36573 -22.871254) (xy 312.316142 -22.848614)
			(xy 312.270282 -22.819147) (xy 312.229082 -22.783452) (xy 312.193382 -22.742257) (xy 312.163909 -22.6964)
			(xy 312.141262 -22.646816) (xy 312.125903 -22.594512) (xy 312.118145 -22.540556) (xy 306.486154 -22.540556)
			(xy 306.46327 -22.549615) (xy 306.401351 -22.565509) (xy 306.337929 -22.573517) (xy 306.305966 -22.573996)
			(xy 306.274935 -22.573556) (xy 306.213333 -22.566005) (xy 306.153111 -22.551007) (xy 306.095163 -22.528786)
			(xy 306.040353 -22.499672) (xy 305.989497 -22.4641) (xy 305.966114 -22.443694) (xy 305.957732 -22.436074)
			(xy 305.936396 -22.429724) (xy 305.837082 -22.443694) (xy 305.818032 -22.45614) (xy 305.81219 -22.465538)
			(xy 305.797127 -22.48867) (xy 305.761423 -22.530767) (xy 305.720028 -22.567283) (xy 305.673806 -22.597456)
			(xy 305.62372 -22.620658) (xy 305.570815 -22.636405) (xy 305.516193 -22.644368) (xy 305.488594 -22.644862)
			(xy 305.46134 -22.644468) (xy 305.407386 -22.63671) (xy 305.355086 -22.621352) (xy 305.305503 -22.598708)
			(xy 305.259648 -22.569238) (xy 305.218454 -22.533542) (xy 305.182759 -22.492347) (xy 305.153289 -22.446491)
			(xy 305.130646 -22.396909) (xy 305.115289 -22.344608) (xy 305.107532 -22.290654) (xy 302.983308 -22.290654)
			(xy 302.971091 -22.316716) (xy 302.940318 -22.363229) (xy 302.903101 -22.404766) (xy 302.860233 -22.440441)
			(xy 302.812627 -22.469495) (xy 302.761298 -22.491307) (xy 302.707341 -22.505413) (xy 302.651904 -22.511513)
			(xy 302.59617 -22.509476) (xy 302.541327 -22.499346) (xy 302.488543 -22.481339) (xy 302.438943 -22.455838)
			(xy 302.393585 -22.423387) (xy 302.353436 -22.384678) (xy 302.31935 -22.340535) (xy 302.292054 -22.2919)
			(xy 302.272131 -22.239809) (xy 302.260005 -22.185372) (xy 302.255934 -22.12975) (xy 299.322552 -22.12975)
			(xy 299.311838 -22.168998) (xy 299.292058 -22.215828) (xy 299.266236 -22.259618) (xy 299.250862 -22.279864)
			(xy 299.244258 -22.2885) (xy 299.238924 -22.308566) (xy 299.254926 -22.404324) (xy 299.266356 -22.42185)
			(xy 299.275246 -22.427692) (xy 299.297652 -22.442893) (xy 299.338387 -22.47856) (xy 299.373668 -22.51963)
			(xy 299.402786 -22.565276) (xy 299.425155 -22.614582) (xy 299.440327 -22.666556) (xy 299.447995 -22.720153)
			(xy 299.448474 -22.747224) (xy 299.447988 -22.774475) (xy 299.440232 -22.828423) (xy 299.424877 -22.880718)
			(xy 299.402235 -22.930295) (xy 299.372769 -22.976145) (xy 299.337078 -23.017336) (xy 299.295887 -23.053027)
			(xy 299.250037 -23.082493) (xy 299.20046 -23.105135) (xy 299.148165 -23.12049) (xy 299.094217 -23.128246)
			(xy 299.039715 -23.128246) (xy 298.985767 -23.12049) (xy 298.933472 -23.105135) (xy 298.883895 -23.082493)
			(xy 298.838045 -23.053027) (xy 298.796854 -23.017336) (xy 298.761163 -22.976145) (xy 298.731697 -22.930295)
			(xy 298.709055 -22.880718) (xy 298.6937 -22.828423) (xy 298.685944 -22.774475) (xy 298.685458 -22.747224)
			(xy 298.685903 -22.721807) (xy 298.692651 -22.671422) (xy 298.70603 -22.62238) (xy 298.725803 -22.575549)
			(xy 298.75162 -22.531758) (xy 298.766992 -22.511512) (xy 298.773596 -22.502876) (xy 298.77893 -22.48281)
			(xy 298.762928 -22.387052) (xy 298.751498 -22.369526) (xy 298.742608 -22.363684) (xy 298.72018 -22.348513)
			(xy 298.679448 -22.31284) (xy 298.64417 -22.271764) (xy 298.615056 -22.226113) (xy 298.59269 -22.176802)
			(xy 298.577522 -22.124825) (xy 298.569857 -22.071225) (xy 298.56938 -22.044152) (xy 275.0947 -22.044152)
			(xy 275.0947 -23.14575) (xy 302.255934 -23.14575) (xy 302.260005 -23.090128) (xy 302.272131 -23.035691)
			(xy 302.292054 -22.9836) (xy 302.31935 -22.934965) (xy 302.353436 -22.890822) (xy 302.393585 -22.852113)
			(xy 302.438943 -22.819662) (xy 302.488543 -22.794161) (xy 302.541327 -22.776154) (xy 302.59617 -22.766024)
			(xy 302.651904 -22.763987) (xy 302.707341 -22.770087) (xy 302.761298 -22.784193) (xy 302.812627 -22.806005)
			(xy 302.860233 -22.835059) (xy 302.903101 -22.870734) (xy 302.940318 -22.912271) (xy 302.971091 -22.958784)
			(xy 302.994763 -23.009281) (xy 303.010831 -23.062688) (xy 303.018951 -23.117864) (xy 303.01946 -23.14575)
			(xy 303.018951 -23.173636) (xy 303.014794 -23.201884) (xy 308.375556 -23.201884) (xy 308.379627 -23.146262)
			(xy 308.391753 -23.091825) (xy 308.411676 -23.039734) (xy 308.438972 -22.991099) (xy 308.473058 -22.946956)
			(xy 308.513207 -22.908247) (xy 308.558565 -22.875796) (xy 308.608165 -22.850295) (xy 308.660949 -22.832288)
			(xy 308.715792 -22.822158) (xy 308.771526 -22.820121) (xy 308.826963 -22.826221) (xy 308.88092 -22.840327)
			(xy 308.932249 -22.862139) (xy 308.979855 -22.891193) (xy 309.022723 -22.926868) (xy 309.05994 -22.968405)
			(xy 309.090713 -23.014918) (xy 309.114385 -23.065415) (xy 309.130453 -23.118822) (xy 309.138573 -23.173998)
			(xy 309.139082 -23.201884) (xy 310.375552 -23.201884) (xy 310.379623 -23.146262) (xy 310.391749 -23.091825)
			(xy 310.411672 -23.039734) (xy 310.438968 -22.991099) (xy 310.473054 -22.946956) (xy 310.513203 -22.908247)
			(xy 310.558561 -22.875796) (xy 310.608161 -22.850295) (xy 310.660945 -22.832288) (xy 310.715788 -22.822158)
			(xy 310.771522 -22.820121) (xy 310.826959 -22.826221) (xy 310.880916 -22.840327) (xy 310.932245 -22.862139)
			(xy 310.979851 -22.891193) (xy 311.022719 -22.926868) (xy 311.059936 -22.968405) (xy 311.088342 -23.011341)
			(xy 318.429888 -23.011341) (xy 318.429888 -22.947419) (xy 318.437899 -22.884001) (xy 318.453796 -22.822087)
			(xy 318.477328 -22.762654) (xy 318.508122 -22.706639) (xy 318.545695 -22.654924) (xy 318.589452 -22.608327)
			(xy 318.638705 -22.567582) (xy 318.692676 -22.533331) (xy 318.750515 -22.506114) (xy 318.811308 -22.486361)
			(xy 318.874098 -22.474383) (xy 318.937894 -22.47037) (xy 319.00169 -22.474383) (xy 319.06448 -22.486361)
			(xy 319.125273 -22.506114) (xy 319.183112 -22.533331) (xy 319.237083 -22.567582) (xy 319.286336 -22.608327)
			(xy 319.330093 -22.654924) (xy 319.367666 -22.706639) (xy 319.39846 -22.762654) (xy 319.421992 -22.822087)
			(xy 319.437889 -22.884001) (xy 319.4459 -22.947419) (xy 319.446402 -22.97938) (xy 319.4459 -23.011341)
			(xy 319.437889 -23.074759) (xy 319.421992 -23.136673) (xy 319.39846 -23.196106) (xy 319.367666 -23.252121)
			(xy 319.330093 -23.303836) (xy 319.286336 -23.350433) (xy 319.237083 -23.391178) (xy 319.183112 -23.425429)
			(xy 319.125273 -23.452646) (xy 319.06448 -23.472399) (xy 319.00169 -23.484377) (xy 318.937894 -23.488391)
			(xy 318.874098 -23.484377) (xy 318.811308 -23.472399) (xy 318.750515 -23.452646) (xy 318.692676 -23.425429)
			(xy 318.638705 -23.391178) (xy 318.589452 -23.350433) (xy 318.545695 -23.303836) (xy 318.508122 -23.252121)
			(xy 318.477328 -23.196106) (xy 318.453796 -23.136673) (xy 318.437899 -23.074759) (xy 318.429888 -23.011341)
			(xy 311.088342 -23.011341) (xy 311.090709 -23.014918) (xy 311.114381 -23.065415) (xy 311.130449 -23.118822)
			(xy 311.138569 -23.173998) (xy 311.139078 -23.201884) (xy 311.138569 -23.22977) (xy 311.130449 -23.284946)
			(xy 311.114381 -23.338353) (xy 311.090709 -23.38885) (xy 311.059936 -23.435363) (xy 311.022719 -23.4769)
			(xy 310.979851 -23.512575) (xy 310.932245 -23.541629) (xy 310.880916 -23.563441) (xy 310.826959 -23.577547)
			(xy 310.771522 -23.583647) (xy 310.715788 -23.58161) (xy 310.660945 -23.57148) (xy 310.608161 -23.553473)
			(xy 310.558561 -23.527972) (xy 310.513203 -23.495521) (xy 310.473054 -23.456812) (xy 310.438968 -23.412669)
			(xy 310.411672 -23.364034) (xy 310.391749 -23.311943) (xy 310.379623 -23.257506) (xy 310.375552 -23.201884)
			(xy 309.139082 -23.201884) (xy 309.138573 -23.22977) (xy 309.130453 -23.284946) (xy 309.114385 -23.338353)
			(xy 309.090713 -23.38885) (xy 309.05994 -23.435363) (xy 309.022723 -23.4769) (xy 308.979855 -23.512575)
			(xy 308.932249 -23.541629) (xy 308.88092 -23.563441) (xy 308.826963 -23.577547) (xy 308.771526 -23.583647)
			(xy 308.715792 -23.58161) (xy 308.660949 -23.57148) (xy 308.608165 -23.553473) (xy 308.558565 -23.527972)
			(xy 308.513207 -23.495521) (xy 308.473058 -23.456812) (xy 308.438972 -23.412669) (xy 308.411676 -23.364034)
			(xy 308.391753 -23.311943) (xy 308.379627 -23.257506) (xy 308.375556 -23.201884) (xy 303.014794 -23.201884)
			(xy 303.010831 -23.228812) (xy 302.994763 -23.282219) (xy 302.971091 -23.332716) (xy 302.940318 -23.379229)
			(xy 302.903101 -23.420766) (xy 302.860233 -23.456441) (xy 302.812627 -23.485495) (xy 302.761298 -23.507307)
			(xy 302.707341 -23.521413) (xy 302.651904 -23.527513) (xy 302.59617 -23.525476) (xy 302.541327 -23.515346)
			(xy 302.488543 -23.497339) (xy 302.438943 -23.471838) (xy 302.393585 -23.439387) (xy 302.353436 -23.400678)
			(xy 302.31935 -23.356535) (xy 302.292054 -23.3079) (xy 302.272131 -23.255809) (xy 302.260005 -23.201372)
			(xy 302.255934 -23.14575) (xy 275.0947 -23.14575) (xy 275.0947 -23.763224) (xy 298.684948 -23.763224)
			(xy 298.689019 -23.707602) (xy 298.701145 -23.653165) (xy 298.721068 -23.601074) (xy 298.748364 -23.552439)
			(xy 298.78245 -23.508296) (xy 298.822599 -23.469587) (xy 298.867957 -23.437136) (xy 298.917557 -23.411635)
			(xy 298.970341 -23.393628) (xy 299.025184 -23.383498) (xy 299.080918 -23.381461) (xy 299.136355 -23.387561)
			(xy 299.190312 -23.401667) (xy 299.241641 -23.423479) (xy 299.289247 -23.452533) (xy 299.332115 -23.488208)
			(xy 299.369332 -23.529745) (xy 299.400105 -23.576258) (xy 299.423777 -23.626755) (xy 299.439845 -23.680162)
			(xy 299.447965 -23.735338) (xy 299.448474 -23.763224) (xy 299.447965 -23.79111) (xy 299.44445 -23.814997)
			(xy 300.713896 -23.814997) (xy 300.713896 -23.751075) (xy 300.721907 -23.687657) (xy 300.737804 -23.625743)
			(xy 300.761336 -23.56631) (xy 300.79213 -23.510295) (xy 300.829703 -23.45858) (xy 300.87346 -23.411983)
			(xy 300.922713 -23.371238) (xy 300.976684 -23.336987) (xy 301.034523 -23.30977) (xy 301.095316 -23.290017)
			(xy 301.158106 -23.278039) (xy 301.221902 -23.274026) (xy 301.285698 -23.278039) (xy 301.348488 -23.290017)
			(xy 301.409281 -23.30977) (xy 301.46712 -23.336987) (xy 301.521091 -23.371238) (xy 301.570344 -23.411983)
			(xy 301.614101 -23.45858) (xy 301.651674 -23.510295) (xy 301.682468 -23.56631) (xy 301.706 -23.625743)
			(xy 301.721897 -23.687657) (xy 301.729908 -23.751075) (xy 301.73041 -23.783036) (xy 301.730243 -23.793661)
			(xy 303.145946 -23.793661) (xy 303.145946 -23.729739) (xy 303.153957 -23.666321) (xy 303.169854 -23.604407)
			(xy 303.193386 -23.544974) (xy 303.22418 -23.488959) (xy 303.261753 -23.437244) (xy 303.30551 -23.390647)
			(xy 303.354763 -23.349902) (xy 303.408734 -23.315651) (xy 303.466573 -23.288434) (xy 303.527366 -23.268681)
			(xy 303.590156 -23.256703) (xy 303.653952 -23.25269) (xy 303.717748 -23.256703) (xy 303.780538 -23.268681)
			(xy 303.841331 -23.288434) (xy 303.89917 -23.315651) (xy 303.953141 -23.349902) (xy 304.002394 -23.390647)
			(xy 304.046151 -23.437244) (xy 304.083724 -23.488959) (xy 304.114518 -23.544974) (xy 304.13805 -23.604407)
			(xy 304.153947 -23.666321) (xy 304.161958 -23.729739) (xy 304.16246 -23.7617) (xy 304.161958 -23.793661)
			(xy 304.153947 -23.857079) (xy 304.13805 -23.918993) (xy 304.114518 -23.978426) (xy 304.083724 -24.034441)
			(xy 304.046151 -24.086156) (xy 304.011698 -24.122845) (xy 305.963314 -24.122845) (xy 305.963314 -24.058923)
			(xy 305.971325 -23.995505) (xy 305.987222 -23.933591) (xy 306.010754 -23.874158) (xy 306.041548 -23.818143)
			(xy 306.079121 -23.766428) (xy 306.122878 -23.719831) (xy 306.172131 -23.679086) (xy 306.226102 -23.644835)
			(xy 306.283941 -23.617618) (xy 306.344734 -23.597865) (xy 306.407524 -23.585887) (xy 306.47132 -23.581874)
			(xy 306.535116 -23.585887) (xy 306.597906 -23.597865) (xy 306.658699 -23.617618) (xy 306.716538 -23.644835)
			(xy 306.770509 -23.679086) (xy 306.819762 -23.719831) (xy 306.863519 -23.766428) (xy 306.901092 -23.818143)
			(xy 306.931886 -23.874158) (xy 306.955418 -23.933591) (xy 306.971315 -23.995505) (xy 306.979326 -24.058923)
			(xy 306.979828 -24.090884) (xy 308.375556 -24.090884) (xy 308.379627 -24.035262) (xy 308.391753 -23.980825)
			(xy 308.411676 -23.928734) (xy 308.438972 -23.880099) (xy 308.473058 -23.835956) (xy 308.513207 -23.797247)
			(xy 308.558565 -23.764796) (xy 308.608165 -23.739295) (xy 308.660949 -23.721288) (xy 308.715792 -23.711158)
			(xy 308.771526 -23.709121) (xy 308.826963 -23.715221) (xy 308.88092 -23.729327) (xy 308.932249 -23.751139)
			(xy 308.979855 -23.780193) (xy 309.022723 -23.815868) (xy 309.05994 -23.857405) (xy 309.090713 -23.903918)
			(xy 309.114385 -23.954415) (xy 309.116457 -23.961301) (xy 311.353956 -23.961301) (xy 311.353956 -23.897379)
			(xy 311.361967 -23.833961) (xy 311.377864 -23.772047) (xy 311.401396 -23.712614) (xy 311.43219 -23.656599)
			(xy 311.469763 -23.604884) (xy 311.51352 -23.558287) (xy 311.562773 -23.517542) (xy 311.616744 -23.483291)
			(xy 311.674583 -23.456074) (xy 311.735376 -23.436321) (xy 311.798166 -23.424343) (xy 311.861962 -23.42033)
			(xy 311.925758 -23.424343) (xy 311.988548 -23.436321) (xy 312.049341 -23.456074) (xy 312.10718 -23.483291)
			(xy 312.161151 -23.517542) (xy 312.210404 -23.558287) (xy 312.254161 -23.604884) (xy 312.26472 -23.619417)
			(xy 320.413882 -23.619417) (xy 320.413882 -23.555495) (xy 320.421893 -23.492077) (xy 320.43779 -23.430163)
			(xy 320.461322 -23.37073) (xy 320.492116 -23.314715) (xy 320.529689 -23.263) (xy 320.573446 -23.216403)
			(xy 320.622699 -23.175658) (xy 320.67667 -23.141407) (xy 320.734509 -23.11419) (xy 320.795302 -23.094437)
			(xy 320.858092 -23.082459) (xy 320.921888 -23.078446) (xy 320.985684 -23.082459) (xy 321.048474 -23.094437)
			(xy 321.109267 -23.11419) (xy 321.167106 -23.141407) (xy 321.221077 -23.175658) (xy 321.27033 -23.216403)
			(xy 321.314087 -23.263) (xy 321.35166 -23.314715) (xy 321.382454 -23.37073) (xy 321.405986 -23.430163)
			(xy 321.421883 -23.492077) (xy 321.429894 -23.555495) (xy 321.430189 -23.574248) (xy 329.027794 -23.574248)
			(xy 329.031823 -23.483242) (xy 329.04388 -23.392948) (xy 329.06387 -23.304073) (xy 329.091636 -23.217313)
			(xy 329.126962 -23.133346) (xy 329.16957 -23.05283) (xy 329.219128 -22.976394) (xy 329.275247 -22.904638)
			(xy 329.337488 -22.838122) (xy 329.405365 -22.777367) (xy 329.478345 -22.722849) (xy 329.555858 -22.674995)
			(xy 329.637297 -22.634178) (xy 329.722025 -22.600719) (xy 329.809379 -22.574878) (xy 329.898674 -22.55686)
			(xy 329.989212 -22.546803) (xy 330.080285 -22.544788) (xy 330.17118 -22.55083) (xy 330.261185 -22.564881)
			(xy 330.349596 -22.586832) (xy 330.435721 -22.616511) (xy 330.518886 -22.653685) (xy 330.59844 -22.698064)
			(xy 330.67376 -22.749301) (xy 330.744258 -22.806994) (xy 330.80938 -22.870691) (xy 330.868618 -22.939895)
			(xy 330.921508 -23.014064) (xy 330.967637 -23.092616) (xy 331.006642 -23.174939) (xy 331.038219 -23.260386)
			(xy 331.06212 -23.34829) (xy 331.07405 -23.41499) (xy 331.456028 -23.41499) (xy 331.460099 -23.359368)
			(xy 331.472225 -23.304931) (xy 331.492148 -23.25284) (xy 331.519444 -23.204205) (xy 331.55353 -23.160062)
			(xy 331.593679 -23.121353) (xy 331.639037 -23.088902) (xy 331.688637 -23.063401) (xy 331.741421 -23.045394)
			(xy 331.796264 -23.035264) (xy 331.851998 -23.033227) (xy 331.907435 -23.039327) (xy 331.961392 -23.053433)
			(xy 332.012721 -23.075245) (xy 332.060327 -23.104299) (xy 332.103195 -23.139974) (xy 332.140412 -23.181511)
			(xy 332.171185 -23.228024) (xy 332.194857 -23.278521) (xy 332.210925 -23.331928) (xy 332.219045 -23.387104)
			(xy 332.219554 -23.41499) (xy 332.219045 -23.442876) (xy 332.210925 -23.498052) (xy 332.194857 -23.551459)
			(xy 332.171185 -23.601956) (xy 332.140412 -23.648469) (xy 332.103195 -23.690006) (xy 332.060327 -23.725681)
			(xy 332.012721 -23.754735) (xy 331.961392 -23.776547) (xy 331.907435 -23.790653) (xy 331.851998 -23.796753)
			(xy 331.796264 -23.794716) (xy 331.741421 -23.784586) (xy 331.688637 -23.766579) (xy 331.639037 -23.741078)
			(xy 331.593679 -23.708627) (xy 331.55353 -23.669918) (xy 331.519444 -23.625775) (xy 331.492148 -23.57714)
			(xy 331.472225 -23.525049) (xy 331.460099 -23.470612) (xy 331.456028 -23.41499) (xy 331.07405 -23.41499)
			(xy 331.078159 -23.437962) (xy 331.08621 -23.5287) (xy 331.086714 -23.574248) (xy 331.08621 -23.619796)
			(xy 331.078159 -23.710534) (xy 331.06212 -23.800206) (xy 331.038219 -23.88811) (xy 331.006642 -23.973557)
			(xy 330.967637 -24.05588) (xy 330.921508 -24.134432) (xy 330.868618 -24.208601) (xy 330.80938 -24.277805)
			(xy 330.744258 -24.341502) (xy 330.67376 -24.399195) (xy 330.59844 -24.450432) (xy 330.518886 -24.494811)
			(xy 330.435721 -24.531985) (xy 330.349596 -24.561664) (xy 330.261185 -24.583615) (xy 330.17118 -24.597666)
			(xy 330.080285 -24.603708) (xy 329.989212 -24.601693) (xy 329.898674 -24.591636) (xy 329.809379 -24.573618)
			(xy 329.722025 -24.547777) (xy 329.637297 -24.514318) (xy 329.555858 -24.473501) (xy 329.478345 -24.425647)
			(xy 329.405365 -24.371129) (xy 329.337488 -24.310374) (xy 329.275247 -24.243858) (xy 329.219128 -24.172102)
			(xy 329.16957 -24.095666) (xy 329.126962 -24.01515) (xy 329.091636 -23.931183) (xy 329.06387 -23.844423)
			(xy 329.04388 -23.755548) (xy 329.031823 -23.665254) (xy 329.027794 -23.574248) (xy 321.430189 -23.574248)
			(xy 321.430396 -23.587456) (xy 321.429894 -23.619417) (xy 321.421883 -23.682835) (xy 321.405986 -23.744749)
			(xy 321.382454 -23.804182) (xy 321.35166 -23.860197) (xy 321.314087 -23.911912) (xy 321.27033 -23.958509)
			(xy 321.221077 -23.999254) (xy 321.167106 -24.033505) (xy 321.109267 -24.060722) (xy 321.048474 -24.080475)
			(xy 320.985684 -24.092453) (xy 320.921888 -24.096467) (xy 320.858092 -24.092453) (xy 320.795302 -24.080475)
			(xy 320.734509 -24.060722) (xy 320.67667 -24.033505) (xy 320.622699 -23.999254) (xy 320.573446 -23.958509)
			(xy 320.529689 -23.911912) (xy 320.492116 -23.860197) (xy 320.461322 -23.804182) (xy 320.43779 -23.744749)
			(xy 320.421893 -23.682835) (xy 320.413882 -23.619417) (xy 312.26472 -23.619417) (xy 312.291734 -23.656599)
			(xy 312.322528 -23.712614) (xy 312.34606 -23.772047) (xy 312.361957 -23.833961) (xy 312.369968 -23.897379)
			(xy 312.37047 -23.92934) (xy 312.369968 -23.961301) (xy 312.361957 -24.024719) (xy 312.34606 -24.086633)
			(xy 312.322528 -24.146066) (xy 312.291734 -24.202081) (xy 312.254161 -24.253796) (xy 312.210404 -24.300393)
			(xy 312.161151 -24.341138) (xy 312.10718 -24.375389) (xy 312.049341 -24.402606) (xy 311.988548 -24.422359)
			(xy 311.925758 -24.434337) (xy 311.861962 -24.438351) (xy 311.798166 -24.434337) (xy 311.735376 -24.422359)
			(xy 311.674583 -24.402606) (xy 311.616744 -24.375389) (xy 311.562773 -24.341138) (xy 311.51352 -24.300393)
			(xy 311.469763 -24.253796) (xy 311.43219 -24.202081) (xy 311.401396 -24.146066) (xy 311.377864 -24.086633)
			(xy 311.361967 -24.024719) (xy 311.353956 -23.961301) (xy 309.116457 -23.961301) (xy 309.130453 -24.007822)
			(xy 309.138573 -24.062998) (xy 309.139082 -24.090884) (xy 309.138573 -24.11877) (xy 309.130453 -24.173946)
			(xy 309.114385 -24.227353) (xy 309.090713 -24.27785) (xy 309.05994 -24.324363) (xy 309.022723 -24.3659)
			(xy 308.979855 -24.401575) (xy 308.932249 -24.430629) (xy 308.88092 -24.452441) (xy 308.826963 -24.466547)
			(xy 308.771526 -24.472647) (xy 308.715792 -24.47061) (xy 308.660949 -24.46048) (xy 308.608165 -24.442473)
			(xy 308.558565 -24.416972) (xy 308.513207 -24.384521) (xy 308.473058 -24.345812) (xy 308.438972 -24.301669)
			(xy 308.411676 -24.253034) (xy 308.391753 -24.200943) (xy 308.379627 -24.146506) (xy 308.375556 -24.090884)
			(xy 306.979828 -24.090884) (xy 306.979326 -24.122845) (xy 306.971315 -24.186263) (xy 306.955418 -24.248177)
			(xy 306.931886 -24.30761) (xy 306.901092 -24.363625) (xy 306.863519 -24.41534) (xy 306.819762 -24.461937)
			(xy 306.770509 -24.502682) (xy 306.716538 -24.536933) (xy 306.658699 -24.56415) (xy 306.597906 -24.583903)
			(xy 306.535116 -24.595881) (xy 306.47132 -24.599895) (xy 306.407524 -24.595881) (xy 306.344734 -24.583903)
			(xy 306.283941 -24.56415) (xy 306.226102 -24.536933) (xy 306.172131 -24.502682) (xy 306.122878 -24.461937)
			(xy 306.079121 -24.41534) (xy 306.041548 -24.363625) (xy 306.010754 -24.30761) (xy 305.987222 -24.248177)
			(xy 305.971325 -24.186263) (xy 305.963314 -24.122845) (xy 304.011698 -24.122845) (xy 304.002394 -24.132753)
			(xy 303.953141 -24.173498) (xy 303.89917 -24.207749) (xy 303.841331 -24.234966) (xy 303.780538 -24.254719)
			(xy 303.717748 -24.266697) (xy 303.653952 -24.270711) (xy 303.590156 -24.266697) (xy 303.527366 -24.254719)
			(xy 303.466573 -24.234966) (xy 303.408734 -24.207749) (xy 303.354763 -24.173498) (xy 303.30551 -24.132753)
			(xy 303.261753 -24.086156) (xy 303.22418 -24.034441) (xy 303.193386 -23.978426) (xy 303.169854 -23.918993)
			(xy 303.153957 -23.857079) (xy 303.145946 -23.793661) (xy 301.730243 -23.793661) (xy 301.729908 -23.814997)
			(xy 301.721897 -23.878415) (xy 301.706 -23.940329) (xy 301.682468 -23.999762) (xy 301.651674 -24.055777)
			(xy 301.614101 -24.107492) (xy 301.570344 -24.154089) (xy 301.521091 -24.194834) (xy 301.46712 -24.229085)
			(xy 301.409281 -24.256302) (xy 301.348488 -24.276055) (xy 301.285698 -24.288033) (xy 301.221902 -24.292047)
			(xy 301.158106 -24.288033) (xy 301.095316 -24.276055) (xy 301.034523 -24.256302) (xy 300.976684 -24.229085)
			(xy 300.922713 -24.194834) (xy 300.87346 -24.154089) (xy 300.829703 -24.107492) (xy 300.79213 -24.055777)
			(xy 300.761336 -23.999762) (xy 300.737804 -23.940329) (xy 300.721907 -23.878415) (xy 300.713896 -23.814997)
			(xy 299.44445 -23.814997) (xy 299.439845 -23.846286) (xy 299.423777 -23.899693) (xy 299.400105 -23.95019)
			(xy 299.369332 -23.996703) (xy 299.332115 -24.03824) (xy 299.289247 -24.073915) (xy 299.241641 -24.102969)
			(xy 299.190312 -24.124781) (xy 299.136355 -24.138887) (xy 299.080918 -24.144987) (xy 299.025184 -24.14295)
			(xy 298.970341 -24.13282) (xy 298.917557 -24.114813) (xy 298.867957 -24.089312) (xy 298.822599 -24.056861)
			(xy 298.78245 -24.018152) (xy 298.748364 -23.974009) (xy 298.721068 -23.925374) (xy 298.701145 -23.873283)
			(xy 298.689019 -23.818846) (xy 298.684948 -23.763224) (xy 275.0947 -23.763224) (xy 275.0947 -25.354237)
			(xy 301.901092 -25.354237) (xy 301.901092 -25.290315) (xy 301.909103 -25.226897) (xy 301.925 -25.164983)
			(xy 301.948532 -25.10555) (xy 301.979326 -25.049535) (xy 302.016899 -24.99782) (xy 302.060656 -24.951223)
			(xy 302.109909 -24.910478) (xy 302.16388 -24.876227) (xy 302.221719 -24.84901) (xy 302.282512 -24.829257)
			(xy 302.345302 -24.817279) (xy 302.409098 -24.813266) (xy 302.472894 -24.817279) (xy 302.535684 -24.829257)
			(xy 302.596477 -24.84901) (xy 302.654316 -24.876227) (xy 302.708287 -24.910478) (xy 302.750377 -24.945297)
			(xy 339.19134 -24.945297) (xy 339.19134 -24.881375) (xy 339.199351 -24.817957) (xy 339.215248 -24.756043)
			(xy 339.23878 -24.69661) (xy 339.269574 -24.640595) (xy 339.307147 -24.58888) (xy 339.350904 -24.542283)
			(xy 339.400157 -24.501538) (xy 339.454128 -24.467287) (xy 339.511967 -24.44007) (xy 339.57276 -24.420317)
			(xy 339.63555 -24.408339) (xy 339.699346 -24.404326) (xy 339.763142 -24.408339) (xy 339.825932 -24.420317)
			(xy 339.886725 -24.44007) (xy 339.944564 -24.467287) (xy 339.998535 -24.501538) (xy 340.047788 -24.542283)
			(xy 340.091545 -24.58888) (xy 340.129118 -24.640595) (xy 340.159912 -24.69661) (xy 340.183444 -24.756043)
			(xy 340.199341 -24.817957) (xy 340.207352 -24.881375) (xy 340.207519 -24.892) (xy 346.990689 -24.892)
			(xy 346.994703 -24.828205) (xy 347.00668 -24.765416) (xy 347.026433 -24.704624) (xy 347.053649 -24.646786)
			(xy 347.087899 -24.592816) (xy 347.128643 -24.543563) (xy 347.175238 -24.499806) (xy 347.226951 -24.462233)
			(xy 347.282965 -24.431438) (xy 347.342396 -24.407906) (xy 347.404309 -24.392008) (xy 347.467726 -24.383995)
			(xy 347.499686 -24.383492) (xy 347.533244 -24.38402) (xy 347.599774 -24.39287) (xy 347.664563 -24.410391)
			(xy 347.726485 -24.43628) (xy 347.784466 -24.470086) (xy 347.837497 -24.511223) (xy 347.884659 -24.558976)
			(xy 347.905324 -24.585422) (xy 347.91199 -24.593416) (xy 347.930089 -24.603651) (xy 347.940376 -24.605234)
			(xy 348.013782 -24.613616) (xy 348.024206 -24.614246) (xy 348.044136 -24.608077) (xy 348.05239 -24.601678)
			(xy 348.0732 -24.584571) (xy 348.118691 -24.555722) (xy 348.167791 -24.533567) (xy 348.219522 -24.518545)
			(xy 348.272852 -24.510958) (xy 348.299786 -24.510492) (xy 348.32704 -24.510954) (xy 348.380992 -24.51871)
			(xy 348.433291 -24.534065) (xy 348.482873 -24.556706) (xy 348.528728 -24.586174) (xy 348.569923 -24.621868)
			(xy 348.605618 -24.663061) (xy 348.635087 -24.708914) (xy 348.657731 -24.758495) (xy 348.673087 -24.810794)
			(xy 348.680845 -24.864747) (xy 348.680845 -24.919253) (xy 348.673087 -24.973206) (xy 348.657731 -25.025505)
			(xy 348.635087 -25.075086) (xy 348.605618 -25.120939) (xy 348.569923 -25.162132) (xy 348.528728 -25.197826)
			(xy 348.482873 -25.227294) (xy 348.433291 -25.249935) (xy 348.380992 -25.26529) (xy 348.32704 -25.273046)
			(xy 348.299786 -25.273508) (xy 348.272852 -25.273025) (xy 348.219521 -25.265442) (xy 348.167789 -25.250428)
			(xy 348.118684 -25.228282) (xy 348.073185 -25.199445) (xy 348.05239 -25.182322) (xy 348.044149 -25.1759)
			(xy 348.02421 -25.169733) (xy 348.013782 -25.170384) (xy 347.940376 -25.178766) (xy 347.930108 -25.18041)
			(xy 347.912017 -25.190621) (xy 347.905324 -25.198578) (xy 347.884651 -25.225019) (xy 347.837502 -25.272786)
			(xy 347.784476 -25.313933) (xy 347.726496 -25.347743) (xy 347.664572 -25.373628) (xy 347.599779 -25.391139)
			(xy 347.533245 -25.39997) (xy 347.499686 -25.400508) (xy 347.467726 -25.400005) (xy 347.404309 -25.391992)
			(xy 347.342396 -25.376094) (xy 347.282965 -25.352562) (xy 347.226951 -25.321767) (xy 347.175238 -25.284194)
			(xy 347.128643 -25.240437) (xy 347.087899 -25.191184) (xy 347.053649 -25.137214) (xy 347.026433 -25.079376)
			(xy 347.00668 -25.018584) (xy 346.994703 -24.955795) (xy 346.990689 -24.892) (xy 340.207519 -24.892)
			(xy 340.207854 -24.913336) (xy 340.207352 -24.945297) (xy 340.199341 -25.008715) (xy 340.183444 -25.070629)
			(xy 340.159912 -25.130062) (xy 340.129118 -25.186077) (xy 340.091545 -25.237792) (xy 340.047788 -25.284389)
			(xy 339.998535 -25.325134) (xy 339.944564 -25.359385) (xy 339.886725 -25.386602) (xy 339.825932 -25.406355)
			(xy 339.763142 -25.418333) (xy 339.699346 -25.422347) (xy 339.63555 -25.418333) (xy 339.57276 -25.406355)
			(xy 339.511967 -25.386602) (xy 339.454128 -25.359385) (xy 339.400157 -25.325134) (xy 339.350904 -25.284389)
			(xy 339.307147 -25.237792) (xy 339.269574 -25.186077) (xy 339.23878 -25.130062) (xy 339.215248 -25.070629)
			(xy 339.199351 -25.008715) (xy 339.19134 -24.945297) (xy 302.750377 -24.945297) (xy 302.75754 -24.951223)
			(xy 302.801297 -24.99782) (xy 302.83887 -25.049535) (xy 302.869664 -25.10555) (xy 302.893196 -25.164983)
			(xy 302.909093 -25.226897) (xy 302.917104 -25.290315) (xy 302.917606 -25.322276) (xy 302.917104 -25.354237)
			(xy 302.909093 -25.417655) (xy 302.893196 -25.479569) (xy 302.869664 -25.539002) (xy 302.83887 -25.595017)
			(xy 302.819084 -25.62225) (xy 304.549554 -25.62225) (xy 304.553625 -25.566628) (xy 304.565751 -25.512191)
			(xy 304.585674 -25.4601) (xy 304.61297 -25.411465) (xy 304.647056 -25.367322) (xy 304.687205 -25.328613)
			(xy 304.732563 -25.296162) (xy 304.782163 -25.270661) (xy 304.834947 -25.252654) (xy 304.88979 -25.242524)
			(xy 304.945524 -25.240487) (xy 305.000961 -25.246587) (xy 305.054918 -25.260693) (xy 305.106247 -25.282505)
			(xy 305.153853 -25.311559) (xy 305.196721 -25.347234) (xy 305.233938 -25.388771) (xy 305.264711 -25.435284)
			(xy 305.288383 -25.485781) (xy 305.304451 -25.539188) (xy 305.312571 -25.594364) (xy 305.31308 -25.62225)
			(xy 305.312571 -25.650136) (xy 305.308264 -25.6794) (xy 318.658238 -25.6794) (xy 318.662309 -25.623778)
			(xy 318.674435 -25.569341) (xy 318.694358 -25.51725) (xy 318.721654 -25.468615) (xy 318.75574 -25.424472)
			(xy 318.795889 -25.385763) (xy 318.841247 -25.353312) (xy 318.890847 -25.327811) (xy 318.943631 -25.309804)
			(xy 318.998474 -25.299674) (xy 319.054208 -25.297637) (xy 319.109645 -25.303737) (xy 319.163602 -25.317843)
			(xy 319.214931 -25.339655) (xy 319.262537 -25.368709) (xy 319.305405 -25.404384) (xy 319.342622 -25.445921)
			(xy 319.373395 -25.492434) (xy 319.397067 -25.542931) (xy 319.413135 -25.596338) (xy 319.421255 -25.651514)
			(xy 319.421764 -25.6794) (xy 319.421255 -25.707286) (xy 319.413135 -25.762462) (xy 319.397067 -25.815869)
			(xy 319.373395 -25.866366) (xy 319.342622 -25.912879) (xy 319.305405 -25.954416) (xy 319.262537 -25.990091)
			(xy 319.214931 -26.019145) (xy 319.163602 -26.040957) (xy 319.109645 -26.055063) (xy 319.054208 -26.061163)
			(xy 318.998474 -26.059126) (xy 318.943631 -26.048996) (xy 318.890847 -26.030989) (xy 318.841247 -26.005488)
			(xy 318.795889 -25.973037) (xy 318.75574 -25.934328) (xy 318.721654 -25.890185) (xy 318.694358 -25.84155)
			(xy 318.674435 -25.789459) (xy 318.662309 -25.735022) (xy 318.658238 -25.6794) (xy 305.308264 -25.6794)
			(xy 305.304451 -25.705312) (xy 305.288383 -25.758719) (xy 305.264711 -25.809216) (xy 305.233938 -25.855729)
			(xy 305.196721 -25.897266) (xy 305.153853 -25.932941) (xy 305.106247 -25.961995) (xy 305.054918 -25.983807)
			(xy 305.000961 -25.997913) (xy 304.945524 -26.004013) (xy 304.88979 -26.001976) (xy 304.834947 -25.991846)
			(xy 304.782163 -25.973839) (xy 304.732563 -25.948338) (xy 304.687205 -25.915887) (xy 304.647056 -25.877178)
			(xy 304.61297 -25.833035) (xy 304.585674 -25.7844) (xy 304.565751 -25.732309) (xy 304.553625 -25.677872)
			(xy 304.549554 -25.62225) (xy 302.819084 -25.62225) (xy 302.801297 -25.646732) (xy 302.75754 -25.693329)
			(xy 302.708287 -25.734074) (xy 302.654316 -25.768325) (xy 302.596477 -25.795542) (xy 302.535684 -25.815295)
			(xy 302.472894 -25.827273) (xy 302.409098 -25.831287) (xy 302.345302 -25.827273) (xy 302.282512 -25.815295)
			(xy 302.221719 -25.795542) (xy 302.16388 -25.768325) (xy 302.109909 -25.734074) (xy 302.060656 -25.693329)
			(xy 302.016899 -25.646732) (xy 301.979326 -25.595017) (xy 301.948532 -25.539002) (xy 301.925 -25.479569)
			(xy 301.909103 -25.417655) (xy 301.901092 -25.354237) (xy 275.0947 -25.354237) (xy 275.0947 -26.114248)
			(xy 329.027794 -26.114248) (xy 329.031823 -26.023242) (xy 329.04388 -25.932948) (xy 329.06387 -25.844073)
			(xy 329.091636 -25.757313) (xy 329.126962 -25.673346) (xy 329.16957 -25.59283) (xy 329.219128 -25.516394)
			(xy 329.275247 -25.444638) (xy 329.337488 -25.378122) (xy 329.405365 -25.317367) (xy 329.478345 -25.262849)
			(xy 329.555858 -25.214995) (xy 329.637297 -25.174178) (xy 329.722025 -25.140719) (xy 329.809379 -25.114878)
			(xy 329.898674 -25.09686) (xy 329.989212 -25.086803) (xy 330.080285 -25.084788) (xy 330.17118 -25.09083)
			(xy 330.261185 -25.104881) (xy 330.349596 -25.126832) (xy 330.435721 -25.156511) (xy 330.518886 -25.193685)
			(xy 330.59844 -25.238064) (xy 330.67376 -25.289301) (xy 330.744258 -25.346994) (xy 330.80938 -25.410691)
			(xy 330.868618 -25.479895) (xy 330.921508 -25.554064) (xy 330.967637 -25.632616) (xy 331.006642 -25.714939)
			(xy 331.038219 -25.800386) (xy 331.06212 -25.88829) (xy 331.078159 -25.977962) (xy 331.08621 -26.0687)
			(xy 331.086714 -26.114248) (xy 331.08621 -26.159796) (xy 331.078159 -26.250534) (xy 331.07795 -26.2517)
			(xy 331.686651 -26.2517) (xy 331.690665 -26.187901) (xy 331.702643 -26.125108) (xy 331.722397 -26.064312)
			(xy 331.749614 -26.00647) (xy 331.783866 -25.952496) (xy 331.824612 -25.90324) (xy 331.871211 -25.859479)
			(xy 331.922926 -25.821904) (xy 331.978943 -25.791106) (xy 332.038379 -25.767572) (xy 332.100295 -25.751672)
			(xy 332.163715 -25.743657) (xy 332.195678 -25.743154) (xy 332.226674 -25.743629) (xy 332.288205 -25.751185)
			(xy 332.348361 -25.766163) (xy 332.40625 -25.788342) (xy 332.461015 -25.817391) (xy 332.511844 -25.852882)
			(xy 332.557982 -25.894286) (xy 332.598746 -25.940992) (xy 332.633532 -25.992305) (xy 332.661823 -26.047466)
			(xy 332.672944 -26.076402) (xy 332.672944 -26.076656) (xy 332.676977 -26.086134) (xy 332.691128 -26.101077)
			(xy 332.700376 -26.105612) (xy 332.76794 -26.134822) (xy 332.777573 -26.138458) (xy 332.798143 -26.138597)
			(xy 332.807818 -26.135076) (xy 332.839131 -26.122467) (xy 332.904263 -26.104724) (xy 332.97117 -26.095762)
			(xy 333.004922 -26.095198) (xy 333.00543 -26.095198) (xy 333.040326 -26.095795) (xy 333.109462 -26.105337)
			(xy 333.176643 -26.124249) (xy 333.240603 -26.152177) (xy 333.30014 -26.188595) (xy 333.327502 -26.21026)
			(xy 333.334441 -26.215506) (xy 333.350814 -26.221345) (xy 333.359506 -26.22169) (xy 333.389478 -26.22169)
			(xy 333.398161 -26.221306) (xy 333.414519 -26.215462) (xy 333.421482 -26.21026) (xy 333.448859 -26.188614)
			(xy 333.508392 -26.152191) (xy 333.572348 -26.124256) (xy 333.639525 -26.105333) (xy 333.708659 -26.095778)
			(xy 333.743554 -26.095198) (xy 333.775519 -26.095664) (xy 333.838944 -26.103671) (xy 333.900866 -26.119565)
			(xy 333.960308 -26.143095) (xy 334.016331 -26.17389) (xy 334.068053 -26.211463) (xy 334.114657 -26.255224)
			(xy 334.155409 -26.30448) (xy 334.189666 -26.358456) (xy 334.216887 -26.416301) (xy 334.236643 -26.4771)
			(xy 334.248623 -26.539897) (xy 334.252638 -26.6037) (xy 334.248623 -26.667503) (xy 334.237147 -26.727658)
			(xy 334.8134 -26.727658) (xy 334.817471 -26.672036) (xy 334.829597 -26.617599) (xy 334.84952 -26.565508)
			(xy 334.876816 -26.516873) (xy 334.910902 -26.47273) (xy 334.951051 -26.434021) (xy 334.996409 -26.40157)
			(xy 335.046009 -26.376069) (xy 335.098793 -26.358062) (xy 335.153636 -26.347932) (xy 335.20937 -26.345895)
			(xy 335.264807 -26.351995) (xy 335.318764 -26.366101) (xy 335.370093 -26.387913) (xy 335.417699 -26.416967)
			(xy 335.460567 -26.452642) (xy 335.497784 -26.494179) (xy 335.528557 -26.540692) (xy 335.552229 -26.591189)
			(xy 335.568297 -26.644596) (xy 335.576417 -26.699772) (xy 335.576926 -26.727658) (xy 335.576417 -26.755544)
			(xy 335.575817 -26.759619) (xy 336.687408 -26.759619) (xy 336.687408 -26.695697) (xy 336.695419 -26.632279)
			(xy 336.711316 -26.570365) (xy 336.734848 -26.510932) (xy 336.765642 -26.454917) (xy 336.803215 -26.403202)
			(xy 336.846972 -26.356605) (xy 336.896225 -26.31586) (xy 336.950196 -26.281609) (xy 337.008035 -26.254392)
			(xy 337.068828 -26.234639) (xy 337.131618 -26.222661) (xy 337.195414 -26.218648) (xy 337.25921 -26.222661)
			(xy 337.322 -26.234639) (xy 337.382793 -26.254392) (xy 337.440632 -26.281609) (xy 337.494603 -26.31586)
			(xy 337.543856 -26.356605) (xy 337.587613 -26.403202) (xy 337.625186 -26.454917) (xy 337.65598 -26.510932)
			(xy 337.679512 -26.570365) (xy 337.695409 -26.632279) (xy 337.70342 -26.695697) (xy 337.703531 -26.702766)
			(xy 367.122708 -26.702766) (xy 367.126779 -26.647144) (xy 367.138905 -26.592707) (xy 367.158828 -26.540616)
			(xy 367.186124 -26.491981) (xy 367.22021 -26.447838) (xy 367.260359 -26.409129) (xy 367.305717 -26.376678)
			(xy 367.355317 -26.351177) (xy 367.408101 -26.33317) (xy 367.462944 -26.32304) (xy 367.518678 -26.321003)
			(xy 367.574115 -26.327103) (xy 367.628072 -26.341209) (xy 367.679401 -26.363021) (xy 367.727007 -26.392075)
			(xy 367.769875 -26.42775) (xy 367.807092 -26.469287) (xy 367.837865 -26.5158) (xy 367.861537 -26.566297)
			(xy 367.877605 -26.619704) (xy 367.885725 -26.67488) (xy 367.886234 -26.702766) (xy 367.885725 -26.730652)
			(xy 367.877605 -26.785828) (xy 367.861537 -26.839235) (xy 367.837865 -26.889732) (xy 367.807092 -26.936245)
			(xy 367.769875 -26.977782) (xy 367.727007 -27.013457) (xy 367.679401 -27.042511) (xy 367.628072 -27.064323)
			(xy 367.574115 -27.078429) (xy 367.518678 -27.084529) (xy 367.462944 -27.082492) (xy 367.408101 -27.072362)
			(xy 367.355317 -27.054355) (xy 367.305717 -27.028854) (xy 367.260359 -26.996403) (xy 367.22021 -26.957694)
			(xy 367.186124 -26.913551) (xy 367.158828 -26.864916) (xy 367.138905 -26.812825) (xy 367.126779 -26.758388)
			(xy 367.122708 -26.702766) (xy 337.703531 -26.702766) (xy 337.703922 -26.727658) (xy 337.70342 -26.759619)
			(xy 337.695409 -26.823037) (xy 337.679512 -26.884951) (xy 337.65598 -26.944384) (xy 337.625186 -27.000399)
			(xy 337.587613 -27.052114) (xy 337.543856 -27.098711) (xy 337.494603 -27.139456) (xy 337.440632 -27.173707)
			(xy 337.382793 -27.200924) (xy 337.322 -27.220677) (xy 337.25921 -27.232655) (xy 337.195414 -27.236669)
			(xy 337.131618 -27.232655) (xy 337.068828 -27.220677) (xy 337.008035 -27.200924) (xy 336.950196 -27.173707)
			(xy 336.896225 -27.139456) (xy 336.846972 -27.098711) (xy 336.803215 -27.052114) (xy 336.765642 -27.000399)
			(xy 336.734848 -26.944384) (xy 336.711316 -26.884951) (xy 336.695419 -26.823037) (xy 336.687408 -26.759619)
			(xy 335.575817 -26.759619) (xy 335.568297 -26.81072) (xy 335.552229 -26.864127) (xy 335.528557 -26.914624)
			(xy 335.497784 -26.961137) (xy 335.460567 -27.002674) (xy 335.417699 -27.038349) (xy 335.370093 -27.067403)
			(xy 335.318764 -27.089215) (xy 335.264807 -27.103321) (xy 335.20937 -27.109421) (xy 335.153636 -27.107384)
			(xy 335.098793 -27.097254) (xy 335.046009 -27.079247) (xy 334.996409 -27.053746) (xy 334.951051 -27.021295)
			(xy 334.910902 -26.982586) (xy 334.876816 -26.938443) (xy 334.84952 -26.889808) (xy 334.829597 -26.837717)
			(xy 334.817471 -26.78328) (xy 334.8134 -26.727658) (xy 334.237147 -26.727658) (xy 334.236643 -26.7303)
			(xy 334.216887 -26.791099) (xy 334.189666 -26.848944) (xy 334.155409 -26.90292) (xy 334.114657 -26.952176)
			(xy 334.068053 -26.995937) (xy 334.016331 -27.03351) (xy 333.960308 -27.064305) (xy 333.900866 -27.087835)
			(xy 333.838944 -27.103729) (xy 333.775519 -27.111736) (xy 333.743554 -27.112214) (xy 333.708658 -27.111623)
			(xy 333.639521 -27.10208) (xy 333.572341 -27.083166) (xy 333.508381 -27.055236) (xy 333.448844 -27.018817)
			(xy 333.421482 -26.997152) (xy 333.414547 -26.991901) (xy 333.398171 -26.986064) (xy 333.389478 -26.985722)
			(xy 333.359506 -26.985722) (xy 333.350822 -26.986097) (xy 333.334464 -26.991946) (xy 333.327502 -26.997152)
			(xy 333.300132 -27.018807) (xy 333.240597 -27.055228) (xy 333.176639 -27.083161) (xy 333.109461 -27.102082)
			(xy 333.040326 -27.111635) (xy 333.00543 -27.112214) (xy 332.974433 -27.111753) (xy 332.912901 -27.104197)
			(xy 332.852744 -27.089219) (xy 332.794853 -27.06704) (xy 332.740088 -27.037989) (xy 332.689259 -27.002497)
			(xy 332.643121 -26.96109) (xy 332.602357 -26.914382) (xy 332.567573 -26.863067) (xy 332.539284 -26.807903)
			(xy 332.528164 -26.778966) (xy 332.528164 -26.778712) (xy 332.524103 -26.769247) (xy 332.509973 -26.754297)
			(xy 332.500732 -26.749756) (xy 332.433168 -26.720546) (xy 332.423534 -26.716911) (xy 332.402964 -26.716769)
			(xy 332.39329 -26.720292) (xy 332.361977 -26.732902) (xy 332.296845 -26.750643) (xy 332.229938 -26.759605)
			(xy 332.196186 -26.76017) (xy 332.195678 -26.76017) (xy 332.163715 -26.759743) (xy 332.100295 -26.751728)
			(xy 332.038379 -26.735828) (xy 331.978943 -26.712294) (xy 331.922926 -26.681496) (xy 331.871211 -26.643921)
			(xy 331.824612 -26.60016) (xy 331.783866 -26.550904) (xy 331.749614 -26.49693) (xy 331.722397 -26.439088)
			(xy 331.702643 -26.378292) (xy 331.690665 -26.315499) (xy 331.686651 -26.2517) (xy 331.07795 -26.2517)
			(xy 331.06212 -26.340206) (xy 331.038219 -26.42811) (xy 331.006642 -26.513557) (xy 330.967637 -26.59588)
			(xy 330.921508 -26.674432) (xy 330.868618 -26.748601) (xy 330.80938 -26.817805) (xy 330.744258 -26.881502)
			(xy 330.67376 -26.939195) (xy 330.59844 -26.990432) (xy 330.518886 -27.034811) (xy 330.435721 -27.071985)
			(xy 330.349596 -27.101664) (xy 330.261185 -27.123615) (xy 330.17118 -27.137666) (xy 330.080285 -27.143708)
			(xy 329.989212 -27.141693) (xy 329.898674 -27.131636) (xy 329.809379 -27.113618) (xy 329.722025 -27.087777)
			(xy 329.637297 -27.054318) (xy 329.555858 -27.013501) (xy 329.478345 -26.965647) (xy 329.405365 -26.911129)
			(xy 329.337488 -26.850374) (xy 329.275247 -26.783858) (xy 329.219128 -26.712102) (xy 329.16957 -26.635666)
			(xy 329.126962 -26.55515) (xy 329.091636 -26.471183) (xy 329.06387 -26.384423) (xy 329.04388 -26.295548)
			(xy 329.031823 -26.205254) (xy 329.027794 -26.114248) (xy 275.0947 -26.114248) (xy 275.0947 -27.289463)
			(xy 362.50092 -27.289463) (xy 362.50092 -27.225541) (xy 362.508931 -27.162123) (xy 362.524828 -27.100209)
			(xy 362.54836 -27.040776) (xy 362.579154 -26.984761) (xy 362.616727 -26.933046) (xy 362.660484 -26.886449)
			(xy 362.709737 -26.845704) (xy 362.763708 -26.811453) (xy 362.821547 -26.784236) (xy 362.88234 -26.764483)
			(xy 362.94513 -26.752505) (xy 363.008926 -26.748492) (xy 363.072722 -26.752505) (xy 363.135512 -26.764483)
			(xy 363.196305 -26.784236) (xy 363.254144 -26.811453) (xy 363.308115 -26.845704) (xy 363.357368 -26.886449)
			(xy 363.401125 -26.933046) (xy 363.438698 -26.984761) (xy 363.469492 -27.040776) (xy 363.493024 -27.100209)
			(xy 363.508921 -27.162123) (xy 363.509322 -27.1653) (xy 363.984284 -27.1653) (xy 363.988355 -27.109678)
			(xy 364.000481 -27.055241) (xy 364.020404 -27.00315) (xy 364.0477 -26.954515) (xy 364.081786 -26.910372)
			(xy 364.121935 -26.871663) (xy 364.167293 -26.839212) (xy 364.216893 -26.813711) (xy 364.269677 -26.795704)
			(xy 364.32452 -26.785574) (xy 364.380254 -26.783537) (xy 364.435691 -26.789637) (xy 364.489648 -26.803743)
			(xy 364.540977 -26.825555) (xy 364.588583 -26.854609) (xy 364.631451 -26.890284) (xy 364.668668 -26.931821)
			(xy 364.699441 -26.978334) (xy 364.723113 -27.028831) (xy 364.739181 -27.082238) (xy 364.747301 -27.137414)
			(xy 364.74781 -27.1653) (xy 364.747301 -27.193186) (xy 364.739181 -27.248362) (xy 364.723113 -27.301769)
			(xy 364.699441 -27.352266) (xy 364.668668 -27.398779) (xy 364.631451 -27.440316) (xy 364.588583 -27.475991)
			(xy 364.540977 -27.505045) (xy 364.489648 -27.526857) (xy 364.435691 -27.540963) (xy 364.380254 -27.547063)
			(xy 364.32452 -27.545026) (xy 364.269677 -27.534896) (xy 364.216893 -27.516889) (xy 364.167293 -27.491388)
			(xy 364.121935 -27.458937) (xy 364.081786 -27.420228) (xy 364.0477 -27.376085) (xy 364.020404 -27.32745)
			(xy 364.000481 -27.275359) (xy 363.988355 -27.220922) (xy 363.984284 -27.1653) (xy 363.509322 -27.1653)
			(xy 363.516932 -27.225541) (xy 363.517434 -27.257502) (xy 363.516932 -27.289463) (xy 363.508921 -27.352881)
			(xy 363.493024 -27.414795) (xy 363.469492 -27.474228) (xy 363.438698 -27.530243) (xy 363.401125 -27.581958)
			(xy 363.357368 -27.628555) (xy 363.308115 -27.6693) (xy 363.254144 -27.703551) (xy 363.196305 -27.730768)
			(xy 363.135512 -27.750521) (xy 363.072722 -27.762499) (xy 363.008926 -27.766513) (xy 362.94513 -27.762499)
			(xy 362.88234 -27.750521) (xy 362.821547 -27.730768) (xy 362.763708 -27.703551) (xy 362.709737 -27.6693)
			(xy 362.660484 -27.628555) (xy 362.616727 -27.581958) (xy 362.579154 -27.530243) (xy 362.54836 -27.474228)
			(xy 362.524828 -27.414795) (xy 362.508931 -27.352881) (xy 362.50092 -27.289463) (xy 275.0947 -27.289463)
			(xy 275.0947 -27.695398) (xy 356.4669 -27.695398) (xy 356.470971 -27.639776) (xy 356.483097 -27.585339)
			(xy 356.50302 -27.533248) (xy 356.530316 -27.484613) (xy 356.564402 -27.44047) (xy 356.604551 -27.401761)
			(xy 356.649909 -27.36931) (xy 356.699509 -27.343809) (xy 356.752293 -27.325802) (xy 356.807136 -27.315672)
			(xy 356.86287 -27.313635) (xy 356.918307 -27.319735) (xy 356.972264 -27.333841) (xy 357.023593 -27.355653)
			(xy 357.071199 -27.384707) (xy 357.114067 -27.420382) (xy 357.151284 -27.461919) (xy 357.182057 -27.508432)
			(xy 357.205729 -27.558929) (xy 357.221797 -27.612336) (xy 357.229917 -27.667512) (xy 357.230426 -27.695398)
			(xy 357.229917 -27.723284) (xy 357.221797 -27.77846) (xy 357.205729 -27.831867) (xy 357.182057 -27.882364)
			(xy 357.151284 -27.928877) (xy 357.114067 -27.970414) (xy 357.071199 -28.006089) (xy 357.023593 -28.035143)
			(xy 356.972264 -28.056955) (xy 356.918307 -28.071061) (xy 356.86287 -28.077161) (xy 356.807136 -28.075124)
			(xy 356.752293 -28.064994) (xy 356.699509 -28.046987) (xy 356.649909 -28.021486) (xy 356.604551 -27.989035)
			(xy 356.564402 -27.950326) (xy 356.530316 -27.906183) (xy 356.50302 -27.857548) (xy 356.483097 -27.805457)
			(xy 356.470971 -27.75102) (xy 356.4669 -27.695398) (xy 275.0947 -27.695398) (xy 275.0947 -28.654248)
			(xy 329.154802 -28.654248) (xy 329.158768 -28.569717) (xy 329.170633 -28.48593) (xy 329.190291 -28.403621)
			(xy 329.217571 -28.323515) (xy 329.252232 -28.246316) (xy 329.29397 -28.172701) (xy 329.342417 -28.103318)
			(xy 329.397149 -28.038777) (xy 329.457685 -27.979645) (xy 329.523491 -27.926441) (xy 329.593991 -27.879633)
			(xy 329.668563 -27.839632) (xy 329.746554 -27.80679) (xy 329.827278 -27.781396) (xy 329.910025 -27.763673)
			(xy 329.994067 -27.753775) (xy 330.078668 -27.751792) (xy 330.163082 -27.757739) (xy 330.246569 -27.771564)
			(xy 330.328394 -27.793147) (xy 330.407838 -27.822297) (xy 330.484204 -27.858758) (xy 330.55682 -27.90221)
			(xy 330.625048 -27.952271) (xy 330.688288 -28.008501) (xy 330.745985 -28.070406) (xy 330.797632 -28.137442)
			(xy 330.842774 -28.209019) (xy 330.880587 -28.283662) (xy 331.81366 -28.283662) (xy 331.817731 -28.22804)
			(xy 331.829857 -28.173603) (xy 331.84978 -28.121512) (xy 331.877076 -28.072877) (xy 331.911162 -28.028734)
			(xy 331.951311 -27.990025) (xy 331.996669 -27.957574) (xy 332.046269 -27.932073) (xy 332.099053 -27.914066)
			(xy 332.153896 -27.903936) (xy 332.20963 -27.901899) (xy 332.265067 -27.907999) (xy 332.319024 -27.922105)
			(xy 332.370353 -27.943917) (xy 332.417959 -27.972971) (xy 332.460827 -28.008646) (xy 332.498044 -28.050183)
			(xy 332.528817 -28.096696) (xy 332.552489 -28.147193) (xy 332.568557 -28.2006) (xy 332.576677 -28.255776)
			(xy 332.577186 -28.283662) (xy 332.576677 -28.311548) (xy 332.568557 -28.366724) (xy 332.552489 -28.420131)
			(xy 332.528817 -28.470628) (xy 332.498044 -28.517141) (xy 332.460827 -28.558678) (xy 332.417959 -28.594353)
			(xy 332.370353 -28.623407) (xy 332.319024 -28.645219) (xy 332.265067 -28.659325) (xy 332.20963 -28.665425)
			(xy 332.153896 -28.663388) (xy 332.099053 -28.653258) (xy 332.046269 -28.635251) (xy 331.996669 -28.60975)
			(xy 331.951311 -28.577299) (xy 331.911162 -28.53859) (xy 331.877076 -28.494447) (xy 331.84978 -28.445812)
			(xy 331.829857 -28.393721) (xy 331.817731 -28.339284) (xy 331.81366 -28.283662) (xy 330.880587 -28.283662)
			(xy 330.881016 -28.284509) (xy 330.91202 -28.363248) (xy 330.935515 -28.444545) (xy 330.951294 -28.527684)
			(xy 330.959218 -28.611936) (xy 330.959714 -28.654248) (xy 330.959218 -28.69656) (xy 330.951294 -28.780812)
			(xy 330.935515 -28.863951) (xy 330.91202 -28.945248) (xy 330.881016 -29.023987) (xy 330.842774 -29.099477)
			(xy 330.797632 -29.171054) (xy 330.745985 -29.23809) (xy 330.688288 -29.299995) (xy 330.625048 -29.356225)
			(xy 330.55682 -29.406286) (xy 330.484204 -29.449738) (xy 330.407838 -29.486199) (xy 330.328394 -29.515349)
			(xy 330.246569 -29.536932) (xy 330.163082 -29.550757) (xy 330.078668 -29.556704) (xy 329.994067 -29.554721)
			(xy 329.910025 -29.544823) (xy 329.827278 -29.5271) (xy 329.746554 -29.501706) (xy 329.668563 -29.468864)
			(xy 329.593991 -29.428863) (xy 329.523491 -29.382055) (xy 329.457685 -29.328851) (xy 329.397149 -29.269719)
			(xy 329.342417 -29.205178) (xy 329.29397 -29.135795) (xy 329.252232 -29.06218) (xy 329.217571 -28.984981)
			(xy 329.190291 -28.904875) (xy 329.170633 -28.822566) (xy 329.158768 -28.738779) (xy 329.154802 -28.654248)
			(xy 275.0947 -28.654248) (xy 275.0947 -30.7396) (xy 320.330077 -30.7396) (xy 320.334091 -30.675804)
			(xy 320.346069 -30.613014) (xy 320.365821 -30.55222) (xy 320.393038 -30.494381) (xy 320.427288 -30.440409)
			(xy 320.468033 -30.391156) (xy 320.51463 -30.347397) (xy 320.566343 -30.309824) (xy 320.622358 -30.279028)
			(xy 320.681791 -30.255495) (xy 320.743705 -30.239596) (xy 320.807123 -30.231583) (xy 320.839084 -30.23108)
			(xy 320.871236 -30.231527) (xy 320.935027 -30.239627) (xy 320.997287 -30.255711) (xy 321.057019 -30.279523)
			(xy 321.113269 -30.310681) (xy 321.165138 -30.348689) (xy 321.211796 -30.392938) (xy 321.23253 -30.417516)
			(xy 321.238998 -30.424765) (xy 321.255974 -30.434174) (xy 321.26555 -30.435804) (xy 321.3354 -30.444186)
			(xy 321.345126 -30.444887) (xy 321.363933 -30.439793) (xy 321.371976 -30.43428) (xy 321.37223 -30.43428)
			(xy 321.394344 -30.418297) (xy 321.442227 -30.39214) (xy 321.493347 -30.373066) (xy 321.546661 -30.361463)
			(xy 321.601084 -30.357569) (xy 321.655507 -30.361463) (xy 321.708821 -30.373066) (xy 321.759941 -30.39214)
			(xy 321.807824 -30.418297) (xy 321.829938 -30.43428) (xy 321.830192 -30.43428) (xy 321.838206 -30.439851)
			(xy 321.857035 -30.444933) (xy 321.866768 -30.444186) (xy 321.936618 -30.435804) (xy 321.946181 -30.434128)
			(xy 321.963156 -30.424742) (xy 321.969638 -30.417516) (xy 321.990352 -30.392924) (xy 322.037028 -30.3487)
			(xy 322.088907 -30.310713) (xy 322.145161 -30.27957) (xy 322.204892 -30.255766) (xy 322.267148 -30.239682)
			(xy 322.330934 -30.231574) (xy 322.363084 -30.23108) (xy 322.395046 -30.231584) (xy 322.458467 -30.239594)
			(xy 322.520383 -30.25549) (xy 322.57982 -30.27902) (xy 322.635838 -30.309815) (xy 322.687554 -30.347388)
			(xy 322.734154 -30.391147) (xy 322.774902 -30.440401) (xy 322.809155 -30.494373) (xy 322.836373 -30.552214)
			(xy 322.853118 -30.603748) (xy 345.218798 -30.603748) (xy 345.218798 -30.549252) (xy 345.226553 -30.49531)
			(xy 345.241906 -30.443021) (xy 345.264543 -30.393448) (xy 345.294005 -30.347602) (xy 345.329691 -30.306415)
			(xy 345.370875 -30.270725) (xy 345.416718 -30.24126) (xy 345.466289 -30.218618) (xy 345.518577 -30.203261)
			(xy 345.572518 -30.195501) (xy 345.599766 -30.195012) (xy 345.626566 -30.195483) (xy 345.679641 -30.202969)
			(xy 345.731144 -30.217814) (xy 345.780062 -30.239724) (xy 345.82543 -30.268268) (xy 345.866353 -30.302883)
			(xy 345.902027 -30.342887) (xy 345.917266 -30.364938) (xy 345.9261 -30.377422) (xy 345.949808 -30.396729)
			(xy 345.978169 -30.408151) (xy 346.00864 -30.410663) (xy 346.038488 -30.404041) (xy 346.065038 -30.388879)
			(xy 346.085908 -30.366535) (xy 346.093034 -30.353) (xy 346.107309 -30.324885) (xy 346.141809 -30.272106)
			(xy 346.182572 -30.223998) (xy 346.228972 -30.181301) (xy 346.280295 -30.14467) (xy 346.335755 -30.114667)
			(xy 346.3945 -30.091753) (xy 346.455627 -30.07628) (xy 346.518198 -30.068485) (xy 346.549726 -30.068012)
			(xy 346.581687 -30.068476) (xy 346.645105 -30.07649) (xy 346.707019 -30.09239) (xy 346.766452 -30.115923)
			(xy 346.822466 -30.14672) (xy 346.874179 -30.184295) (xy 346.901819 -30.210252) (xy 356.03307 -30.210252)
			(xy 356.033542 -30.183701) (xy 356.040896 -30.13111) (xy 356.055468 -30.080046) (xy 356.076978 -30.031495)
			(xy 356.105009 -29.986394) (xy 356.139022 -29.945614) (xy 356.178359 -29.909942) (xy 356.22226 -29.880067)
			(xy 356.269879 -29.856565) (xy 356.294944 -29.847794) (xy 356.303199 -29.844729) (xy 356.317105 -29.833949)
			(xy 356.322122 -29.826712) (xy 356.338124 -29.801058) (xy 356.342634 -29.793281) (xy 356.346401 -29.775712)
			(xy 356.34549 -29.766768) (xy 356.343131 -29.749146) (xy 356.340589 -29.71368) (xy 356.34041 -29.695902)
			(xy 356.34041 -29.695394) (xy 356.340874 -29.663854) (xy 356.348677 -29.601257) (xy 356.364163 -29.540107)
			(xy 356.387094 -29.481342) (xy 356.417118 -29.425864) (xy 356.453773 -29.374526) (xy 356.496496 -29.328117)
			(xy 356.544632 -29.287348) (xy 356.597441 -29.252846) (xy 356.654112 -29.225141) (xy 356.713775 -29.204659)
			(xy 356.775513 -29.191714) (xy 356.838379 -29.186504) (xy 356.901405 -29.189111) (xy 356.963626 -29.199493)
			(xy 357.024084 -29.217492) (xy 357.081852 -29.242831) (xy 357.136042 -29.27512) (xy 357.185822 -29.313865)
			(xy 357.230427 -29.358469) (xy 357.269173 -29.408248) (xy 357.301464 -29.462437) (xy 357.326804 -29.520205)
			(xy 357.344804 -29.580662) (xy 357.355188 -29.642883) (xy 357.357796 -29.705909) (xy 357.352588 -29.768775)
			(xy 357.339644 -29.830513) (xy 357.319163 -29.890176) (xy 357.29146 -29.946848) (xy 357.256959 -29.999658)
			(xy 357.216192 -30.047795) (xy 357.169783 -30.09052) (xy 357.118446 -30.127176) (xy 357.062969 -30.157201)
			(xy 357.004204 -30.180133) (xy 356.943054 -30.19562) (xy 356.880458 -30.203425) (xy 356.848918 -30.203902)
			(xy 356.845108 -30.203902) (xy 356.808278 -30.236668) (xy 356.801913 -30.242849) (xy 356.793472 -30.258441)
			(xy 356.791768 -30.267148) (xy 356.787209 -30.293885) (xy 356.771623 -30.345831) (xy 356.748835 -30.395046)
			(xy 356.719304 -30.440536) (xy 356.683627 -30.481383) (xy 356.642522 -30.516763) (xy 356.613397 -30.535372)
			(xy 366.785652 -30.535372) (xy 366.786155 -30.501238) (xy 366.795282 -30.433582) (xy 366.81338 -30.367755)
			(xy 366.840125 -30.304943) (xy 366.875035 -30.246276) (xy 366.917482 -30.192807) (xy 366.966703 -30.145501)
			(xy 366.993932 -30.124908) (xy 367.002489 -30.118034) (xy 367.013292 -30.098955) (xy 367.01476 -30.088078)
			(xy 367.020856 -30.011878) (xy 367.021295 -30.000992) (xy 367.014046 -29.980467) (xy 367.006886 -29.972254)
			(xy 367.006632 -29.972) (xy 366.986521 -29.950492) (xy 366.952454 -29.902468) (xy 366.926167 -29.849781)
			(xy 366.908285 -29.793682) (xy 366.899232 -29.735502) (xy 366.898682 -29.706062) (xy 366.899168 -29.678811)
			(xy 366.906924 -29.624863) (xy 366.922279 -29.572568) (xy 366.944921 -29.522991) (xy 366.974387 -29.477141)
			(xy 367.010078 -29.43595) (xy 367.051269 -29.400259) (xy 367.097119 -29.370793) (xy 367.146696 -29.348151)
			(xy 367.198991 -29.332796) (xy 367.252939 -29.32504) (xy 367.307441 -29.32504) (xy 367.361389 -29.332796)
			(xy 367.413684 -29.348151) (xy 367.463261 -29.370793) (xy 367.509111 -29.400259) (xy 367.550302 -29.43595)
			(xy 367.585993 -29.477141) (xy 367.603339 -29.504132) (xy 368.262154 -29.504132) (xy 368.262568 -29.478286)
			(xy 368.269555 -29.42707) (xy 368.283393 -29.377265) (xy 368.303829 -29.329785) (xy 368.330487 -29.285498)
			(xy 368.362879 -29.245215) (xy 368.400414 -29.209675) (xy 368.421158 -29.194252) (xy 368.429573 -29.187671)
			(xy 368.44036 -29.169251) (xy 368.441986 -29.158692) (xy 368.450368 -29.083508) (xy 368.450932 -29.072911)
			(xy 368.444511 -29.052709) (xy 368.437922 -29.044392) (xy 368.437922 -29.044138) (xy 368.41785 -29.020807)
			(xy 368.382828 -28.970194) (xy 368.354174 -28.915724) (xy 368.332306 -28.858193) (xy 368.317544 -28.798442)
			(xy 368.310105 -28.737346) (xy 368.309652 -28.706572) (xy 368.310154 -28.674611) (xy 368.318165 -28.611193)
			(xy 368.334062 -28.549279) (xy 368.357594 -28.489846) (xy 368.388388 -28.433831) (xy 368.425961 -28.382116)
			(xy 368.469718 -28.335519) (xy 368.518971 -28.294774) (xy 368.572942 -28.260523) (xy 368.630781 -28.233306)
			(xy 368.691574 -28.213553) (xy 368.754364 -28.201575) (xy 368.81816 -28.197562) (xy 368.881956 -28.201575)
			(xy 368.944746 -28.213553) (xy 369.005539 -28.233306) (xy 369.063378 -28.260523) (xy 369.117349 -28.294774)
			(xy 369.166602 -28.335519) (xy 369.210359 -28.382116) (xy 369.247932 -28.433831) (xy 369.278726 -28.489846)
			(xy 369.302258 -28.549279) (xy 369.318155 -28.611193) (xy 369.326166 -28.674611) (xy 369.326668 -28.706572)
			(xy 369.326097 -28.739267) (xy 369.317718 -28.804119) (xy 369.301095 -28.867361) (xy 369.276502 -28.927951)
			(xy 369.244344 -28.984888) (xy 369.205153 -29.037233) (xy 369.159575 -29.084122) (xy 369.108363 -29.124781)
			(xy 369.052361 -29.15854) (xy 369.02263 -29.172154) (xy 369.013126 -29.176967) (xy 368.998813 -29.192709)
			(xy 368.994944 -29.202634) (xy 368.967766 -29.284676) (xy 368.969798 -29.306012) (xy 368.975132 -29.31541)
			(xy 368.987004 -29.337059) (xy 369.005699 -29.382759) (xy 369.018354 -29.430486) (xy 369.024759 -29.479444)
			(xy 369.02517 -29.504132) (xy 369.024684 -29.531383) (xy 369.016928 -29.585331) (xy 369.001573 -29.637626)
			(xy 368.978931 -29.687203) (xy 368.949465 -29.733053) (xy 368.913774 -29.774244) (xy 368.872583 -29.809935)
			(xy 368.826733 -29.839401) (xy 368.777156 -29.862043) (xy 368.724861 -29.877398) (xy 368.670913 -29.885154)
			(xy 368.616411 -29.885154) (xy 368.562463 -29.877398) (xy 368.510168 -29.862043) (xy 368.460591 -29.839401)
			(xy 368.414741 -29.809935) (xy 368.37355 -29.774244) (xy 368.337859 -29.733053) (xy 368.308393 -29.687203)
			(xy 368.285751 -29.637626) (xy 368.270396 -29.585331) (xy 368.26264 -29.531383) (xy 368.262154 -29.504132)
			(xy 367.603339 -29.504132) (xy 367.615459 -29.522991) (xy 367.638101 -29.572568) (xy 367.653456 -29.624863)
			(xy 367.661212 -29.678811) (xy 367.661698 -29.706062) (xy 367.661226 -29.734244) (xy 367.652919 -29.789994)
			(xy 367.636508 -29.843917) (xy 367.612351 -29.894843) (xy 367.580971 -29.941666) (xy 367.562384 -29.962856)
			(xy 367.555018 -29.970984) (xy 367.548414 -29.991812) (xy 367.559844 -30.09011) (xy 367.571274 -30.108652)
			(xy 367.580418 -30.115002) (xy 367.605734 -30.132786) (xy 367.652263 -30.173566) (xy 367.693502 -30.219688)
			(xy 367.728841 -30.270473) (xy 367.757758 -30.32517) (xy 367.779825 -30.382971) (xy 367.794717 -30.443022)
			(xy 367.802215 -30.504437) (xy 367.802668 -30.535372) (xy 367.802166 -30.567333) (xy 367.794155 -30.630751)
			(xy 367.778258 -30.692665) (xy 367.754726 -30.752098) (xy 367.723932 -30.808113) (xy 367.686359 -30.859828)
			(xy 367.642602 -30.906425) (xy 367.593349 -30.94717) (xy 367.539378 -30.981421) (xy 367.481539 -31.008638)
			(xy 367.420746 -31.028391) (xy 367.357956 -31.040369) (xy 367.29416 -31.044383) (xy 367.230364 -31.040369)
			(xy 367.167574 -31.028391) (xy 367.106781 -31.008638) (xy 367.048942 -30.981421) (xy 366.994971 -30.94717)
			(xy 366.945718 -30.906425) (xy 366.901961 -30.859828) (xy 366.864388 -30.808113) (xy 366.833594 -30.752098)
			(xy 366.810062 -30.692665) (xy 366.794165 -30.630751) (xy 366.786154 -30.567333) (xy 366.785652 -30.535372)
			(xy 356.613397 -30.535372) (xy 356.59682 -30.545964) (xy 356.547441 -30.568395) (xy 356.495383 -30.583604)
			(xy 356.441695 -30.591284) (xy 356.414578 -30.59176) (xy 356.387322 -30.591365) (xy 356.333366 -30.583604)
			(xy 356.281064 -30.568243) (xy 356.231481 -30.545594) (xy 356.185625 -30.51612) (xy 356.144432 -30.480419)
			(xy 356.108738 -30.439218) (xy 356.079272 -30.393358) (xy 356.056633 -30.34377) (xy 356.041281 -30.291465)
			(xy 356.03353 -30.237508) (xy 356.03307 -30.210252) (xy 346.901819 -30.210252) (xy 346.920776 -30.228054)
			(xy 346.96152 -30.277308) (xy 346.995771 -30.33128) (xy 347.022987 -30.389119) (xy 347.042739 -30.449913)
			(xy 347.054717 -30.512704) (xy 347.058731 -30.5765) (xy 347.054717 -30.640296) (xy 347.042739 -30.703087)
			(xy 347.022987 -30.763881) (xy 346.995771 -30.82172) (xy 346.96152 -30.875692) (xy 346.920776 -30.924946)
			(xy 346.874179 -30.968705) (xy 346.822466 -31.00628) (xy 346.766452 -31.037077) (xy 346.707019 -31.06061)
			(xy 346.645105 -31.07651) (xy 346.581687 -31.084524) (xy 346.549726 -31.085028) (xy 346.518199 -31.084582)
			(xy 346.455632 -31.076767) (xy 346.394511 -31.061279) (xy 346.335772 -31.038355) (xy 346.280317 -31.008347)
			(xy 346.228996 -30.971715) (xy 346.182597 -30.929021) (xy 346.14183 -30.880919) (xy 346.107321 -30.828148)
			(xy 346.093034 -30.80004) (xy 346.085855 -30.786566) (xy 346.064959 -30.764327) (xy 346.038433 -30.749242)
			(xy 346.008637 -30.742653) (xy 345.978223 -30.745149) (xy 345.949899 -30.756505) (xy 345.926186 -30.775713)
			(xy 345.917266 -30.788102) (xy 345.901996 -30.810129) (xy 345.86632 -30.850126) (xy 345.825398 -30.884738)
			(xy 345.780037 -30.913284) (xy 345.731127 -30.935202) (xy 345.679632 -30.950062) (xy 345.626564 -30.95757)
			(xy 345.599766 -30.958028) (xy 345.572518 -30.957499) (xy 345.518577 -30.949739) (xy 345.466289 -30.934382)
			(xy 345.416718 -30.91174) (xy 345.370875 -30.882275) (xy 345.329691 -30.846585) (xy 345.294005 -30.805398)
			(xy 345.264543 -30.759552) (xy 345.241906 -30.709979) (xy 345.226553 -30.65769) (xy 345.218798 -30.603748)
			(xy 322.853118 -30.603748) (xy 322.856127 -30.61301) (xy 322.868106 -30.675802) (xy 322.87212 -30.7396)
			(xy 322.868106 -30.803398) (xy 322.856127 -30.86619) (xy 322.836373 -30.926986) (xy 322.809155 -30.984827)
			(xy 322.774902 -31.038799) (xy 322.734154 -31.088053) (xy 322.687554 -31.131812) (xy 322.635838 -31.169385)
			(xy 322.57982 -31.20018) (xy 322.520383 -31.22371) (xy 322.458467 -31.239606) (xy 322.395046 -31.247616)
			(xy 322.363084 -31.248096) (xy 322.330935 -31.247573) (xy 322.267148 -31.239483) (xy 322.204891 -31.22341)
			(xy 322.14516 -31.19961) (xy 322.088909 -31.168463) (xy 322.037038 -31.130468) (xy 321.990375 -31.086232)
			(xy 321.969638 -31.06166) (xy 321.963186 -31.054395) (xy 321.946198 -31.044996) (xy 321.936618 -31.043372)
			(xy 321.866768 -31.03499) (xy 321.857042 -31.034276) (xy 321.838235 -31.03938) (xy 321.830192 -31.044896)
			(xy 321.829938 -31.044896) (xy 321.807824 -31.060879) (xy 321.759941 -31.087036) (xy 321.708821 -31.10611)
			(xy 321.655507 -31.117713) (xy 321.601084 -31.121607) (xy 321.546661 -31.117713) (xy 321.493347 -31.10611)
			(xy 321.442227 -31.087036) (xy 321.394344 -31.060879) (xy 321.37223 -31.044896) (xy 321.371976 -31.044896)
			(xy 321.363938 -31.039365) (xy 321.345128 -31.034256) (xy 321.3354 -31.03499) (xy 321.26555 -31.043372)
			(xy 321.255985 -31.045041) (xy 321.239012 -31.054432) (xy 321.23253 -31.06166) (xy 321.211773 -31.086214)
			(xy 321.165105 -31.130441) (xy 321.113234 -31.168432) (xy 321.056987 -31.199581) (xy 320.997263 -31.223391)
			(xy 320.935013 -31.239482) (xy 320.871232 -31.247598) (xy 320.839084 -31.248096) (xy 320.807123 -31.247617)
			(xy 320.743705 -31.239604) (xy 320.681791 -31.223705) (xy 320.622358 -31.200172) (xy 320.566343 -31.169376)
			(xy 320.51463 -31.131803) (xy 320.468033 -31.088044) (xy 320.427288 -31.038791) (xy 320.393038 -30.984819)
			(xy 320.365821 -30.92698) (xy 320.346069 -30.866186) (xy 320.334091 -30.803396) (xy 320.330077 -30.7396)
			(xy 275.0947 -30.7396) (xy 275.0947 -31.429706) (xy 314.379354 -31.429706) (xy 314.383425 -31.374084)
			(xy 314.395551 -31.319647) (xy 314.415474 -31.267556) (xy 314.44277 -31.218921) (xy 314.476856 -31.174778)
			(xy 314.517005 -31.136069) (xy 314.562363 -31.103618) (xy 314.611963 -31.078117) (xy 314.664747 -31.06011)
			(xy 314.71959 -31.04998) (xy 314.775324 -31.047943) (xy 314.830761 -31.054043) (xy 314.884718 -31.068149)
			(xy 314.936047 -31.089961) (xy 314.983653 -31.119015) (xy 315.026521 -31.15469) (xy 315.063738 -31.196227)
			(xy 315.094511 -31.24274) (xy 315.118183 -31.293237) (xy 315.134251 -31.346644) (xy 315.142371 -31.40182)
			(xy 315.14288 -31.429706) (xy 315.142371 -31.457592) (xy 315.134251 -31.512768) (xy 315.118183 -31.566175)
			(xy 315.094511 -31.616672) (xy 315.063738 -31.663185) (xy 315.026521 -31.704722) (xy 315.013369 -31.715667)
			(xy 317.676016 -31.715667) (xy 317.676016 -31.651745) (xy 317.684027 -31.588327) (xy 317.699924 -31.526413)
			(xy 317.723456 -31.46698) (xy 317.75425 -31.410965) (xy 317.791823 -31.35925) (xy 317.83558 -31.312653)
			(xy 317.884833 -31.271908) (xy 317.938804 -31.237657) (xy 317.996643 -31.21044) (xy 318.057436 -31.190687)
			(xy 318.120226 -31.178709) (xy 318.184022 -31.174696) (xy 318.247818 -31.178709) (xy 318.310608 -31.190687)
			(xy 318.371401 -31.21044) (xy 318.42924 -31.237657) (xy 318.483211 -31.271908) (xy 318.532464 -31.312653)
			(xy 318.576221 -31.35925) (xy 318.613794 -31.410965) (xy 318.644588 -31.46698) (xy 318.66812 -31.526413)
			(xy 318.684017 -31.588327) (xy 318.692028 -31.651745) (xy 318.69253 -31.683706) (xy 318.692028 -31.715667)
			(xy 318.684017 -31.779085) (xy 318.66812 -31.840999) (xy 318.644588 -31.900432) (xy 318.624097 -31.937706)
			(xy 329.987654 -31.937706) (xy 329.991725 -31.882084) (xy 330.003851 -31.827647) (xy 330.023774 -31.775556)
			(xy 330.05107 -31.726921) (xy 330.085156 -31.682778) (xy 330.125305 -31.644069) (xy 330.170663 -31.611618)
			(xy 330.220263 -31.586117) (xy 330.273047 -31.56811) (xy 330.32789 -31.55798) (xy 330.383624 -31.555943)
			(xy 330.439061 -31.562043) (xy 330.493018 -31.576149) (xy 330.544347 -31.597961) (xy 330.591953 -31.627015)
			(xy 330.634821 -31.66269) (xy 330.672038 -31.704227) (xy 330.702811 -31.75074) (xy 330.726483 -31.801237)
			(xy 330.742551 -31.854644) (xy 330.750671 -31.90982) (xy 330.75118 -31.937706) (xy 330.750671 -31.965592)
			(xy 330.742551 -32.020768) (xy 330.726483 -32.074175) (xy 330.702811 -32.124672) (xy 330.672038 -32.171185)
			(xy 330.634821 -32.212722) (xy 330.591953 -32.248397) (xy 330.544347 -32.277451) (xy 330.493018 -32.299263)
			(xy 330.439061 -32.313369) (xy 330.383624 -32.319469) (xy 330.32789 -32.317432) (xy 330.273047 -32.307302)
			(xy 330.220263 -32.289295) (xy 330.170663 -32.263794) (xy 330.125305 -32.231343) (xy 330.085156 -32.192634)
			(xy 330.05107 -32.148491) (xy 330.023774 -32.099856) (xy 330.003851 -32.047765) (xy 329.991725 -31.993328)
			(xy 329.987654 -31.937706) (xy 318.624097 -31.937706) (xy 318.613794 -31.956447) (xy 318.576221 -32.008162)
			(xy 318.532464 -32.054759) (xy 318.483211 -32.095504) (xy 318.42924 -32.129755) (xy 318.371401 -32.156972)
			(xy 318.310608 -32.176725) (xy 318.247818 -32.188703) (xy 318.184022 -32.192717) (xy 318.120226 -32.188703)
			(xy 318.057436 -32.176725) (xy 317.996643 -32.156972) (xy 317.938804 -32.129755) (xy 317.884833 -32.095504)
			(xy 317.83558 -32.054759) (xy 317.791823 -32.008162) (xy 317.75425 -31.956447) (xy 317.723456 -31.900432)
			(xy 317.699924 -31.840999) (xy 317.684027 -31.779085) (xy 317.676016 -31.715667) (xy 315.013369 -31.715667)
			(xy 314.983653 -31.740397) (xy 314.936047 -31.769451) (xy 314.884718 -31.791263) (xy 314.830761 -31.805369)
			(xy 314.775324 -31.811469) (xy 314.71959 -31.809432) (xy 314.664747 -31.799302) (xy 314.611963 -31.781295)
			(xy 314.562363 -31.755794) (xy 314.517005 -31.723343) (xy 314.476856 -31.684634) (xy 314.44277 -31.640491)
			(xy 314.415474 -31.591856) (xy 314.395551 -31.539765) (xy 314.383425 -31.485328) (xy 314.379354 -31.429706)
			(xy 275.0947 -31.429706) (xy 275.0947 -32.733953) (xy 306.433468 -32.733953) (xy 306.433468 -32.670031)
			(xy 306.441479 -32.606613) (xy 306.457376 -32.544699) (xy 306.480908 -32.485266) (xy 306.511702 -32.429251)
			(xy 306.549275 -32.377536) (xy 306.593032 -32.330939) (xy 306.642285 -32.290194) (xy 306.696256 -32.255943)
			(xy 306.754095 -32.228726) (xy 306.814888 -32.208973) (xy 306.877678 -32.196995) (xy 306.941474 -32.192982)
			(xy 307.00527 -32.196995) (xy 307.06806 -32.208973) (xy 307.128853 -32.228726) (xy 307.186692 -32.255943)
			(xy 307.240663 -32.290194) (xy 307.289916 -32.330939) (xy 307.333673 -32.377536) (xy 307.371246 -32.429251)
			(xy 307.40204 -32.485266) (xy 307.425572 -32.544699) (xy 307.441469 -32.606613) (xy 307.44948 -32.670031)
			(xy 307.449982 -32.701992) (xy 307.44948 -32.733953) (xy 307.441469 -32.797371) (xy 307.425572 -32.859285)
			(xy 307.40204 -32.918718) (xy 307.371246 -32.974733) (xy 307.333673 -33.026448) (xy 307.289916 -33.073045)
			(xy 307.240663 -33.11379) (xy 307.186692 -33.148041) (xy 307.128853 -33.175258) (xy 307.06806 -33.195011)
			(xy 307.00527 -33.206989) (xy 306.941474 -33.211003) (xy 306.877678 -33.206989) (xy 306.814888 -33.195011)
			(xy 306.754095 -33.175258) (xy 306.696256 -33.148041) (xy 306.642285 -33.11379) (xy 306.593032 -33.073045)
			(xy 306.549275 -33.026448) (xy 306.511702 -32.974733) (xy 306.480908 -32.918718) (xy 306.457376 -32.859285)
			(xy 306.441479 -32.797371) (xy 306.433468 -32.733953) (xy 275.0947 -32.733953) (xy 275.0947 -34.001964)
			(xy 292.65221 -34.001964) (xy 292.656162 -33.910171) (xy 292.667992 -33.819057) (xy 292.687609 -33.729297)
			(xy 292.714871 -33.641556) (xy 292.749574 -33.556484) (xy 292.791462 -33.474709) (xy 292.840225 -33.396838)
			(xy 292.895501 -33.323448) (xy 292.956882 -33.255081) (xy 293.023913 -33.192243) (xy 293.096097 -33.135401)
			(xy 293.172901 -33.084974) (xy 293.253755 -33.041336) (xy 293.338061 -33.00481) (xy 293.425195 -32.975667)
			(xy 293.514512 -32.954122) (xy 293.60535 -32.940336) (xy 293.697037 -32.934409) (xy 293.788894 -32.936386)
			(xy 293.880242 -32.946252) (xy 293.970402 -32.963934) (xy 294.05871 -32.989301) (xy 294.144509 -33.022166)
			(xy 294.227166 -33.062285) (xy 294.306068 -33.109361) (xy 294.380631 -33.163045) (xy 294.450303 -33.222941)
			(xy 294.514568 -33.288604) (xy 294.566721 -33.351978) (xy 309.607966 -33.351978) (xy 309.608516 -33.317937)
			(xy 309.617592 -33.250462) (xy 309.63559 -33.184802) (xy 309.662191 -33.122131) (xy 309.696917 -33.063571)
			(xy 309.739148 -33.010169) (xy 309.788127 -32.96288) (xy 309.81523 -32.942276) (xy 309.822669 -32.936346)
			(xy 309.832848 -32.920291) (xy 309.835042 -32.911034) (xy 309.840884 -32.880554) (xy 309.842259 -32.871088)
			(xy 309.838739 -32.852301) (xy 309.834026 -32.843978) (xy 309.815435 -32.813393) (xy 309.78609 -32.748112)
			(xy 309.766198 -32.679358) (xy 309.756152 -32.608493) (xy 309.75554 -32.572706) (xy 309.756042 -32.540745)
			(xy 309.764053 -32.477327) (xy 309.77995 -32.415413) (xy 309.803482 -32.35598) (xy 309.834276 -32.299965)
			(xy 309.871849 -32.24825) (xy 309.915606 -32.201653) (xy 309.964859 -32.160908) (xy 310.01883 -32.126657)
			(xy 310.076669 -32.09944) (xy 310.137462 -32.079687) (xy 310.200252 -32.067709) (xy 310.264048 -32.063696)
			(xy 310.327844 -32.067709) (xy 310.390634 -32.079687) (xy 310.451427 -32.09944) (xy 310.509266 -32.126657)
			(xy 310.563237 -32.160908) (xy 310.61249 -32.201653) (xy 310.656247 -32.24825) (xy 310.69382 -32.299965)
			(xy 310.724614 -32.35598) (xy 310.748146 -32.415413) (xy 310.764043 -32.477327) (xy 310.772054 -32.540745)
			(xy 310.772556 -32.572706) (xy 310.77202 -32.604667) (xy 312.843666 -32.604667) (xy 312.843666 -32.540745)
			(xy 312.851677 -32.477327) (xy 312.867574 -32.415413) (xy 312.891106 -32.35598) (xy 312.9219 -32.299965)
			(xy 312.959473 -32.24825) (xy 313.00323 -32.201653) (xy 313.052483 -32.160908) (xy 313.106454 -32.126657)
			(xy 313.164293 -32.09944) (xy 313.225086 -32.079687) (xy 313.287876 -32.067709) (xy 313.351672 -32.063696)
			(xy 313.415468 -32.067709) (xy 313.478258 -32.079687) (xy 313.539051 -32.09944) (xy 313.59689 -32.126657)
			(xy 313.650861 -32.160908) (xy 313.700114 -32.201653) (xy 313.743871 -32.24825) (xy 313.781444 -32.299965)
			(xy 313.812238 -32.35598) (xy 313.83577 -32.415413) (xy 313.851667 -32.477327) (xy 313.859678 -32.540745)
			(xy 313.86018 -32.572706) (xy 314.379354 -32.572706) (xy 314.383425 -32.517084) (xy 314.395551 -32.462647)
			(xy 314.415474 -32.410556) (xy 314.44277 -32.361921) (xy 314.476856 -32.317778) (xy 314.517005 -32.279069)
			(xy 314.562363 -32.246618) (xy 314.611963 -32.221117) (xy 314.664747 -32.20311) (xy 314.71959 -32.19298)
			(xy 314.775324 -32.190943) (xy 314.830761 -32.197043) (xy 314.884718 -32.211149) (xy 314.936047 -32.232961)
			(xy 314.983653 -32.262015) (xy 315.026521 -32.29769) (xy 315.063738 -32.339227) (xy 315.094511 -32.38574)
			(xy 315.118183 -32.436237) (xy 315.134251 -32.489644) (xy 315.142371 -32.54482) (xy 315.14288 -32.572706)
			(xy 315.142371 -32.600592) (xy 315.134251 -32.655768) (xy 315.118183 -32.709175) (xy 315.094511 -32.759672)
			(xy 315.063738 -32.806185) (xy 315.026521 -32.847722) (xy 314.983653 -32.883397) (xy 314.936047 -32.912451)
			(xy 314.884718 -32.934263) (xy 314.830761 -32.948369) (xy 314.782258 -32.953706) (xy 329.987654 -32.953706)
			(xy 329.991725 -32.898084) (xy 330.003851 -32.843647) (xy 330.023774 -32.791556) (xy 330.05107 -32.742921)
			(xy 330.085156 -32.698778) (xy 330.125305 -32.660069) (xy 330.170663 -32.627618) (xy 330.220263 -32.602117)
			(xy 330.273047 -32.58411) (xy 330.32789 -32.57398) (xy 330.383624 -32.571943) (xy 330.439061 -32.578043)
			(xy 330.493018 -32.592149) (xy 330.544347 -32.613961) (xy 330.591953 -32.643015) (xy 330.634821 -32.67869)
			(xy 330.672038 -32.720227) (xy 330.702811 -32.76674) (xy 330.726483 -32.817237) (xy 330.742551 -32.870644)
			(xy 330.750671 -32.92582) (xy 330.75118 -32.953706) (xy 330.750671 -32.981592) (xy 330.742551 -33.036768)
			(xy 330.726483 -33.090175) (xy 330.702811 -33.140672) (xy 330.672038 -33.187185) (xy 330.634821 -33.228722)
			(xy 330.591953 -33.264397) (xy 330.544347 -33.293451) (xy 330.493018 -33.315263) (xy 330.439061 -33.329369)
			(xy 330.383624 -33.335469) (xy 330.32789 -33.333432) (xy 330.273047 -33.323302) (xy 330.220263 -33.305295)
			(xy 330.170663 -33.279794) (xy 330.125305 -33.247343) (xy 330.085156 -33.208634) (xy 330.05107 -33.164491)
			(xy 330.023774 -33.115856) (xy 330.003851 -33.063765) (xy 329.991725 -33.009328) (xy 329.987654 -32.953706)
			(xy 314.782258 -32.953706) (xy 314.775324 -32.954469) (xy 314.71959 -32.952432) (xy 314.664747 -32.942302)
			(xy 314.611963 -32.924295) (xy 314.562363 -32.898794) (xy 314.517005 -32.866343) (xy 314.476856 -32.827634)
			(xy 314.44277 -32.783491) (xy 314.415474 -32.734856) (xy 314.395551 -32.682765) (xy 314.383425 -32.628328)
			(xy 314.379354 -32.572706) (xy 313.86018 -32.572706) (xy 313.859678 -32.604667) (xy 313.851667 -32.668085)
			(xy 313.83577 -32.729999) (xy 313.812238 -32.789432) (xy 313.781444 -32.845447) (xy 313.743871 -32.897162)
			(xy 313.700114 -32.943759) (xy 313.650861 -32.984504) (xy 313.59689 -33.018755) (xy 313.539051 -33.045972)
			(xy 313.478258 -33.065725) (xy 313.415468 -33.077703) (xy 313.351672 -33.081717) (xy 313.287876 -33.077703)
			(xy 313.225086 -33.065725) (xy 313.164293 -33.045972) (xy 313.106454 -33.018755) (xy 313.052483 -32.984504)
			(xy 313.00323 -32.943759) (xy 312.959473 -32.897162) (xy 312.9219 -32.845447) (xy 312.891106 -32.789432)
			(xy 312.867574 -32.729999) (xy 312.851677 -32.668085) (xy 312.843666 -32.604667) (xy 310.77202 -32.604667)
			(xy 310.771985 -32.606746) (xy 310.762912 -32.67422) (xy 310.744916 -32.739879) (xy 310.718319 -32.80255)
			(xy 310.683596 -32.86111) (xy 310.641369 -32.914513) (xy 310.592393 -32.961803) (xy 310.565292 -32.982408)
			(xy 310.557863 -32.988348) (xy 310.547678 -33.004396) (xy 310.54548 -33.01365) (xy 310.539638 -33.04413)
			(xy 310.538269 -33.053596) (xy 310.541784 -33.072383) (xy 310.546496 -33.080706) (xy 310.565083 -33.111294)
			(xy 310.594428 -33.176574) (xy 310.614321 -33.245327) (xy 310.624369 -33.316191) (xy 310.624982 -33.351978)
			(xy 310.624408 -33.386266) (xy 310.61519 -33.454221) (xy 310.596931 -33.520322) (xy 310.569961 -33.583373)
			(xy 310.552846 -33.61309) (xy 310.548514 -33.620924) (xy 310.545143 -33.638495) (xy 310.546242 -33.64738)
			(xy 310.551322 -33.677098) (xy 310.55309 -33.685812) (xy 310.561804 -33.701296) (xy 310.56834 -33.707324)
			(xy 310.591934 -33.728092) (xy 310.609839 -33.747667) (xy 312.843666 -33.747667) (xy 312.843666 -33.683745)
			(xy 312.851677 -33.620327) (xy 312.867574 -33.558413) (xy 312.891106 -33.49898) (xy 312.9219 -33.442965)
			(xy 312.959473 -33.39125) (xy 313.00323 -33.344653) (xy 313.052483 -33.303908) (xy 313.106454 -33.269657)
			(xy 313.164293 -33.24244) (xy 313.225086 -33.222687) (xy 313.287876 -33.210709) (xy 313.351672 -33.206696)
			(xy 313.415468 -33.210709) (xy 313.478258 -33.222687) (xy 313.539051 -33.24244) (xy 313.59689 -33.269657)
			(xy 313.650861 -33.303908) (xy 313.700114 -33.344653) (xy 313.743871 -33.39125) (xy 313.781444 -33.442965)
			(xy 313.812238 -33.49898) (xy 313.83577 -33.558413) (xy 313.851667 -33.620327) (xy 313.859678 -33.683745)
			(xy 313.86018 -33.715706) (xy 314.379354 -33.715706) (xy 314.383425 -33.660084) (xy 314.395551 -33.605647)
			(xy 314.415474 -33.553556) (xy 314.44277 -33.504921) (xy 314.476856 -33.460778) (xy 314.517005 -33.422069)
			(xy 314.562363 -33.389618) (xy 314.611963 -33.364117) (xy 314.664747 -33.34611) (xy 314.71959 -33.33598)
			(xy 314.775324 -33.333943) (xy 314.830761 -33.340043) (xy 314.884718 -33.354149) (xy 314.936047 -33.375961)
			(xy 314.983653 -33.405015) (xy 315.026521 -33.44069) (xy 315.047855 -33.4645) (xy 330.984606 -33.4645)
			(xy 330.984992 -33.434159) (xy 330.992211 -33.373908) (xy 331.006559 -33.314946) (xy 331.027831 -33.258115)
			(xy 331.055724 -33.204223) (xy 331.08984 -33.15404) (xy 331.129694 -33.108279) (xy 331.174716 -33.067594)
			(xy 331.199236 -33.049718) (xy 331.208779 -33.042047) (xy 331.219923 -33.020288) (xy 331.220572 -33.008062)
			(xy 331.220572 -32.925258) (xy 331.219947 -32.913027) (xy 331.208789 -32.891267) (xy 331.199236 -32.883602)
			(xy 331.174715 -32.865733) (xy 331.129713 -32.825032) (xy 331.089878 -32.779263) (xy 331.055776 -32.729076)
			(xy 331.027893 -32.675186) (xy 331.006625 -32.618358) (xy 330.992276 -32.559403) (xy 330.985048 -32.499158)
			(xy 330.984606 -32.46882) (xy 330.985072 -32.435647) (xy 330.993687 -32.369863) (xy 331.010788 -32.305758)
			(xy 331.036083 -32.244423) (xy 331.069142 -32.1869) (xy 331.109403 -32.134167) (xy 331.156183 -32.087119)
			(xy 331.208685 -32.046557) (xy 331.237082 -32.0294) (xy 331.244532 -32.024603) (xy 331.255831 -32.010968)
			(xy 331.261846 -31.994312) (xy 331.262228 -31.985458) (xy 331.262228 -31.898082) (xy 331.26198 -31.889207)
			(xy 331.255961 -31.872511) (xy 331.244588 -31.858886) (xy 331.237082 -31.85414) (xy 331.208691 -31.836982)
			(xy 331.156212 -31.796402) (xy 331.109454 -31.749345) (xy 331.06921 -31.696608) (xy 331.036162 -31.639088)
			(xy 331.010872 -31.577759) (xy 330.993769 -31.513664) (xy 330.985143 -31.447889) (xy 330.984606 -31.41472)
			(xy 330.985108 -31.382759) (xy 330.993119 -31.319341) (xy 331.009016 -31.257427) (xy 331.032548 -31.197994)
			(xy 331.063342 -31.141979) (xy 331.100915 -31.090264) (xy 331.144672 -31.043667) (xy 331.193925 -31.002922)
			(xy 331.247896 -30.968671) (xy 331.305735 -30.941454) (xy 331.366528 -30.921701) (xy 331.429318 -30.909723)
			(xy 331.493114 -30.90571) (xy 331.55691 -30.909723) (xy 331.6197 -30.921701) (xy 331.680493 -30.941454)
			(xy 331.738332 -30.968671) (xy 331.792303 -31.002922) (xy 331.841556 -31.043667) (xy 331.885313 -31.090264)
			(xy 331.922886 -31.141979) (xy 331.937797 -31.169102) (xy 376.508262 -31.169102) (xy 376.512333 -31.11348)
			(xy 376.524459 -31.059043) (xy 376.544382 -31.006952) (xy 376.571678 -30.958317) (xy 376.605764 -30.914174)
			(xy 376.645913 -30.875465) (xy 376.691271 -30.843014) (xy 376.740871 -30.817513) (xy 376.793655 -30.799506)
			(xy 376.848498 -30.789376) (xy 376.904232 -30.787339) (xy 376.959669 -30.793439) (xy 377.013626 -30.807545)
			(xy 377.064955 -30.829357) (xy 377.112561 -30.858411) (xy 377.155429 -30.894086) (xy 377.192646 -30.935623)
			(xy 377.223419 -30.982136) (xy 377.247091 -31.032633) (xy 377.263159 -31.08604) (xy 377.271279 -31.141216)
			(xy 377.271788 -31.169102) (xy 377.271279 -31.196988) (xy 377.263159 -31.252164) (xy 377.247091 -31.305571)
			(xy 377.223419 -31.356068) (xy 377.192646 -31.402581) (xy 377.169283 -31.428656) (xy 378.647122 -31.428656)
			(xy 378.654878 -31.3747) (xy 378.670234 -31.322396) (xy 378.692878 -31.27281) (xy 378.722348 -31.226952)
			(xy 378.758045 -31.185754) (xy 378.799241 -31.150056) (xy 378.845098 -31.120585) (xy 378.894683 -31.097939)
			(xy 378.946986 -31.082581) (xy 379.000942 -31.074823) (xy 379.028198 -31.07436) (xy 379.02896 -31.07436)
			(xy 379.048599 -31.074636) (xy 379.087665 -31.078709) (xy 379.106938 -31.082488) (xy 379.120233 -31.084882)
			(xy 379.147194 -31.083355) (xy 379.17281 -31.074805) (xy 379.195283 -31.059832) (xy 379.213038 -31.039485)
			(xy 379.22483 -31.015191) (xy 379.229832 -30.988653) (xy 379.227693 -30.961734) (xy 379.223524 -30.948884)
			(xy 379.214085 -30.921342) (xy 379.200856 -30.864642) (xy 379.194205 -30.8068) (xy 379.193806 -30.777688)
			(xy 379.193806 -30.777434) (xy 379.194232 -30.745891) (xy 379.202031 -30.683288) (xy 379.217514 -30.62213)
			(xy 379.240443 -30.563358) (xy 379.270465 -30.507873) (xy 379.30712 -30.456527) (xy 379.349845 -30.41011)
			(xy 379.397983 -30.369334) (xy 379.450795 -30.334826) (xy 379.50747 -30.307115) (xy 379.567138 -30.286628)
			(xy 379.628881 -30.273678) (xy 379.691752 -30.268465) (xy 379.754785 -30.271068) (xy 379.817012 -30.281449)
			(xy 379.877477 -30.299447) (xy 379.935252 -30.324786) (xy 379.989448 -30.357076) (xy 380.039235 -30.395822)
			(xy 380.083846 -30.440429) (xy 380.101961 -30.463701) (xy 384.51891 -30.463701) (xy 384.51891 -30.399779)
			(xy 384.526921 -30.336361) (xy 384.542818 -30.274447) (xy 384.56635 -30.215014) (xy 384.597144 -30.158999)
			(xy 384.634717 -30.107284) (xy 384.678474 -30.060687) (xy 384.727727 -30.019942) (xy 384.781698 -29.985691)
			(xy 384.839537 -29.958474) (xy 384.90033 -29.938721) (xy 384.96312 -29.926743) (xy 385.026916 -29.92273)
			(xy 385.090712 -29.926743) (xy 385.153502 -29.938721) (xy 385.214295 -29.958474) (xy 385.272134 -29.985691)
			(xy 385.326105 -30.019942) (xy 385.375358 -30.060687) (xy 385.419115 -30.107284) (xy 385.456688 -30.158999)
			(xy 385.487482 -30.215014) (xy 385.511014 -30.274447) (xy 385.526911 -30.336361) (xy 385.534922 -30.399779)
			(xy 385.535424 -30.43174) (xy 385.535017 -30.457648) (xy 386.4389 -30.457648) (xy 386.442971 -30.402026)
			(xy 386.455097 -30.347589) (xy 386.47502 -30.295498) (xy 386.502316 -30.246863) (xy 386.536402 -30.20272)
			(xy 386.576551 -30.164011) (xy 386.621909 -30.13156) (xy 386.671509 -30.106059) (xy 386.724293 -30.088052)
			(xy 386.779136 -30.077922) (xy 386.83487 -30.075885) (xy 386.890307 -30.081985) (xy 386.944264 -30.096091)
			(xy 386.995593 -30.117903) (xy 387.043199 -30.146957) (xy 387.086067 -30.182632) (xy 387.123284 -30.224169)
			(xy 387.154057 -30.270682) (xy 387.177729 -30.321179) (xy 387.193797 -30.374586) (xy 387.201917 -30.429762)
			(xy 387.202426 -30.457648) (xy 387.201917 -30.485534) (xy 387.193797 -30.54071) (xy 387.177729 -30.594117)
			(xy 387.154057 -30.644614) (xy 387.123284 -30.691127) (xy 387.086067 -30.732664) (xy 387.043199 -30.768339)
			(xy 386.995593 -30.797393) (xy 386.944264 -30.819205) (xy 386.890307 -30.833311) (xy 386.83487 -30.839411)
			(xy 386.779136 -30.837374) (xy 386.724293 -30.827244) (xy 386.671509 -30.809237) (xy 386.621909 -30.783736)
			(xy 386.576551 -30.751285) (xy 386.536402 -30.712576) (xy 386.502316 -30.668433) (xy 386.47502 -30.619798)
			(xy 386.455097 -30.567707) (xy 386.442971 -30.51327) (xy 386.4389 -30.457648) (xy 385.535017 -30.457648)
			(xy 385.534922 -30.463701) (xy 385.526911 -30.527119) (xy 385.511014 -30.589033) (xy 385.487482 -30.648466)
			(xy 385.456688 -30.704481) (xy 385.419115 -30.756196) (xy 385.375358 -30.802793) (xy 385.326105 -30.843538)
			(xy 385.272134 -30.877789) (xy 385.214295 -30.905006) (xy 385.153502 -30.924759) (xy 385.090712 -30.936737)
			(xy 385.026916 -30.940751) (xy 384.96312 -30.936737) (xy 384.90033 -30.924759) (xy 384.839537 -30.905006)
			(xy 384.781698 -30.877789) (xy 384.727727 -30.843538) (xy 384.678474 -30.802793) (xy 384.634717 -30.756196)
			(xy 384.597144 -30.704481) (xy 384.56635 -30.648466) (xy 384.542818 -30.589033) (xy 384.526921 -30.527119)
			(xy 384.51891 -30.463701) (xy 380.101961 -30.463701) (xy 380.122597 -30.490212) (xy 380.154892 -30.544406)
			(xy 380.180237 -30.602178) (xy 380.19824 -30.662641) (xy 380.208627 -30.724867) (xy 380.211236 -30.7879)
			(xy 380.206029 -30.850771) (xy 380.193085 -30.912516) (xy 380.176954 -30.959509) (xy 424.459394 -30.959509)
			(xy 424.459394 -30.895587) (xy 424.467405 -30.832169) (xy 424.483302 -30.770255) (xy 424.506834 -30.710822)
			(xy 424.537628 -30.654807) (xy 424.575201 -30.603092) (xy 424.618958 -30.556495) (xy 424.668211 -30.51575)
			(xy 424.722182 -30.481499) (xy 424.780021 -30.454282) (xy 424.840814 -30.434529) (xy 424.903604 -30.422551)
			(xy 424.9674 -30.418538) (xy 425.031196 -30.422551) (xy 425.093986 -30.434529) (xy 425.154779 -30.454282)
			(xy 425.212618 -30.481499) (xy 425.266589 -30.51575) (xy 425.315842 -30.556495) (xy 425.359599 -30.603092)
			(xy 425.397172 -30.654807) (xy 425.407475 -30.673548) (xy 427.043342 -30.673548) (xy 427.043833 -30.641362)
			(xy 427.05196 -30.577506) (xy 427.068076 -30.515184) (xy 427.091926 -30.455393) (xy 427.123127 -30.399089)
			(xy 427.161181 -30.34717) (xy 427.20548 -30.300465) (xy 427.255317 -30.259722) (xy 427.309896 -30.225592)
			(xy 427.368344 -30.198618) (xy 427.429727 -30.179232) (xy 427.493065 -30.167745) (xy 427.52518 -30.165548)
			(xy 427.533794 -30.164738) (xy 427.549765 -30.15812) (xy 427.556422 -30.152594) (xy 427.57852 -30.132782)
			(xy 427.584727 -30.126818) (xy 427.593029 -30.111748) (xy 427.594776 -30.103318) (xy 427.599531 -30.076894)
			(xy 427.615607 -30.025667) (xy 427.638711 -29.977202) (xy 427.668386 -29.932457) (xy 427.704044 -29.892319)
			(xy 427.744982 -29.85758) (xy 427.790388 -29.828928) (xy 427.839365 -29.80693) (xy 427.890944 -29.79202)
			(xy 427.944105 -29.784495) (xy 427.97095 -29.78404) (xy 427.998204 -29.784502) (xy 428.052157 -29.792253)
			(xy 428.104458 -29.807605) (xy 428.154041 -29.830246) (xy 428.199897 -29.859713) (xy 428.241091 -29.895407)
			(xy 428.276786 -29.936601) (xy 428.305055 -29.980593) (xy 434.463438 -29.980593) (xy 434.463438 -29.916671)
			(xy 434.471449 -29.853253) (xy 434.487346 -29.791339) (xy 434.510878 -29.731906) (xy 434.541672 -29.675891)
			(xy 434.579245 -29.624176) (xy 434.623002 -29.577579) (xy 434.672255 -29.536834) (xy 434.726226 -29.502583)
			(xy 434.784065 -29.475366) (xy 434.844858 -29.455613) (xy 434.907648 -29.443635) (xy 434.971444 -29.439622)
			(xy 435.03524 -29.443635) (xy 435.09803 -29.455613) (xy 435.158823 -29.475366) (xy 435.216662 -29.502583)
			(xy 435.270633 -29.536834) (xy 435.319886 -29.577579) (xy 435.363643 -29.624176) (xy 435.401216 -29.675891)
			(xy 435.43201 -29.731906) (xy 435.455542 -29.791339) (xy 435.471439 -29.853253) (xy 435.47945 -29.916671)
			(xy 435.479952 -29.948632) (xy 435.47945 -29.980593) (xy 435.471439 -30.044011) (xy 435.455542 -30.105925)
			(xy 435.43201 -30.165358) (xy 435.401216 -30.221373) (xy 435.363643 -30.273088) (xy 435.319886 -30.319685)
			(xy 435.270633 -30.36043) (xy 435.216662 -30.394681) (xy 435.158823 -30.421898) (xy 435.09803 -30.441651)
			(xy 435.03524 -30.453629) (xy 434.971444 -30.457643) (xy 434.907648 -30.453629) (xy 434.844858 -30.441651)
			(xy 434.784065 -30.421898) (xy 434.726226 -30.394681) (xy 434.672255 -30.36043) (xy 434.623002 -30.319685)
			(xy 434.579245 -30.273088) (xy 434.541672 -30.221373) (xy 434.510878 -30.165358) (xy 434.487346 -30.105925)
			(xy 434.471449 -30.044011) (xy 434.463438 -29.980593) (xy 428.305055 -29.980593) (xy 428.306253 -29.982457)
			(xy 428.328894 -30.03204) (xy 428.344246 -30.084341) (xy 428.351998 -30.138294) (xy 428.352458 -30.165548)
			(xy 428.351924 -30.194552) (xy 428.343157 -30.251893) (xy 428.325803 -30.307243) (xy 428.300262 -30.359325)
			(xy 428.267125 -30.406935) (xy 428.227156 -30.448975) (xy 428.181278 -30.484472) (xy 428.130552 -30.512609)
			(xy 428.103538 -30.52318) (xy 428.095679 -30.526495) (xy 428.082566 -30.537387) (xy 428.077884 -30.544516)
			(xy 428.06239 -30.57017) (xy 428.058213 -30.577788) (xy 428.054709 -30.594795) (xy 428.055532 -30.603444)
			(xy 428.057799 -30.620881) (xy 428.060216 -30.655965) (xy 428.060358 -30.673548) (xy 428.059694 -30.710469)
			(xy 428.048978 -30.78353) (xy 428.039022 -30.81909) (xy 428.039022 -30.819344) (xy 428.036529 -30.829116)
			(xy 428.038631 -30.849158) (xy 428.043086 -30.858206) (xy 428.078138 -30.921706) (xy 428.083344 -30.930331)
			(xy 428.099061 -30.942906) (xy 428.108618 -30.94609) (xy 428.108872 -30.94609) (xy 428.140453 -30.95556)
			(xy 428.149682 -30.959509) (xy 430.047394 -30.959509) (xy 430.047394 -30.895587) (xy 430.055405 -30.832169)
			(xy 430.071302 -30.770255) (xy 430.094834 -30.710822) (xy 430.125628 -30.654807) (xy 430.163201 -30.603092)
			(xy 430.206958 -30.556495) (xy 430.256211 -30.51575) (xy 430.310182 -30.481499) (xy 430.368021 -30.454282)
			(xy 430.428814 -30.434529) (xy 430.491604 -30.422551) (xy 430.5554 -30.418538) (xy 430.619196 -30.422551)
			(xy 430.681986 -30.434529) (xy 430.742779 -30.454282) (xy 430.800618 -30.481499) (xy 430.854589 -30.51575)
			(xy 430.903842 -30.556495) (xy 430.947599 -30.603092) (xy 430.985172 -30.654807) (xy 431.015966 -30.710822)
			(xy 431.039498 -30.770255) (xy 431.055395 -30.832169) (xy 431.063406 -30.895587) (xy 431.063908 -30.927548)
			(xy 431.063406 -30.959509) (xy 431.055395 -31.022927) (xy 431.039498 -31.084841) (xy 431.015966 -31.144274)
			(xy 430.985172 -31.200289) (xy 430.947599 -31.252004) (xy 430.903842 -31.298601) (xy 430.854589 -31.339346)
			(xy 430.800618 -31.373597) (xy 430.742779 -31.400814) (xy 430.681986 -31.420567) (xy 430.619196 -31.432545)
			(xy 430.5554 -31.436559) (xy 430.491604 -31.432545) (xy 430.428814 -31.420567) (xy 430.368021 -31.400814)
			(xy 430.310182 -31.373597) (xy 430.256211 -31.339346) (xy 430.206958 -31.298601) (xy 430.163201 -31.252004)
			(xy 430.125628 -31.200289) (xy 430.094834 -31.144274) (xy 430.071302 -31.084841) (xy 430.055405 -31.022927)
			(xy 430.047394 -30.959509) (xy 428.149682 -30.959509) (xy 428.201069 -30.981498) (xy 428.257824 -31.015051)
			(xy 428.309767 -31.055658) (xy 428.356027 -31.102638) (xy 428.395827 -31.155201) (xy 428.428501 -31.212468)
			(xy 428.4535 -31.273476) (xy 428.470404 -31.337204) (xy 428.478932 -31.402582) (xy 428.479458 -31.435548)
			(xy 428.479458 -31.435802) (xy 428.479037 -31.46601) (xy 428.471896 -31.526003) (xy 428.457692 -31.584726)
			(xy 428.436626 -31.641351) (xy 428.408993 -31.695078) (xy 428.375185 -31.74515) (xy 428.35576 -31.768288)
			(xy 428.350091 -31.775342) (xy 428.343718 -31.792267) (xy 428.343314 -31.801308) (xy 428.343314 -31.831788)
			(xy 428.343725 -31.840826) (xy 428.35011 -31.857742) (xy 428.35576 -31.864808) (xy 428.375153 -31.88797)
			(xy 428.408944 -31.938047) (xy 428.436569 -31.991772) (xy 428.457638 -32.04839) (xy 428.471855 -32.107104)
			(xy 428.47902 -32.167089) (xy 428.479458 -32.197294) (xy 428.479458 -32.197548) (xy 428.478956 -32.229509)
			(xy 430.047394 -32.229509) (xy 430.047394 -32.165587) (xy 430.055405 -32.102169) (xy 430.071302 -32.040255)
			(xy 430.094834 -31.980822) (xy 430.125628 -31.924807) (xy 430.163201 -31.873092) (xy 430.206958 -31.826495)
			(xy 430.256211 -31.78575) (xy 430.310182 -31.751499) (xy 430.368021 -31.724282) (xy 430.428814 -31.704529)
			(xy 430.491604 -31.692551) (xy 430.5554 -31.688538) (xy 430.619196 -31.692551) (xy 430.681986 -31.704529)
			(xy 430.742779 -31.724282) (xy 430.800618 -31.751499) (xy 430.854589 -31.78575) (xy 430.903842 -31.826495)
			(xy 430.947599 -31.873092) (xy 430.985172 -31.924807) (xy 431.015966 -31.980822) (xy 431.039498 -32.040255)
			(xy 431.055395 -32.102169) (xy 431.063406 -32.165587) (xy 431.063908 -32.197548) (xy 431.063406 -32.229509)
			(xy 431.055395 -32.292927) (xy 431.039498 -32.354841) (xy 431.015966 -32.414274) (xy 430.985172 -32.470289)
			(xy 430.947599 -32.522004) (xy 430.903842 -32.568601) (xy 430.854589 -32.609346) (xy 430.800618 -32.643597)
			(xy 430.742779 -32.670814) (xy 430.681986 -32.690567) (xy 430.619196 -32.702545) (xy 430.5554 -32.706559)
			(xy 430.491604 -32.702545) (xy 430.428814 -32.690567) (xy 430.368021 -32.670814) (xy 430.310182 -32.643597)
			(xy 430.256211 -32.609346) (xy 430.206958 -32.568601) (xy 430.163201 -32.522004) (xy 430.125628 -32.470289)
			(xy 430.094834 -32.414274) (xy 430.071302 -32.354841) (xy 430.055405 -32.292927) (xy 430.047394 -32.229509)
			(xy 428.478956 -32.229509) (xy 428.470945 -32.292927) (xy 428.455048 -32.354841) (xy 428.431516 -32.414274)
			(xy 428.400722 -32.470289) (xy 428.363149 -32.522004) (xy 428.319392 -32.568601) (xy 428.270139 -32.609346)
			(xy 428.216168 -32.643597) (xy 428.158329 -32.670814) (xy 428.097536 -32.690567) (xy 428.034746 -32.702545)
			(xy 427.97095 -32.706559) (xy 427.907154 -32.702545) (xy 427.844364 -32.690567) (xy 427.783571 -32.670814)
			(xy 427.725732 -32.643597) (xy 427.671761 -32.609346) (xy 427.622508 -32.568601) (xy 427.578751 -32.522004)
			(xy 427.541178 -32.470289) (xy 427.510384 -32.414274) (xy 427.486852 -32.354841) (xy 427.470955 -32.292927)
			(xy 427.462944 -32.229509) (xy 427.462442 -32.197548) (xy 427.462442 -32.197294) (xy 427.462861 -32.167086)
			(xy 427.470002 -32.107092) (xy 427.484206 -32.048369) (xy 427.505273 -31.991745) (xy 427.532906 -31.938018)
			(xy 427.566714 -31.887946) (xy 427.58614 -31.864808) (xy 427.591811 -31.857755) (xy 427.598183 -31.840829)
			(xy 427.598586 -31.831788) (xy 427.598586 -31.801308) (xy 427.598177 -31.79227) (xy 427.591791 -31.775354)
			(xy 427.58614 -31.768288) (xy 427.566745 -31.745127) (xy 427.532954 -31.69505) (xy 427.50533 -31.641325)
			(xy 427.484261 -31.584707) (xy 427.470044 -31.525992) (xy 427.46288 -31.466008) (xy 427.462442 -31.435802)
			(xy 427.462442 -31.435548) (xy 427.463106 -31.398627) (xy 427.473821 -31.325566) (xy 427.483778 -31.290006)
			(xy 427.483778 -31.289752) (xy 427.486274 -31.279981) (xy 427.48417 -31.259938) (xy 427.479714 -31.25089)
			(xy 427.444662 -31.18739) (xy 427.439457 -31.178765) (xy 427.423739 -31.16619) (xy 427.414182 -31.163006)
			(xy 427.413928 -31.163006) (xy 427.382346 -31.153539) (xy 427.32173 -31.127601) (xy 427.264975 -31.094047)
			(xy 427.213032 -31.05344) (xy 427.166772 -31.006461) (xy 427.126972 -30.953896) (xy 427.094298 -30.89663)
			(xy 427.069299 -30.835621) (xy 427.052395 -30.771892) (xy 427.043868 -30.706514) (xy 427.043342 -30.673548)
			(xy 425.407475 -30.673548) (xy 425.427966 -30.710822) (xy 425.451498 -30.770255) (xy 425.467395 -30.832169)
			(xy 425.475406 -30.895587) (xy 425.475908 -30.927548) (xy 425.475406 -30.959509) (xy 425.467395 -31.022927)
			(xy 425.451498 -31.084841) (xy 425.427966 -31.144274) (xy 425.397172 -31.200289) (xy 425.359599 -31.252004)
			(xy 425.315842 -31.298601) (xy 425.266589 -31.339346) (xy 425.212618 -31.373597) (xy 425.154779 -31.400814)
			(xy 425.093986 -31.420567) (xy 425.031196 -31.432545) (xy 424.9674 -31.436559) (xy 424.903604 -31.432545)
			(xy 424.840814 -31.420567) (xy 424.780021 -31.400814) (xy 424.722182 -31.373597) (xy 424.668211 -31.339346)
			(xy 424.618958 -31.298601) (xy 424.575201 -31.252004) (xy 424.537628 -31.200289) (xy 424.506834 -31.144274)
			(xy 424.483302 -31.084841) (xy 424.467405 -31.022927) (xy 424.459394 -30.959509) (xy 380.176954 -30.959509)
			(xy 380.172603 -30.972185) (xy 380.144898 -31.028863) (xy 380.110394 -31.081678) (xy 380.069623 -31.12982)
			(xy 380.02321 -31.172549) (xy 379.971868 -31.209209) (xy 379.916386 -31.239237) (xy 379.857615 -31.262172)
			(xy 379.79646 -31.27766) (xy 379.733857 -31.285465) (xy 379.702314 -31.285942) (xy 379.673698 -31.285566)
			(xy 379.616828 -31.279136) (xy 379.56104 -31.266356) (xy 379.533912 -31.25724) (xy 379.521055 -31.253104)
			(xy 379.494126 -31.251129) (xy 379.467623 -31.256293) (xy 379.443405 -31.268233) (xy 379.42317 -31.286112)
			(xy 379.408339 -31.308676) (xy 379.399952 -31.334342) (xy 379.398596 -31.361309) (xy 379.40107 -31.374588)
			(xy 379.405139 -31.39466) (xy 379.409464 -31.435389) (xy 379.409706 -31.455868) (xy 379.409279 -31.483124)
			(xy 379.401526 -31.537081) (xy 379.386173 -31.589385) (xy 379.363532 -31.638972) (xy 379.334064 -31.684832)
			(xy 379.29837 -31.726031) (xy 379.257175 -31.761732) (xy 379.211319 -31.791206) (xy 379.161736 -31.813854)
			(xy 379.109434 -31.829214) (xy 379.055478 -31.836975) (xy 379.000966 -31.836979) (xy 378.94701 -31.829224)
			(xy 378.894706 -31.813869) (xy 378.845119 -31.791227) (xy 378.79926 -31.761758) (xy 378.758062 -31.726063)
			(xy 378.722362 -31.684867) (xy 378.69289 -31.639011) (xy 378.670243 -31.589426) (xy 378.654883 -31.537124)
			(xy 378.647124 -31.483168) (xy 378.647122 -31.428656) (xy 377.169283 -31.428656) (xy 377.155429 -31.444118)
			(xy 377.112561 -31.479793) (xy 377.064955 -31.508847) (xy 377.013626 -31.530659) (xy 376.959669 -31.544765)
			(xy 376.904232 -31.550865) (xy 376.848498 -31.548828) (xy 376.793655 -31.538698) (xy 376.740871 -31.520691)
			(xy 376.691271 -31.49519) (xy 376.645913 -31.462739) (xy 376.605764 -31.42403) (xy 376.571678 -31.379887)
			(xy 376.544382 -31.331252) (xy 376.524459 -31.279161) (xy 376.512333 -31.224724) (xy 376.508262 -31.169102)
			(xy 331.937797 -31.169102) (xy 331.95368 -31.197994) (xy 331.977212 -31.257427) (xy 331.993109 -31.319341)
			(xy 332.00112 -31.382759) (xy 332.001622 -31.41472) (xy 332.001095 -31.447891) (xy 331.992487 -31.513672)
			(xy 331.975395 -31.577774) (xy 331.950109 -31.639108) (xy 331.917058 -31.696631) (xy 331.876805 -31.749366)
			(xy 331.830034 -31.796416) (xy 331.777539 -31.836981) (xy 331.749146 -31.85414) (xy 331.741729 -31.858982)
			(xy 331.730422 -31.872596) (xy 331.724392 -31.889234) (xy 331.724 -31.898082) (xy 331.724 -31.985458)
			(xy 331.724324 -31.994326) (xy 331.730314 -32.011015) (xy 331.741655 -32.024645) (xy 331.749146 -32.0294)
			(xy 331.777518 -32.046589) (xy 331.829995 -32.087166) (xy 331.876753 -32.134219) (xy 331.916998 -32.186951)
			(xy 331.950047 -32.244467) (xy 331.975341 -32.305791) (xy 331.992449 -32.369882) (xy 332.001082 -32.435653)
			(xy 332.001622 -32.46882) (xy 332.001164 -32.499159) (xy 331.993954 -32.559407) (xy 331.990535 -32.573468)
			(xy 370.77345 -32.573468) (xy 370.777521 -32.517846) (xy 370.789647 -32.463409) (xy 370.80957 -32.411318)
			(xy 370.836866 -32.362683) (xy 370.870952 -32.31854) (xy 370.911101 -32.279831) (xy 370.956459 -32.24738)
			(xy 371.006059 -32.221879) (xy 371.058843 -32.203872) (xy 371.113686 -32.193742) (xy 371.16942 -32.191705)
			(xy 371.222521 -32.197548) (xy 424.585382 -32.197548) (xy 424.589453 -32.141926) (xy 424.601579 -32.087489)
			(xy 424.621502 -32.035398) (xy 424.648798 -31.986763) (xy 424.682884 -31.94262) (xy 424.723033 -31.903911)
			(xy 424.768391 -31.87146) (xy 424.817991 -31.845959) (xy 424.870775 -31.827952) (xy 424.925618 -31.817822)
			(xy 424.981352 -31.815785) (xy 425.036789 -31.821885) (xy 425.090746 -31.835991) (xy 425.142075 -31.857803)
			(xy 425.189681 -31.886857) (xy 425.232549 -31.922532) (xy 425.269766 -31.964069) (xy 425.300539 -32.010582)
			(xy 425.324211 -32.061079) (xy 425.340279 -32.114486) (xy 425.348399 -32.169662) (xy 425.348908 -32.197548)
			(xy 425.348399 -32.225434) (xy 425.340279 -32.28061) (xy 425.324211 -32.334017) (xy 425.300539 -32.384514)
			(xy 425.269766 -32.431027) (xy 425.232549 -32.472564) (xy 425.189681 -32.508239) (xy 425.142075 -32.537293)
			(xy 425.090746 -32.559105) (xy 425.036789 -32.573211) (xy 424.981352 -32.579311) (xy 424.925618 -32.577274)
			(xy 424.870775 -32.567144) (xy 424.817991 -32.549137) (xy 424.768391 -32.523636) (xy 424.723033 -32.491185)
			(xy 424.682884 -32.452476) (xy 424.648798 -32.408333) (xy 424.621502 -32.359698) (xy 424.601579 -32.307607)
			(xy 424.589453 -32.25317) (xy 424.585382 -32.197548) (xy 371.222521 -32.197548) (xy 371.224857 -32.197805)
			(xy 371.278814 -32.211911) (xy 371.330143 -32.233723) (xy 371.377749 -32.262777) (xy 371.420617 -32.298452)
			(xy 371.457834 -32.339989) (xy 371.488607 -32.386502) (xy 371.512279 -32.436999) (xy 371.528347 -32.490406)
			(xy 371.536467 -32.545582) (xy 371.536976 -32.573468) (xy 371.536467 -32.601354) (xy 371.528347 -32.65653)
			(xy 371.512279 -32.709937) (xy 371.488607 -32.760434) (xy 371.457834 -32.806947) (xy 371.420617 -32.848484)
			(xy 371.377749 -32.884159) (xy 371.330143 -32.913213) (xy 371.278814 -32.935025) (xy 371.224857 -32.949131)
			(xy 371.16942 -32.955231) (xy 371.113686 -32.953194) (xy 371.058843 -32.943064) (xy 371.006059 -32.925057)
			(xy 370.956459 -32.899556) (xy 370.911101 -32.867105) (xy 370.870952 -32.828396) (xy 370.836866 -32.784253)
			(xy 370.80957 -32.735618) (xy 370.789647 -32.683527) (xy 370.777521 -32.62909) (xy 370.77345 -32.573468)
			(xy 331.990535 -32.573468) (xy 331.979616 -32.618366) (xy 331.958355 -32.675196) (xy 331.930472 -32.729088)
			(xy 331.896365 -32.779273) (xy 331.856521 -32.825035) (xy 331.811507 -32.865724) (xy 331.786992 -32.883602)
			(xy 331.777445 -32.891268) (xy 331.766302 -32.91303) (xy 331.765656 -32.925258) (xy 331.765656 -33.008062)
			(xy 331.766318 -33.020288) (xy 331.777448 -33.04205) (xy 331.786992 -33.049718) (xy 331.787341 -33.049972)
			(xy 365.599216 -33.049972) (xy 365.603287 -32.99435) (xy 365.615413 -32.939913) (xy 365.635336 -32.887822)
			(xy 365.662632 -32.839187) (xy 365.696718 -32.795044) (xy 365.736867 -32.756335) (xy 365.782225 -32.723884)
			(xy 365.831825 -32.698383) (xy 365.884609 -32.680376) (xy 365.939452 -32.670246) (xy 365.995186 -32.668209)
			(xy 366.050623 -32.674309) (xy 366.10458 -32.688415) (xy 366.155909 -32.710227) (xy 366.203515 -32.739281)
			(xy 366.246383 -32.774956) (xy 366.2836 -32.816493) (xy 366.314373 -32.863006) (xy 366.338045 -32.913503)
			(xy 366.354113 -32.96691) (xy 366.362233 -33.022086) (xy 366.362742 -33.049972) (xy 366.362233 -33.077858)
			(xy 366.354113 -33.133034) (xy 366.338045 -33.186441) (xy 366.314373 -33.236938) (xy 366.2836 -33.283451)
			(xy 366.246383 -33.324988) (xy 366.235316 -33.334198) (xy 379.484888 -33.334198) (xy 379.488959 -33.278576)
			(xy 379.501085 -33.224139) (xy 379.521008 -33.172048) (xy 379.548304 -33.123413) (xy 379.58239 -33.07927)
			(xy 379.622539 -33.040561) (xy 379.667897 -33.00811) (xy 379.717497 -32.982609) (xy 379.770281 -32.964602)
			(xy 379.825124 -32.954472) (xy 379.880858 -32.952435) (xy 379.936295 -32.958535) (xy 379.990252 -32.972641)
			(xy 380.041581 -32.994453) (xy 380.089187 -33.023507) (xy 380.132055 -33.059182) (xy 380.169272 -33.100719)
			(xy 380.200045 -33.147232) (xy 380.223717 -33.197729) (xy 380.239785 -33.251136) (xy 380.247905 -33.306312)
			(xy 380.248414 -33.334198) (xy 380.247905 -33.362084) (xy 380.239785 -33.41726) (xy 380.223717 -33.470667)
			(xy 380.210196 -33.499509) (xy 424.459394 -33.499509) (xy 424.459394 -33.435587) (xy 424.467405 -33.372169)
			(xy 424.483302 -33.310255) (xy 424.506834 -33.250822) (xy 424.537628 -33.194807) (xy 424.575201 -33.143092)
			(xy 424.618958 -33.096495) (xy 424.668211 -33.05575) (xy 424.722182 -33.021499) (xy 424.780021 -32.994282)
			(xy 424.840814 -32.974529) (xy 424.903604 -32.962551) (xy 424.9674 -32.958538) (xy 425.031196 -32.962551)
			(xy 425.093986 -32.974529) (xy 425.154779 -32.994282) (xy 425.212618 -33.021499) (xy 425.266589 -33.05575)
			(xy 425.315842 -33.096495) (xy 425.359599 -33.143092) (xy 425.397172 -33.194807) (xy 425.427966 -33.250822)
			(xy 425.451498 -33.310255) (xy 425.467395 -33.372169) (xy 425.475406 -33.435587) (xy 425.475908 -33.467548)
			(xy 425.475406 -33.499509) (xy 430.047394 -33.499509) (xy 430.047394 -33.435587) (xy 430.055405 -33.372169)
			(xy 430.071302 -33.310255) (xy 430.094834 -33.250822) (xy 430.125628 -33.194807) (xy 430.163201 -33.143092)
			(xy 430.206958 -33.096495) (xy 430.256211 -33.05575) (xy 430.310182 -33.021499) (xy 430.368021 -32.994282)
			(xy 430.428814 -32.974529) (xy 430.491604 -32.962551) (xy 430.5554 -32.958538) (xy 430.619196 -32.962551)
			(xy 430.681986 -32.974529) (xy 430.742779 -32.994282) (xy 430.800618 -33.021499) (xy 430.854589 -33.05575)
			(xy 430.903842 -33.096495) (xy 430.947599 -33.143092) (xy 430.985172 -33.194807) (xy 431.015966 -33.250822)
			(xy 431.039498 -33.310255) (xy 431.055395 -33.372169) (xy 431.063406 -33.435587) (xy 431.063908 -33.467548)
			(xy 431.063406 -33.499509) (xy 431.055395 -33.562927) (xy 431.039498 -33.624841) (xy 431.015966 -33.684274)
			(xy 430.985172 -33.740289) (xy 430.957851 -33.777893) (xy 434.69534 -33.777893) (xy 434.69534 -33.713971)
			(xy 434.703351 -33.650553) (xy 434.719248 -33.588639) (xy 434.74278 -33.529206) (xy 434.773574 -33.473191)
			(xy 434.811147 -33.421476) (xy 434.854904 -33.374879) (xy 434.904157 -33.334134) (xy 434.958128 -33.299883)
			(xy 435.015967 -33.272666) (xy 435.07676 -33.252913) (xy 435.13955 -33.240935) (xy 435.203346 -33.236922)
			(xy 435.267142 -33.240935) (xy 435.329932 -33.252913) (xy 435.390725 -33.272666) (xy 435.448564 -33.299883)
			(xy 435.502535 -33.334134) (xy 435.551788 -33.374879) (xy 435.595545 -33.421476) (xy 435.633118 -33.473191)
			(xy 435.663912 -33.529206) (xy 435.687444 -33.588639) (xy 435.703341 -33.650553) (xy 435.711352 -33.713971)
			(xy 435.711854 -33.745932) (xy 435.711352 -33.777893) (xy 435.703341 -33.841311) (xy 435.687444 -33.903225)
			(xy 435.663912 -33.962658) (xy 435.633118 -34.018673) (xy 435.595545 -34.070388) (xy 435.551788 -34.116985)
			(xy 435.502535 -34.15773) (xy 435.448564 -34.191981) (xy 435.390725 -34.219198) (xy 435.329932 -34.238951)
			(xy 435.267142 -34.250929) (xy 435.203346 -34.254943) (xy 435.13955 -34.250929) (xy 435.07676 -34.238951)
			(xy 435.015967 -34.219198) (xy 434.958128 -34.191981) (xy 434.904157 -34.15773) (xy 434.854904 -34.116985)
			(xy 434.811147 -34.070388) (xy 434.773574 -34.018673) (xy 434.74278 -33.962658) (xy 434.719248 -33.903225)
			(xy 434.703351 -33.841311) (xy 434.69534 -33.777893) (xy 430.957851 -33.777893) (xy 430.947599 -33.792004)
			(xy 430.903842 -33.838601) (xy 430.854589 -33.879346) (xy 430.800618 -33.913597) (xy 430.742779 -33.940814)
			(xy 430.681986 -33.960567) (xy 430.619196 -33.972545) (xy 430.5554 -33.976559) (xy 430.491604 -33.972545)
			(xy 430.428814 -33.960567) (xy 430.368021 -33.940814) (xy 430.310182 -33.913597) (xy 430.256211 -33.879346)
			(xy 430.206958 -33.838601) (xy 430.163201 -33.792004) (xy 430.125628 -33.740289) (xy 430.094834 -33.684274)
			(xy 430.071302 -33.624841) (xy 430.055405 -33.562927) (xy 430.047394 -33.499509) (xy 425.475406 -33.499509)
			(xy 425.467395 -33.562927) (xy 425.451498 -33.624841) (xy 425.427966 -33.684274) (xy 425.397172 -33.740289)
			(xy 425.359599 -33.792004) (xy 425.315842 -33.838601) (xy 425.266589 -33.879346) (xy 425.212618 -33.913597)
			(xy 425.154779 -33.940814) (xy 425.093986 -33.960567) (xy 425.031196 -33.972545) (xy 424.9674 -33.976559)
			(xy 424.903604 -33.972545) (xy 424.840814 -33.960567) (xy 424.780021 -33.940814) (xy 424.722182 -33.913597)
			(xy 424.668211 -33.879346) (xy 424.618958 -33.838601) (xy 424.575201 -33.792004) (xy 424.537628 -33.740289)
			(xy 424.506834 -33.684274) (xy 424.483302 -33.624841) (xy 424.467405 -33.562927) (xy 424.459394 -33.499509)
			(xy 380.210196 -33.499509) (xy 380.200045 -33.521164) (xy 380.169272 -33.567677) (xy 380.132055 -33.609214)
			(xy 380.089187 -33.644889) (xy 380.041581 -33.673943) (xy 379.990252 -33.695755) (xy 379.936295 -33.709861)
			(xy 379.880858 -33.715961) (xy 379.825124 -33.713924) (xy 379.770281 -33.703794) (xy 379.717497 -33.685787)
			(xy 379.667897 -33.660286) (xy 379.622539 -33.627835) (xy 379.58239 -33.589126) (xy 379.548304 -33.544983)
			(xy 379.521008 -33.496348) (xy 379.501085 -33.444257) (xy 379.488959 -33.38982) (xy 379.484888 -33.334198)
			(xy 366.235316 -33.334198) (xy 366.203515 -33.360663) (xy 366.155909 -33.389717) (xy 366.10458 -33.411529)
			(xy 366.050623 -33.425635) (xy 365.995186 -33.431735) (xy 365.939452 -33.429698) (xy 365.884609 -33.419568)
			(xy 365.831825 -33.401561) (xy 365.782225 -33.37606) (xy 365.736867 -33.343609) (xy 365.696718 -33.3049)
			(xy 365.662632 -33.260757) (xy 365.635336 -33.212122) (xy 365.615413 -33.160031) (xy 365.603287 -33.105594)
			(xy 365.599216 -33.049972) (xy 331.787341 -33.049972) (xy 331.811529 -33.067567) (xy 331.856529 -33.108271)
			(xy 331.896362 -33.154043) (xy 331.930462 -33.204234) (xy 331.958343 -33.258127) (xy 331.979609 -33.314957)
			(xy 331.993956 -33.373914) (xy 332.001181 -33.434161) (xy 332.001622 -33.4645) (xy 332.00112 -33.496461)
			(xy 331.993109 -33.559879) (xy 331.977212 -33.621793) (xy 331.95368 -33.681226) (xy 331.922886 -33.737241)
			(xy 331.885313 -33.788956) (xy 331.841556 -33.835553) (xy 331.792303 -33.876298) (xy 331.738332 -33.910549)
			(xy 331.680493 -33.937766) (xy 331.6197 -33.957519) (xy 331.55691 -33.969497) (xy 331.493114 -33.973511)
			(xy 331.429318 -33.969497) (xy 331.366528 -33.957519) (xy 331.305735 -33.937766) (xy 331.247896 -33.910549)
			(xy 331.193925 -33.876298) (xy 331.144672 -33.835553) (xy 331.100915 -33.788956) (xy 331.063342 -33.737241)
			(xy 331.032548 -33.681226) (xy 331.009016 -33.621793) (xy 330.993119 -33.559879) (xy 330.985108 -33.496461)
			(xy 330.984606 -33.4645) (xy 315.047855 -33.4645) (xy 315.063738 -33.482227) (xy 315.094511 -33.52874)
			(xy 315.118183 -33.579237) (xy 315.134251 -33.632644) (xy 315.142371 -33.68782) (xy 315.14288 -33.715706)
			(xy 315.142371 -33.743592) (xy 315.134251 -33.798768) (xy 315.118183 -33.852175) (xy 315.094511 -33.902672)
			(xy 315.063738 -33.949185) (xy 315.026521 -33.990722) (xy 314.983653 -34.026397) (xy 314.936047 -34.055451)
			(xy 314.884718 -34.077263) (xy 314.830761 -34.091369) (xy 314.775324 -34.097469) (xy 314.71959 -34.095432)
			(xy 314.664747 -34.085302) (xy 314.611963 -34.067295) (xy 314.562363 -34.041794) (xy 314.517005 -34.009343)
			(xy 314.476856 -33.970634) (xy 314.44277 -33.926491) (xy 314.415474 -33.877856) (xy 314.395551 -33.825765)
			(xy 314.383425 -33.771328) (xy 314.379354 -33.715706) (xy 313.86018 -33.715706) (xy 313.859678 -33.747667)
			(xy 313.851667 -33.811085) (xy 313.83577 -33.872999) (xy 313.812238 -33.932432) (xy 313.781444 -33.988447)
			(xy 313.743871 -34.040162) (xy 313.700114 -34.086759) (xy 313.672176 -34.109871) (xy 326.513438 -34.109871)
			(xy 326.513438 -34.045949) (xy 326.521449 -33.982531) (xy 326.537346 -33.920617) (xy 326.560878 -33.861184)
			(xy 326.591672 -33.805169) (xy 326.629245 -33.753454) (xy 326.673002 -33.706857) (xy 326.722255 -33.666112)
			(xy 326.776226 -33.631861) (xy 326.834065 -33.604644) (xy 326.894858 -33.584891) (xy 326.957648 -33.572913)
			(xy 327.021444 -33.5689) (xy 327.08524 -33.572913) (xy 327.14803 -33.584891) (xy 327.208823 -33.604644)
			(xy 327.266662 -33.631861) (xy 327.320633 -33.666112) (xy 327.369886 -33.706857) (xy 327.413643 -33.753454)
			(xy 327.451216 -33.805169) (xy 327.48201 -33.861184) (xy 327.505542 -33.920617) (xy 327.518146 -33.969706)
			(xy 329.987654 -33.969706) (xy 329.991725 -33.914084) (xy 330.003851 -33.859647) (xy 330.023774 -33.807556)
			(xy 330.05107 -33.758921) (xy 330.085156 -33.714778) (xy 330.125305 -33.676069) (xy 330.170663 -33.643618)
			(xy 330.220263 -33.618117) (xy 330.273047 -33.60011) (xy 330.32789 -33.58998) (xy 330.383624 -33.587943)
			(xy 330.439061 -33.594043) (xy 330.493018 -33.608149) (xy 330.544347 -33.629961) (xy 330.591953 -33.659015)
			(xy 330.634821 -33.69469) (xy 330.672038 -33.736227) (xy 330.702811 -33.78274) (xy 330.726483 -33.833237)
			(xy 330.742551 -33.886644) (xy 330.750671 -33.94182) (xy 330.75118 -33.969706) (xy 330.750671 -33.997592)
			(xy 330.742551 -34.052768) (xy 330.726483 -34.106175) (xy 330.702811 -34.156672) (xy 330.672038 -34.203185)
			(xy 330.634821 -34.244722) (xy 330.591953 -34.280397) (xy 330.544347 -34.309451) (xy 330.493018 -34.331263)
			(xy 330.439061 -34.345369) (xy 330.383624 -34.351469) (xy 330.32789 -34.349432) (xy 330.273047 -34.339302)
			(xy 330.220263 -34.321295) (xy 330.170663 -34.295794) (xy 330.125305 -34.263343) (xy 330.085156 -34.224634)
			(xy 330.05107 -34.180491) (xy 330.023774 -34.131856) (xy 330.003851 -34.079765) (xy 329.991725 -34.025328)
			(xy 329.987654 -33.969706) (xy 327.518146 -33.969706) (xy 327.521439 -33.982531) (xy 327.52945 -34.045949)
			(xy 327.529952 -34.07791) (xy 327.52945 -34.109871) (xy 327.521439 -34.173289) (xy 327.505542 -34.235203)
			(xy 327.48201 -34.294636) (xy 327.451216 -34.350651) (xy 327.413643 -34.402366) (xy 327.369886 -34.448963)
			(xy 327.320633 -34.489708) (xy 327.266662 -34.523959) (xy 327.208823 -34.551176) (xy 327.14803 -34.570929)
			(xy 327.08524 -34.582907) (xy 327.021444 -34.586921) (xy 326.957648 -34.582907) (xy 326.894858 -34.570929)
			(xy 326.834065 -34.551176) (xy 326.776226 -34.523959) (xy 326.722255 -34.489708) (xy 326.673002 -34.448963)
			(xy 326.629245 -34.402366) (xy 326.591672 -34.350651) (xy 326.560878 -34.294636) (xy 326.537346 -34.235203)
			(xy 326.521449 -34.173289) (xy 326.513438 -34.109871) (xy 313.672176 -34.109871) (xy 313.650861 -34.127504)
			(xy 313.59689 -34.161755) (xy 313.539051 -34.188972) (xy 313.478258 -34.208725) (xy 313.415468 -34.220703)
			(xy 313.351672 -34.224717) (xy 313.287876 -34.220703) (xy 313.225086 -34.208725) (xy 313.164293 -34.188972)
			(xy 313.106454 -34.161755) (xy 313.052483 -34.127504) (xy 313.00323 -34.086759) (xy 312.959473 -34.040162)
			(xy 312.9219 -33.988447) (xy 312.891106 -33.932432) (xy 312.867574 -33.872999) (xy 312.851677 -33.811085)
			(xy 312.843666 -33.747667) (xy 310.609839 -33.747667) (xy 310.634358 -33.774474) (xy 310.670747 -33.825728)
			(xy 310.700549 -33.881072) (xy 310.723308 -33.939664) (xy 310.73868 -34.000613) (xy 310.74643 -34.062991)
			(xy 310.746902 -34.09442) (xy 310.7464 -34.126381) (xy 310.738389 -34.189799) (xy 310.722492 -34.251713)
			(xy 310.69896 -34.311146) (xy 310.668166 -34.367161) (xy 310.630593 -34.418876) (xy 310.586836 -34.465473)
			(xy 310.537583 -34.506218) (xy 310.483612 -34.540469) (xy 310.425773 -34.567686) (xy 310.36498 -34.587439)
			(xy 310.30219 -34.599417) (xy 310.238394 -34.603431) (xy 310.174598 -34.599417) (xy 310.111808 -34.587439)
			(xy 310.051015 -34.567686) (xy 309.993176 -34.540469) (xy 309.939205 -34.506218) (xy 309.889952 -34.465473)
			(xy 309.846195 -34.418876) (xy 309.808622 -34.367161) (xy 309.777828 -34.311146) (xy 309.754296 -34.251713)
			(xy 309.738399 -34.189799) (xy 309.730388 -34.126381) (xy 309.729886 -34.09442) (xy 309.730463 -34.060132)
			(xy 309.739681 -33.992178) (xy 309.75794 -33.926076) (xy 309.784908 -33.863025) (xy 309.802022 -33.833308)
			(xy 309.806311 -33.825455) (xy 309.809707 -33.807899) (xy 309.808626 -33.799018) (xy 309.803546 -33.7693)
			(xy 309.80176 -33.760591) (xy 309.793057 -33.745105) (xy 309.786528 -33.739074) (xy 309.762946 -33.718292)
			(xy 309.72052 -33.671914) (xy 309.684127 -33.620664) (xy 309.654323 -33.565322) (xy 309.631562 -33.506731)
			(xy 309.616189 -33.445783) (xy 309.608438 -33.383406) (xy 309.607966 -33.351978) (xy 294.566721 -33.351978)
			(xy 294.572951 -33.359548) (xy 294.625018 -33.435249) (xy 294.670386 -33.515146) (xy 294.708717 -33.598646)
			(xy 294.739728 -33.685133) (xy 294.763189 -33.773966) (xy 294.778928 -33.864486) (xy 294.786826 -33.956025)
			(xy 294.78732 -34.001964) (xy 294.786976 -34.033925) (xy 306.433468 -34.033925) (xy 306.433468 -33.970003)
			(xy 306.441479 -33.906585) (xy 306.457376 -33.844671) (xy 306.480908 -33.785238) (xy 306.511702 -33.729223)
			(xy 306.549275 -33.677508) (xy 306.593032 -33.630911) (xy 306.642285 -33.590166) (xy 306.696256 -33.555915)
			(xy 306.754095 -33.528698) (xy 306.814888 -33.508945) (xy 306.877678 -33.496967) (xy 306.941474 -33.492954)
			(xy 307.00527 -33.496967) (xy 307.06806 -33.508945) (xy 307.128853 -33.528698) (xy 307.186692 -33.555915)
			(xy 307.240663 -33.590166) (xy 307.289916 -33.630911) (xy 307.333673 -33.677508) (xy 307.371246 -33.729223)
			(xy 307.40204 -33.785238) (xy 307.425572 -33.844671) (xy 307.441469 -33.906585) (xy 307.44948 -33.970003)
			(xy 307.449982 -34.001964) (xy 307.44948 -34.033925) (xy 307.441469 -34.097343) (xy 307.425572 -34.159257)
			(xy 307.40204 -34.21869) (xy 307.371246 -34.274705) (xy 307.333673 -34.32642) (xy 307.289916 -34.373017)
			(xy 307.240663 -34.413762) (xy 307.186692 -34.448013) (xy 307.128853 -34.47523) (xy 307.06806 -34.494983)
			(xy 307.00527 -34.506961) (xy 306.941474 -34.510975) (xy 306.877678 -34.506961) (xy 306.814888 -34.494983)
			(xy 306.754095 -34.47523) (xy 306.696256 -34.448013) (xy 306.642285 -34.413762) (xy 306.593032 -34.373017)
			(xy 306.549275 -34.32642) (xy 306.511702 -34.274705) (xy 306.480908 -34.21869) (xy 306.457376 -34.159257)
			(xy 306.441479 -34.097343) (xy 306.433468 -34.033925) (xy 294.786976 -34.033925) (xy 294.786826 -34.047903)
			(xy 294.778928 -34.139442) (xy 294.763189 -34.229962) (xy 294.739728 -34.318795) (xy 294.708717 -34.405282)
			(xy 294.670386 -34.488782) (xy 294.625018 -34.568679) (xy 294.572951 -34.64438) (xy 294.514568 -34.715324)
			(xy 294.450303 -34.780987) (xy 294.380631 -34.840883) (xy 294.355876 -34.858706) (xy 314.379354 -34.858706)
			(xy 314.383425 -34.803084) (xy 314.395551 -34.748647) (xy 314.415474 -34.696556) (xy 314.44277 -34.647921)
			(xy 314.476856 -34.603778) (xy 314.517005 -34.565069) (xy 314.562363 -34.532618) (xy 314.611963 -34.507117)
			(xy 314.664747 -34.48911) (xy 314.71959 -34.47898) (xy 314.775324 -34.476943) (xy 314.830761 -34.483043)
			(xy 314.884718 -34.497149) (xy 314.936047 -34.518961) (xy 314.983653 -34.548015) (xy 315.026521 -34.58369)
			(xy 315.063738 -34.625227) (xy 315.094511 -34.67174) (xy 315.118183 -34.722237) (xy 315.134251 -34.775644)
			(xy 315.142371 -34.83082) (xy 315.14288 -34.858706) (xy 315.142371 -34.886592) (xy 315.134251 -34.941768)
			(xy 315.118183 -34.995175) (xy 315.107639 -35.017667) (xy 316.847468 -35.017667) (xy 316.847468 -34.953745)
			(xy 316.855479 -34.890327) (xy 316.871376 -34.828413) (xy 316.894908 -34.76898) (xy 316.925702 -34.712965)
			(xy 316.963275 -34.66125) (xy 317.007032 -34.614653) (xy 317.056285 -34.573908) (xy 317.110256 -34.539657)
			(xy 317.168095 -34.51244) (xy 317.228888 -34.492687) (xy 317.291678 -34.480709) (xy 317.355474 -34.476696)
			(xy 317.41927 -34.480709) (xy 317.48206 -34.492687) (xy 317.542853 -34.51244) (xy 317.600692 -34.539657)
			(xy 317.654663 -34.573908) (xy 317.703916 -34.614653) (xy 317.747673 -34.66125) (xy 317.785246 -34.712965)
			(xy 317.81604 -34.76898) (xy 317.839572 -34.828413) (xy 317.855469 -34.890327) (xy 317.861549 -34.938462)
			(xy 318.432942 -34.938462) (xy 318.433428 -34.911211) (xy 318.441184 -34.857263) (xy 318.456539 -34.804968)
			(xy 318.479181 -34.755391) (xy 318.508647 -34.709541) (xy 318.544338 -34.66835) (xy 318.585529 -34.632659)
			(xy 318.631379 -34.603193) (xy 318.680956 -34.580551) (xy 318.733251 -34.565196) (xy 318.787199 -34.55744)
			(xy 318.841701 -34.55744) (xy 318.895649 -34.565196) (xy 318.947944 -34.580551) (xy 318.997521 -34.603193)
			(xy 319.043371 -34.632659) (xy 319.084562 -34.66835) (xy 319.120253 -34.709541) (xy 319.149719 -34.755391)
			(xy 319.172361 -34.804968) (xy 319.187716 -34.857263) (xy 319.195472 -34.911211) (xy 319.195958 -34.938462)
			(xy 319.195458 -34.965688) (xy 319.187725 -35.019589) (xy 319.172412 -35.071845) (xy 319.149829 -35.121393)
			(xy 319.120433 -35.16723) (xy 319.102994 -35.188144) (xy 319.097152 -35.195002) (xy 319.090548 -35.212274)
			(xy 319.091056 -35.297618) (xy 319.097406 -35.314636) (xy 319.103502 -35.321494) (xy 319.121336 -35.342477)
			(xy 319.151369 -35.388636) (xy 319.174454 -35.438633) (xy 319.190113 -35.491429) (xy 319.19435 -35.52063)
			(xy 332.996286 -35.52063) (xy 332.996752 -35.489054) (xy 333.004562 -35.426386) (xy 333.020078 -35.365169)
			(xy 333.04306 -35.306347) (xy 333.073155 -35.250827) (xy 333.109899 -35.199464) (xy 333.152724 -35.15305)
			(xy 333.200971 -35.112301) (xy 333.227172 -35.094672) (xy 333.239088 -35.086436) (xy 333.257993 -35.064501)
			(xy 333.269977 -35.038141) (xy 333.274078 -35.009475) (xy 333.269964 -34.980812) (xy 333.257966 -34.954457)
			(xy 333.239051 -34.932532) (xy 333.227172 -34.924238) (xy 333.201002 -34.906567) (xy 333.152768 -34.865814)
			(xy 333.109952 -34.819401) (xy 333.073213 -34.768042) (xy 333.043117 -34.71253) (xy 333.020128 -34.653718)
			(xy 333.004599 -34.592511) (xy 332.996769 -34.529853) (xy 332.996286 -34.49828) (xy 332.996788 -34.466319)
			(xy 333.004799 -34.402901) (xy 333.020696 -34.340987) (xy 333.044228 -34.281554) (xy 333.075022 -34.225539)
			(xy 333.112595 -34.173824) (xy 333.156352 -34.127227) (xy 333.205605 -34.086482) (xy 333.259576 -34.052231)
			(xy 333.317415 -34.025014) (xy 333.378208 -34.005261) (xy 333.440998 -33.993283) (xy 333.504794 -33.98927)
			(xy 333.56859 -33.993283) (xy 333.63138 -34.005261) (xy 333.692173 -34.025014) (xy 333.750012 -34.052231)
			(xy 333.803983 -34.086482) (xy 333.853236 -34.127227) (xy 333.896993 -34.173824) (xy 333.923791 -34.210709)
			(xy 377.608332 -34.210709) (xy 377.608332 -34.146787) (xy 377.616343 -34.083369) (xy 377.63224 -34.021455)
			(xy 377.655772 -33.962022) (xy 377.686566 -33.906007) (xy 377.724139 -33.854292) (xy 377.767896 -33.807695)
			(xy 377.817149 -33.76695) (xy 377.87112 -33.732699) (xy 377.928959 -33.705482) (xy 377.989752 -33.685729)
			(xy 378.052542 -33.673751) (xy 378.116338 -33.669738) (xy 378.180134 -33.673751) (xy 378.242924 -33.685729)
			(xy 378.303717 -33.705482) (xy 378.361556 -33.732699) (xy 378.415527 -33.76695) (xy 378.46478 -33.807695)
			(xy 378.508537 -33.854292) (xy 378.54611 -33.906007) (xy 378.576904 -33.962022) (xy 378.600436 -34.021455)
			(xy 378.616333 -34.083369) (xy 378.624344 -34.146787) (xy 378.624846 -34.178748) (xy 378.624344 -34.210709)
			(xy 378.616333 -34.274127) (xy 378.600436 -34.336041) (xy 378.576904 -34.395474) (xy 378.54611 -34.451489)
			(xy 378.508537 -34.503204) (xy 378.46478 -34.549801) (xy 378.415527 -34.590546) (xy 378.361556 -34.624797)
			(xy 378.303717 -34.652014) (xy 378.242924 -34.671767) (xy 378.180134 -34.683745) (xy 378.116338 -34.687759)
			(xy 378.052542 -34.683745) (xy 377.989752 -34.671767) (xy 377.928959 -34.652014) (xy 377.87112 -34.624797)
			(xy 377.817149 -34.590546) (xy 377.767896 -34.549801) (xy 377.724139 -34.503204) (xy 377.686566 -34.451489)
			(xy 377.655772 -34.395474) (xy 377.63224 -34.336041) (xy 377.616343 -34.274127) (xy 377.608332 -34.210709)
			(xy 333.923791 -34.210709) (xy 333.934566 -34.225539) (xy 333.96536 -34.281554) (xy 333.988892 -34.340987)
			(xy 334.004789 -34.402901) (xy 334.0128 -34.466319) (xy 334.013302 -34.49828) (xy 334.01285 -34.529857)
			(xy 334.005038 -34.592525) (xy 333.98952 -34.653743) (xy 333.966536 -34.712565) (xy 333.936439 -34.768085)
			(xy 333.899694 -34.819448) (xy 333.856867 -34.865861) (xy 333.808618 -34.90661) (xy 333.782416 -34.924238)
			(xy 333.770627 -34.932615) (xy 333.751801 -34.954544) (xy 333.739865 -34.980865) (xy 333.735772 -35.009475)
			(xy 333.739851 -35.038087) (xy 333.751774 -35.064415) (xy 333.77059 -35.086353) (xy 333.782416 -35.094672)
			(xy 333.80861 -35.112307) (xy 333.856841 -35.153069) (xy 333.899653 -35.199489) (xy 333.936388 -35.250852)
			(xy 333.96648 -35.306369) (xy 333.989466 -35.365185) (xy 334.004992 -35.426395) (xy 334.006388 -35.437572)
			(xy 371.09781 -35.437572) (xy 371.098374 -35.404015) (xy 371.107216 -35.337486) (xy 371.124731 -35.272698)
			(xy 371.150614 -35.210776) (xy 371.184415 -35.152795) (xy 371.225547 -35.099763) (xy 371.273296 -35.0526)
			(xy 371.29974 -35.031934) (xy 371.307736 -35.025269) (xy 371.317973 -35.007171) (xy 371.319552 -34.996882)
			(xy 371.327934 -34.923476) (xy 371.328527 -34.913053) (xy 371.322382 -34.893125) (xy 371.315996 -34.884868)
			(xy 371.298873 -34.864072) (xy 371.270025 -34.818577) (xy 371.247873 -34.769474) (xy 371.232855 -34.71774)
			(xy 371.225273 -34.664407) (xy 371.22481 -34.637472) (xy 371.225296 -34.610221) (xy 371.233052 -34.556273)
			(xy 371.248407 -34.503978) (xy 371.271049 -34.454401) (xy 371.300515 -34.408551) (xy 371.336206 -34.36736)
			(xy 371.377397 -34.331669) (xy 371.423247 -34.302203) (xy 371.472824 -34.279561) (xy 371.525119 -34.264206)
			(xy 371.579067 -34.25645) (xy 371.633569 -34.25645) (xy 371.687517 -34.264206) (xy 371.739812 -34.279561)
			(xy 371.789389 -34.302203) (xy 371.835239 -34.331669) (xy 371.87643 -34.36736) (xy 371.912121 -34.408551)
			(xy 371.941587 -34.454401) (xy 371.964229 -34.503978) (xy 371.979584 -34.556273) (xy 371.98734 -34.610221)
			(xy 371.987826 -34.637472) (xy 371.987373 -34.664407) (xy 371.979781 -34.717739) (xy 371.96476 -34.769472)
			(xy 371.964743 -34.769509) (xy 424.459394 -34.769509) (xy 424.459394 -34.705587) (xy 424.467405 -34.642169)
			(xy 424.483302 -34.580255) (xy 424.506834 -34.520822) (xy 424.537628 -34.464807) (xy 424.575201 -34.413092)
			(xy 424.618958 -34.366495) (xy 424.668211 -34.32575) (xy 424.722182 -34.291499) (xy 424.780021 -34.264282)
			(xy 424.840814 -34.244529) (xy 424.903604 -34.232551) (xy 424.9674 -34.228538) (xy 425.031196 -34.232551)
			(xy 425.093986 -34.244529) (xy 425.154779 -34.264282) (xy 425.212618 -34.291499) (xy 425.266589 -34.32575)
			(xy 425.315842 -34.366495) (xy 425.359599 -34.413092) (xy 425.397172 -34.464807) (xy 425.427966 -34.520822)
			(xy 425.451498 -34.580255) (xy 425.467395 -34.642169) (xy 425.475406 -34.705587) (xy 425.475908 -34.737548)
			(xy 425.475406 -34.769509) (xy 430.047394 -34.769509) (xy 430.047394 -34.705587) (xy 430.055405 -34.642169)
			(xy 430.071302 -34.580255) (xy 430.094834 -34.520822) (xy 430.125628 -34.464807) (xy 430.163201 -34.413092)
			(xy 430.206958 -34.366495) (xy 430.256211 -34.32575) (xy 430.310182 -34.291499) (xy 430.368021 -34.264282)
			(xy 430.428814 -34.244529) (xy 430.491604 -34.232551) (xy 430.5554 -34.228538) (xy 430.619196 -34.232551)
			(xy 430.681986 -34.244529) (xy 430.742779 -34.264282) (xy 430.800618 -34.291499) (xy 430.854589 -34.32575)
			(xy 430.903842 -34.366495) (xy 430.920937 -34.3847) (xy 435.70651 -34.3847) (xy 435.710524 -34.320904)
			(xy 435.722503 -34.258114) (xy 435.742257 -34.19732) (xy 435.769475 -34.139482) (xy 435.803727 -34.085512)
			(xy 435.844474 -34.03626) (xy 435.891073 -33.992504) (xy 435.942789 -33.954934) (xy 435.998806 -33.924141)
			(xy 436.058241 -33.900613) (xy 436.120156 -33.88472) (xy 436.183575 -33.876713) (xy 436.215536 -33.876234)
			(xy 436.246824 -33.876703) (xy 436.308927 -33.884379) (xy 436.369618 -33.899622) (xy 436.427978 -33.922202)
			(xy 436.483124 -33.951777) (xy 436.53422 -33.9879) (xy 436.580495 -34.030023) (xy 436.621247 -34.07751)
			(xy 436.638954 -34.10331) (xy 436.64646 -34.113476) (xy 436.668746 -34.125327) (xy 436.681372 -34.125916)
			(xy 436.7657 -34.125916) (xy 436.77831 -34.1253) (xy 436.800558 -34.113424) (xy 436.808118 -34.10331)
			(xy 436.825848 -34.077528) (xy 436.866604 -34.03005) (xy 436.912879 -33.987934) (xy 436.963973 -33.951815)
			(xy 437.019114 -33.92224) (xy 437.077468 -33.899656) (xy 437.138153 -33.884405) (xy 437.20025 -33.876718)
			(xy 437.231536 -33.876234) (xy 437.263498 -33.876654) (xy 437.326918 -33.88467) (xy 437.388833 -33.900571)
			(xy 437.448267 -33.924107) (xy 437.504283 -33.954905) (xy 437.555998 -33.992481) (xy 437.602595 -34.036242)
			(xy 437.643341 -34.085498) (xy 437.677592 -34.139472) (xy 437.704808 -34.197313) (xy 437.724561 -34.258109)
			(xy 437.733573 -34.305353) (xy 439.88834 -34.305353) (xy 439.88834 -34.250847) (xy 439.896096 -34.196896)
			(xy 439.911452 -34.144598) (xy 439.934094 -34.095018) (xy 439.963561 -34.049164) (xy 439.999253 -34.00797)
			(xy 440.040444 -33.972275) (xy 440.086296 -33.942805) (xy 440.135876 -33.92016) (xy 440.188173 -33.904802)
			(xy 440.242123 -33.897042) (xy 440.269376 -33.896554) (xy 440.295717 -33.897) (xy 440.347898 -33.904253)
			(xy 440.398587 -33.91861) (xy 440.446821 -33.939799) (xy 440.491684 -33.967418) (xy 440.532324 -34.000943)
			(xy 440.567969 -34.039735) (xy 440.58332 -34.061146) (xy 440.591669 -34.072455) (xy 440.613331 -34.090355)
			(xy 440.639053 -34.101668) (xy 440.666886 -34.105537) (xy 440.694719 -34.101668) (xy 440.720441 -34.090355)
			(xy 440.742103 -34.072455) (xy 440.750452 -34.061146) (xy 440.76582 -34.039747) (xy 440.801456 -34.000945)
			(xy 440.84209 -33.967414) (xy 440.88695 -33.93979) (xy 440.935183 -33.918599) (xy 440.985873 -33.904244)
			(xy 441.038055 -33.896997) (xy 441.064396 -33.896554) (xy 441.091646 -33.897093) (xy 441.145592 -33.904849)
			(xy 441.197885 -33.920203) (xy 441.247461 -33.942843) (xy 441.29331 -33.972308) (xy 441.334499 -34.007998)
			(xy 441.37019 -34.049187) (xy 441.399655 -34.095035) (xy 441.422296 -34.144611) (xy 441.43765 -34.196904)
			(xy 441.445407 -34.25085) (xy 441.445407 -34.30535) (xy 441.43765 -34.359296) (xy 441.422296 -34.411589)
			(xy 441.399655 -34.461165) (xy 441.37019 -34.507013) (xy 441.334499 -34.548202) (xy 441.29331 -34.583892)
			(xy 441.247461 -34.613357) (xy 441.197885 -34.635997) (xy 441.145592 -34.651351) (xy 441.091646 -34.659107)
			(xy 441.064396 -34.65957) (xy 441.038054 -34.659135) (xy 440.985873 -34.651879) (xy 440.935185 -34.637519)
			(xy 440.886951 -34.616328) (xy 440.842089 -34.588707) (xy 440.801449 -34.555182) (xy 440.765803 -34.516389)
			(xy 440.750452 -34.494978) (xy 440.742103 -34.483669) (xy 440.720441 -34.465769) (xy 440.694719 -34.454456)
			(xy 440.666886 -34.450587) (xy 440.639053 -34.454456) (xy 440.613331 -34.465769) (xy 440.591669 -34.483669)
			(xy 440.58332 -34.494978) (xy 440.567977 -34.516395) (xy 440.532336 -34.555195) (xy 440.491697 -34.588725)
			(xy 440.446833 -34.616346) (xy 440.398596 -34.637534) (xy 440.347903 -34.651885) (xy 440.295719 -34.659129)
			(xy 440.269376 -34.65957) (xy 440.242123 -34.659158) (xy 440.188173 -34.651398) (xy 440.135876 -34.63604)
			(xy 440.086296 -34.613395) (xy 440.040444 -34.583925) (xy 439.999253 -34.54823) (xy 439.963561 -34.507036)
			(xy 439.934094 -34.461182) (xy 439.911452 -34.411602) (xy 439.896096 -34.359304) (xy 439.88834 -34.305353)
			(xy 437.733573 -34.305353) (xy 437.736539 -34.320902) (xy 437.740553 -34.3847) (xy 437.736539 -34.448498)
			(xy 437.724561 -34.511291) (xy 437.704808 -34.572087) (xy 437.677592 -34.629928) (xy 437.643341 -34.683902)
			(xy 437.602595 -34.733158) (xy 437.555998 -34.776919) (xy 437.504283 -34.814495) (xy 437.448267 -34.845293)
			(xy 437.388833 -34.868829) (xy 437.326918 -34.88473) (xy 437.263498 -34.892746) (xy 437.231536 -34.89325)
			(xy 437.200247 -34.89281) (xy 437.138142 -34.88513) (xy 437.077451 -34.869883) (xy 437.01909 -34.847299)
			(xy 436.963945 -34.81772) (xy 436.912848 -34.781594) (xy 436.866574 -34.739466) (xy 436.825824 -34.691976)
			(xy 436.808118 -34.666174) (xy 436.800558 -34.656056) (xy 436.778313 -34.644177) (xy 436.7657 -34.643568)
			(xy 436.681372 -34.643568) (xy 436.668769 -34.644234) (xy 436.64652 -34.656075) (xy 436.638954 -34.666174)
			(xy 436.621237 -34.691965) (xy 436.580479 -34.739443) (xy 436.534203 -34.78156) (xy 436.483107 -34.817679)
			(xy 436.427964 -34.847253) (xy 436.369608 -34.869835) (xy 436.308922 -34.885083) (xy 436.246822 -34.892768)
			(xy 436.215536 -34.89325) (xy 436.183575 -34.892687) (xy 436.120156 -34.88468) (xy 436.058241 -34.868787)
			(xy 435.998806 -34.845259) (xy 435.942789 -34.814466) (xy 435.891073 -34.776896) (xy 435.844474 -34.73314)
			(xy 435.803727 -34.683888) (xy 435.769475 -34.629918) (xy 435.742257 -34.57208) (xy 435.722503 -34.511286)
			(xy 435.710524 -34.448496) (xy 435.70651 -34.3847) (xy 430.920937 -34.3847) (xy 430.947599 -34.413092)
			(xy 430.985172 -34.464807) (xy 431.015966 -34.520822) (xy 431.039498 -34.580255) (xy 431.055395 -34.642169)
			(xy 431.063406 -34.705587) (xy 431.063908 -34.737548) (xy 431.063406 -34.769509) (xy 431.055395 -34.832927)
			(xy 431.039498 -34.894841) (xy 431.015966 -34.954274) (xy 430.985172 -35.010289) (xy 430.947599 -35.062004)
			(xy 430.903842 -35.108601) (xy 430.854589 -35.149346) (xy 430.800618 -35.183597) (xy 430.742779 -35.210814)
			(xy 430.681986 -35.230567) (xy 430.619196 -35.242545) (xy 430.5554 -35.246559) (xy 430.491604 -35.242545)
			(xy 430.428814 -35.230567) (xy 430.368021 -35.210814) (xy 430.310182 -35.183597) (xy 430.256211 -35.149346)
			(xy 430.206958 -35.108601) (xy 430.163201 -35.062004) (xy 430.125628 -35.010289) (xy 430.094834 -34.954274)
			(xy 430.071302 -34.894841) (xy 430.055405 -34.832927) (xy 430.047394 -34.769509) (xy 425.475406 -34.769509)
			(xy 425.467395 -34.832927) (xy 425.451498 -34.894841) (xy 425.427966 -34.954274) (xy 425.397172 -35.010289)
			(xy 425.359599 -35.062004) (xy 425.315842 -35.108601) (xy 425.266589 -35.149346) (xy 425.212618 -35.183597)
			(xy 425.154779 -35.210814) (xy 425.093986 -35.230567) (xy 425.031196 -35.242545) (xy 424.9674 -35.246559)
			(xy 424.903604 -35.242545) (xy 424.840814 -35.230567) (xy 424.780021 -35.210814) (xy 424.722182 -35.183597)
			(xy 424.668211 -35.149346) (xy 424.618958 -35.108601) (xy 424.575201 -35.062004) (xy 424.537628 -35.010289)
			(xy 424.506834 -34.954274) (xy 424.483302 -34.894841) (xy 424.467405 -34.832927) (xy 424.459394 -34.769509)
			(xy 371.964743 -34.769509) (xy 371.942608 -34.818576) (xy 371.913766 -34.864074) (xy 371.89664 -34.884868)
			(xy 371.890241 -34.893125) (xy 371.88406 -34.913052) (xy 371.884702 -34.923476) (xy 371.893084 -34.996882)
			(xy 371.894694 -35.007158) (xy 371.904928 -35.025246) (xy 371.912896 -35.031934) (xy 371.939369 -35.052568)
			(xy 371.987134 -35.099725) (xy 372.028277 -35.152757) (xy 372.062083 -35.210744) (xy 372.087963 -35.272675)
			(xy 372.105468 -35.337473) (xy 372.114292 -35.404011) (xy 372.114826 -35.437572) (xy 372.114324 -35.469533)
			(xy 372.106313 -35.532951) (xy 372.090416 -35.594865) (xy 372.066884 -35.654298) (xy 372.03609 -35.710313)
			(xy 371.998517 -35.762028) (xy 371.95476 -35.808625) (xy 371.905507 -35.84937) (xy 371.851536 -35.883621)
			(xy 371.793697 -35.910838) (xy 371.732904 -35.930591) (xy 371.670114 -35.942569) (xy 371.606318 -35.946583)
			(xy 371.542522 -35.942569) (xy 371.479732 -35.930591) (xy 371.418939 -35.910838) (xy 371.3611 -35.883621)
			(xy 371.307129 -35.84937) (xy 371.257876 -35.808625) (xy 371.214119 -35.762028) (xy 371.176546 -35.710313)
			(xy 371.145752 -35.654298) (xy 371.12222 -35.594865) (xy 371.106323 -35.532951) (xy 371.098312 -35.469533)
			(xy 371.09781 -35.437572) (xy 334.006388 -35.437572) (xy 334.01282 -35.489056) (xy 334.013302 -35.52063)
			(xy 334.0128 -35.552591) (xy 334.004789 -35.616009) (xy 333.988892 -35.677923) (xy 333.96536 -35.737356)
			(xy 333.934566 -35.793371) (xy 333.896993 -35.845086) (xy 333.853236 -35.891683) (xy 333.803983 -35.932428)
			(xy 333.750012 -35.966679) (xy 333.692173 -35.993896) (xy 333.650157 -36.007548) (xy 419.359332 -36.007548)
			(xy 419.363403 -35.951926) (xy 419.375529 -35.897489) (xy 419.395452 -35.845398) (xy 419.422748 -35.796763)
			(xy 419.456834 -35.75262) (xy 419.496983 -35.713911) (xy 419.542341 -35.68146) (xy 419.591941 -35.655959)
			(xy 419.644725 -35.637952) (xy 419.699568 -35.627822) (xy 419.755302 -35.625785) (xy 419.810739 -35.631885)
			(xy 419.864696 -35.645991) (xy 419.916025 -35.667803) (xy 419.963631 -35.696857) (xy 420.006499 -35.732532)
			(xy 420.043716 -35.774069) (xy 420.074489 -35.820582) (xy 420.098161 -35.871079) (xy 420.114229 -35.924486)
			(xy 420.122349 -35.979662) (xy 420.122858 -36.007548) (xy 420.122349 -36.035434) (xy 420.114229 -36.09061)
			(xy 420.098161 -36.144017) (xy 420.074489 -36.194514) (xy 420.043716 -36.241027) (xy 420.006499 -36.282564)
			(xy 419.963631 -36.318239) (xy 419.916025 -36.347293) (xy 419.864696 -36.369105) (xy 419.810739 -36.383211)
			(xy 419.755302 -36.389311) (xy 419.699568 -36.387274) (xy 419.644725 -36.377144) (xy 419.591941 -36.359137)
			(xy 419.542341 -36.333636) (xy 419.496983 -36.301185) (xy 419.456834 -36.262476) (xy 419.422748 -36.218333)
			(xy 419.395452 -36.169698) (xy 419.375529 -36.117607) (xy 419.363403 -36.06317) (xy 419.359332 -36.007548)
			(xy 333.650157 -36.007548) (xy 333.63138 -36.013649) (xy 333.56859 -36.025627) (xy 333.504794 -36.029641)
			(xy 333.440998 -36.025627) (xy 333.378208 -36.013649) (xy 333.317415 -35.993896) (xy 333.259576 -35.966679)
			(xy 333.205605 -35.932428) (xy 333.156352 -35.891683) (xy 333.112595 -35.845086) (xy 333.075022 -35.793371)
			(xy 333.044228 -35.737356) (xy 333.020696 -35.677923) (xy 333.004799 -35.616009) (xy 332.996788 -35.552591)
			(xy 332.996286 -35.52063) (xy 319.19435 -35.52063) (xy 319.19802 -35.545927) (xy 319.198498 -35.573462)
			(xy 319.19801 -35.600831) (xy 319.190198 -35.65501) (xy 319.174714 -35.707513) (xy 319.151877 -35.75726)
			(xy 319.122157 -35.803228) (xy 319.104518 -35.82416) (xy 319.104264 -35.824414) (xy 319.098661 -35.831489)
			(xy 319.092425 -35.848415) (xy 319.092072 -35.857434) (xy 319.092072 -35.92449) (xy 319.09244 -35.933506)
			(xy 319.098681 -35.950422) (xy 319.104264 -35.95751) (xy 319.104518 -35.95751) (xy 319.104518 -35.957764)
			(xy 319.122156 -35.978697) (xy 319.151868 -36.024669) (xy 319.174704 -36.074417) (xy 319.190195 -36.126917)
			(xy 319.198024 -36.181093) (xy 319.198498 -36.208462) (xy 326.107296 -36.208462) (xy 326.111367 -36.15284)
			(xy 326.123493 -36.098403) (xy 326.143416 -36.046312) (xy 326.170712 -35.997677) (xy 326.204798 -35.953534)
			(xy 326.244947 -35.914825) (xy 326.290305 -35.882374) (xy 326.339905 -35.856873) (xy 326.392689 -35.838866)
			(xy 326.447532 -35.828736) (xy 326.503266 -35.826699) (xy 326.558703 -35.832799) (xy 326.61266 -35.846905)
			(xy 326.663989 -35.868717) (xy 326.711595 -35.897771) (xy 326.754463 -35.933446) (xy 326.79168 -35.974983)
			(xy 326.822453 -36.021496) (xy 326.846125 -36.071993) (xy 326.862193 -36.1254) (xy 326.870313 -36.180576)
			(xy 326.870822 -36.208462) (xy 326.870313 -36.236348) (xy 326.862193 -36.291524) (xy 326.846125 -36.344931)
			(xy 326.822453 -36.395428) (xy 326.79168 -36.441941) (xy 326.754463 -36.483478) (xy 326.711595 -36.519153)
			(xy 326.663989 -36.548207) (xy 326.61266 -36.570019) (xy 326.558703 -36.584125) (xy 326.503266 -36.590225)
			(xy 326.447532 -36.588188) (xy 326.392689 -36.578058) (xy 326.339905 -36.560051) (xy 326.290305 -36.53455)
			(xy 326.244947 -36.502099) (xy 326.204798 -36.46339) (xy 326.170712 -36.419247) (xy 326.143416 -36.370612)
			(xy 326.123493 -36.318521) (xy 326.111367 -36.264084) (xy 326.107296 -36.208462) (xy 319.198498 -36.208462)
			(xy 319.198012 -36.235713) (xy 319.190256 -36.289661) (xy 319.174901 -36.341956) (xy 319.152259 -36.391533)
			(xy 319.122793 -36.437383) (xy 319.087102 -36.478574) (xy 319.045911 -36.514265) (xy 319.000061 -36.543731)
			(xy 318.950484 -36.566373) (xy 318.898189 -36.581728) (xy 318.844241 -36.589484) (xy 318.789739 -36.589484)
			(xy 318.735791 -36.581728) (xy 318.683496 -36.566373) (xy 318.633919 -36.543731) (xy 318.588069 -36.514265)
			(xy 318.546878 -36.478574) (xy 318.511187 -36.437383) (xy 318.481721 -36.391533) (xy 318.459079 -36.341956)
			(xy 318.443724 -36.289661) (xy 318.435968 -36.235713) (xy 318.435482 -36.208462) (xy 318.435964 -36.181092)
			(xy 318.443775 -36.126913) (xy 318.459259 -36.074409) (xy 318.482098 -36.024662) (xy 318.511821 -35.978695)
			(xy 318.529462 -35.957764) (xy 318.529716 -35.95751) (xy 318.535306 -35.950426) (xy 318.54155 -35.933507)
			(xy 318.541908 -35.92449) (xy 318.541908 -35.857434) (xy 318.541533 -35.848419) (xy 318.535298 -35.831502)
			(xy 318.529716 -35.824414) (xy 318.529462 -35.824414) (xy 318.529462 -35.82416) (xy 318.511831 -35.803221)
			(xy 318.482119 -35.75725) (xy 318.459282 -35.707504) (xy 318.443789 -35.655005) (xy 318.435958 -35.600831)
			(xy 318.435482 -35.573462) (xy 318.435987 -35.546236) (xy 318.443717 -35.492334) (xy 318.459028 -35.440079)
			(xy 318.481611 -35.39053) (xy 318.511006 -35.344693) (xy 318.528446 -35.32378) (xy 318.534288 -35.316922)
			(xy 318.540892 -35.29965) (xy 318.540384 -35.214306) (xy 318.534034 -35.197288) (xy 318.527938 -35.19043)
			(xy 318.510121 -35.169432) (xy 318.480085 -35.123278) (xy 318.456996 -35.073285) (xy 318.441333 -35.020492)
			(xy 318.433422 -34.965996) (xy 318.432942 -34.938462) (xy 317.861549 -34.938462) (xy 317.86348 -34.953745)
			(xy 317.863982 -34.985706) (xy 317.86348 -35.017667) (xy 317.855469 -35.081085) (xy 317.839572 -35.142999)
			(xy 317.81604 -35.202432) (xy 317.785246 -35.258447) (xy 317.747673 -35.310162) (xy 317.703916 -35.356759)
			(xy 317.654663 -35.397504) (xy 317.600692 -35.431755) (xy 317.542853 -35.458972) (xy 317.48206 -35.478725)
			(xy 317.41927 -35.490703) (xy 317.355474 -35.494717) (xy 317.291678 -35.490703) (xy 317.228888 -35.478725)
			(xy 317.168095 -35.458972) (xy 317.110256 -35.431755) (xy 317.056285 -35.397504) (xy 317.007032 -35.356759)
			(xy 316.963275 -35.310162) (xy 316.925702 -35.258447) (xy 316.894908 -35.202432) (xy 316.871376 -35.142999)
			(xy 316.855479 -35.081085) (xy 316.847468 -35.017667) (xy 315.107639 -35.017667) (xy 315.094511 -35.045672)
			(xy 315.063738 -35.092185) (xy 315.026521 -35.133722) (xy 314.983653 -35.169397) (xy 314.936047 -35.198451)
			(xy 314.884718 -35.220263) (xy 314.830761 -35.234369) (xy 314.775324 -35.240469) (xy 314.71959 -35.238432)
			(xy 314.664747 -35.228302) (xy 314.611963 -35.210295) (xy 314.562363 -35.184794) (xy 314.517005 -35.152343)
			(xy 314.476856 -35.113634) (xy 314.44277 -35.069491) (xy 314.415474 -35.020856) (xy 314.395551 -34.968765)
			(xy 314.383425 -34.914328) (xy 314.379354 -34.858706) (xy 294.355876 -34.858706) (xy 294.306068 -34.894567)
			(xy 294.227166 -34.941643) (xy 294.144509 -34.981762) (xy 294.05871 -35.014627) (xy 293.970402 -35.039994)
			(xy 293.880242 -35.057676) (xy 293.788894 -35.067542) (xy 293.697037 -35.069519) (xy 293.60535 -35.063592)
			(xy 293.514512 -35.049806) (xy 293.425195 -35.028261) (xy 293.338061 -34.999118) (xy 293.253755 -34.962592)
			(xy 293.172901 -34.918954) (xy 293.096097 -34.868527) (xy 293.023913 -34.811685) (xy 292.956882 -34.748847)
			(xy 292.895501 -34.68048) (xy 292.840225 -34.60709) (xy 292.791462 -34.529219) (xy 292.749574 -34.447444)
			(xy 292.714871 -34.362372) (xy 292.687609 -34.274631) (xy 292.667992 -34.184871) (xy 292.656162 -34.093757)
			(xy 292.65221 -34.001964) (xy 275.0947 -34.001964) (xy 275.0947 -35.975849) (xy 308.465498 -35.975849)
			(xy 308.465498 -35.921351) (xy 308.473254 -35.867409) (xy 308.488607 -35.815119) (xy 308.511245 -35.765546)
			(xy 308.540707 -35.719699) (xy 308.576394 -35.678512) (xy 308.617579 -35.642822) (xy 308.663423 -35.613357)
			(xy 308.712995 -35.590716) (xy 308.765283 -35.575359) (xy 308.819225 -35.5676) (xy 308.846474 -35.567112)
			(xy 308.873844 -35.56759) (xy 308.928022 -35.575405) (xy 308.980526 -35.590891) (xy 309.030273 -35.61373)
			(xy 309.07624 -35.643452) (xy 309.097172 -35.661092) (xy 309.097426 -35.661346) (xy 309.104526 -35.666913)
			(xy 309.121433 -35.67317) (xy 309.130446 -35.673538) (xy 309.197502 -35.673538) (xy 309.206518 -35.673174)
			(xy 309.223435 -35.66693) (xy 309.230522 -35.661346) (xy 309.230522 -35.661092) (xy 309.230776 -35.661092)
			(xy 309.251705 -35.643449) (xy 309.297679 -35.613738) (xy 309.347427 -35.590903) (xy 309.399928 -35.575413)
			(xy 309.454105 -35.567586) (xy 309.481474 -35.567112) (xy 309.50873 -35.567533) (xy 309.562686 -35.575287)
			(xy 309.61499 -35.590642) (xy 309.664576 -35.613284) (xy 309.710435 -35.642753) (xy 309.751633 -35.678449)
			(xy 309.787331 -35.719644) (xy 309.816803 -35.765501) (xy 309.839449 -35.815086) (xy 309.854807 -35.867388)
			(xy 309.862565 -35.921345) (xy 309.862565 -35.975855) (xy 309.854807 -36.029812) (xy 309.839449 -36.082114)
			(xy 309.831394 -36.09975) (xy 312.321954 -36.09975) (xy 312.326025 -36.044128) (xy 312.338151 -35.989691)
			(xy 312.358074 -35.9376) (xy 312.38537 -35.888965) (xy 312.419456 -35.844822) (xy 312.459605 -35.806113)
			(xy 312.504963 -35.773662) (xy 312.554563 -35.748161) (xy 312.607347 -35.730154) (xy 312.66219 -35.720024)
			(xy 312.717924 -35.717987) (xy 312.773361 -35.724087) (xy 312.827318 -35.738193) (xy 312.878647 -35.760005)
			(xy 312.926253 -35.789059) (xy 312.969121 -35.824734) (xy 313.006338 -35.866271) (xy 313.037111 -35.912784)
			(xy 313.060783 -35.963281) (xy 313.076851 -36.016688) (xy 313.084971 -36.071864) (xy 313.08548 -36.09975)
			(xy 313.084971 -36.127636) (xy 313.076851 -36.182812) (xy 313.060783 -36.236219) (xy 313.037111 -36.286716)
			(xy 313.006338 -36.333229) (xy 312.969121 -36.374766) (xy 312.926253 -36.410441) (xy 312.878647 -36.439495)
			(xy 312.827318 -36.461307) (xy 312.773361 -36.475413) (xy 312.717924 -36.481513) (xy 312.66219 -36.479476)
			(xy 312.607347 -36.469346) (xy 312.554563 -36.451339) (xy 312.504963 -36.425838) (xy 312.459605 -36.393387)
			(xy 312.419456 -36.354678) (xy 312.38537 -36.310535) (xy 312.358074 -36.2619) (xy 312.338151 -36.209809)
			(xy 312.326025 -36.155372) (xy 312.321954 -36.09975) (xy 309.831394 -36.09975) (xy 309.816803 -36.131699)
			(xy 309.787331 -36.177556) (xy 309.751633 -36.218751) (xy 309.710435 -36.254447) (xy 309.664576 -36.283916)
			(xy 309.61499 -36.306558) (xy 309.562686 -36.321913) (xy 309.50873 -36.329667) (xy 309.481474 -36.330128)
			(xy 309.454102 -36.329695) (xy 309.399921 -36.321872) (xy 309.347417 -36.306376) (xy 309.297671 -36.283526)
			(xy 309.251706 -36.253794) (xy 309.230776 -36.236148) (xy 309.230522 -36.235894) (xy 309.223434 -36.23031)
			(xy 309.206518 -36.224062) (xy 309.197502 -36.223702) (xy 309.130446 -36.223702) (xy 309.121431 -36.224081)
			(xy 309.104514 -36.230313) (xy 309.097426 -36.235894) (xy 309.097426 -36.236148) (xy 309.097172 -36.236148)
			(xy 309.076217 -36.253759) (xy 309.030251 -36.283477) (xy 308.98051 -36.306319) (xy 308.928014 -36.321816)
			(xy 308.873842 -36.329651) (xy 308.846474 -36.330128) (xy 308.819225 -36.3296) (xy 308.765283 -36.321841)
			(xy 308.712995 -36.306484) (xy 308.663423 -36.283843) (xy 308.617579 -36.254378) (xy 308.576394 -36.218688)
			(xy 308.540707 -36.177501) (xy 308.511245 -36.131654) (xy 308.488607 -36.082081) (xy 308.473254 -36.029791)
			(xy 308.465498 -35.975849) (xy 275.0947 -35.975849) (xy 275.0947 -37.017706) (xy 329.987654 -37.017706)
			(xy 329.991725 -36.962084) (xy 330.003851 -36.907647) (xy 330.023774 -36.855556) (xy 330.05107 -36.806921)
			(xy 330.085156 -36.762778) (xy 330.125305 -36.724069) (xy 330.170663 -36.691618) (xy 330.220263 -36.666117)
			(xy 330.273047 -36.64811) (xy 330.32789 -36.63798) (xy 330.383624 -36.635943) (xy 330.439061 -36.642043)
			(xy 330.493018 -36.656149) (xy 330.544347 -36.677961) (xy 330.591953 -36.707015) (xy 330.634821 -36.74269)
			(xy 330.672038 -36.784227) (xy 330.702811 -36.83074) (xy 330.726483 -36.881237) (xy 330.742551 -36.934644)
			(xy 330.750671 -36.98982) (xy 330.75118 -37.017706) (xy 330.751073 -37.023548) (xy 427.462442 -37.023548)
			(xy 427.462895 -36.99226) (xy 427.470573 -36.930155) (xy 427.485818 -36.869464) (xy 427.508401 -36.811104)
			(xy 427.537978 -36.755958) (xy 427.574103 -36.704862) (xy 427.616228 -36.658588) (xy 427.663717 -36.617836)
			(xy 427.689518 -36.60013) (xy 427.699629 -36.592562) (xy 427.711513 -36.570323) (xy 427.712124 -36.557712)
			(xy 427.712124 -36.473384) (xy 427.711515 -36.460773) (xy 427.699633 -36.438525) (xy 427.689518 -36.430966)
			(xy 427.663731 -36.413243) (xy 427.616253 -36.372487) (xy 427.574136 -36.326211) (xy 427.538017 -36.275115)
			(xy 427.508443 -36.219973) (xy 427.48586 -36.161618) (xy 427.470611 -36.100933) (xy 427.462925 -36.038834)
			(xy 427.462442 -36.007548) (xy 427.462944 -35.975587) (xy 427.470955 -35.912169) (xy 427.486852 -35.850255)
			(xy 427.510384 -35.790822) (xy 427.541178 -35.734807) (xy 427.578751 -35.683092) (xy 427.622508 -35.636495)
			(xy 427.671761 -35.59575) (xy 427.725732 -35.561499) (xy 427.783571 -35.534282) (xy 427.844364 -35.514529)
			(xy 427.907154 -35.502551) (xy 427.97095 -35.498538) (xy 428.034746 -35.502551) (xy 428.097536 -35.514529)
			(xy 428.158329 -35.534282) (xy 428.216168 -35.561499) (xy 428.270139 -35.59575) (xy 428.319392 -35.636495)
			(xy 428.363149 -35.683092) (xy 428.400722 -35.734807) (xy 428.431516 -35.790822) (xy 428.455048 -35.850255)
			(xy 428.470945 -35.912169) (xy 428.478956 -35.975587) (xy 428.479458 -36.007548) (xy 428.479002 -36.038836)
			(xy 428.478919 -36.039509) (xy 430.047394 -36.039509) (xy 430.047394 -35.975587) (xy 430.055405 -35.912169)
			(xy 430.071302 -35.850255) (xy 430.094834 -35.790822) (xy 430.125628 -35.734807) (xy 430.163201 -35.683092)
			(xy 430.206958 -35.636495) (xy 430.256211 -35.59575) (xy 430.310182 -35.561499) (xy 430.368021 -35.534282)
			(xy 430.428814 -35.514529) (xy 430.491604 -35.502551) (xy 430.5554 -35.498538) (xy 430.619196 -35.502551)
			(xy 430.681986 -35.514529) (xy 430.742779 -35.534282) (xy 430.800618 -35.561499) (xy 430.854589 -35.59575)
			(xy 430.903842 -35.636495) (xy 430.947599 -35.683092) (xy 430.985172 -35.734807) (xy 431.015966 -35.790822)
			(xy 431.039498 -35.850255) (xy 431.055395 -35.912169) (xy 431.056561 -35.921399) (xy 435.51068 -35.921399)
			(xy 435.51068 -35.857477) (xy 435.518691 -35.794059) (xy 435.534588 -35.732145) (xy 435.55812 -35.672712)
			(xy 435.588914 -35.616697) (xy 435.626487 -35.564982) (xy 435.670244 -35.518385) (xy 435.719497 -35.47764)
			(xy 435.773468 -35.443389) (xy 435.831307 -35.416172) (xy 435.8921 -35.396419) (xy 435.95489 -35.384441)
			(xy 436.018686 -35.380428) (xy 436.082482 -35.384441) (xy 436.145272 -35.396419) (xy 436.206065 -35.416172)
			(xy 436.263904 -35.443389) (xy 436.317875 -35.47764) (xy 436.367128 -35.518385) (xy 436.410885 -35.564982)
			(xy 436.448458 -35.616697) (xy 436.479252 -35.672712) (xy 436.502784 -35.732145) (xy 436.518681 -35.794059)
			(xy 436.526692 -35.857477) (xy 436.527194 -35.889438) (xy 436.526692 -35.921399) (xy 436.518681 -35.984817)
			(xy 436.502784 -36.046731) (xy 436.479252 -36.106164) (xy 436.448458 -36.162179) (xy 436.410885 -36.213894)
			(xy 436.367128 -36.260491) (xy 436.3309 -36.290461) (xy 453.885294 -36.290461) (xy 453.885294 -36.226539)
			(xy 453.893305 -36.163121) (xy 453.909202 -36.101207) (xy 453.932734 -36.041774) (xy 453.963528 -35.985759)
			(xy 454.001101 -35.934044) (xy 454.044858 -35.887447) (xy 454.094111 -35.846702) (xy 454.148082 -35.812451)
			(xy 454.205921 -35.785234) (xy 454.266714 -35.765481) (xy 454.329504 -35.753503) (xy 454.3933 -35.74949)
			(xy 454.457096 -35.753503) (xy 454.519886 -35.765481) (xy 454.580679 -35.785234) (xy 454.638518 -35.812451)
			(xy 454.692489 -35.846702) (xy 454.741742 -35.887447) (xy 454.785499 -35.934044) (xy 454.823072 -35.985759)
			(xy 454.853866 -36.041774) (xy 454.877398 -36.101207) (xy 454.893295 -36.163121) (xy 454.901306 -36.226539)
			(xy 454.901808 -36.2585) (xy 454.901306 -36.290461) (xy 454.893295 -36.353879) (xy 454.877398 -36.415793)
			(xy 454.853866 -36.475226) (xy 454.823072 -36.531241) (xy 454.785499 -36.582956) (xy 454.741742 -36.629553)
			(xy 454.692489 -36.670298) (xy 454.638518 -36.704549) (xy 454.580679 -36.731766) (xy 454.519886 -36.751519)
			(xy 454.457096 -36.763497) (xy 454.3933 -36.767511) (xy 454.329504 -36.763497) (xy 454.266714 -36.751519)
			(xy 454.205921 -36.731766) (xy 454.148082 -36.704549) (xy 454.094111 -36.670298) (xy 454.044858 -36.629553)
			(xy 454.001101 -36.582956) (xy 453.963528 -36.531241) (xy 453.932734 -36.475226) (xy 453.909202 -36.415793)
			(xy 453.893305 -36.353879) (xy 453.885294 -36.290461) (xy 436.3309 -36.290461) (xy 436.317875 -36.301236)
			(xy 436.263904 -36.335487) (xy 436.206065 -36.362704) (xy 436.145272 -36.382457) (xy 436.082482 -36.394435)
			(xy 436.018686 -36.398449) (xy 435.95489 -36.394435) (xy 435.8921 -36.382457) (xy 435.831307 -36.362704)
			(xy 435.773468 -36.335487) (xy 435.719497 -36.301236) (xy 435.670244 -36.260491) (xy 435.626487 -36.213894)
			(xy 435.588914 -36.162179) (xy 435.55812 -36.106164) (xy 435.534588 -36.046731) (xy 435.518691 -35.984817)
			(xy 435.51068 -35.921399) (xy 431.056561 -35.921399) (xy 431.063406 -35.975587) (xy 431.063908 -36.007548)
			(xy 431.063406 -36.039509) (xy 431.055395 -36.102927) (xy 431.039498 -36.164841) (xy 431.015966 -36.224274)
			(xy 430.985172 -36.280289) (xy 430.947599 -36.332004) (xy 430.903842 -36.378601) (xy 430.854589 -36.419346)
			(xy 430.800618 -36.453597) (xy 430.742779 -36.480814) (xy 430.681986 -36.500567) (xy 430.638298 -36.508901)
			(xy 432.592474 -36.508901) (xy 432.592474 -36.444979) (xy 432.600485 -36.381561) (xy 432.616382 -36.319647)
			(xy 432.639914 -36.260214) (xy 432.670708 -36.204199) (xy 432.708281 -36.152484) (xy 432.752038 -36.105887)
			(xy 432.801291 -36.065142) (xy 432.855262 -36.030891) (xy 432.913101 -36.003674) (xy 432.973894 -35.983921)
			(xy 433.036684 -35.971943) (xy 433.10048 -35.96793) (xy 433.164276 -35.971943) (xy 433.227066 -35.983921)
			(xy 433.287859 -36.003674) (xy 433.345698 -36.030891) (xy 433.399669 -36.065142) (xy 433.448922 -36.105887)
			(xy 433.492679 -36.152484) (xy 433.530252 -36.204199) (xy 433.561046 -36.260214) (xy 433.584578 -36.319647)
			(xy 433.600475 -36.381561) (xy 433.608486 -36.444979) (xy 433.608988 -36.47694) (xy 433.608486 -36.508901)
			(xy 433.600475 -36.572319) (xy 433.584578 -36.634233) (xy 433.561046 -36.693666) (xy 433.530252 -36.749681)
			(xy 433.492679 -36.801396) (xy 433.448922 -36.847993) (xy 433.399669 -36.888738) (xy 433.345698 -36.922989)
			(xy 433.287859 -36.950206) (xy 433.227066 -36.969959) (xy 433.164276 -36.981937) (xy 433.10048 -36.985951)
			(xy 433.036684 -36.981937) (xy 432.973894 -36.969959) (xy 432.913101 -36.950206) (xy 432.855262 -36.922989)
			(xy 432.801291 -36.888738) (xy 432.752038 -36.847993) (xy 432.708281 -36.801396) (xy 432.670708 -36.749681)
			(xy 432.639914 -36.693666) (xy 432.616382 -36.634233) (xy 432.600485 -36.572319) (xy 432.592474 -36.508901)
			(xy 430.638298 -36.508901) (xy 430.619196 -36.512545) (xy 430.5554 -36.516559) (xy 430.491604 -36.512545)
			(xy 430.428814 -36.500567) (xy 430.368021 -36.480814) (xy 430.310182 -36.453597) (xy 430.256211 -36.419346)
			(xy 430.206958 -36.378601) (xy 430.163201 -36.332004) (xy 430.125628 -36.280289) (xy 430.094834 -36.224274)
			(xy 430.071302 -36.164841) (xy 430.055405 -36.102927) (xy 430.047394 -36.039509) (xy 428.478919 -36.039509)
			(xy 428.471325 -36.10094) (xy 428.45608 -36.161632) (xy 428.433498 -36.219992) (xy 428.403921 -36.275137)
			(xy 428.367796 -36.326234) (xy 428.325671 -36.372508) (xy 428.278183 -36.41326) (xy 428.252382 -36.430966)
			(xy 428.242227 -36.438485) (xy 428.230366 -36.460761) (xy 428.229776 -36.473384) (xy 428.229776 -36.557712)
			(xy 428.230388 -36.570322) (xy 428.242268 -36.59257) (xy 428.252382 -36.60013) (xy 428.278167 -36.617855)
			(xy 428.325646 -36.658612) (xy 428.367763 -36.704887) (xy 428.403881 -36.755982) (xy 428.433456 -36.811124)
			(xy 428.456039 -36.869479) (xy 428.471289 -36.930164) (xy 428.478975 -36.992262) (xy 428.479458 -37.023548)
			(xy 428.478956 -37.055509) (xy 428.470945 -37.118927) (xy 428.455048 -37.180841) (xy 428.431516 -37.240274)
			(xy 428.400722 -37.296289) (xy 428.391117 -37.309509) (xy 430.047394 -37.309509) (xy 430.047394 -37.245587)
			(xy 430.055405 -37.182169) (xy 430.071302 -37.120255) (xy 430.094834 -37.060822) (xy 430.125628 -37.004807)
			(xy 430.163201 -36.953092) (xy 430.206958 -36.906495) (xy 430.256211 -36.86575) (xy 430.310182 -36.831499)
			(xy 430.368021 -36.804282) (xy 430.428814 -36.784529) (xy 430.491604 -36.772551) (xy 430.5554 -36.768538)
			(xy 430.619196 -36.772551) (xy 430.681986 -36.784529) (xy 430.742779 -36.804282) (xy 430.800618 -36.831499)
			(xy 430.854589 -36.86575) (xy 430.903842 -36.906495) (xy 430.947599 -36.953092) (xy 430.985172 -37.004807)
			(xy 431.015966 -37.060822) (xy 431.039498 -37.120255) (xy 431.055395 -37.182169) (xy 431.063406 -37.245587)
			(xy 431.063908 -37.277548) (xy 431.063406 -37.309509) (xy 431.055395 -37.372927) (xy 431.039498 -37.434841)
			(xy 431.033809 -37.449209) (xy 436.785506 -37.449209) (xy 436.785506 -37.385287) (xy 436.793517 -37.321869)
			(xy 436.809414 -37.259955) (xy 436.832946 -37.200522) (xy 436.86374 -37.144507) (xy 436.901313 -37.092792)
			(xy 436.94507 -37.046195) (xy 436.994323 -37.00545) (xy 437.048294 -36.971199) (xy 437.106133 -36.943982)
			(xy 437.166926 -36.924229) (xy 437.229716 -36.912251) (xy 437.293512 -36.908238) (xy 437.357308 -36.912251)
			(xy 437.420098 -36.924229) (xy 437.480891 -36.943982) (xy 437.53873 -36.971199) (xy 437.592701 -37.00545)
			(xy 437.641954 -37.046195) (xy 437.685711 -37.092792) (xy 437.723284 -37.144507) (xy 437.747387 -37.188351)
			(xy 456.105762 -37.188351) (xy 456.105762 -37.124429) (xy 456.113773 -37.061011) (xy 456.12967 -36.999097)
			(xy 456.153202 -36.939664) (xy 456.183996 -36.883649) (xy 456.221569 -36.831934) (xy 456.265326 -36.785337)
			(xy 456.314579 -36.744592) (xy 456.36855 -36.710341) (xy 456.426389 -36.683124) (xy 456.487182 -36.663371)
			(xy 456.549972 -36.651393) (xy 456.613768 -36.64738) (xy 456.677564 -36.651393) (xy 456.740354 -36.663371)
			(xy 456.801147 -36.683124) (xy 456.858986 -36.710341) (xy 456.912957 -36.744592) (xy 456.96221 -36.785337)
			(xy 457.005967 -36.831934) (xy 457.04354 -36.883649) (xy 457.074334 -36.939664) (xy 457.097866 -36.999097)
			(xy 457.113763 -37.061011) (xy 457.121774 -37.124429) (xy 457.122276 -37.15639) (xy 457.121774 -37.188351)
			(xy 457.113763 -37.251769) (xy 457.097866 -37.313683) (xy 457.074334 -37.373116) (xy 457.04354 -37.429131)
			(xy 457.005967 -37.480846) (xy 456.96221 -37.527443) (xy 456.912957 -37.568188) (xy 456.858986 -37.602439)
			(xy 456.801147 -37.629656) (xy 456.740354 -37.649409) (xy 456.677564 -37.661387) (xy 456.613768 -37.665401)
			(xy 456.549972 -37.661387) (xy 456.487182 -37.649409) (xy 456.426389 -37.629656) (xy 456.36855 -37.602439)
			(xy 456.314579 -37.568188) (xy 456.265326 -37.527443) (xy 456.221569 -37.480846) (xy 456.183996 -37.429131)
			(xy 456.153202 -37.373116) (xy 456.12967 -37.313683) (xy 456.113773 -37.251769) (xy 456.105762 -37.188351)
			(xy 437.747387 -37.188351) (xy 437.754078 -37.200522) (xy 437.77761 -37.259955) (xy 437.793507 -37.321869)
			(xy 437.801518 -37.385287) (xy 437.80202 -37.417248) (xy 437.801518 -37.449209) (xy 437.793507 -37.512627)
			(xy 437.77761 -37.574541) (xy 437.754078 -37.633974) (xy 437.723284 -37.689989) (xy 437.685711 -37.741704)
			(xy 437.641954 -37.788301) (xy 437.592701 -37.829046) (xy 437.53873 -37.863297) (xy 437.480891 -37.890514)
			(xy 437.420098 -37.910267) (xy 437.357308 -37.922245) (xy 437.293512 -37.926259) (xy 437.229716 -37.922245)
			(xy 437.166926 -37.910267) (xy 437.106133 -37.890514) (xy 437.048294 -37.863297) (xy 436.994323 -37.829046)
			(xy 436.94507 -37.788301) (xy 436.901313 -37.741704) (xy 436.86374 -37.689989) (xy 436.832946 -37.633974)
			(xy 436.809414 -37.574541) (xy 436.793517 -37.512627) (xy 436.785506 -37.449209) (xy 431.033809 -37.449209)
			(xy 431.015966 -37.494274) (xy 430.985172 -37.550289) (xy 430.947599 -37.602004) (xy 430.903842 -37.648601)
			(xy 430.854589 -37.689346) (xy 430.800618 -37.723597) (xy 430.742779 -37.750814) (xy 430.681986 -37.770567)
			(xy 430.619196 -37.782545) (xy 430.5554 -37.786559) (xy 430.491604 -37.782545) (xy 430.428814 -37.770567)
			(xy 430.368021 -37.750814) (xy 430.310182 -37.723597) (xy 430.256211 -37.689346) (xy 430.206958 -37.648601)
			(xy 430.163201 -37.602004) (xy 430.125628 -37.550289) (xy 430.094834 -37.494274) (xy 430.071302 -37.434841)
			(xy 430.055405 -37.372927) (xy 430.047394 -37.309509) (xy 428.391117 -37.309509) (xy 428.363149 -37.348004)
			(xy 428.319392 -37.394601) (xy 428.270139 -37.435346) (xy 428.216168 -37.469597) (xy 428.158329 -37.496814)
			(xy 428.097536 -37.516567) (xy 428.034746 -37.528545) (xy 427.97095 -37.532559) (xy 427.907154 -37.528545)
			(xy 427.844364 -37.516567) (xy 427.783571 -37.496814) (xy 427.725732 -37.469597) (xy 427.671761 -37.435346)
			(xy 427.622508 -37.394601) (xy 427.578751 -37.348004) (xy 427.541178 -37.296289) (xy 427.510384 -37.240274)
			(xy 427.486852 -37.180841) (xy 427.470955 -37.118927) (xy 427.462944 -37.055509) (xy 427.462442 -37.023548)
			(xy 330.751073 -37.023548) (xy 330.750671 -37.045592) (xy 330.742551 -37.100768) (xy 330.726483 -37.154175)
			(xy 330.702811 -37.204672) (xy 330.672038 -37.251185) (xy 330.634821 -37.292722) (xy 330.591953 -37.328397)
			(xy 330.544347 -37.357451) (xy 330.493018 -37.379263) (xy 330.439061 -37.393369) (xy 330.383624 -37.399469)
			(xy 330.32789 -37.397432) (xy 330.273047 -37.387302) (xy 330.220263 -37.369295) (xy 330.170663 -37.343794)
			(xy 330.125305 -37.311343) (xy 330.085156 -37.272634) (xy 330.05107 -37.228491) (xy 330.023774 -37.179856)
			(xy 330.003851 -37.127765) (xy 329.991725 -37.073328) (xy 329.987654 -37.017706) (xy 275.0947 -37.017706)
			(xy 275.0947 -38.839648) (xy 324.116192 -38.839648) (xy 324.116653 -38.807757) (xy 324.124646 -38.744478)
			(xy 324.140488 -38.682695) (xy 324.16393 -38.623377) (xy 324.194604 -38.567456) (xy 324.232029 -38.515808)
			(xy 324.275617 -38.469244) (xy 324.299834 -38.448488) (xy 324.306946 -38.442646) (xy 324.31609 -38.42639)
			(xy 324.327774 -38.350444) (xy 324.328767 -38.341291) (xy 324.324843 -38.323316) (xy 324.320154 -38.315392)
			(xy 324.320154 -38.315138) (xy 324.305614 -38.291859) (xy 324.282663 -38.242003) (xy 324.267079 -38.189377)
			(xy 324.259183 -38.135062) (xy 324.258686 -38.10762) (xy 324.259172 -38.080369) (xy 324.266928 -38.026421)
			(xy 324.282283 -37.974126) (xy 324.304925 -37.924549) (xy 324.334391 -37.878699) (xy 324.370082 -37.837508)
			(xy 324.411273 -37.801817) (xy 324.457123 -37.772351) (xy 324.5067 -37.749709) (xy 324.558995 -37.734354)
			(xy 324.612943 -37.726598) (xy 324.667445 -37.726598) (xy 324.721393 -37.734354) (xy 324.773688 -37.749709)
			(xy 324.823265 -37.772351) (xy 324.869115 -37.801817) (xy 324.910306 -37.837508) (xy 324.945997 -37.878699)
			(xy 324.975463 -37.924549) (xy 324.97787 -37.92982) (xy 331.451456 -37.92982) (xy 331.455527 -37.874198)
			(xy 331.467653 -37.819761) (xy 331.487576 -37.76767) (xy 331.514872 -37.719035) (xy 331.548958 -37.674892)
			(xy 331.589107 -37.636183) (xy 331.634465 -37.603732) (xy 331.684065 -37.578231) (xy 331.736849 -37.560224)
			(xy 331.791692 -37.550094) (xy 331.847426 -37.548057) (xy 331.902863 -37.554157) (xy 331.95682 -37.568263)
			(xy 332.008149 -37.590075) (xy 332.055755 -37.619129) (xy 332.098623 -37.654804) (xy 332.13584 -37.696341)
			(xy 332.166613 -37.742854) (xy 332.190285 -37.793351) (xy 332.206353 -37.846758) (xy 332.214473 -37.901934)
			(xy 332.214982 -37.92982) (xy 332.214473 -37.957706) (xy 332.206353 -38.012882) (xy 332.190285 -38.066289)
			(xy 332.166613 -38.116786) (xy 332.13584 -38.163299) (xy 332.098623 -38.204836) (xy 332.055755 -38.240511)
			(xy 332.008149 -38.269565) (xy 331.95682 -38.291377) (xy 331.902863 -38.305483) (xy 331.847426 -38.311583)
			(xy 331.791692 -38.309546) (xy 331.736849 -38.299416) (xy 331.684065 -38.281409) (xy 331.634465 -38.255908)
			(xy 331.589107 -38.223457) (xy 331.548958 -38.184748) (xy 331.514872 -38.140605) (xy 331.487576 -38.09197)
			(xy 331.467653 -38.039879) (xy 331.455527 -37.985442) (xy 331.451456 -37.92982) (xy 324.97787 -37.92982)
			(xy 324.998105 -37.974126) (xy 325.01346 -38.026421) (xy 325.021216 -38.080369) (xy 325.021702 -38.10762)
			(xy 325.021702 -38.108128) (xy 325.021122 -38.137534) (xy 325.012051 -38.195644) (xy 324.994173 -38.251674)
			(xy 324.967912 -38.304299) (xy 324.951344 -38.3286) (xy 324.94633 -38.336351) (xy 324.941633 -38.354185)
			(xy 324.9422 -38.363398) (xy 324.950582 -38.439852) (xy 324.958964 -38.456362) (xy 324.965822 -38.462712)
			(xy 324.988004 -38.483418) (xy 325.027836 -38.529197) (xy 325.061939 -38.579388) (xy 325.089831 -38.63328)
			(xy 325.111115 -38.690107) (xy 325.125488 -38.749062) (xy 325.132747 -38.809307) (xy 325.132892 -38.81882)
			(xy 331.451456 -38.81882) (xy 331.455527 -38.763198) (xy 331.467653 -38.708761) (xy 331.487576 -38.65667)
			(xy 331.514872 -38.608035) (xy 331.548958 -38.563892) (xy 331.589107 -38.525183) (xy 331.634465 -38.492732)
			(xy 331.684065 -38.467231) (xy 331.736849 -38.449224) (xy 331.791692 -38.439094) (xy 331.847426 -38.437057)
			(xy 331.902863 -38.443157) (xy 331.95682 -38.457263) (xy 332.008149 -38.479075) (xy 332.055755 -38.508129)
			(xy 332.098623 -38.543804) (xy 332.13584 -38.585341) (xy 332.166613 -38.631854) (xy 332.187991 -38.677458)
			(xy 364.950119 -38.677458) (xy 364.950119 -38.622942) (xy 364.957878 -38.568982) (xy 364.973238 -38.516675)
			(xy 364.995886 -38.467087) (xy 365.025361 -38.421228) (xy 365.061064 -38.38003) (xy 365.102266 -38.344333)
			(xy 365.14813 -38.314863) (xy 365.19772 -38.292221) (xy 365.250029 -38.276868) (xy 365.30399 -38.269116)
			(xy 365.331248 -38.268656) (xy 365.331502 -38.268656) (xy 365.355895 -38.269055) (xy 365.404284 -38.275255)
			(xy 365.451486 -38.287579) (xy 365.49673 -38.305827) (xy 365.518192 -38.317424) (xy 365.525643 -38.321265)
			(xy 365.542109 -38.324362) (xy 365.55045 -38.32352) (xy 365.57966 -38.319202) (xy 365.588111 -38.317599)
			(xy 365.603298 -38.30954) (xy 365.609378 -38.303454) (xy 365.630003 -38.281933) (xy 365.675458 -38.243368)
			(xy 365.725114 -38.210386) (xy 365.778287 -38.183441) (xy 365.834247 -38.162902) (xy 365.892227 -38.149052)
			(xy 365.951429 -38.142081) (xy 365.981234 -38.141656) (xy 366.013191 -38.142232) (xy 366.076602 -38.150246)
			(xy 366.138508 -38.166145) (xy 366.197933 -38.189677) (xy 366.253941 -38.22047) (xy 366.305647 -38.258041)
			(xy 366.352238 -38.301795) (xy 366.392977 -38.351043) (xy 366.427223 -38.405009) (xy 366.454436 -38.462842)
			(xy 366.474185 -38.523628) (xy 366.486161 -38.586411) (xy 366.490175 -38.6502) (xy 366.48846 -38.677456)
			(xy 368.850319 -38.677456) (xy 368.850319 -38.622944) (xy 368.858077 -38.568986) (xy 368.873436 -38.516682)
			(xy 368.896082 -38.467096) (xy 368.925554 -38.421237) (xy 368.961253 -38.38004) (xy 369.002452 -38.344343)
			(xy 369.048312 -38.314873) (xy 369.097899 -38.292229) (xy 369.150204 -38.276873) (xy 369.204162 -38.269118)
			(xy 369.231418 -38.268656) (xy 369.231672 -38.268656) (xy 369.256066 -38.269025) (xy 369.304456 -38.275234)
			(xy 369.351658 -38.287567) (xy 369.3969 -38.305823) (xy 369.418362 -38.317424) (xy 369.425819 -38.321252)
			(xy 369.44228 -38.324357) (xy 369.45062 -38.32352) (xy 369.47983 -38.319202) (xy 369.488278 -38.317587)
			(xy 369.503467 -38.309537) (xy 369.509548 -38.303454) (xy 369.530188 -38.281948) (xy 369.57564 -38.243382)
			(xy 369.625293 -38.210398) (xy 369.678464 -38.183451) (xy 369.734422 -38.16291) (xy 369.792399 -38.149057)
			(xy 369.851599 -38.142083) (xy 369.881404 -38.141656) (xy 369.913363 -38.14223) (xy 369.976776 -38.150241)
			(xy 370.038685 -38.166137) (xy 370.098113 -38.189667) (xy 370.154124 -38.22046) (xy 370.205834 -38.25803)
			(xy 370.252428 -38.301784) (xy 370.29317 -38.351034) (xy 370.327418 -38.405001) (xy 370.354633 -38.462835)
			(xy 370.374384 -38.523624) (xy 370.385045 -38.579509) (xy 419.233344 -38.579509) (xy 419.233344 -38.515587)
			(xy 419.241355 -38.452169) (xy 419.257252 -38.390255) (xy 419.280784 -38.330822) (xy 419.311578 -38.274807)
			(xy 419.349151 -38.223092) (xy 419.392908 -38.176495) (xy 419.442161 -38.13575) (xy 419.496132 -38.101499)
			(xy 419.553971 -38.074282) (xy 419.614764 -38.054529) (xy 419.677554 -38.042551) (xy 419.74135 -38.038538)
			(xy 419.757406 -38.039548) (xy 427.588932 -38.039548) (xy 427.593003 -37.983926) (xy 427.605129 -37.929489)
			(xy 427.625052 -37.877398) (xy 427.652348 -37.828763) (xy 427.686434 -37.78462) (xy 427.726583 -37.745911)
			(xy 427.771941 -37.71346) (xy 427.821541 -37.687959) (xy 427.874325 -37.669952) (xy 427.929168 -37.659822)
			(xy 427.984902 -37.657785) (xy 428.040339 -37.663885) (xy 428.094296 -37.677991) (xy 428.145625 -37.699803)
			(xy 428.193231 -37.728857) (xy 428.236099 -37.764532) (xy 428.273316 -37.806069) (xy 428.304089 -37.852582)
			(xy 428.327761 -37.903079) (xy 428.343829 -37.956486) (xy 428.351949 -38.011662) (xy 428.352458 -38.039548)
			(xy 428.351949 -38.067434) (xy 428.343829 -38.12261) (xy 428.327761 -38.176017) (xy 428.304089 -38.226514)
			(xy 428.273316 -38.273027) (xy 428.236099 -38.314564) (xy 428.193231 -38.350239) (xy 428.145625 -38.379293)
			(xy 428.094296 -38.401105) (xy 428.040339 -38.415211) (xy 427.984902 -38.421311) (xy 427.929168 -38.419274)
			(xy 427.874325 -38.409144) (xy 427.821541 -38.391137) (xy 427.771941 -38.365636) (xy 427.726583 -38.333185)
			(xy 427.686434 -38.294476) (xy 427.652348 -38.250333) (xy 427.625052 -38.201698) (xy 427.605129 -38.149607)
			(xy 427.593003 -38.09517) (xy 427.588932 -38.039548) (xy 419.757406 -38.039548) (xy 419.805146 -38.042551)
			(xy 419.867936 -38.054529) (xy 419.928729 -38.074282) (xy 419.986568 -38.101499) (xy 420.040539 -38.13575)
			(xy 420.089792 -38.176495) (xy 420.133549 -38.223092) (xy 420.171122 -38.274807) (xy 420.201916 -38.330822)
			(xy 420.225448 -38.390255) (xy 420.241345 -38.452169) (xy 420.249356 -38.515587) (xy 420.249858 -38.547548)
			(xy 420.249356 -38.579509) (xy 430.047394 -38.579509) (xy 430.047394 -38.515587) (xy 430.055405 -38.452169)
			(xy 430.071302 -38.390255) (xy 430.094834 -38.330822) (xy 430.125628 -38.274807) (xy 430.163201 -38.223092)
			(xy 430.206958 -38.176495) (xy 430.256211 -38.13575) (xy 430.310182 -38.101499) (xy 430.368021 -38.074282)
			(xy 430.428814 -38.054529) (xy 430.491604 -38.042551) (xy 430.5554 -38.038538) (xy 430.619196 -38.042551)
			(xy 430.681986 -38.054529) (xy 430.742779 -38.074282) (xy 430.800618 -38.101499) (xy 430.854589 -38.13575)
			(xy 430.903842 -38.176495) (xy 430.947599 -38.223092) (xy 430.985172 -38.274807) (xy 431.015966 -38.330822)
			(xy 431.039498 -38.390255) (xy 431.055395 -38.452169) (xy 431.063406 -38.515587) (xy 431.063908 -38.547548)
			(xy 431.063406 -38.579509) (xy 431.055395 -38.642927) (xy 431.039498 -38.704841) (xy 431.015966 -38.764274)
			(xy 430.985172 -38.820289) (xy 430.947599 -38.872004) (xy 430.903842 -38.918601) (xy 430.854589 -38.959346)
			(xy 430.800618 -38.993597) (xy 430.742779 -39.020814) (xy 430.681986 -39.040567) (xy 430.619196 -39.052545)
			(xy 430.5554 -39.056559) (xy 430.491604 -39.052545) (xy 430.428814 -39.040567) (xy 430.368021 -39.020814)
			(xy 430.310182 -38.993597) (xy 430.256211 -38.959346) (xy 430.206958 -38.918601) (xy 430.163201 -38.872004)
			(xy 430.125628 -38.820289) (xy 430.094834 -38.764274) (xy 430.071302 -38.704841) (xy 430.055405 -38.642927)
			(xy 430.047394 -38.579509) (xy 420.249356 -38.579509) (xy 420.241345 -38.642927) (xy 420.225448 -38.704841)
			(xy 420.201916 -38.764274) (xy 420.171122 -38.820289) (xy 420.133549 -38.872004) (xy 420.089792 -38.918601)
			(xy 420.040539 -38.959346) (xy 419.986568 -38.993597) (xy 419.928729 -39.020814) (xy 419.867936 -39.040567)
			(xy 419.805146 -39.052545) (xy 419.757418 -39.055548) (xy 427.588932 -39.055548) (xy 427.593003 -38.999926)
			(xy 427.605129 -38.945489) (xy 427.625052 -38.893398) (xy 427.652348 -38.844763) (xy 427.686434 -38.80062)
			(xy 427.726583 -38.761911) (xy 427.771941 -38.72946) (xy 427.821541 -38.703959) (xy 427.874325 -38.685952)
			(xy 427.929168 -38.675822) (xy 427.984902 -38.673785) (xy 428.040339 -38.679885) (xy 428.094296 -38.693991)
			(xy 428.145625 -38.715803) (xy 428.193231 -38.744857) (xy 428.236099 -38.780532) (xy 428.273316 -38.822069)
			(xy 428.304089 -38.868582) (xy 428.327761 -38.919079) (xy 428.343829 -38.972486) (xy 428.351949 -39.027662)
			(xy 428.352458 -39.055548) (xy 428.351949 -39.083434) (xy 428.343829 -39.13861) (xy 428.327761 -39.192017)
			(xy 428.304089 -39.242514) (xy 428.273316 -39.289027) (xy 428.236099 -39.330564) (xy 428.193231 -39.366239)
			(xy 428.145625 -39.395293) (xy 428.094296 -39.417105) (xy 428.040339 -39.431211) (xy 427.984902 -39.437311)
			(xy 427.929168 -39.435274) (xy 427.874325 -39.425144) (xy 427.821541 -39.407137) (xy 427.771941 -39.381636)
			(xy 427.726583 -39.349185) (xy 427.686434 -39.310476) (xy 427.652348 -39.266333) (xy 427.625052 -39.217698)
			(xy 427.605129 -39.165607) (xy 427.593003 -39.11117) (xy 427.588932 -39.055548) (xy 419.757418 -39.055548)
			(xy 419.74135 -39.056559) (xy 419.677554 -39.052545) (xy 419.614764 -39.040567) (xy 419.553971 -39.020814)
			(xy 419.496132 -38.993597) (xy 419.442161 -38.959346) (xy 419.392908 -38.918601) (xy 419.349151 -38.872004)
			(xy 419.311578 -38.820289) (xy 419.280784 -38.764274) (xy 419.257252 -38.704841) (xy 419.241355 -38.642927)
			(xy 419.233344 -38.579509) (xy 370.385045 -38.579509) (xy 370.386361 -38.586409) (xy 370.390375 -38.6502)
			(xy 370.386361 -38.713991) (xy 370.374384 -38.776776) (xy 370.354633 -38.837565) (xy 370.327418 -38.895399)
			(xy 370.29317 -38.949366) (xy 370.252428 -38.998616) (xy 370.205834 -39.04237) (xy 370.154124 -39.07994)
			(xy 370.098113 -39.110733) (xy 370.038685 -39.134263) (xy 369.976776 -39.150159) (xy 369.913363 -39.15817)
			(xy 369.881404 -39.158672) (xy 369.8516 -39.158223) (xy 369.792401 -39.151251) (xy 369.734423 -39.137402)
			(xy 369.678464 -39.116865) (xy 369.625292 -39.089924) (xy 369.575635 -39.056947) (xy 369.530178 -39.018389)
			(xy 369.509548 -38.996874) (xy 369.50346 -38.990798) (xy 369.488276 -38.982745) (xy 369.47983 -38.981126)
			(xy 369.45062 -38.976808) (xy 369.442277 -38.975911) (xy 369.425798 -38.979017) (xy 369.418362 -38.982904)
			(xy 369.39689 -38.994482) (xy 369.351647 -39.012726) (xy 369.304448 -39.025059) (xy 369.256063 -39.031281)
			(xy 369.231672 -39.031672) (xy 369.231418 -39.031672) (xy 369.204162 -39.031282) (xy 369.150204 -39.023527)
			(xy 369.097899 -39.008171) (xy 369.048312 -38.985527) (xy 369.002452 -38.956057) (xy 368.961253 -38.92036)
			(xy 368.925554 -38.879163) (xy 368.896082 -38.833304) (xy 368.873436 -38.783718) (xy 368.858077 -38.731414)
			(xy 368.850319 -38.677456) (xy 366.48846 -38.677456) (xy 366.486161 -38.713989) (xy 366.474185 -38.776772)
			(xy 366.454436 -38.837558) (xy 366.427223 -38.895391) (xy 366.392977 -38.949357) (xy 366.352238 -38.998605)
			(xy 366.305647 -39.042359) (xy 366.253941 -39.07993) (xy 366.197933 -39.110723) (xy 366.138508 -39.134255)
			(xy 366.076602 -39.150154) (xy 366.013191 -39.158168) (xy 365.981234 -39.158672) (xy 365.951428 -39.158271)
			(xy 365.892227 -39.15129) (xy 365.834249 -39.137433) (xy 365.77829 -39.116889) (xy 365.725118 -39.08994)
			(xy 365.675463 -39.056957) (xy 365.630007 -39.018392) (xy 365.609378 -38.996874) (xy 365.603282 -38.990808)
			(xy 365.588104 -38.982749) (xy 365.57966 -38.981126) (xy 365.55045 -38.976808) (xy 365.542109 -38.975877)
			(xy 365.525626 -38.979006) (xy 365.518192 -38.982904) (xy 365.496734 -38.994509) (xy 365.451485 -39.012746)
			(xy 365.404283 -39.025072) (xy 365.355895 -39.031286) (xy 365.331502 -39.031672) (xy 365.331248 -39.031672)
			(xy 365.30399 -39.031284) (xy 365.250029 -39.023532) (xy 365.19772 -39.008179) (xy 365.14813 -38.985537)
			(xy 365.102266 -38.956067) (xy 365.061064 -38.92037) (xy 365.025361 -38.879172) (xy 364.995886 -38.833313)
			(xy 364.973238 -38.783725) (xy 364.957878 -38.731418) (xy 364.950119 -38.677458) (xy 332.187991 -38.677458)
			(xy 332.190285 -38.682351) (xy 332.206353 -38.735758) (xy 332.214473 -38.790934) (xy 332.214982 -38.81882)
			(xy 332.214473 -38.846706) (xy 332.206353 -38.901882) (xy 332.190285 -38.955289) (xy 332.166613 -39.005786)
			(xy 332.13584 -39.052299) (xy 332.098623 -39.093836) (xy 332.055755 -39.129511) (xy 332.008149 -39.158565)
			(xy 331.95682 -39.180377) (xy 331.902863 -39.194483) (xy 331.847426 -39.200583) (xy 331.791692 -39.198546)
			(xy 331.736849 -39.188416) (xy 331.684065 -39.170409) (xy 331.634465 -39.144908) (xy 331.589107 -39.112457)
			(xy 331.548958 -39.073748) (xy 331.514872 -39.029605) (xy 331.487576 -38.98097) (xy 331.467653 -38.928879)
			(xy 331.455527 -38.874442) (xy 331.451456 -38.81882) (xy 325.132892 -38.81882) (xy 325.133208 -38.839648)
			(xy 325.132741 -38.869237) (xy 325.125874 -38.928017) (xy 325.11224 -38.985604) (xy 325.092022 -39.041222)
			(xy 325.065491 -39.094121) (xy 325.033008 -39.143587) (xy 325.014336 -39.166546) (xy 325.008461 -39.174122)
			(xy 325.002323 -39.192266) (xy 325.002398 -39.201852) (xy 325.004176 -39.232586) (xy 325.005064 -39.242072)
			(xy 325.012891 -39.259426) (xy 325.019416 -39.266368) (xy 325.043434 -39.290395) (xy 325.085496 -39.343748)
			(xy 325.120079 -39.402225) (xy 325.14657 -39.464786) (xy 325.164496 -39.530317) (xy 325.173538 -39.597651)
			(xy 325.174102 -39.63162) (xy 325.1736 -39.663581) (xy 325.165589 -39.726999) (xy 325.149692 -39.788913)
			(xy 325.138354 -39.817548) (xy 422.553382 -39.817548) (xy 422.557453 -39.761926) (xy 422.569579 -39.707489)
			(xy 422.589502 -39.655398) (xy 422.616798 -39.606763) (xy 422.650884 -39.56262) (xy 422.691033 -39.523911)
			(xy 422.736391 -39.49146) (xy 422.785991 -39.465959) (xy 422.838775 -39.447952) (xy 422.893618 -39.437822)
			(xy 422.949352 -39.435785) (xy 423.004789 -39.441885) (xy 423.058746 -39.455991) (xy 423.110075 -39.477803)
			(xy 423.157681 -39.506857) (xy 423.200549 -39.542532) (xy 423.237766 -39.584069) (xy 423.268539 -39.630582)
			(xy 423.292211 -39.681079) (xy 423.308279 -39.734486) (xy 423.316399 -39.789662) (xy 423.316908 -39.817548)
			(xy 423.316399 -39.845434) (xy 423.308279 -39.90061) (xy 423.292211 -39.954017) (xy 423.268539 -40.004514)
			(xy 423.237766 -40.051027) (xy 423.200549 -40.092564) (xy 423.187397 -40.103509) (xy 427.462944 -40.103509)
			(xy 427.462944 -40.039587) (xy 427.470955 -39.976169) (xy 427.486852 -39.914255) (xy 427.510384 -39.854822)
			(xy 427.541178 -39.798807) (xy 427.578751 -39.747092) (xy 427.622508 -39.700495) (xy 427.671761 -39.65975)
			(xy 427.725732 -39.625499) (xy 427.783571 -39.598282) (xy 427.844364 -39.578529) (xy 427.907154 -39.566551)
			(xy 427.97095 -39.562538) (xy 428.034746 -39.566551) (xy 428.097536 -39.578529) (xy 428.158329 -39.598282)
			(xy 428.216168 -39.625499) (xy 428.270139 -39.65975) (xy 428.319392 -39.700495) (xy 428.363149 -39.747092)
			(xy 428.400722 -39.798807) (xy 428.428595 -39.849509) (xy 430.047394 -39.849509) (xy 430.047394 -39.785587)
			(xy 430.055405 -39.722169) (xy 430.071302 -39.660255) (xy 430.094834 -39.600822) (xy 430.125628 -39.544807)
			(xy 430.163201 -39.493092) (xy 430.206958 -39.446495) (xy 430.256211 -39.40575) (xy 430.310182 -39.371499)
			(xy 430.368021 -39.344282) (xy 430.428814 -39.324529) (xy 430.491604 -39.312551) (xy 430.5554 -39.308538)
			(xy 430.619196 -39.312551) (xy 430.681986 -39.324529) (xy 430.742779 -39.344282) (xy 430.800618 -39.371499)
			(xy 430.854589 -39.40575) (xy 430.903842 -39.446495) (xy 430.947599 -39.493092) (xy 430.985172 -39.544807)
			(xy 431.015966 -39.600822) (xy 431.039498 -39.660255) (xy 431.055395 -39.722169) (xy 431.063406 -39.785587)
			(xy 431.063908 -39.817548) (xy 431.063406 -39.849509) (xy 431.055395 -39.912927) (xy 431.039498 -39.974841)
			(xy 431.015966 -40.034274) (xy 430.985172 -40.090289) (xy 430.947599 -40.142004) (xy 430.903842 -40.188601)
			(xy 430.854589 -40.229346) (xy 430.800618 -40.263597) (xy 430.742779 -40.290814) (xy 430.681986 -40.310567)
			(xy 430.619196 -40.322545) (xy 430.5554 -40.326559) (xy 430.491604 -40.322545) (xy 430.428814 -40.310567)
			(xy 430.368021 -40.290814) (xy 430.310182 -40.263597) (xy 430.256211 -40.229346) (xy 430.206958 -40.188601)
			(xy 430.163201 -40.142004) (xy 430.125628 -40.090289) (xy 430.094834 -40.034274) (xy 430.071302 -39.974841)
			(xy 430.055405 -39.912927) (xy 430.047394 -39.849509) (xy 428.428595 -39.849509) (xy 428.431516 -39.854822)
			(xy 428.455048 -39.914255) (xy 428.470945 -39.976169) (xy 428.478956 -40.039587) (xy 428.479458 -40.071548)
			(xy 428.478956 -40.103509) (xy 428.470945 -40.166927) (xy 428.455048 -40.228841) (xy 428.431516 -40.288274)
			(xy 428.400722 -40.344289) (xy 428.363149 -40.396004) (xy 428.319392 -40.442601) (xy 428.270139 -40.483346)
			(xy 428.216168 -40.517597) (xy 428.158329 -40.544814) (xy 428.097536 -40.564567) (xy 428.034746 -40.576545)
			(xy 427.97095 -40.580559) (xy 427.907154 -40.576545) (xy 427.844364 -40.564567) (xy 427.783571 -40.544814)
			(xy 427.725732 -40.517597) (xy 427.671761 -40.483346) (xy 427.622508 -40.442601) (xy 427.578751 -40.396004)
			(xy 427.541178 -40.344289) (xy 427.510384 -40.288274) (xy 427.486852 -40.228841) (xy 427.470955 -40.166927)
			(xy 427.462944 -40.103509) (xy 423.187397 -40.103509) (xy 423.157681 -40.128239) (xy 423.110075 -40.157293)
			(xy 423.058746 -40.179105) (xy 423.004789 -40.193211) (xy 422.949352 -40.199311) (xy 422.893618 -40.197274)
			(xy 422.838775 -40.187144) (xy 422.785991 -40.169137) (xy 422.736391 -40.143636) (xy 422.691033 -40.111185)
			(xy 422.650884 -40.072476) (xy 422.616798 -40.028333) (xy 422.589502 -39.979698) (xy 422.569579 -39.927607)
			(xy 422.557453 -39.87317) (xy 422.553382 -39.817548) (xy 325.138354 -39.817548) (xy 325.12616 -39.848346)
			(xy 325.095366 -39.904361) (xy 325.057793 -39.956076) (xy 325.014036 -40.002673) (xy 324.964783 -40.043418)
			(xy 324.910812 -40.077669) (xy 324.852973 -40.104886) (xy 324.79218 -40.124639) (xy 324.72939 -40.136617)
			(xy 324.665594 -40.140631) (xy 324.601798 -40.136617) (xy 324.539008 -40.124639) (xy 324.478215 -40.104886)
			(xy 324.420376 -40.077669) (xy 324.366405 -40.043418) (xy 324.317152 -40.002673) (xy 324.273395 -39.956076)
			(xy 324.235822 -39.904361) (xy 324.205028 -39.848346) (xy 324.181496 -39.788913) (xy 324.165599 -39.726999)
			(xy 324.157588 -39.663581) (xy 324.157086 -39.63162) (xy 324.157536 -39.60203) (xy 324.164406 -39.54325)
			(xy 324.178044 -39.485663) (xy 324.198265 -39.430045) (xy 324.224799 -39.377146) (xy 324.257285 -39.32768)
			(xy 324.275958 -39.304722) (xy 324.281846 -39.297156) (xy 324.287977 -39.279004) (xy 324.287896 -39.269416)
			(xy 324.286118 -39.238682) (xy 324.285247 -39.229194) (xy 324.277408 -39.21184) (xy 324.270878 -39.2049)
			(xy 324.246891 -39.180842) (xy 324.204827 -39.127496) (xy 324.17024 -39.069025) (xy 324.143743 -39.00647)
			(xy 324.125811 -38.940945) (xy 324.11676 -38.873615) (xy 324.116192 -38.839648) (xy 275.0947 -38.839648)
			(xy 275.0947 -40.890698) (xy 304.42738 -40.890698) (xy 304.431451 -40.835076) (xy 304.443577 -40.780639)
			(xy 304.4635 -40.728548) (xy 304.490796 -40.679913) (xy 304.524882 -40.63577) (xy 304.565031 -40.597061)
			(xy 304.610389 -40.56461) (xy 304.659989 -40.539109) (xy 304.712773 -40.521102) (xy 304.767616 -40.510972)
			(xy 304.82335 -40.508935) (xy 304.878787 -40.515035) (xy 304.932744 -40.529141) (xy 304.984073 -40.550953)
			(xy 305.031679 -40.580007) (xy 305.074547 -40.615682) (xy 305.08947 -40.632337) (xy 316.44183 -40.632337)
			(xy 316.44183 -40.568415) (xy 316.449841 -40.504997) (xy 316.465738 -40.443083) (xy 316.48927 -40.38365)
			(xy 316.520064 -40.327635) (xy 316.557637 -40.27592) (xy 316.601394 -40.229323) (xy 316.650647 -40.188578)
			(xy 316.704618 -40.154327) (xy 316.762457 -40.12711) (xy 316.82325 -40.107357) (xy 316.88604 -40.095379)
			(xy 316.949836 -40.091366) (xy 317.013632 -40.095379) (xy 317.076422 -40.107357) (xy 317.137215 -40.12711)
			(xy 317.195054 -40.154327) (xy 317.249025 -40.188578) (xy 317.298278 -40.229323) (xy 317.342035 -40.27592)
			(xy 317.379608 -40.327635) (xy 317.410402 -40.38365) (xy 317.433934 -40.443083) (xy 317.449831 -40.504997)
			(xy 317.457842 -40.568415) (xy 317.458344 -40.600376) (xy 317.457842 -40.632337) (xy 317.455238 -40.652954)
			(xy 320.56781 -40.652954) (xy 320.571881 -40.597332) (xy 320.584007 -40.542895) (xy 320.60393 -40.490804)
			(xy 320.631226 -40.442169) (xy 320.665312 -40.398026) (xy 320.705461 -40.359317) (xy 320.750819 -40.326866)
			(xy 320.800419 -40.301365) (xy 320.853203 -40.283358) (xy 320.908046 -40.273228) (xy 320.96378 -40.271191)
			(xy 321.019217 -40.277291) (xy 321.073174 -40.291397) (xy 321.124503 -40.313209) (xy 321.172109 -40.342263)
			(xy 321.214977 -40.377938) (xy 321.252194 -40.419475) (xy 321.282967 -40.465988) (xy 321.306639 -40.516485)
			(xy 321.322707 -40.569892) (xy 321.330827 -40.625068) (xy 321.331336 -40.652954) (xy 321.330827 -40.68084)
			(xy 321.322707 -40.736016) (xy 321.306639 -40.789423) (xy 321.282967 -40.83992) (xy 321.252194 -40.886433)
			(xy 321.214977 -40.92797) (xy 321.208235 -40.933581) (xy 324.157588 -40.933581) (xy 324.157588 -40.869659)
			(xy 324.165599 -40.806241) (xy 324.181496 -40.744327) (xy 324.205028 -40.684894) (xy 324.235822 -40.628879)
			(xy 324.273395 -40.577164) (xy 324.317152 -40.530567) (xy 324.366405 -40.489822) (xy 324.420376 -40.455571)
			(xy 324.478215 -40.428354) (xy 324.539008 -40.408601) (xy 324.601798 -40.396623) (xy 324.665594 -40.39261)
			(xy 324.72939 -40.396623) (xy 324.79218 -40.408601) (xy 324.852973 -40.428354) (xy 324.910812 -40.455571)
			(xy 324.964783 -40.489822) (xy 325.014036 -40.530567) (xy 325.057793 -40.577164) (xy 325.095366 -40.628879)
			(xy 325.12616 -40.684894) (xy 325.149692 -40.744327) (xy 325.165589 -40.806241) (xy 325.1736 -40.869659)
			(xy 325.174102 -40.90162) (xy 325.1736 -40.933581) (xy 325.165589 -40.996999) (xy 325.149692 -41.058913)
			(xy 325.12616 -41.118346) (xy 325.102736 -41.160954) (xy 327.80681 -41.160954) (xy 327.810881 -41.105332)
			(xy 327.823007 -41.050895) (xy 327.84293 -40.998804) (xy 327.870226 -40.950169) (xy 327.904312 -40.906026)
			(xy 327.944461 -40.867317) (xy 327.989819 -40.834866) (xy 328.039419 -40.809365) (xy 328.092203 -40.791358)
			(xy 328.147046 -40.781228) (xy 328.20278 -40.779191) (xy 328.258217 -40.785291) (xy 328.312174 -40.799397)
			(xy 328.363503 -40.821209) (xy 328.411109 -40.850263) (xy 328.453977 -40.885938) (xy 328.491194 -40.927475)
			(xy 328.521967 -40.973988) (xy 328.545639 -41.024485) (xy 328.561707 -41.077892) (xy 328.569827 -41.133068)
			(xy 328.570336 -41.160954) (xy 328.569827 -41.18884) (xy 328.561707 -41.244016) (xy 328.545639 -41.297423)
			(xy 328.521967 -41.34792) (xy 328.491194 -41.394433) (xy 328.453977 -41.43597) (xy 328.411109 -41.471645)
			(xy 328.363503 -41.500699) (xy 328.312174 -41.522511) (xy 328.258217 -41.536617) (xy 328.20278 -41.542717)
			(xy 328.147046 -41.54068) (xy 328.092203 -41.53055) (xy 328.039419 -41.512543) (xy 327.989819 -41.487042)
			(xy 327.944461 -41.454591) (xy 327.904312 -41.415882) (xy 327.870226 -41.371739) (xy 327.84293 -41.323104)
			(xy 327.823007 -41.271013) (xy 327.810881 -41.216576) (xy 327.80681 -41.160954) (xy 325.102736 -41.160954)
			(xy 325.095366 -41.174361) (xy 325.057793 -41.226076) (xy 325.014036 -41.272673) (xy 324.964783 -41.313418)
			(xy 324.910812 -41.347669) (xy 324.852973 -41.374886) (xy 324.79218 -41.394639) (xy 324.72939 -41.406617)
			(xy 324.665594 -41.410631) (xy 324.601798 -41.406617) (xy 324.539008 -41.394639) (xy 324.478215 -41.374886)
			(xy 324.420376 -41.347669) (xy 324.366405 -41.313418) (xy 324.317152 -41.272673) (xy 324.273395 -41.226076)
			(xy 324.235822 -41.174361) (xy 324.205028 -41.118346) (xy 324.181496 -41.058913) (xy 324.165599 -40.996999)
			(xy 324.157588 -40.933581) (xy 321.208235 -40.933581) (xy 321.172109 -40.963645) (xy 321.124503 -40.992699)
			(xy 321.073174 -41.014511) (xy 321.019217 -41.028617) (xy 320.96378 -41.034717) (xy 320.908046 -41.03268)
			(xy 320.853203 -41.02255) (xy 320.800419 -41.004543) (xy 320.750819 -40.979042) (xy 320.705461 -40.946591)
			(xy 320.665312 -40.907882) (xy 320.631226 -40.863739) (xy 320.60393 -40.815104) (xy 320.584007 -40.763013)
			(xy 320.571881 -40.708576) (xy 320.56781 -40.652954) (xy 317.455238 -40.652954) (xy 317.449831 -40.695755)
			(xy 317.433934 -40.757669) (xy 317.410402 -40.817102) (xy 317.379608 -40.873117) (xy 317.342035 -40.924832)
			(xy 317.298278 -40.971429) (xy 317.249025 -41.012174) (xy 317.195054 -41.046425) (xy 317.137215 -41.073642)
			(xy 317.076422 -41.093395) (xy 317.013632 -41.105373) (xy 316.949836 -41.109387) (xy 316.88604 -41.105373)
			(xy 316.82325 -41.093395) (xy 316.762457 -41.073642) (xy 316.704618 -41.046425) (xy 316.650647 -41.012174)
			(xy 316.601394 -40.971429) (xy 316.557637 -40.924832) (xy 316.520064 -40.873117) (xy 316.48927 -40.817102)
			(xy 316.465738 -40.757669) (xy 316.449841 -40.695755) (xy 316.44183 -40.632337) (xy 305.08947 -40.632337)
			(xy 305.111764 -40.657219) (xy 305.142537 -40.703732) (xy 305.166209 -40.754229) (xy 305.182277 -40.807636)
			(xy 305.190397 -40.862812) (xy 305.190906 -40.890698) (xy 305.190397 -40.918584) (xy 305.182277 -40.97376)
			(xy 305.166209 -41.027167) (xy 305.142537 -41.077664) (xy 305.111764 -41.124177) (xy 305.074547 -41.165714)
			(xy 305.031679 -41.201389) (xy 304.984073 -41.230443) (xy 304.932744 -41.252255) (xy 304.878787 -41.266361)
			(xy 304.82335 -41.272461) (xy 304.767616 -41.270424) (xy 304.712773 -41.260294) (xy 304.659989 -41.242287)
			(xy 304.610389 -41.216786) (xy 304.565031 -41.184335) (xy 304.524882 -41.145626) (xy 304.490796 -41.101483)
			(xy 304.4635 -41.052848) (xy 304.443577 -41.000757) (xy 304.431451 -40.94632) (xy 304.42738 -40.890698)
			(xy 275.0947 -40.890698) (xy 275.0947 -41.906698) (xy 304.42738 -41.906698) (xy 304.431451 -41.851076)
			(xy 304.443577 -41.796639) (xy 304.4635 -41.744548) (xy 304.490796 -41.695913) (xy 304.524882 -41.65177)
			(xy 304.565031 -41.613061) (xy 304.610389 -41.58061) (xy 304.659989 -41.555109) (xy 304.712773 -41.537102)
			(xy 304.767616 -41.526972) (xy 304.82335 -41.524935) (xy 304.878787 -41.531035) (xy 304.932744 -41.545141)
			(xy 304.984073 -41.566953) (xy 305.031679 -41.596007) (xy 305.074547 -41.631682) (xy 305.107943 -41.668954)
			(xy 320.56781 -41.668954) (xy 320.571881 -41.613332) (xy 320.584007 -41.558895) (xy 320.60393 -41.506804)
			(xy 320.631226 -41.458169) (xy 320.665312 -41.414026) (xy 320.705461 -41.375317) (xy 320.750819 -41.342866)
			(xy 320.800419 -41.317365) (xy 320.853203 -41.299358) (xy 320.908046 -41.289228) (xy 320.96378 -41.287191)
			(xy 321.019217 -41.293291) (xy 321.073174 -41.307397) (xy 321.124503 -41.329209) (xy 321.172109 -41.358263)
			(xy 321.214977 -41.393938) (xy 321.252194 -41.435475) (xy 321.282967 -41.481988) (xy 321.306639 -41.532485)
			(xy 321.322707 -41.585892) (xy 321.330827 -41.641068) (xy 321.331336 -41.668954) (xy 321.330827 -41.69684)
			(xy 321.322707 -41.752016) (xy 321.306639 -41.805423) (xy 321.282967 -41.85592) (xy 321.252194 -41.902433)
			(xy 321.214977 -41.94397) (xy 321.172109 -41.979645) (xy 321.124503 -42.008699) (xy 321.073174 -42.030511)
			(xy 321.019217 -42.044617) (xy 320.96378 -42.050717) (xy 320.908046 -42.04868) (xy 320.853203 -42.03855)
			(xy 320.800419 -42.020543) (xy 320.750819 -41.995042) (xy 320.705461 -41.962591) (xy 320.665312 -41.923882)
			(xy 320.631226 -41.879739) (xy 320.60393 -41.831104) (xy 320.584007 -41.779013) (xy 320.571881 -41.724576)
			(xy 320.56781 -41.668954) (xy 305.107943 -41.668954) (xy 305.111764 -41.673219) (xy 305.142537 -41.719732)
			(xy 305.166209 -41.770229) (xy 305.182277 -41.823636) (xy 305.190397 -41.878812) (xy 305.190906 -41.906698)
			(xy 305.190397 -41.934584) (xy 305.182277 -41.98976) (xy 305.166209 -42.043167) (xy 305.142537 -42.093664)
			(xy 305.111764 -42.140177) (xy 305.074547 -42.181714) (xy 305.041862 -42.208915) (xy 324.138792 -42.208915)
			(xy 324.138792 -42.144993) (xy 324.146803 -42.081575) (xy 324.1627 -42.019661) (xy 324.186232 -41.960228)
			(xy 324.217026 -41.904213) (xy 324.254599 -41.852498) (xy 324.298356 -41.805901) (xy 324.347609 -41.765156)
			(xy 324.40158 -41.730905) (xy 324.459419 -41.703688) (xy 324.520212 -41.683935) (xy 324.583002 -41.671957)
			(xy 324.646798 -41.667944) (xy 324.710594 -41.671957) (xy 324.773384 -41.683935) (xy 324.834177 -41.703688)
			(xy 324.892016 -41.730905) (xy 324.945987 -41.765156) (xy 324.99524 -41.805901) (xy 325.038997 -41.852498)
			(xy 325.07657 -41.904213) (xy 325.107364 -41.960228) (xy 325.130896 -42.019661) (xy 325.146793 -42.081575)
			(xy 325.154804 -42.144993) (xy 325.155306 -42.176954) (xy 327.80681 -42.176954) (xy 327.810881 -42.121332)
			(xy 327.823007 -42.066895) (xy 327.84293 -42.014804) (xy 327.870226 -41.966169) (xy 327.904312 -41.922026)
			(xy 327.944461 -41.883317) (xy 327.989819 -41.850866) (xy 328.039419 -41.825365) (xy 328.092203 -41.807358)
			(xy 328.147046 -41.797228) (xy 328.20278 -41.795191) (xy 328.258217 -41.801291) (xy 328.312174 -41.815397)
			(xy 328.363503 -41.837209) (xy 328.411109 -41.866263) (xy 328.453977 -41.901938) (xy 328.491194 -41.943475)
			(xy 328.521967 -41.989988) (xy 328.545639 -42.040485) (xy 328.561707 -42.093892) (xy 328.569827 -42.149068)
			(xy 328.570336 -42.176954) (xy 328.569827 -42.20484) (xy 328.569227 -42.208915) (xy 330.093822 -42.208915)
			(xy 330.093822 -42.144993) (xy 330.101833 -42.081575) (xy 330.11773 -42.019661) (xy 330.141262 -41.960228)
			(xy 330.172056 -41.904213) (xy 330.209629 -41.852498) (xy 330.253386 -41.805901) (xy 330.302639 -41.765156)
			(xy 330.35661 -41.730905) (xy 330.414449 -41.703688) (xy 330.475242 -41.683935) (xy 330.538032 -41.671957)
			(xy 330.601828 -41.667944) (xy 330.665624 -41.671957) (xy 330.728414 -41.683935) (xy 330.789207 -41.703688)
			(xy 330.802837 -41.710102) (xy 342.152238 -41.710102) (xy 342.15619 -41.618309) (xy 342.16802 -41.527195)
			(xy 342.187637 -41.437435) (xy 342.214899 -41.349694) (xy 342.249602 -41.264622) (xy 342.29149 -41.182847)
			(xy 342.340253 -41.104976) (xy 342.395529 -41.031586) (xy 342.45691 -40.963219) (xy 342.523941 -40.900381)
			(xy 342.596125 -40.843539) (xy 342.672929 -40.793112) (xy 342.753783 -40.749474) (xy 342.838089 -40.712948)
			(xy 342.925223 -40.683805) (xy 343.01454 -40.66226) (xy 343.105378 -40.648474) (xy 343.197065 -40.642547)
			(xy 343.288922 -40.644524) (xy 343.38027 -40.65439) (xy 343.47043 -40.672072) (xy 343.558738 -40.697439)
			(xy 343.644537 -40.730304) (xy 343.727194 -40.770423) (xy 343.806096 -40.817499) (xy 343.880659 -40.871183)
			(xy 343.950331 -40.931079) (xy 344.014596 -40.996742) (xy 344.072979 -41.067686) (xy 344.125046 -41.143387)
			(xy 344.170414 -41.223284) (xy 344.208745 -41.306784) (xy 344.239756 -41.393271) (xy 344.263217 -41.482104)
			(xy 344.278956 -41.572624) (xy 344.286854 -41.664163) (xy 344.287348 -41.710102) (xy 344.692238 -41.710102)
			(xy 344.69619 -41.618309) (xy 344.70802 -41.527195) (xy 344.727637 -41.437435) (xy 344.754899 -41.349694)
			(xy 344.789602 -41.264622) (xy 344.83149 -41.182847) (xy 344.880253 -41.104976) (xy 344.935529 -41.031586)
			(xy 344.99691 -40.963219) (xy 345.063941 -40.900381) (xy 345.136125 -40.843539) (xy 345.212929 -40.793112)
			(xy 345.293783 -40.749474) (xy 345.378089 -40.712948) (xy 345.465223 -40.683805) (xy 345.55454 -40.66226)
			(xy 345.645378 -40.648474) (xy 345.737065 -40.642547) (xy 345.828922 -40.644524) (xy 345.92027 -40.65439)
			(xy 346.01043 -40.672072) (xy 346.098738 -40.697439) (xy 346.184537 -40.730304) (xy 346.267194 -40.770423)
			(xy 346.346096 -40.817499) (xy 346.420659 -40.871183) (xy 346.490331 -40.931079) (xy 346.554596 -40.996742)
			(xy 346.612979 -41.067686) (xy 346.665046 -41.143387) (xy 346.710414 -41.223284) (xy 346.748745 -41.306784)
			(xy 346.779756 -41.393271) (xy 346.803217 -41.482104) (xy 346.818956 -41.572624) (xy 346.826854 -41.664163)
			(xy 346.827348 -41.710102) (xy 347.232238 -41.710102) (xy 347.23619 -41.618309) (xy 347.24802 -41.527195)
			(xy 347.267637 -41.437435) (xy 347.294899 -41.349694) (xy 347.329602 -41.264622) (xy 347.37149 -41.182847)
			(xy 347.420253 -41.104976) (xy 347.475529 -41.031586) (xy 347.53691 -40.963219) (xy 347.603941 -40.900381)
			(xy 347.676125 -40.843539) (xy 347.752929 -40.793112) (xy 347.833783 -40.749474) (xy 347.918089 -40.712948)
			(xy 348.005223 -40.683805) (xy 348.09454 -40.66226) (xy 348.185378 -40.648474) (xy 348.277065 -40.642547)
			(xy 348.368922 -40.644524) (xy 348.46027 -40.65439) (xy 348.55043 -40.672072) (xy 348.638738 -40.697439)
			(xy 348.724537 -40.730304) (xy 348.807194 -40.770423) (xy 348.886096 -40.817499) (xy 348.960659 -40.871183)
			(xy 349.030331 -40.931079) (xy 349.094596 -40.996742) (xy 349.152979 -41.067686) (xy 349.205046 -41.143387)
			(xy 349.250414 -41.223284) (xy 349.288745 -41.306784) (xy 349.319756 -41.393271) (xy 349.343217 -41.482104)
			(xy 349.358956 -41.572624) (xy 349.366854 -41.664163) (xy 349.367348 -41.710102) (xy 349.772238 -41.710102)
			(xy 349.77619 -41.618309) (xy 349.78802 -41.527195) (xy 349.807637 -41.437435) (xy 349.834899 -41.349694)
			(xy 349.869602 -41.264622) (xy 349.91149 -41.182847) (xy 349.960253 -41.104976) (xy 350.015529 -41.031586)
			(xy 350.07691 -40.963219) (xy 350.143941 -40.900381) (xy 350.216125 -40.843539) (xy 350.292929 -40.793112)
			(xy 350.373783 -40.749474) (xy 350.458089 -40.712948) (xy 350.545223 -40.683805) (xy 350.63454 -40.66226)
			(xy 350.725378 -40.648474) (xy 350.817065 -40.642547) (xy 350.908922 -40.644524) (xy 351.00027 -40.65439)
			(xy 351.09043 -40.672072) (xy 351.178738 -40.697439) (xy 351.264537 -40.730304) (xy 351.347194 -40.770423)
			(xy 351.426096 -40.817499) (xy 351.500659 -40.871183) (xy 351.570331 -40.931079) (xy 351.634596 -40.996742)
			(xy 351.692979 -41.067686) (xy 351.745046 -41.143387) (xy 351.790414 -41.223284) (xy 351.828745 -41.306784)
			(xy 351.859756 -41.393271) (xy 351.883217 -41.482104) (xy 351.898956 -41.572624) (xy 351.906854 -41.664163)
			(xy 351.907348 -41.710102) (xy 352.312238 -41.710102) (xy 352.31619 -41.618309) (xy 352.32802 -41.527195)
			(xy 352.347637 -41.437435) (xy 352.374899 -41.349694) (xy 352.409602 -41.264622) (xy 352.45149 -41.182847)
			(xy 352.500253 -41.104976) (xy 352.555529 -41.031586) (xy 352.61691 -40.963219) (xy 352.683941 -40.900381)
			(xy 352.756125 -40.843539) (xy 352.832929 -40.793112) (xy 352.913783 -40.749474) (xy 352.998089 -40.712948)
			(xy 353.085223 -40.683805) (xy 353.17454 -40.66226) (xy 353.265378 -40.648474) (xy 353.357065 -40.642547)
			(xy 353.448922 -40.644524) (xy 353.54027 -40.65439) (xy 353.63043 -40.672072) (xy 353.718738 -40.697439)
			(xy 353.804537 -40.730304) (xy 353.887194 -40.770423) (xy 353.966096 -40.817499) (xy 354.040659 -40.871183)
			(xy 354.110331 -40.931079) (xy 354.174596 -40.996742) (xy 354.232979 -41.067686) (xy 354.285046 -41.143387)
			(xy 354.330414 -41.223284) (xy 354.368745 -41.306784) (xy 354.399756 -41.393271) (xy 354.423217 -41.482104)
			(xy 354.438956 -41.572624) (xy 354.446854 -41.664163) (xy 354.446907 -41.669051) (xy 365.732054 -41.669051)
			(xy 365.732054 -41.614549) (xy 365.73981 -41.560601) (xy 365.755164 -41.508306) (xy 365.777803 -41.458729)
			(xy 365.807268 -41.412877) (xy 365.842957 -41.371686) (xy 365.884145 -41.335992) (xy 365.929994 -41.306523)
			(xy 365.979569 -41.283878) (xy 366.031862 -41.268518) (xy 366.085809 -41.260757) (xy 366.11306 -41.260268)
			(xy 366.142681 -41.260807) (xy 366.201209 -41.269972) (xy 366.257618 -41.288074) (xy 366.310551 -41.314676)
			(xy 366.358736 -41.349139) (xy 366.380268 -41.369488) (xy 366.388396 -41.377616) (xy 366.41024 -41.384982)
			(xy 366.500918 -41.373806) (xy 366.512117 -41.371783) (xy 366.531249 -41.359524) (xy 366.537748 -41.350184)
			(xy 366.538002 -41.350184) (xy 366.538002 -41.34993) (xy 366.555407 -41.322553) (xy 366.596089 -41.272019)
			(xy 366.642868 -41.227071) (xy 366.694984 -41.188438) (xy 366.751592 -41.156748) (xy 366.811771 -41.132517)
			(xy 366.874543 -41.116138) (xy 366.938889 -41.107876) (xy 366.971326 -41.10736) (xy 367.003284 -41.107927)
			(xy 367.066696 -41.115941) (xy 367.128603 -41.131839) (xy 367.188029 -41.15537) (xy 367.244038 -41.186164)
			(xy 367.295746 -41.223735) (xy 367.342338 -41.267489) (xy 367.383078 -41.316738) (xy 367.417325 -41.370705)
			(xy 367.444539 -41.428538) (xy 367.464289 -41.489326) (xy 367.476265 -41.55211) (xy 367.480279 -41.6159)
			(xy 367.47827 -41.647829) (xy 369.00332 -41.647829) (xy 369.00332 -41.583907) (xy 369.011331 -41.520489)
			(xy 369.027228 -41.458575) (xy 369.05076 -41.399142) (xy 369.081554 -41.343127) (xy 369.119127 -41.291412)
			(xy 369.162884 -41.244815) (xy 369.212137 -41.20407) (xy 369.266108 -41.169819) (xy 369.323947 -41.142602)
			(xy 369.38474 -41.122849) (xy 369.44753 -41.110871) (xy 369.511326 -41.106858) (xy 369.575122 -41.110871)
			(xy 369.620403 -41.119509) (xy 419.233344 -41.119509) (xy 419.233344 -41.055587) (xy 419.241355 -40.992169)
			(xy 419.257252 -40.930255) (xy 419.280784 -40.870822) (xy 419.311578 -40.814807) (xy 419.349151 -40.763092)
			(xy 419.392908 -40.716495) (xy 419.442161 -40.67575) (xy 419.496132 -40.641499) (xy 419.553971 -40.614282)
			(xy 419.614764 -40.594529) (xy 419.677554 -40.582551) (xy 419.74135 -40.578538) (xy 419.805146 -40.582551)
			(xy 419.867936 -40.594529) (xy 419.928729 -40.614282) (xy 419.986568 -40.641499) (xy 420.040539 -40.67575)
			(xy 420.089792 -40.716495) (xy 420.133549 -40.763092) (xy 420.171122 -40.814807) (xy 420.201916 -40.870822)
			(xy 420.225448 -40.930255) (xy 420.241345 -40.992169) (xy 420.249356 -41.055587) (xy 420.249858 -41.087548)
			(xy 427.588932 -41.087548) (xy 427.593003 -41.031926) (xy 427.605129 -40.977489) (xy 427.625052 -40.925398)
			(xy 427.652348 -40.876763) (xy 427.686434 -40.83262) (xy 427.726583 -40.793911) (xy 427.771941 -40.76146)
			(xy 427.821541 -40.735959) (xy 427.874325 -40.717952) (xy 427.929168 -40.707822) (xy 427.984902 -40.705785)
			(xy 428.040339 -40.711885) (xy 428.094296 -40.725991) (xy 428.145625 -40.747803) (xy 428.193231 -40.776857)
			(xy 428.236099 -40.812532) (xy 428.273316 -40.854069) (xy 428.304089 -40.900582) (xy 428.327761 -40.951079)
			(xy 428.343829 -41.004486) (xy 428.351949 -41.059662) (xy 428.352458 -41.087548) (xy 428.351949 -41.115434)
			(xy 428.351349 -41.119509) (xy 430.047394 -41.119509) (xy 430.047394 -41.055587) (xy 430.055405 -40.992169)
			(xy 430.071302 -40.930255) (xy 430.094834 -40.870822) (xy 430.125628 -40.814807) (xy 430.163201 -40.763092)
			(xy 430.206958 -40.716495) (xy 430.256211 -40.67575) (xy 430.310182 -40.641499) (xy 430.368021 -40.614282)
			(xy 430.428814 -40.594529) (xy 430.491604 -40.582551) (xy 430.5554 -40.578538) (xy 430.619196 -40.582551)
			(xy 430.681986 -40.594529) (xy 430.742779 -40.614282) (xy 430.800618 -40.641499) (xy 430.854589 -40.67575)
			(xy 430.903842 -40.716495) (xy 430.947599 -40.763092) (xy 430.985172 -40.814807) (xy 431.015966 -40.870822)
			(xy 431.039498 -40.930255) (xy 431.055395 -40.992169) (xy 431.063406 -41.055587) (xy 431.063908 -41.087548)
			(xy 431.063406 -41.119509) (xy 431.055395 -41.182927) (xy 431.039498 -41.244841) (xy 431.015966 -41.304274)
			(xy 430.985172 -41.360289) (xy 430.947599 -41.412004) (xy 430.903842 -41.458601) (xy 430.854589 -41.499346)
			(xy 430.800618 -41.533597) (xy 430.742779 -41.560814) (xy 430.681986 -41.580567) (xy 430.619196 -41.592545)
			(xy 430.5554 -41.596559) (xy 430.491604 -41.592545) (xy 430.428814 -41.580567) (xy 430.368021 -41.560814)
			(xy 430.310182 -41.533597) (xy 430.256211 -41.499346) (xy 430.206958 -41.458601) (xy 430.163201 -41.412004)
			(xy 430.125628 -41.360289) (xy 430.094834 -41.304274) (xy 430.071302 -41.244841) (xy 430.055405 -41.182927)
			(xy 430.047394 -41.119509) (xy 428.351349 -41.119509) (xy 428.343829 -41.17061) (xy 428.327761 -41.224017)
			(xy 428.304089 -41.274514) (xy 428.273316 -41.321027) (xy 428.236099 -41.362564) (xy 428.193231 -41.398239)
			(xy 428.145625 -41.427293) (xy 428.094296 -41.449105) (xy 428.040339 -41.463211) (xy 427.984902 -41.469311)
			(xy 427.929168 -41.467274) (xy 427.874325 -41.457144) (xy 427.821541 -41.439137) (xy 427.771941 -41.413636)
			(xy 427.726583 -41.381185) (xy 427.686434 -41.342476) (xy 427.652348 -41.298333) (xy 427.625052 -41.249698)
			(xy 427.605129 -41.197607) (xy 427.593003 -41.14317) (xy 427.588932 -41.087548) (xy 420.249858 -41.087548)
			(xy 420.249356 -41.119509) (xy 420.241345 -41.182927) (xy 420.225448 -41.244841) (xy 420.201916 -41.304274)
			(xy 420.171122 -41.360289) (xy 420.133549 -41.412004) (xy 420.089792 -41.458601) (xy 420.040539 -41.499346)
			(xy 419.986568 -41.533597) (xy 419.928729 -41.560814) (xy 419.867936 -41.580567) (xy 419.805146 -41.592545)
			(xy 419.74135 -41.596559) (xy 419.677554 -41.592545) (xy 419.614764 -41.580567) (xy 419.553971 -41.560814)
			(xy 419.496132 -41.533597) (xy 419.442161 -41.499346) (xy 419.392908 -41.458601) (xy 419.349151 -41.412004)
			(xy 419.311578 -41.360289) (xy 419.280784 -41.304274) (xy 419.257252 -41.244841) (xy 419.241355 -41.182927)
			(xy 419.233344 -41.119509) (xy 369.620403 -41.119509) (xy 369.637912 -41.122849) (xy 369.698705 -41.142602)
			(xy 369.756544 -41.169819) (xy 369.810515 -41.20407) (xy 369.859768 -41.244815) (xy 369.903525 -41.291412)
			(xy 369.941098 -41.343127) (xy 369.971892 -41.399142) (xy 369.995424 -41.458575) (xy 370.011321 -41.520489)
			(xy 370.019332 -41.583907) (xy 370.01965 -41.604184) (xy 370.24894 -41.604184) (xy 370.253011 -41.548562)
			(xy 370.265137 -41.494125) (xy 370.28506 -41.442034) (xy 370.312356 -41.393399) (xy 370.346442 -41.349256)
			(xy 370.386591 -41.310547) (xy 370.431949 -41.278096) (xy 370.481549 -41.252595) (xy 370.534333 -41.234588)
			(xy 370.589176 -41.224458) (xy 370.64491 -41.222421) (xy 370.700347 -41.228521) (xy 370.754304 -41.242627)
			(xy 370.805633 -41.264439) (xy 370.853239 -41.293493) (xy 370.896107 -41.329168) (xy 370.933324 -41.370705)
			(xy 370.964097 -41.417218) (xy 370.987769 -41.467715) (xy 371.003837 -41.521122) (xy 371.011957 -41.576298)
			(xy 371.012466 -41.604184) (xy 371.011957 -41.63207) (xy 371.004324 -41.68394) (xy 413.816292 -41.68394)
			(xy 413.816794 -41.651979) (xy 413.824805 -41.588561) (xy 413.840702 -41.526647) (xy 413.864234 -41.467214)
			(xy 413.895028 -41.411199) (xy 413.932601 -41.359484) (xy 413.976358 -41.312887) (xy 414.025611 -41.272142)
			(xy 414.079582 -41.237891) (xy 414.137421 -41.210674) (xy 414.198214 -41.190921) (xy 414.261004 -41.178943)
			(xy 414.3248 -41.17493) (xy 414.388596 -41.178943) (xy 414.451386 -41.190921) (xy 414.512179 -41.210674)
			(xy 414.570018 -41.237891) (xy 414.623989 -41.272142) (xy 414.673242 -41.312887) (xy 414.716999 -41.359484)
			(xy 414.754572 -41.411199) (xy 414.785366 -41.467214) (xy 414.808898 -41.526647) (xy 414.824795 -41.588561)
			(xy 414.832806 -41.651979) (xy 414.833308 -41.68394) (xy 414.832879 -41.71431) (xy 414.825625 -41.774615)
			(xy 414.811239 -41.833627) (xy 414.789923 -41.890504) (xy 414.761984 -41.944436) (xy 414.727817 -41.994656)
			(xy 414.68791 -42.040447) (xy 414.665668 -42.06113) (xy 414.657032 -42.069004) (xy 414.648396 -42.090594)
			(xy 414.654492 -42.182034) (xy 414.656 -42.193443) (xy 414.667479 -42.213356) (xy 414.67659 -42.220388)
			(xy 414.701838 -42.23817) (xy 414.748212 -42.278954) (xy 414.789309 -42.325051) (xy 414.811863 -42.357548)
			(xy 422.553382 -42.357548) (xy 422.557453 -42.301926) (xy 422.569579 -42.247489) (xy 422.589502 -42.195398)
			(xy 422.616798 -42.146763) (xy 422.650884 -42.10262) (xy 422.691033 -42.063911) (xy 422.736391 -42.03146)
			(xy 422.785991 -42.005959) (xy 422.838775 -41.987952) (xy 422.893618 -41.977822) (xy 422.949352 -41.975785)
			(xy 423.004789 -41.981885) (xy 423.058746 -41.995991) (xy 423.110075 -42.017803) (xy 423.157681 -42.046857)
			(xy 423.200549 -42.082532) (xy 423.237766 -42.124069) (xy 423.268539 -42.170582) (xy 423.292211 -42.221079)
			(xy 423.308279 -42.274486) (xy 423.316399 -42.329662) (xy 423.316908 -42.357548) (xy 423.316399 -42.385434)
			(xy 423.315799 -42.389509) (xy 427.462944 -42.389509) (xy 427.462944 -42.325587) (xy 427.470955 -42.262169)
			(xy 427.486852 -42.200255) (xy 427.510384 -42.140822) (xy 427.541178 -42.084807) (xy 427.578751 -42.033092)
			(xy 427.622508 -41.986495) (xy 427.671761 -41.94575) (xy 427.725732 -41.911499) (xy 427.783571 -41.884282)
			(xy 427.844364 -41.864529) (xy 427.907154 -41.852551) (xy 427.97095 -41.848538) (xy 428.034746 -41.852551)
			(xy 428.097536 -41.864529) (xy 428.158329 -41.884282) (xy 428.216168 -41.911499) (xy 428.270139 -41.94575)
			(xy 428.319392 -41.986495) (xy 428.363149 -42.033092) (xy 428.400722 -42.084807) (xy 428.431516 -42.140822)
			(xy 428.455048 -42.200255) (xy 428.470945 -42.262169) (xy 428.478956 -42.325587) (xy 428.479458 -42.357548)
			(xy 428.478956 -42.389509) (xy 430.047394 -42.389509) (xy 430.047394 -42.325587) (xy 430.055405 -42.262169)
			(xy 430.071302 -42.200255) (xy 430.094834 -42.140822) (xy 430.125628 -42.084807) (xy 430.163201 -42.033092)
			(xy 430.206958 -41.986495) (xy 430.256211 -41.94575) (xy 430.310182 -41.911499) (xy 430.368021 -41.884282)
			(xy 430.428814 -41.864529) (xy 430.491604 -41.852551) (xy 430.5554 -41.848538) (xy 430.619196 -41.852551)
			(xy 430.681986 -41.864529) (xy 430.742779 -41.884282) (xy 430.800618 -41.911499) (xy 430.854589 -41.94575)
			(xy 430.903842 -41.986495) (xy 430.947599 -42.033092) (xy 430.985172 -42.084807) (xy 431.015966 -42.140822)
			(xy 431.039498 -42.200255) (xy 431.055395 -42.262169) (xy 431.063406 -42.325587) (xy 431.063908 -42.357548)
			(xy 431.063406 -42.389509) (xy 431.055395 -42.452927) (xy 431.039498 -42.514841) (xy 431.015966 -42.574274)
			(xy 430.985172 -42.630289) (xy 430.947599 -42.682004) (xy 430.903842 -42.728601) (xy 430.854589 -42.769346)
			(xy 430.800618 -42.803597) (xy 430.742779 -42.830814) (xy 430.681986 -42.850567) (xy 430.619196 -42.862545)
			(xy 430.5554 -42.866559) (xy 430.491604 -42.862545) (xy 430.428814 -42.850567) (xy 430.368021 -42.830814)
			(xy 430.310182 -42.803597) (xy 430.256211 -42.769346) (xy 430.206958 -42.728601) (xy 430.163201 -42.682004)
			(xy 430.125628 -42.630289) (xy 430.094834 -42.574274) (xy 430.071302 -42.514841) (xy 430.055405 -42.452927)
			(xy 430.047394 -42.389509) (xy 428.478956 -42.389509) (xy 428.470945 -42.452927) (xy 428.455048 -42.514841)
			(xy 428.431516 -42.574274) (xy 428.400722 -42.630289) (xy 428.363149 -42.682004) (xy 428.319392 -42.728601)
			(xy 428.270139 -42.769346) (xy 428.216168 -42.803597) (xy 428.158329 -42.830814) (xy 428.097536 -42.850567)
			(xy 428.034746 -42.862545) (xy 427.97095 -42.866559) (xy 427.907154 -42.862545) (xy 427.844364 -42.850567)
			(xy 427.783571 -42.830814) (xy 427.725732 -42.803597) (xy 427.671761 -42.769346) (xy 427.622508 -42.728601)
			(xy 427.578751 -42.682004) (xy 427.541178 -42.630289) (xy 427.510384 -42.574274) (xy 427.486852 -42.514841)
			(xy 427.470955 -42.452927) (xy 427.462944 -42.389509) (xy 423.315799 -42.389509) (xy 423.308279 -42.44061)
			(xy 423.292211 -42.494017) (xy 423.268539 -42.544514) (xy 423.237766 -42.591027) (xy 423.200549 -42.632564)
			(xy 423.157681 -42.668239) (xy 423.110075 -42.697293) (xy 423.058746 -42.719105) (xy 423.004789 -42.733211)
			(xy 422.949352 -42.739311) (xy 422.893618 -42.737274) (xy 422.838775 -42.727144) (xy 422.785991 -42.709137)
			(xy 422.736391 -42.683636) (xy 422.691033 -42.651185) (xy 422.650884 -42.612476) (xy 422.616798 -42.568333)
			(xy 422.589502 -42.519698) (xy 422.569579 -42.467607) (xy 422.557453 -42.41317) (xy 422.553382 -42.357548)
			(xy 414.811863 -42.357548) (xy 414.824521 -42.375786) (xy 414.853333 -42.43041) (xy 414.875319 -42.48812)
			(xy 414.890157 -42.548068) (xy 414.897627 -42.609372) (xy 414.898078 -42.64025) (xy 414.897576 -42.672211)
			(xy 414.889565 -42.735629) (xy 414.873668 -42.797543) (xy 414.850136 -42.856976) (xy 414.819342 -42.912991)
			(xy 414.781769 -42.964706) (xy 414.738012 -43.011303) (xy 414.688759 -43.052048) (xy 414.634788 -43.086299)
			(xy 414.576949 -43.113516) (xy 414.516156 -43.133269) (xy 414.453366 -43.145247) (xy 414.38957 -43.149261)
			(xy 414.325774 -43.145247) (xy 414.262984 -43.133269) (xy 414.202191 -43.113516) (xy 414.144352 -43.086299)
			(xy 414.090381 -43.052048) (xy 414.041128 -43.011303) (xy 413.997371 -42.964706) (xy 413.959798 -42.912991)
			(xy 413.929004 -42.856976) (xy 413.905472 -42.797543) (xy 413.889575 -42.735629) (xy 413.881564 -42.672211)
			(xy 413.881062 -42.64025) (xy 413.881494 -42.60988) (xy 413.888748 -42.549575) (xy 413.903135 -42.490564)
			(xy 413.92445 -42.433688) (xy 413.952389 -42.379755) (xy 413.986555 -42.329536) (xy 414.02646 -42.283744)
			(xy 414.048702 -42.26306) (xy 414.057338 -42.255186) (xy 414.065974 -42.233596) (xy 414.059878 -42.142156)
			(xy 414.058387 -42.130743) (xy 414.046897 -42.110831) (xy 414.03778 -42.103802) (xy 414.012544 -42.086004)
			(xy 413.966166 -42.045225) (xy 413.925067 -41.999131) (xy 413.889852 -41.948399) (xy 413.861039 -41.893777)
			(xy 413.839051 -41.836068) (xy 413.824213 -41.776121) (xy 413.816743 -41.714818) (xy 413.816292 -41.68394)
			(xy 371.004324 -41.68394) (xy 371.003837 -41.687246) (xy 370.987769 -41.740653) (xy 370.964097 -41.79115)
			(xy 370.933324 -41.837663) (xy 370.896107 -41.8792) (xy 370.853239 -41.914875) (xy 370.805633 -41.943929)
			(xy 370.754304 -41.965741) (xy 370.700347 -41.979847) (xy 370.64491 -41.985947) (xy 370.589176 -41.98391)
			(xy 370.534333 -41.97378) (xy 370.481549 -41.955773) (xy 370.431949 -41.930272) (xy 370.386591 -41.897821)
			(xy 370.346442 -41.859112) (xy 370.312356 -41.814969) (xy 370.28506 -41.766334) (xy 370.265137 -41.714243)
			(xy 370.253011 -41.659806) (xy 370.24894 -41.604184) (xy 370.01965 -41.604184) (xy 370.019834 -41.615868)
			(xy 370.019332 -41.647829) (xy 370.011321 -41.711247) (xy 369.995424 -41.773161) (xy 369.971892 -41.832594)
			(xy 369.941098 -41.888609) (xy 369.903525 -41.940324) (xy 369.859768 -41.986921) (xy 369.810515 -42.027666)
			(xy 369.756544 -42.061917) (xy 369.698705 -42.089134) (xy 369.637912 -42.108887) (xy 369.575122 -42.120865)
			(xy 369.511326 -42.124879) (xy 369.44753 -42.120865) (xy 369.38474 -42.108887) (xy 369.323947 -42.089134)
			(xy 369.266108 -42.061917) (xy 369.212137 -42.027666) (xy 369.162884 -41.986921) (xy 369.119127 -41.940324)
			(xy 369.081554 -41.888609) (xy 369.05076 -41.832594) (xy 369.027228 -41.773161) (xy 369.011331 -41.711247)
			(xy 369.00332 -41.647829) (xy 367.47827 -41.647829) (xy 367.476265 -41.67969) (xy 367.464289 -41.742474)
			(xy 367.444539 -41.803262) (xy 367.417325 -41.861095) (xy 367.383078 -41.915062) (xy 367.342338 -41.964311)
			(xy 367.295746 -42.008065) (xy 367.244038 -42.045636) (xy 367.188029 -42.07643) (xy 367.128603 -42.099961)
			(xy 367.066696 -42.115859) (xy 367.003284 -42.123873) (xy 366.971326 -42.124376) (xy 366.940805 -42.123921)
			(xy 366.880203 -42.116605) (xy 366.820913 -42.102088) (xy 366.763786 -42.080579) (xy 366.709645 -42.052386)
			(xy 366.659268 -42.017915) (xy 366.613379 -41.977661) (xy 366.572639 -41.932205) (xy 366.554766 -41.90746)
			(xy 366.548162 -41.897808) (xy 366.528096 -41.886632) (xy 366.436656 -41.881044) (xy 366.425344 -41.880983)
			(xy 366.404385 -41.889419) (xy 366.39627 -41.8973) (xy 366.396016 -41.897554) (xy 366.377883 -41.916996)
			(xy 366.33711 -41.951115) (xy 366.291993 -41.979239) (xy 366.243406 -42.000822) (xy 366.192292 -42.015445)
			(xy 366.139642 -42.022826) (xy 366.11306 -42.023284) (xy 366.085809 -42.022843) (xy 366.031862 -42.015082)
			(xy 365.979569 -41.999722) (xy 365.929994 -41.977077) (xy 365.884145 -41.947608) (xy 365.842957 -41.911914)
			(xy 365.807268 -41.870723) (xy 365.777803 -41.824871) (xy 365.755164 -41.775294) (xy 365.73981 -41.722999)
			(xy 365.732054 -41.669051) (xy 354.446907 -41.669051) (xy 354.447348 -41.710102) (xy 354.446854 -41.756041)
			(xy 354.438956 -41.84758) (xy 354.423217 -41.9381) (xy 354.399756 -42.026933) (xy 354.368745 -42.11342)
			(xy 354.330414 -42.19692) (xy 354.285046 -42.276817) (xy 354.232979 -42.352518) (xy 354.174596 -42.423462)
			(xy 354.110331 -42.489125) (xy 354.040659 -42.549021) (xy 353.966096 -42.602705) (xy 353.887194 -42.649781)
			(xy 353.804537 -42.6899) (xy 353.718738 -42.722765) (xy 353.63043 -42.748132) (xy 353.54027 -42.765814)
			(xy 353.448922 -42.77568) (xy 353.357065 -42.777657) (xy 353.265378 -42.77173) (xy 353.17454 -42.757944)
			(xy 353.085223 -42.736399) (xy 352.998089 -42.707256) (xy 352.913783 -42.67073) (xy 352.832929 -42.627092)
			(xy 352.756125 -42.576665) (xy 352.683941 -42.519823) (xy 352.61691 -42.456985) (xy 352.555529 -42.388618)
			(xy 352.500253 -42.315228) (xy 352.45149 -42.237357) (xy 352.409602 -42.155582) (xy 352.374899 -42.07051)
			(xy 352.347637 -41.982769) (xy 352.32802 -41.893009) (xy 352.31619 -41.801895) (xy 352.312238 -41.710102)
			(xy 351.907348 -41.710102) (xy 351.906854 -41.756041) (xy 351.898956 -41.84758) (xy 351.883217 -41.9381)
			(xy 351.859756 -42.026933) (xy 351.828745 -42.11342) (xy 351.790414 -42.19692) (xy 351.745046 -42.276817)
			(xy 351.692979 -42.352518) (xy 351.634596 -42.423462) (xy 351.570331 -42.489125) (xy 351.500659 -42.549021)
			(xy 351.426096 -42.602705) (xy 351.347194 -42.649781) (xy 351.264537 -42.6899) (xy 351.178738 -42.722765)
			(xy 351.09043 -42.748132) (xy 351.00027 -42.765814) (xy 350.908922 -42.77568) (xy 350.817065 -42.777657)
			(xy 350.725378 -42.77173) (xy 350.63454 -42.757944) (xy 350.545223 -42.736399) (xy 350.458089 -42.707256)
			(xy 350.373783 -42.67073) (xy 350.292929 -42.627092) (xy 350.216125 -42.576665) (xy 350.143941 -42.519823)
			(xy 350.07691 -42.456985) (xy 350.015529 -42.388618) (xy 349.960253 -42.315228) (xy 349.91149 -42.237357)
			(xy 349.869602 -42.155582) (xy 349.834899 -42.07051) (xy 349.807637 -41.982769) (xy 349.78802 -41.893009)
			(xy 349.77619 -41.801895) (xy 349.772238 -41.710102) (xy 349.367348 -41.710102) (xy 349.366854 -41.756041)
			(xy 349.358956 -41.84758) (xy 349.343217 -41.9381) (xy 349.319756 -42.026933) (xy 349.288745 -42.11342)
			(xy 349.250414 -42.19692) (xy 349.205046 -42.276817) (xy 349.152979 -42.352518) (xy 349.094596 -42.423462)
			(xy 349.030331 -42.489125) (xy 348.960659 -42.549021) (xy 348.886096 -42.602705) (xy 348.807194 -42.649781)
			(xy 348.724537 -42.6899) (xy 348.638738 -42.722765) (xy 348.55043 -42.748132) (xy 348.46027 -42.765814)
			(xy 348.368922 -42.77568) (xy 348.277065 -42.777657) (xy 348.185378 -42.77173) (xy 348.09454 -42.757944)
			(xy 348.005223 -42.736399) (xy 347.918089 -42.707256) (xy 347.833783 -42.67073) (xy 347.752929 -42.627092)
			(xy 347.676125 -42.576665) (xy 347.603941 -42.519823) (xy 347.53691 -42.456985) (xy 347.475529 -42.388618)
			(xy 347.420253 -42.315228) (xy 347.37149 -42.237357) (xy 347.329602 -42.155582) (xy 347.294899 -42.07051)
			(xy 347.267637 -41.982769) (xy 347.24802 -41.893009) (xy 347.23619 -41.801895) (xy 347.232238 -41.710102)
			(xy 346.827348 -41.710102) (xy 346.826854 -41.756041) (xy 346.818956 -41.84758) (xy 346.803217 -41.9381)
			(xy 346.779756 -42.026933) (xy 346.748745 -42.11342) (xy 346.710414 -42.19692) (xy 346.665046 -42.276817)
			(xy 346.612979 -42.352518) (xy 346.554596 -42.423462) (xy 346.490331 -42.489125) (xy 346.420659 -42.549021)
			(xy 346.346096 -42.602705) (xy 346.267194 -42.649781) (xy 346.184537 -42.6899) (xy 346.098738 -42.722765)
			(xy 346.01043 -42.748132) (xy 345.92027 -42.765814) (xy 345.828922 -42.77568) (xy 345.737065 -42.777657)
			(xy 345.645378 -42.77173) (xy 345.55454 -42.757944) (xy 345.465223 -42.736399) (xy 345.378089 -42.707256)
			(xy 345.293783 -42.67073) (xy 345.212929 -42.627092) (xy 345.136125 -42.576665) (xy 345.063941 -42.519823)
			(xy 344.99691 -42.456985) (xy 344.935529 -42.388618) (xy 344.880253 -42.315228) (xy 344.83149 -42.237357)
			(xy 344.789602 -42.155582) (xy 344.754899 -42.07051) (xy 344.727637 -41.982769) (xy 344.70802 -41.893009)
			(xy 344.69619 -41.801895) (xy 344.692238 -41.710102) (xy 344.287348 -41.710102) (xy 344.286854 -41.756041)
			(xy 344.278956 -41.84758) (xy 344.263217 -41.9381) (xy 344.239756 -42.026933) (xy 344.208745 -42.11342)
			(xy 344.170414 -42.19692) (xy 344.125046 -42.276817) (xy 344.072979 -42.352518) (xy 344.014596 -42.423462)
			(xy 343.950331 -42.489125) (xy 343.880659 -42.549021) (xy 343.806096 -42.602705) (xy 343.727194 -42.649781)
			(xy 343.644537 -42.6899) (xy 343.558738 -42.722765) (xy 343.47043 -42.748132) (xy 343.38027 -42.765814)
			(xy 343.288922 -42.77568) (xy 343.197065 -42.777657) (xy 343.105378 -42.77173) (xy 343.01454 -42.757944)
			(xy 342.925223 -42.736399) (xy 342.838089 -42.707256) (xy 342.753783 -42.67073) (xy 342.672929 -42.627092)
			(xy 342.596125 -42.576665) (xy 342.523941 -42.519823) (xy 342.45691 -42.456985) (xy 342.395529 -42.388618)
			(xy 342.340253 -42.315228) (xy 342.29149 -42.237357) (xy 342.249602 -42.155582) (xy 342.214899 -42.07051)
			(xy 342.187637 -41.982769) (xy 342.16802 -41.893009) (xy 342.15619 -41.801895) (xy 342.152238 -41.710102)
			(xy 330.802837 -41.710102) (xy 330.847046 -41.730905) (xy 330.901017 -41.765156) (xy 330.95027 -41.805901)
			(xy 330.994027 -41.852498) (xy 331.0316 -41.904213) (xy 331.062394 -41.960228) (xy 331.085926 -42.019661)
			(xy 331.101823 -42.081575) (xy 331.109834 -42.144993) (xy 331.110336 -42.176954) (xy 331.109834 -42.208915)
			(xy 331.101823 -42.272333) (xy 331.085926 -42.334247) (xy 331.062394 -42.39368) (xy 331.0316 -42.449695)
			(xy 330.994027 -42.50141) (xy 330.95027 -42.548007) (xy 330.901017 -42.588752) (xy 330.847046 -42.623003)
			(xy 330.789207 -42.65022) (xy 330.728414 -42.669973) (xy 330.665624 -42.681951) (xy 330.601828 -42.685965)
			(xy 330.538032 -42.681951) (xy 330.475242 -42.669973) (xy 330.414449 -42.65022) (xy 330.35661 -42.623003)
			(xy 330.302639 -42.588752) (xy 330.253386 -42.548007) (xy 330.209629 -42.50141) (xy 330.172056 -42.449695)
			(xy 330.141262 -42.39368) (xy 330.11773 -42.334247) (xy 330.101833 -42.272333) (xy 330.093822 -42.208915)
			(xy 328.569227 -42.208915) (xy 328.561707 -42.260016) (xy 328.545639 -42.313423) (xy 328.521967 -42.36392)
			(xy 328.491194 -42.410433) (xy 328.453977 -42.45197) (xy 328.411109 -42.487645) (xy 328.363503 -42.516699)
			(xy 328.312174 -42.538511) (xy 328.258217 -42.552617) (xy 328.20278 -42.558717) (xy 328.147046 -42.55668)
			(xy 328.092203 -42.54655) (xy 328.039419 -42.528543) (xy 327.989819 -42.503042) (xy 327.944461 -42.470591)
			(xy 327.904312 -42.431882) (xy 327.870226 -42.387739) (xy 327.84293 -42.339104) (xy 327.823007 -42.287013)
			(xy 327.810881 -42.232576) (xy 327.80681 -42.176954) (xy 325.155306 -42.176954) (xy 325.154804 -42.208915)
			(xy 325.146793 -42.272333) (xy 325.130896 -42.334247) (xy 325.107364 -42.39368) (xy 325.07657 -42.449695)
			(xy 325.038997 -42.50141) (xy 324.99524 -42.548007) (xy 324.945987 -42.588752) (xy 324.892016 -42.623003)
			(xy 324.834177 -42.65022) (xy 324.773384 -42.669973) (xy 324.710594 -42.681951) (xy 324.646798 -42.685965)
			(xy 324.583002 -42.681951) (xy 324.520212 -42.669973) (xy 324.459419 -42.65022) (xy 324.40158 -42.623003)
			(xy 324.347609 -42.588752) (xy 324.298356 -42.548007) (xy 324.254599 -42.50141) (xy 324.217026 -42.449695)
			(xy 324.186232 -42.39368) (xy 324.1627 -42.334247) (xy 324.146803 -42.272333) (xy 324.138792 -42.208915)
			(xy 305.041862 -42.208915) (xy 305.031679 -42.217389) (xy 304.984073 -42.246443) (xy 304.932744 -42.268255)
			(xy 304.878787 -42.282361) (xy 304.82335 -42.288461) (xy 304.767616 -42.286424) (xy 304.712773 -42.276294)
			(xy 304.659989 -42.258287) (xy 304.610389 -42.232786) (xy 304.565031 -42.200335) (xy 304.524882 -42.161626)
			(xy 304.490796 -42.117483) (xy 304.4635 -42.068848) (xy 304.443577 -42.016757) (xy 304.431451 -41.96232)
			(xy 304.42738 -41.906698) (xy 275.0947 -41.906698) (xy 275.0947 -42.684954) (xy 320.56781 -42.684954)
			(xy 320.571881 -42.629332) (xy 320.584007 -42.574895) (xy 320.60393 -42.522804) (xy 320.631226 -42.474169)
			(xy 320.665312 -42.430026) (xy 320.705461 -42.391317) (xy 320.750819 -42.358866) (xy 320.800419 -42.333365)
			(xy 320.853203 -42.315358) (xy 320.908046 -42.305228) (xy 320.96378 -42.303191) (xy 321.019217 -42.309291)
			(xy 321.073174 -42.323397) (xy 321.124503 -42.345209) (xy 321.172109 -42.374263) (xy 321.214977 -42.409938)
			(xy 321.252194 -42.451475) (xy 321.282967 -42.497988) (xy 321.306639 -42.548485) (xy 321.322707 -42.601892)
			(xy 321.330827 -42.657068) (xy 321.331336 -42.684954) (xy 321.330827 -42.71284) (xy 321.322707 -42.768016)
			(xy 321.306639 -42.821423) (xy 321.282967 -42.87192) (xy 321.260631 -42.90568) (xy 412.7881 -42.90568)
			(xy 412.788602 -42.873719) (xy 412.796613 -42.810301) (xy 412.81251 -42.748387) (xy 412.836042 -42.688954)
			(xy 412.866836 -42.632939) (xy 412.904409 -42.581224) (xy 412.948166 -42.534627) (xy 412.997419 -42.493882)
			(xy 413.05139 -42.459631) (xy 413.109229 -42.432414) (xy 413.170022 -42.412661) (xy 413.232812 -42.400683)
			(xy 413.296608 -42.39667) (xy 413.360404 -42.400683) (xy 413.423194 -42.412661) (xy 413.483987 -42.432414)
			(xy 413.541826 -42.459631) (xy 413.595797 -42.493882) (xy 413.64505 -42.534627) (xy 413.688807 -42.581224)
			(xy 413.72638 -42.632939) (xy 413.757174 -42.688954) (xy 413.780706 -42.748387) (xy 413.796603 -42.810301)
			(xy 413.804614 -42.873719) (xy 413.805116 -42.90568) (xy 413.804653 -42.935718) (xy 413.797587 -42.995377)
			(xy 413.783538 -43.053787) (xy 413.762703 -43.110134) (xy 413.735373 -43.163633) (xy 413.701927 -43.213538)
			(xy 413.662833 -43.259153) (xy 413.641032 -43.279822) (xy 413.633852 -43.287033) (xy 413.625331 -43.305493)
			(xy 413.624522 -43.315636) (xy 413.62249 -43.38828) (xy 413.62265 -43.398471) (xy 413.629972 -43.417469)
			(xy 413.636714 -43.42511) (xy 413.656655 -43.446581) (xy 413.690404 -43.49448) (xy 413.716438 -43.546974)
			(xy 413.734145 -43.602829) (xy 413.743109 -43.660735) (xy 413.743648 -43.690032) (xy 413.743162 -43.717283)
			(xy 413.735406 -43.771231) (xy 413.720051 -43.823526) (xy 413.703064 -43.86072) (xy 432.992784 -43.86072)
			(xy 432.992784 -38.636956) (xy 432.993164 -38.626881) (xy 433.000914 -38.608282) (xy 433.00777 -38.600888)
			(xy 433.502562 -38.10635) (xy 433.509987 -38.099541) (xy 433.528567 -38.091802) (xy 433.53863 -38.091364)
			(xy 441.160154 -38.091364) (xy 441.170223 -38.091796) (xy 441.188822 -38.09951) (xy 441.196222 -38.10635)
			(xy 441.665614 -38.575488) (xy 441.672443 -38.582897) (xy 441.680169 -38.601489) (xy 441.6806 -38.611556)
			(xy 441.6806 -40.49586) (xy 444.544438 -40.49586) (xy 444.544438 -40.344212) (xy 444.552375 -40.192771)
			(xy 444.568226 -40.041953) (xy 444.591949 -39.892172) (xy 444.623479 -39.743837) (xy 444.662728 -39.597356)
			(xy 444.70959 -39.45313) (xy 444.763936 -39.311553) (xy 444.825617 -39.173016) (xy 444.894464 -39.037896)
			(xy 444.970289 -38.906564) (xy 445.052882 -38.779381) (xy 445.142019 -38.656695) (xy 445.237455 -38.538842)
			(xy 445.338927 -38.426145) (xy 445.446159 -38.318913) (xy 445.558856 -38.217441) (xy 445.676709 -38.122005)
			(xy 445.799395 -38.032868) (xy 445.926578 -37.950275) (xy 446.05791 -37.87445) (xy 446.19303 -37.805603)
			(xy 446.331567 -37.743922) (xy 446.473144 -37.689576) (xy 446.61737 -37.642714) (xy 446.763851 -37.603465)
			(xy 446.912186 -37.571935) (xy 447.061967 -37.548212) (xy 447.212785 -37.532361) (xy 447.364226 -37.524424)
			(xy 447.515874 -37.524424) (xy 447.667315 -37.532361) (xy 447.818133 -37.548212) (xy 447.967914 -37.571935)
			(xy 448.116249 -37.603465) (xy 448.26273 -37.642714) (xy 448.406956 -37.689576) (xy 448.548533 -37.743922)
			(xy 448.68707 -37.805603) (xy 448.82219 -37.87445) (xy 448.915893 -37.92855) (xy 461.429352 -37.92855)
			(xy 461.433423 -37.872928) (xy 461.445549 -37.818491) (xy 461.465472 -37.7664) (xy 461.492768 -37.717765)
			(xy 461.526854 -37.673622) (xy 461.567003 -37.634913) (xy 461.612361 -37.602462) (xy 461.661961 -37.576961)
			(xy 461.714745 -37.558954) (xy 461.769588 -37.548824) (xy 461.825322 -37.546787) (xy 461.880759 -37.552887)
			(xy 461.934716 -37.566993) (xy 461.986045 -37.588805) (xy 462.033651 -37.617859) (xy 462.076519 -37.653534)
			(xy 462.113736 -37.695071) (xy 462.144509 -37.741584) (xy 462.168181 -37.792081) (xy 462.184249 -37.845488)
			(xy 462.192369 -37.900664) (xy 462.192878 -37.92855) (xy 462.192369 -37.956436) (xy 462.184249 -38.011612)
			(xy 462.168181 -38.065019) (xy 462.144509 -38.115516) (xy 462.135982 -38.128405) (xy 464.608158 -38.128405)
			(xy 464.608158 -38.064483) (xy 464.616169 -38.001065) (xy 464.632066 -37.939151) (xy 464.655598 -37.879718)
			(xy 464.686392 -37.823703) (xy 464.723965 -37.771988) (xy 464.767722 -37.725391) (xy 464.816975 -37.684646)
			(xy 464.870946 -37.650395) (xy 464.928785 -37.623178) (xy 464.989578 -37.603425) (xy 465.052368 -37.591447)
			(xy 465.116164 -37.587434) (xy 465.17996 -37.591447) (xy 465.24275 -37.603425) (xy 465.303543 -37.623178)
			(xy 465.361382 -37.650395) (xy 465.415353 -37.684646) (xy 465.464606 -37.725391) (xy 465.508363 -37.771988)
			(xy 465.545936 -37.823703) (xy 465.57673 -37.879718) (xy 465.600262 -37.939151) (xy 465.616159 -38.001065)
			(xy 465.62417 -38.064483) (xy 465.624672 -38.096444) (xy 465.62417 -38.128405) (xy 465.616159 -38.191823)
			(xy 465.600262 -38.253737) (xy 465.57673 -38.31317) (xy 465.545936 -38.369185) (xy 465.508363 -38.4209)
			(xy 465.464606 -38.467497) (xy 465.415353 -38.508242) (xy 465.361382 -38.542493) (xy 465.303543 -38.56971)
			(xy 465.24275 -38.589463) (xy 465.17996 -38.601441) (xy 465.116164 -38.605455) (xy 465.052368 -38.601441)
			(xy 464.989578 -38.589463) (xy 464.928785 -38.56971) (xy 464.870946 -38.542493) (xy 464.816975 -38.508242)
			(xy 464.767722 -38.467497) (xy 464.723965 -38.4209) (xy 464.686392 -38.369185) (xy 464.655598 -38.31317)
			(xy 464.632066 -38.253737) (xy 464.616169 -38.191823) (xy 464.608158 -38.128405) (xy 462.135982 -38.128405)
			(xy 462.113736 -38.162029) (xy 462.076519 -38.203566) (xy 462.033651 -38.239241) (xy 461.986045 -38.268295)
			(xy 461.934716 -38.290107) (xy 461.880759 -38.304213) (xy 461.825322 -38.310313) (xy 461.769588 -38.308276)
			(xy 461.714745 -38.298146) (xy 461.661961 -38.280139) (xy 461.612361 -38.254638) (xy 461.567003 -38.222187)
			(xy 461.526854 -38.183478) (xy 461.492768 -38.139335) (xy 461.465472 -38.0907) (xy 461.445549 -38.038609)
			(xy 461.433423 -37.984172) (xy 461.429352 -37.92855) (xy 448.915893 -37.92855) (xy 448.953522 -37.950275)
			(xy 449.080705 -38.032868) (xy 449.203391 -38.122005) (xy 449.321244 -38.217441) (xy 449.433941 -38.318913)
			(xy 449.541173 -38.426145) (xy 449.642645 -38.538842) (xy 449.690386 -38.597797) (xy 453.489054 -38.597797)
			(xy 453.489054 -38.533875) (xy 453.497065 -38.470457) (xy 453.512962 -38.408543) (xy 453.536494 -38.34911)
			(xy 453.567288 -38.293095) (xy 453.604861 -38.24138) (xy 453.648618 -38.194783) (xy 453.697871 -38.154038)
			(xy 453.751842 -38.119787) (xy 453.809681 -38.09257) (xy 453.870474 -38.072817) (xy 453.933264 -38.060839)
			(xy 453.99706 -38.056826) (xy 454.060856 -38.060839) (xy 454.123646 -38.072817) (xy 454.184439 -38.09257)
			(xy 454.242278 -38.119787) (xy 454.296249 -38.154038) (xy 454.345502 -38.194783) (xy 454.389259 -38.24138)
			(xy 454.426832 -38.293095) (xy 454.457626 -38.34911) (xy 454.481158 -38.408543) (xy 454.497055 -38.470457)
			(xy 454.505066 -38.533875) (xy 454.505568 -38.565836) (xy 454.505066 -38.597797) (xy 454.497055 -38.661215)
			(xy 454.481158 -38.723129) (xy 454.457626 -38.782562) (xy 454.426832 -38.838577) (xy 454.389259 -38.890292)
			(xy 454.345502 -38.936889) (xy 454.296249 -38.977634) (xy 454.242278 -39.011885) (xy 454.184439 -39.039102)
			(xy 454.123646 -39.058855) (xy 454.060856 -39.070833) (xy 453.99706 -39.074847) (xy 453.933264 -39.070833)
			(xy 453.870474 -39.058855) (xy 453.809681 -39.039102) (xy 453.751842 -39.011885) (xy 453.697871 -38.977634)
			(xy 453.648618 -38.936889) (xy 453.604861 -38.890292) (xy 453.567288 -38.838577) (xy 453.536494 -38.782562)
			(xy 453.512962 -38.723129) (xy 453.497065 -38.661215) (xy 453.489054 -38.597797) (xy 449.690386 -38.597797)
			(xy 449.738081 -38.656695) (xy 449.827218 -38.779381) (xy 449.909811 -38.906564) (xy 449.985636 -39.037896)
			(xy 450.054483 -39.173016) (xy 450.116164 -39.311553) (xy 450.17051 -39.45313) (xy 450.217372 -39.597356)
			(xy 450.256621 -39.743837) (xy 450.28297 -39.867797) (xy 453.489054 -39.867797) (xy 453.489054 -39.803875)
			(xy 453.497065 -39.740457) (xy 453.512962 -39.678543) (xy 453.536494 -39.61911) (xy 453.567288 -39.563095)
			(xy 453.604861 -39.51138) (xy 453.648618 -39.464783) (xy 453.697871 -39.424038) (xy 453.751842 -39.389787)
			(xy 453.809681 -39.36257) (xy 453.870474 -39.342817) (xy 453.933264 -39.330839) (xy 453.99706 -39.326826)
			(xy 454.060856 -39.330839) (xy 454.123646 -39.342817) (xy 454.184439 -39.36257) (xy 454.242278 -39.389787)
			(xy 454.296249 -39.424038) (xy 454.345502 -39.464783) (xy 454.389259 -39.51138) (xy 454.426832 -39.563095)
			(xy 454.457626 -39.61911) (xy 454.481158 -39.678543) (xy 454.497055 -39.740457) (xy 454.504253 -39.797439)
			(xy 457.343504 -39.797439) (xy 457.343504 -39.733517) (xy 457.351515 -39.670099) (xy 457.367412 -39.608185)
			(xy 457.390944 -39.548752) (xy 457.421738 -39.492737) (xy 457.459311 -39.441022) (xy 457.503068 -39.394425)
			(xy 457.552321 -39.35368) (xy 457.606292 -39.319429) (xy 457.664131 -39.292212) (xy 457.724924 -39.272459)
			(xy 457.787714 -39.260481) (xy 457.85151 -39.256468) (xy 457.915306 -39.260481) (xy 457.978096 -39.272459)
			(xy 458.038889 -39.292212) (xy 458.096728 -39.319429) (xy 458.150699 -39.35368) (xy 458.199952 -39.394425)
			(xy 458.243709 -39.441022) (xy 458.281282 -39.492737) (xy 458.312076 -39.548752) (xy 458.335608 -39.608185)
			(xy 458.351505 -39.670099) (xy 458.359516 -39.733517) (xy 458.360018 -39.765478) (xy 458.359516 -39.797439)
			(xy 458.351505 -39.860857) (xy 458.335608 -39.922771) (xy 458.312076 -39.982204) (xy 458.281282 -40.038219)
			(xy 458.243709 -40.089934) (xy 458.199952 -40.136531) (xy 458.150699 -40.177276) (xy 458.096728 -40.211527)
			(xy 458.038889 -40.238744) (xy 457.978096 -40.258497) (xy 457.915306 -40.270475) (xy 457.85151 -40.274489)
			(xy 457.787714 -40.270475) (xy 457.724924 -40.258497) (xy 457.664131 -40.238744) (xy 457.606292 -40.211527)
			(xy 457.552321 -40.177276) (xy 457.503068 -40.136531) (xy 457.459311 -40.089934) (xy 457.421738 -40.038219)
			(xy 457.390944 -39.982204) (xy 457.367412 -39.922771) (xy 457.351515 -39.860857) (xy 457.343504 -39.797439)
			(xy 454.504253 -39.797439) (xy 454.505066 -39.803875) (xy 454.505568 -39.835836) (xy 454.505066 -39.867797)
			(xy 454.497055 -39.931215) (xy 454.481158 -39.993129) (xy 454.457626 -40.052562) (xy 454.426832 -40.108577)
			(xy 454.389259 -40.160292) (xy 454.345502 -40.206889) (xy 454.296249 -40.247634) (xy 454.242278 -40.281885)
			(xy 454.184439 -40.309102) (xy 454.123646 -40.328855) (xy 454.060856 -40.340833) (xy 453.99706 -40.344847)
			(xy 453.933264 -40.340833) (xy 453.870474 -40.328855) (xy 453.809681 -40.309102) (xy 453.751842 -40.281885)
			(xy 453.697871 -40.247634) (xy 453.648618 -40.206889) (xy 453.604861 -40.160292) (xy 453.567288 -40.108577)
			(xy 453.536494 -40.052562) (xy 453.512962 -39.993129) (xy 453.497065 -39.931215) (xy 453.489054 -39.867797)
			(xy 450.28297 -39.867797) (xy 450.288151 -39.892172) (xy 450.311874 -40.041953) (xy 450.327725 -40.192771)
			(xy 450.335662 -40.344212) (xy 450.336158 -40.420036) (xy 450.335746 -40.483047) (xy 460.011828 -40.483047)
			(xy 460.011828 -40.428553) (xy 460.019583 -40.374614) (xy 460.034935 -40.322328) (xy 460.057572 -40.272759)
			(xy 460.087032 -40.226915) (xy 460.122717 -40.185731) (xy 460.163899 -40.150044) (xy 460.209741 -40.120581)
			(xy 460.259309 -40.097942) (xy 460.311595 -40.082587) (xy 460.365533 -40.07483) (xy 460.39278 -40.074342)
			(xy 460.393034 -40.074342) (xy 460.421949 -40.074887) (xy 460.479112 -40.083642) (xy 460.534302 -40.100916)
			(xy 460.586256 -40.126315) (xy 460.633786 -40.159257) (xy 460.655162 -40.178736) (xy 460.663544 -40.18661)
			(xy 460.685388 -40.193976) (xy 460.774796 -40.182038) (xy 460.785933 -40.18) (xy 460.804923 -40.167723)
			(xy 460.811372 -40.158416) (xy 460.833385 -40.12369) (xy 460.882933 -40.058069) (xy 460.938324 -39.9973)
			(xy 460.999086 -39.941902) (xy 461.064701 -39.892346) (xy 461.134609 -39.849056) (xy 461.208213 -39.812402)
			(xy 461.284885 -39.782696) (xy 461.363971 -39.760191) (xy 461.444796 -39.74508) (xy 461.526671 -39.737491)
			(xy 461.567784 -39.73703) (xy 461.608888 -39.737467) (xy 461.690745 -39.745051) (xy 461.771554 -39.760156)
			(xy 461.850624 -39.782653) (xy 461.927281 -39.81235) (xy 462.00087 -39.848993) (xy 462.070765 -39.89227)
			(xy 462.136368 -39.941812) (xy 462.19712 -39.997196) (xy 462.252502 -40.057949) (xy 462.302042 -40.123553)
			(xy 462.345318 -40.193449) (xy 462.381959 -40.267039) (xy 462.411654 -40.343697) (xy 462.434149 -40.422768)
			(xy 462.449252 -40.503576) (xy 462.456834 -40.585434) (xy 462.457292 -40.626538) (xy 462.456794 -40.66708)
			(xy 462.449391 -40.747825) (xy 462.434676 -40.827563) (xy 462.412772 -40.905633) (xy 462.383861 -40.981387)
			(xy 462.348181 -41.054199) (xy 462.327498 -41.089072) (xy 462.323028 -41.097223) (xy 462.319657 -41.11549)
			(xy 462.32302 -41.133757) (xy 462.327498 -41.141904) (xy 462.348217 -41.176758) (xy 462.38393 -41.249562)
			(xy 462.412861 -41.325316) (xy 462.434769 -41.403391) (xy 462.449472 -41.483138) (xy 462.456848 -41.563893)
			(xy 462.457292 -41.604438) (xy 462.456788 -41.646786) (xy 462.448737 -41.7311) (xy 462.443972 -41.755822)
			(xy 463.196176 -41.755822) (xy 463.200247 -41.7002) (xy 463.212373 -41.645763) (xy 463.232296 -41.593672)
			(xy 463.259592 -41.545037) (xy 463.293678 -41.500894) (xy 463.333827 -41.462185) (xy 463.379185 -41.429734)
			(xy 463.428785 -41.404233) (xy 463.481569 -41.386226) (xy 463.536412 -41.376096) (xy 463.592146 -41.374059)
			(xy 463.647583 -41.380159) (xy 463.70154 -41.394265) (xy 463.752869 -41.416077) (xy 463.800475 -41.445131)
			(xy 463.843343 -41.480806) (xy 463.88056 -41.522343) (xy 463.911333 -41.568856) (xy 463.935005 -41.619353)
			(xy 463.951073 -41.67276) (xy 463.959193 -41.727936) (xy 463.959702 -41.755822) (xy 463.959193 -41.783708)
			(xy 463.951073 -41.838884) (xy 463.935005 -41.892291) (xy 463.911333 -41.942788) (xy 463.88056 -41.989301)
			(xy 463.843343 -42.030838) (xy 463.800475 -42.066513) (xy 463.752869 -42.095567) (xy 463.70154 -42.117379)
			(xy 463.647583 -42.131485) (xy 463.592146 -42.137585) (xy 463.536412 -42.135548) (xy 463.481569 -42.125418)
			(xy 463.428785 -42.107411) (xy 463.379185 -42.08191) (xy 463.333827 -42.049459) (xy 463.293678 -42.01075)
			(xy 463.259592 -41.966607) (xy 463.232296 -41.917972) (xy 463.212373 -41.865881) (xy 463.200247 -41.811444)
			(xy 463.196176 -41.755822) (xy 462.443972 -41.755822) (xy 462.432708 -41.814266) (xy 462.408847 -41.895533)
			(xy 462.377368 -41.974163) (xy 462.338557 -42.049444) (xy 462.292767 -42.120696) (xy 462.240411 -42.187272)
			(xy 462.181963 -42.24857) (xy 462.117953 -42.304035) (xy 462.048961 -42.353164) (xy 461.975611 -42.395513)
			(xy 461.898568 -42.430697) (xy 461.818529 -42.458399) (xy 461.73622 -42.478367) (xy 461.652385 -42.49042)
			(xy 461.567784 -42.494451) (xy 461.483183 -42.49042) (xy 461.399348 -42.478367) (xy 461.317039 -42.458399)
			(xy 461.237 -42.430697) (xy 461.159957 -42.395513) (xy 461.086607 -42.353164) (xy 461.017615 -42.304035)
			(xy 460.953605 -42.24857) (xy 460.895157 -42.187272) (xy 460.842801 -42.120696) (xy 460.797011 -42.049444)
			(xy 460.7582 -41.974163) (xy 460.726721 -41.895533) (xy 460.70286 -41.814266) (xy 460.686831 -41.7311)
			(xy 460.67878 -41.646786) (xy 460.678276 -41.604438) (xy 460.678753 -41.563896) (xy 460.686159 -41.483149)
			(xy 460.700877 -41.403411) (xy 460.722784 -41.325341) (xy 460.7517 -41.249587) (xy 460.787385 -41.176776)
			(xy 460.80807 -41.141904) (xy 460.812555 -41.13376) (xy 460.815914 -41.11549) (xy 460.812547 -41.09722)
			(xy 460.80807 -41.089072) (xy 460.786783 -41.053196) (xy 460.75026 -40.978189) (xy 460.720922 -40.900091)
			(xy 460.709518 -40.859964) (xy 460.705995 -40.849136) (xy 460.691219 -40.831852) (xy 460.68107 -40.82669)
			(xy 460.609188 -40.79494) (xy 460.598582 -40.790873) (xy 460.575903 -40.791396) (xy 460.5655 -40.795956)
			(xy 460.538593 -40.808993) (xy 460.481727 -40.827448) (xy 460.422673 -40.836781) (xy 460.39278 -40.837358)
			(xy 460.365533 -40.83677) (xy 460.311595 -40.829013) (xy 460.259309 -40.813658) (xy 460.209741 -40.791019)
			(xy 460.163899 -40.761556) (xy 460.122717 -40.725869) (xy 460.087032 -40.684685) (xy 460.057572 -40.638841)
			(xy 460.034935 -40.589272) (xy 460.019583 -40.536986) (xy 460.011828 -40.483047) (xy 450.335746 -40.483047)
			(xy 450.335662 -40.49586) (xy 450.327725 -40.647301) (xy 450.311874 -40.798119) (xy 450.288151 -40.9479)
			(xy 450.256621 -41.096235) (xy 450.217372 -41.242716) (xy 450.17051 -41.386942) (xy 450.169621 -41.389257)
			(xy 451.959466 -41.389257) (xy 451.959466 -41.325335) (xy 451.967477 -41.261917) (xy 451.983374 -41.200003)
			(xy 452.006906 -41.14057) (xy 452.0377 -41.084555) (xy 452.075273 -41.03284) (xy 452.11903 -40.986243)
			(xy 452.168283 -40.945498) (xy 452.222254 -40.911247) (xy 452.280093 -40.88403) (xy 452.340886 -40.864277)
			(xy 452.403676 -40.852299) (xy 452.467472 -40.848286) (xy 452.531268 -40.852299) (xy 452.594058 -40.864277)
			(xy 452.654851 -40.88403) (xy 452.71269 -40.911247) (xy 452.766661 -40.945498) (xy 452.815914 -40.986243)
			(xy 452.859671 -41.03284) (xy 452.897244 -41.084555) (xy 452.908943 -41.105836) (xy 453.615042 -41.105836)
			(xy 453.619113 -41.050214) (xy 453.631239 -40.995777) (xy 453.651162 -40.943686) (xy 453.678458 -40.895051)
			(xy 453.712544 -40.850908) (xy 453.752693 -40.812199) (xy 453.798051 -40.779748) (xy 453.847651 -40.754247)
			(xy 453.900435 -40.73624) (xy 453.955278 -40.72611) (xy 454.011012 -40.724073) (xy 454.066449 -40.730173)
			(xy 454.120406 -40.744279) (xy 454.171735 -40.766091) (xy 454.219341 -40.795145) (xy 454.262209 -40.83082)
			(xy 454.299426 -40.872357) (xy 454.330199 -40.91887) (xy 454.353871 -40.969367) (xy 454.369939 -41.022774)
			(xy 454.378059 -41.07795) (xy 454.378568 -41.105836) (xy 454.378059 -41.133722) (xy 454.369939 -41.188898)
			(xy 454.353871 -41.242305) (xy 454.330199 -41.292802) (xy 454.299426 -41.339315) (xy 454.262209 -41.380852)
			(xy 454.219341 -41.416527) (xy 454.171735 -41.445581) (xy 454.120406 -41.467393) (xy 454.066449 -41.481499)
			(xy 454.011012 -41.487599) (xy 453.955278 -41.485562) (xy 453.900435 -41.475432) (xy 453.847651 -41.457425)
			(xy 453.798051 -41.431924) (xy 453.752693 -41.399473) (xy 453.712544 -41.360764) (xy 453.678458 -41.316621)
			(xy 453.651162 -41.267986) (xy 453.631239 -41.215895) (xy 453.619113 -41.161458) (xy 453.615042 -41.105836)
			(xy 452.908943 -41.105836) (xy 452.928038 -41.14057) (xy 452.95157 -41.200003) (xy 452.967467 -41.261917)
			(xy 452.975478 -41.325335) (xy 452.97598 -41.357296) (xy 452.975478 -41.389257) (xy 452.967467 -41.452675)
			(xy 452.95157 -41.514589) (xy 452.928038 -41.574022) (xy 452.897244 -41.630037) (xy 452.859671 -41.681752)
			(xy 452.815914 -41.728349) (xy 452.766661 -41.769094) (xy 452.71269 -41.803345) (xy 452.654851 -41.830562)
			(xy 452.594058 -41.850315) (xy 452.531268 -41.862293) (xy 452.467472 -41.866307) (xy 452.403676 -41.862293)
			(xy 452.340886 -41.850315) (xy 452.280093 -41.830562) (xy 452.222254 -41.803345) (xy 452.168283 -41.769094)
			(xy 452.11903 -41.728349) (xy 452.075273 -41.681752) (xy 452.0377 -41.630037) (xy 452.006906 -41.574022)
			(xy 451.983374 -41.514589) (xy 451.967477 -41.452675) (xy 451.959466 -41.389257) (xy 450.169621 -41.389257)
			(xy 450.116164 -41.528519) (xy 450.054483 -41.667056) (xy 449.985636 -41.802176) (xy 449.909811 -41.933508)
			(xy 449.827218 -42.060691) (xy 449.759572 -42.153797) (xy 453.489054 -42.153797) (xy 453.489054 -42.089875)
			(xy 453.497065 -42.026457) (xy 453.512962 -41.964543) (xy 453.536494 -41.90511) (xy 453.567288 -41.849095)
			(xy 453.604861 -41.79738) (xy 453.648618 -41.750783) (xy 453.697871 -41.710038) (xy 453.751842 -41.675787)
			(xy 453.809681 -41.64857) (xy 453.870474 -41.628817) (xy 453.933264 -41.616839) (xy 453.99706 -41.612826)
			(xy 454.060856 -41.616839) (xy 454.123646 -41.628817) (xy 454.184439 -41.64857) (xy 454.242278 -41.675787)
			(xy 454.296249 -41.710038) (xy 454.345502 -41.750783) (xy 454.350234 -41.755822) (xy 456.828142 -41.755822)
			(xy 456.832213 -41.7002) (xy 456.844339 -41.645763) (xy 456.864262 -41.593672) (xy 456.891558 -41.545037)
			(xy 456.925644 -41.500894) (xy 456.965793 -41.462185) (xy 457.011151 -41.429734) (xy 457.060751 -41.404233)
			(xy 457.113535 -41.386226) (xy 457.168378 -41.376096) (xy 457.224112 -41.374059) (xy 457.279549 -41.380159)
			(xy 457.333506 -41.394265) (xy 457.384835 -41.416077) (xy 457.432441 -41.445131) (xy 457.475309 -41.480806)
			(xy 457.512526 -41.522343) (xy 457.543299 -41.568856) (xy 457.566971 -41.619353) (xy 457.583039 -41.67276)
			(xy 457.591159 -41.727936) (xy 457.591668 -41.755822) (xy 457.591159 -41.783708) (xy 457.583039 -41.838884)
			(xy 457.566971 -41.892291) (xy 457.543299 -41.942788) (xy 457.512526 -41.989301) (xy 457.475309 -42.030838)
			(xy 457.432441 -42.066513) (xy 457.384835 -42.095567) (xy 457.333506 -42.117379) (xy 457.279549 -42.131485)
			(xy 457.224112 -42.137585) (xy 457.168378 -42.135548) (xy 457.113535 -42.125418) (xy 457.060751 -42.107411)
			(xy 457.011151 -42.08191) (xy 456.965793 -42.049459) (xy 456.925644 -42.01075) (xy 456.891558 -41.966607)
			(xy 456.864262 -41.917972) (xy 456.844339 -41.865881) (xy 456.832213 -41.811444) (xy 456.828142 -41.755822)
			(xy 454.350234 -41.755822) (xy 454.389259 -41.79738) (xy 454.426832 -41.849095) (xy 454.457626 -41.90511)
			(xy 454.481158 -41.964543) (xy 454.497055 -42.026457) (xy 454.505066 -42.089875) (xy 454.505568 -42.121836)
			(xy 454.505066 -42.153797) (xy 454.497055 -42.217215) (xy 454.481158 -42.279129) (xy 454.457626 -42.338562)
			(xy 454.426832 -42.394577) (xy 454.389259 -42.446292) (xy 454.345502 -42.492889) (xy 454.296249 -42.533634)
			(xy 454.242278 -42.567885) (xy 454.184439 -42.595102) (xy 454.123646 -42.614855) (xy 454.060856 -42.626833)
			(xy 453.99706 -42.630847) (xy 453.933264 -42.626833) (xy 453.870474 -42.614855) (xy 453.809681 -42.595102)
			(xy 453.751842 -42.567885) (xy 453.697871 -42.533634) (xy 453.648618 -42.492889) (xy 453.604861 -42.446292)
			(xy 453.567288 -42.394577) (xy 453.536494 -42.338562) (xy 453.512962 -42.279129) (xy 453.497065 -42.217215)
			(xy 453.489054 -42.153797) (xy 449.759572 -42.153797) (xy 449.738081 -42.183377) (xy 449.642645 -42.30123)
			(xy 449.541173 -42.413927) (xy 449.433941 -42.521159) (xy 449.321244 -42.622631) (xy 449.203391 -42.718067)
			(xy 449.080705 -42.807204) (xy 448.953522 -42.889797) (xy 448.82219 -42.965622) (xy 448.68707 -43.034469)
			(xy 448.548533 -43.09615) (xy 448.406956 -43.150496) (xy 448.26273 -43.197358) (xy 448.116249 -43.236607)
			(xy 447.967914 -43.268137) (xy 447.818133 -43.29186) (xy 447.667315 -43.307711) (xy 447.515874 -43.315648)
			(xy 447.364226 -43.315648) (xy 447.212785 -43.307711) (xy 447.061967 -43.29186) (xy 446.912186 -43.268137)
			(xy 446.763851 -43.236607) (xy 446.61737 -43.197358) (xy 446.473144 -43.150496) (xy 446.331567 -43.09615)
			(xy 446.19303 -43.034469) (xy 446.05791 -42.965622) (xy 445.926578 -42.889797) (xy 445.799395 -42.807204)
			(xy 445.676709 -42.718067) (xy 445.558856 -42.622631) (xy 445.446159 -42.521159) (xy 445.338927 -42.413927)
			(xy 445.237455 -42.30123) (xy 445.142019 -42.183377) (xy 445.052882 -42.060691) (xy 444.970289 -41.933508)
			(xy 444.894464 -41.802176) (xy 444.825617 -41.667056) (xy 444.763936 -41.528519) (xy 444.70959 -41.386942)
			(xy 444.662728 -41.242716) (xy 444.623479 -41.096235) (xy 444.591949 -40.9479) (xy 444.568226 -40.798119)
			(xy 444.552375 -40.647301) (xy 444.544438 -40.49586) (xy 441.6806 -40.49586) (xy 441.6806 -43.82008)
			(xy 441.68019 -43.830152) (xy 441.672461 -43.848751) (xy 441.665614 -43.856148) (xy 441.130182 -44.391326)
			(xy 441.122785 -44.39817) (xy 441.104183 -44.405887) (xy 441.094114 -44.406312) (xy 433.53863 -44.406312)
			(xy 433.528559 -44.405894) (xy 433.50996 -44.398171) (xy 433.502562 -44.391326) (xy 433.00777 -43.896788)
			(xy 433.000928 -43.88939) (xy 432.99321 -43.870789) (xy 432.992784 -43.86072) (xy 413.703064 -43.86072)
			(xy 413.697409 -43.873103) (xy 413.667943 -43.918953) (xy 413.632252 -43.960144) (xy 413.591061 -43.995835)
			(xy 413.545211 -44.025301) (xy 413.495634 -44.047943) (xy 413.443339 -44.063298) (xy 413.389391 -44.071054)
			(xy 413.334889 -44.071054) (xy 413.280941 -44.063298) (xy 413.228646 -44.047943) (xy 413.179069 -44.025301)
			(xy 413.133219 -43.995835) (xy 413.092028 -43.960144) (xy 413.056337 -43.918953) (xy 413.026871 -43.873103)
			(xy 413.004229 -43.823526) (xy 412.988874 -43.771231) (xy 412.981118 -43.717283) (xy 412.980632 -43.690032)
			(xy 412.981131 -43.661368) (xy 412.989717 -43.604686) (xy 413.006686 -43.549927) (xy 413.031655 -43.498322)
			(xy 413.047434 -43.474386) (xy 413.052849 -43.465695) (xy 413.056906 -43.44564) (xy 413.055308 -43.435524)
			(xy 413.041338 -43.364658) (xy 413.038862 -43.354722) (xy 413.027337 -43.337818) (xy 413.018986 -43.331892)
			(xy 412.99281 -43.314207) (xy 412.944574 -43.273414) (xy 412.901758 -43.226964) (xy 412.86502 -43.175572)
			(xy 412.834926 -43.120028) (xy 412.811939 -43.061186) (xy 412.796411 -42.999952) (xy 412.788582 -42.937266)
			(xy 412.7881 -42.90568) (xy 321.260631 -42.90568) (xy 321.252194 -42.918433) (xy 321.214977 -42.95997)
			(xy 321.172109 -42.995645) (xy 321.124503 -43.024699) (xy 321.073174 -43.046511) (xy 321.019217 -43.060617)
			(xy 320.96378 -43.066717) (xy 320.908046 -43.06468) (xy 320.853203 -43.05455) (xy 320.800419 -43.036543)
			(xy 320.750819 -43.011042) (xy 320.705461 -42.978591) (xy 320.665312 -42.939882) (xy 320.631226 -42.895739)
			(xy 320.60393 -42.847104) (xy 320.584007 -42.795013) (xy 320.571881 -42.740576) (xy 320.56781 -42.684954)
			(xy 275.0947 -42.684954) (xy 275.0947 -43.989498) (xy 301.802036 -43.989498) (xy 301.806107 -43.933876)
			(xy 301.818233 -43.879439) (xy 301.838156 -43.827348) (xy 301.865452 -43.778713) (xy 301.899538 -43.73457)
			(xy 301.939687 -43.695861) (xy 301.985045 -43.66341) (xy 302.034645 -43.637909) (xy 302.087429 -43.619902)
			(xy 302.142272 -43.609772) (xy 302.198006 -43.607735) (xy 302.253443 -43.613835) (xy 302.3074 -43.627941)
			(xy 302.358729 -43.649753) (xy 302.406335 -43.678807) (xy 302.449203 -43.714482) (xy 302.48642 -43.756019)
			(xy 302.507797 -43.78833) (xy 308.362094 -43.78833) (xy 308.366165 -43.732708) (xy 308.378291 -43.678271)
			(xy 308.398214 -43.62618) (xy 308.42551 -43.577545) (xy 308.459596 -43.533402) (xy 308.499745 -43.494693)
			(xy 308.545103 -43.462242) (xy 308.594703 -43.436741) (xy 308.647487 -43.418734) (xy 308.70233 -43.408604)
			(xy 308.758064 -43.406567) (xy 308.813501 -43.412667) (xy 308.867458 -43.426773) (xy 308.918787 -43.448585)
			(xy 308.966393 -43.477639) (xy 309.009261 -43.513314) (xy 309.046478 -43.554851) (xy 309.077251 -43.601364)
			(xy 309.100923 -43.651861) (xy 309.115693 -43.700954) (xy 320.56781 -43.700954) (xy 320.571881 -43.645332)
			(xy 320.584007 -43.590895) (xy 320.60393 -43.538804) (xy 320.631226 -43.490169) (xy 320.665312 -43.446026)
			(xy 320.705461 -43.407317) (xy 320.750819 -43.374866) (xy 320.800419 -43.349365) (xy 320.853203 -43.331358)
			(xy 320.908046 -43.321228) (xy 320.96378 -43.319191) (xy 321.019217 -43.325291) (xy 321.073174 -43.339397)
			(xy 321.124503 -43.361209) (xy 321.172109 -43.390263) (xy 321.214977 -43.425938) (xy 321.252194 -43.467475)
			(xy 321.282967 -43.513988) (xy 321.306639 -43.564485) (xy 321.319104 -43.605915) (xy 324.138792 -43.605915)
			(xy 324.138792 -43.541993) (xy 324.146803 -43.478575) (xy 324.1627 -43.416661) (xy 324.186232 -43.357228)
			(xy 324.217026 -43.301213) (xy 324.254599 -43.249498) (xy 324.298356 -43.202901) (xy 324.347609 -43.162156)
			(xy 324.40158 -43.127905) (xy 324.459419 -43.100688) (xy 324.520212 -43.080935) (xy 324.583002 -43.068957)
			(xy 324.646798 -43.064944) (xy 324.710594 -43.068957) (xy 324.773384 -43.080935) (xy 324.834177 -43.100688)
			(xy 324.892016 -43.127905) (xy 324.945987 -43.162156) (xy 324.99524 -43.202901) (xy 325.038997 -43.249498)
			(xy 325.07657 -43.301213) (xy 325.107364 -43.357228) (xy 325.130896 -43.416661) (xy 325.146793 -43.478575)
			(xy 325.154804 -43.541993) (xy 325.155306 -43.573954) (xy 327.80681 -43.573954) (xy 327.810881 -43.518332)
			(xy 327.823007 -43.463895) (xy 327.84293 -43.411804) (xy 327.870226 -43.363169) (xy 327.904312 -43.319026)
			(xy 327.944461 -43.280317) (xy 327.989819 -43.247866) (xy 328.039419 -43.222365) (xy 328.092203 -43.204358)
			(xy 328.147046 -43.194228) (xy 328.20278 -43.192191) (xy 328.258217 -43.198291) (xy 328.312174 -43.212397)
			(xy 328.363503 -43.234209) (xy 328.411109 -43.263263) (xy 328.453977 -43.298938) (xy 328.491194 -43.340475)
			(xy 328.521967 -43.386988) (xy 328.545639 -43.437485) (xy 328.561707 -43.490892) (xy 328.569827 -43.546068)
			(xy 328.570336 -43.573954) (xy 328.569827 -43.60184) (xy 328.569227 -43.605915) (xy 330.093822 -43.605915)
			(xy 330.093822 -43.541993) (xy 330.101833 -43.478575) (xy 330.11773 -43.416661) (xy 330.141262 -43.357228)
			(xy 330.172056 -43.301213) (xy 330.209629 -43.249498) (xy 330.253386 -43.202901) (xy 330.302639 -43.162156)
			(xy 330.35661 -43.127905) (xy 330.414449 -43.100688) (xy 330.475242 -43.080935) (xy 330.538032 -43.068957)
			(xy 330.601828 -43.064944) (xy 330.665624 -43.068957) (xy 330.728414 -43.080935) (xy 330.789207 -43.100688)
			(xy 330.847046 -43.127905) (xy 330.901017 -43.162156) (xy 330.95027 -43.202901) (xy 330.994027 -43.249498)
			(xy 331.0316 -43.301213) (xy 331.062394 -43.357228) (xy 331.085926 -43.416661) (xy 331.101823 -43.478575)
			(xy 331.109834 -43.541993) (xy 331.110336 -43.573954) (xy 331.109834 -43.605915) (xy 331.101823 -43.669333)
			(xy 331.085926 -43.731247) (xy 331.062394 -43.79068) (xy 331.0316 -43.846695) (xy 330.994027 -43.89841)
			(xy 330.95027 -43.945007) (xy 330.901017 -43.985752) (xy 330.847046 -44.020003) (xy 330.789207 -44.04722)
			(xy 330.728414 -44.066973) (xy 330.665624 -44.078951) (xy 330.601828 -44.082965) (xy 330.538032 -44.078951)
			(xy 330.475242 -44.066973) (xy 330.414449 -44.04722) (xy 330.35661 -44.020003) (xy 330.302639 -43.985752)
			(xy 330.253386 -43.945007) (xy 330.209629 -43.89841) (xy 330.172056 -43.846695) (xy 330.141262 -43.79068)
			(xy 330.11773 -43.731247) (xy 330.101833 -43.669333) (xy 330.093822 -43.605915) (xy 328.569227 -43.605915)
			(xy 328.561707 -43.657016) (xy 328.545639 -43.710423) (xy 328.521967 -43.76092) (xy 328.491194 -43.807433)
			(xy 328.453977 -43.84897) (xy 328.411109 -43.884645) (xy 328.363503 -43.913699) (xy 328.312174 -43.935511)
			(xy 328.258217 -43.949617) (xy 328.20278 -43.955717) (xy 328.147046 -43.95368) (xy 328.092203 -43.94355)
			(xy 328.039419 -43.925543) (xy 327.989819 -43.900042) (xy 327.944461 -43.867591) (xy 327.904312 -43.828882)
			(xy 327.870226 -43.784739) (xy 327.84293 -43.736104) (xy 327.823007 -43.684013) (xy 327.810881 -43.629576)
			(xy 327.80681 -43.573954) (xy 325.155306 -43.573954) (xy 325.154804 -43.605915) (xy 325.146793 -43.669333)
			(xy 325.130896 -43.731247) (xy 325.107364 -43.79068) (xy 325.07657 -43.846695) (xy 325.038997 -43.89841)
			(xy 324.99524 -43.945007) (xy 324.945987 -43.985752) (xy 324.892016 -44.020003) (xy 324.834177 -44.04722)
			(xy 324.773384 -44.066973) (xy 324.710594 -44.078951) (xy 324.646798 -44.082965) (xy 324.583002 -44.078951)
			(xy 324.520212 -44.066973) (xy 324.459419 -44.04722) (xy 324.40158 -44.020003) (xy 324.347609 -43.985752)
			(xy 324.298356 -43.945007) (xy 324.254599 -43.89841) (xy 324.217026 -43.846695) (xy 324.186232 -43.79068)
			(xy 324.1627 -43.731247) (xy 324.146803 -43.669333) (xy 324.138792 -43.605915) (xy 321.319104 -43.605915)
			(xy 321.322707 -43.617892) (xy 321.330827 -43.673068) (xy 321.331336 -43.700954) (xy 321.330827 -43.72884)
			(xy 321.322707 -43.784016) (xy 321.306639 -43.837423) (xy 321.282967 -43.88792) (xy 321.252194 -43.934433)
			(xy 321.214977 -43.97597) (xy 321.172109 -44.011645) (xy 321.124503 -44.040699) (xy 321.073174 -44.062511)
			(xy 321.019217 -44.076617) (xy 320.96378 -44.082717) (xy 320.908046 -44.08068) (xy 320.853203 -44.07055)
			(xy 320.800419 -44.052543) (xy 320.750819 -44.027042) (xy 320.705461 -43.994591) (xy 320.665312 -43.955882)
			(xy 320.631226 -43.911739) (xy 320.60393 -43.863104) (xy 320.584007 -43.811013) (xy 320.571881 -43.756576)
			(xy 320.56781 -43.700954) (xy 309.115693 -43.700954) (xy 309.116991 -43.705268) (xy 309.125111 -43.760444)
			(xy 309.12562 -43.78833) (xy 309.125111 -43.816216) (xy 309.116991 -43.871392) (xy 309.100923 -43.924799)
			(xy 309.077251 -43.975296) (xy 309.046478 -44.021809) (xy 309.009261 -44.063346) (xy 308.966393 -44.099021)
			(xy 308.918787 -44.128075) (xy 308.867458 -44.149887) (xy 308.813501 -44.163993) (xy 308.758064 -44.170093)
			(xy 308.70233 -44.168056) (xy 308.647487 -44.157926) (xy 308.594703 -44.139919) (xy 308.545103 -44.114418)
			(xy 308.499745 -44.081967) (xy 308.459596 -44.043258) (xy 308.42551 -43.999115) (xy 308.398214 -43.95048)
			(xy 308.378291 -43.898389) (xy 308.366165 -43.843952) (xy 308.362094 -43.78833) (xy 302.507797 -43.78833)
			(xy 302.517193 -43.802532) (xy 302.540865 -43.853029) (xy 302.556933 -43.906436) (xy 302.565053 -43.961612)
			(xy 302.565562 -43.989498) (xy 302.565053 -44.017384) (xy 302.556933 -44.07256) (xy 302.540865 -44.125967)
			(xy 302.517193 -44.176464) (xy 302.48642 -44.222977) (xy 302.449203 -44.264514) (xy 302.406335 -44.300189)
			(xy 302.358729 -44.329243) (xy 302.3074 -44.351055) (xy 302.253443 -44.365161) (xy 302.198006 -44.371261)
			(xy 302.142272 -44.369224) (xy 302.087429 -44.359094) (xy 302.034645 -44.341087) (xy 301.985045 -44.315586)
			(xy 301.939687 -44.283135) (xy 301.899538 -44.244426) (xy 301.865452 -44.200283) (xy 301.838156 -44.151648)
			(xy 301.818233 -44.099557) (xy 301.806107 -44.04512) (xy 301.802036 -43.989498) (xy 275.0947 -43.989498)
			(xy 275.0947 -45.005498) (xy 301.80864 -45.005498) (xy 301.812711 -44.949876) (xy 301.824837 -44.895439)
			(xy 301.84476 -44.843348) (xy 301.872056 -44.794713) (xy 301.906142 -44.75057) (xy 301.946291 -44.711861)
			(xy 301.991649 -44.67941) (xy 302.041249 -44.653909) (xy 302.094033 -44.635902) (xy 302.148876 -44.625772)
			(xy 302.20461 -44.623735) (xy 302.260047 -44.629835) (xy 302.314004 -44.643941) (xy 302.365333 -44.665753)
			(xy 302.412939 -44.694807) (xy 302.455807 -44.730482) (xy 302.493024 -44.772019) (xy 302.523797 -44.818532)
			(xy 302.547469 -44.869029) (xy 302.563537 -44.922436) (xy 302.571657 -44.977612) (xy 302.572166 -45.005498)
			(xy 302.571657 -45.033384) (xy 302.563537 -45.08856) (xy 302.547469 -45.141967) (xy 302.523797 -45.192464)
			(xy 302.493024 -45.238977) (xy 302.455807 -45.280514) (xy 302.412939 -45.316189) (xy 302.365333 -45.345243)
			(xy 302.314004 -45.367055) (xy 302.260047 -45.381161) (xy 302.20461 -45.387261) (xy 302.148876 -45.385224)
			(xy 302.094033 -45.375094) (xy 302.041249 -45.357087) (xy 301.991649 -45.331586) (xy 301.946291 -45.299135)
			(xy 301.906142 -45.260426) (xy 301.872056 -45.216283) (xy 301.84476 -45.167648) (xy 301.824837 -45.115557)
			(xy 301.812711 -45.06112) (xy 301.80864 -45.005498) (xy 275.0947 -45.005498) (xy 275.0947 -46.021498)
			(xy 304.29454 -46.021498) (xy 304.295042 -45.990016) (xy 304.302815 -45.927533) (xy 304.318244 -45.866488)
			(xy 304.34109 -45.807814) (xy 304.371006 -45.752411) (xy 304.407533 -45.701124) (xy 304.450112 -45.654739)
			(xy 304.498092 -45.613966) (xy 304.524156 -45.596302) (xy 304.534254 -45.588876) (xy 304.546248 -45.566902)
			(xy 304.547016 -45.554392) (xy 304.547524 -45.469556) (xy 304.546942 -45.456975) (xy 304.535229 -45.434718)
			(xy 304.525172 -45.427138) (xy 304.499672 -45.40936) (xy 304.452742 -45.368596) (xy 304.411132 -45.322414)
			(xy 304.375463 -45.271503) (xy 304.346267 -45.216623) (xy 304.323981 -45.158593) (xy 304.308936 -45.098278)
			(xy 304.301357 -45.036579) (xy 304.30089 -45.005498) (xy 304.301392 -44.973537) (xy 304.309403 -44.910119)
			(xy 304.3253 -44.848205) (xy 304.348832 -44.788772) (xy 304.379626 -44.732757) (xy 304.417199 -44.681042)
			(xy 304.460956 -44.634445) (xy 304.510209 -44.5937) (xy 304.56418 -44.559449) (xy 304.622019 -44.532232)
			(xy 304.682812 -44.512479) (xy 304.745602 -44.500501) (xy 304.809398 -44.496488) (xy 304.873194 -44.500501)
			(xy 304.935984 -44.512479) (xy 304.996777 -44.532232) (xy 305.054616 -44.559449) (xy 305.108587 -44.5937)
			(xy 305.15784 -44.634445) (xy 305.201597 -44.681042) (xy 305.23917 -44.732757) (xy 305.245492 -44.744257)
			(xy 320.568709 -44.744257) (xy 320.568709 -44.689743) (xy 320.576468 -44.635783) (xy 320.591827 -44.583476)
			(xy 320.614474 -44.533888) (xy 320.643948 -44.488028) (xy 320.67965 -44.44683) (xy 320.720851 -44.411132)
			(xy 320.766713 -44.381661) (xy 320.816302 -44.359017) (xy 320.86861 -44.343662) (xy 320.922571 -44.335907)
			(xy 320.949828 -44.335446) (xy 320.979579 -44.336065) (xy 321.038354 -44.345336) (xy 321.094983 -44.363603)
			(xy 321.148097 -44.390424) (xy 321.172586 -44.407328) (xy 321.184515 -44.415349) (xy 321.211592 -44.42497)
			(xy 321.240278 -44.426666) (xy 321.2683 -44.420302) (xy 321.29344 -44.406382) (xy 321.313705 -44.386009)
			(xy 321.327492 -44.360797) (xy 321.331082 -44.346876) (xy 321.33831 -44.316476) (xy 321.359297 -44.257617)
			(xy 321.387338 -44.201773) (xy 321.422009 -44.149785) (xy 321.462789 -44.102437) (xy 321.509062 -44.060442)
			(xy 321.560132 -44.024432) (xy 321.615229 -43.994951) (xy 321.673523 -43.972442) (xy 321.734136 -43.957245)
			(xy 321.796154 -43.949589) (xy 321.827398 -43.949112) (xy 321.859362 -43.949553) (xy 321.922785 -43.957565)
			(xy 321.984704 -43.973463) (xy 322.044142 -43.996996) (xy 322.100162 -44.027793) (xy 322.151881 -44.065368)
			(xy 322.198482 -44.10913) (xy 322.239231 -44.158386) (xy 322.273485 -44.212362) (xy 322.300704 -44.270205)
			(xy 322.320459 -44.331004) (xy 322.332437 -44.393799) (xy 322.336452 -44.4576) (xy 322.332437 -44.521401)
			(xy 322.320459 -44.584196) (xy 322.300704 -44.644995) (xy 322.273485 -44.702838) (xy 322.244244 -44.748915)
			(xy 324.138792 -44.748915) (xy 324.138792 -44.684993) (xy 324.146803 -44.621575) (xy 324.1627 -44.559661)
			(xy 324.186232 -44.500228) (xy 324.217026 -44.444213) (xy 324.254599 -44.392498) (xy 324.298356 -44.345901)
			(xy 324.347609 -44.305156) (xy 324.40158 -44.270905) (xy 324.459419 -44.243688) (xy 324.520212 -44.223935)
			(xy 324.583002 -44.211957) (xy 324.646798 -44.207944) (xy 324.710594 -44.211957) (xy 324.773384 -44.223935)
			(xy 324.834177 -44.243688) (xy 324.847807 -44.250102) (xy 342.152238 -44.250102) (xy 342.15619 -44.158309)
			(xy 342.16802 -44.067195) (xy 342.187637 -43.977435) (xy 342.214899 -43.889694) (xy 342.249602 -43.804622)
			(xy 342.29149 -43.722847) (xy 342.340253 -43.644976) (xy 342.395529 -43.571586) (xy 342.45691 -43.503219)
			(xy 342.523941 -43.440381) (xy 342.596125 -43.383539) (xy 342.672929 -43.333112) (xy 342.753783 -43.289474)
			(xy 342.838089 -43.252948) (xy 342.925223 -43.223805) (xy 343.01454 -43.20226) (xy 343.105378 -43.188474)
			(xy 343.197065 -43.182547) (xy 343.288922 -43.184524) (xy 343.38027 -43.19439) (xy 343.47043 -43.212072)
			(xy 343.558738 -43.237439) (xy 343.644537 -43.270304) (xy 343.727194 -43.310423) (xy 343.806096 -43.357499)
			(xy 343.880659 -43.411183) (xy 343.950331 -43.471079) (xy 344.014596 -43.536742) (xy 344.072979 -43.607686)
			(xy 344.125046 -43.683387) (xy 344.170414 -43.763284) (xy 344.208745 -43.846784) (xy 344.239756 -43.933271)
			(xy 344.263217 -44.022104) (xy 344.278956 -44.112624) (xy 344.286854 -44.204163) (xy 344.287348 -44.250102)
			(xy 344.692238 -44.250102) (xy 344.69619 -44.158309) (xy 344.70802 -44.067195) (xy 344.727637 -43.977435)
			(xy 344.754899 -43.889694) (xy 344.789602 -43.804622) (xy 344.83149 -43.722847) (xy 344.880253 -43.644976)
			(xy 344.935529 -43.571586) (xy 344.99691 -43.503219) (xy 345.063941 -43.440381) (xy 345.136125 -43.383539)
			(xy 345.212929 -43.333112) (xy 345.293783 -43.289474) (xy 345.378089 -43.252948) (xy 345.465223 -43.223805)
			(xy 345.55454 -43.20226) (xy 345.645378 -43.188474) (xy 345.737065 -43.182547) (xy 345.828922 -43.184524)
			(xy 345.92027 -43.19439) (xy 346.01043 -43.212072) (xy 346.098738 -43.237439) (xy 346.184537 -43.270304)
			(xy 346.267194 -43.310423) (xy 346.346096 -43.357499) (xy 346.420659 -43.411183) (xy 346.490331 -43.471079)
			(xy 346.554596 -43.536742) (xy 346.612979 -43.607686) (xy 346.665046 -43.683387) (xy 346.710414 -43.763284)
			(xy 346.748745 -43.846784) (xy 346.779756 -43.933271) (xy 346.803217 -44.022104) (xy 346.818956 -44.112624)
			(xy 346.826854 -44.204163) (xy 346.827348 -44.250102) (xy 347.232238 -44.250102) (xy 347.23619 -44.158309)
			(xy 347.24802 -44.067195) (xy 347.267637 -43.977435) (xy 347.294899 -43.889694) (xy 347.329602 -43.804622)
			(xy 347.37149 -43.722847) (xy 347.420253 -43.644976) (xy 347.475529 -43.571586) (xy 347.53691 -43.503219)
			(xy 347.603941 -43.440381) (xy 347.676125 -43.383539) (xy 347.752929 -43.333112) (xy 347.833783 -43.289474)
			(xy 347.918089 -43.252948) (xy 348.005223 -43.223805) (xy 348.09454 -43.20226) (xy 348.185378 -43.188474)
			(xy 348.277065 -43.182547) (xy 348.368922 -43.184524) (xy 348.46027 -43.19439) (xy 348.55043 -43.212072)
			(xy 348.638738 -43.237439) (xy 348.724537 -43.270304) (xy 348.807194 -43.310423) (xy 348.886096 -43.357499)
			(xy 348.960659 -43.411183) (xy 349.030331 -43.471079) (xy 349.094596 -43.536742) (xy 349.152979 -43.607686)
			(xy 349.205046 -43.683387) (xy 349.250414 -43.763284) (xy 349.288745 -43.846784) (xy 349.319756 -43.933271)
			(xy 349.343217 -44.022104) (xy 349.358956 -44.112624) (xy 349.366854 -44.204163) (xy 349.367348 -44.250102)
			(xy 349.772238 -44.250102) (xy 349.77619 -44.158309) (xy 349.78802 -44.067195) (xy 349.807637 -43.977435)
			(xy 349.834899 -43.889694) (xy 349.869602 -43.804622) (xy 349.91149 -43.722847) (xy 349.960253 -43.644976)
			(xy 350.015529 -43.571586) (xy 350.07691 -43.503219) (xy 350.143941 -43.440381) (xy 350.216125 -43.383539)
			(xy 350.292929 -43.333112) (xy 350.373783 -43.289474) (xy 350.458089 -43.252948) (xy 350.545223 -43.223805)
			(xy 350.63454 -43.20226) (xy 350.725378 -43.188474) (xy 350.817065 -43.182547) (xy 350.908922 -43.184524)
			(xy 351.00027 -43.19439) (xy 351.09043 -43.212072) (xy 351.178738 -43.237439) (xy 351.264537 -43.270304)
			(xy 351.347194 -43.310423) (xy 351.426096 -43.357499) (xy 351.500659 -43.411183) (xy 351.570331 -43.471079)
			(xy 351.634596 -43.536742) (xy 351.692979 -43.607686) (xy 351.745046 -43.683387) (xy 351.790414 -43.763284)
			(xy 351.828745 -43.846784) (xy 351.859756 -43.933271) (xy 351.883217 -44.022104) (xy 351.898956 -44.112624)
			(xy 351.906854 -44.204163) (xy 351.907348 -44.250102) (xy 352.312238 -44.250102) (xy 352.31619 -44.158309)
			(xy 352.32802 -44.067195) (xy 352.347637 -43.977435) (xy 352.374899 -43.889694) (xy 352.409602 -43.804622)
			(xy 352.45149 -43.722847) (xy 352.500253 -43.644976) (xy 352.555529 -43.571586) (xy 352.61691 -43.503219)
			(xy 352.683941 -43.440381) (xy 352.756125 -43.383539) (xy 352.832929 -43.333112) (xy 352.913783 -43.289474)
			(xy 352.998089 -43.252948) (xy 353.085223 -43.223805) (xy 353.17454 -43.20226) (xy 353.265378 -43.188474)
			(xy 353.357065 -43.182547) (xy 353.448922 -43.184524) (xy 353.54027 -43.19439) (xy 353.63043 -43.212072)
			(xy 353.718738 -43.237439) (xy 353.804537 -43.270304) (xy 353.887194 -43.310423) (xy 353.966096 -43.357499)
			(xy 354.040659 -43.411183) (xy 354.110331 -43.471079) (xy 354.174596 -43.536742) (xy 354.232979 -43.607686)
			(xy 354.285046 -43.683387) (xy 354.330414 -43.763284) (xy 354.368745 -43.846784) (xy 354.399756 -43.933271)
			(xy 354.423217 -44.022104) (xy 354.438956 -44.112624) (xy 354.446854 -44.204163) (xy 354.447348 -44.250102)
			(xy 354.447224 -44.261632) (xy 365.192372 -44.261632) (xy 365.194978 -44.198599) (xy 365.205361 -44.136373)
			(xy 365.22336 -44.075909) (xy 365.248701 -44.018136) (xy 365.280993 -43.96394) (xy 365.319741 -43.914156)
			(xy 365.36435 -43.869547) (xy 365.414134 -43.830798) (xy 365.468328 -43.798505) (xy 365.526101 -43.773163)
			(xy 365.586565 -43.755162) (xy 365.648791 -43.744779) (xy 365.711824 -43.742172) (xy 365.774695 -43.747382)
			(xy 365.836438 -43.760329) (xy 365.896106 -43.780814) (xy 365.952782 -43.808522) (xy 366.005595 -43.843028)
			(xy 366.053735 -43.883802) (xy 366.096461 -43.930217) (xy 366.133118 -43.981561) (xy 366.163142 -44.037045)
			(xy 366.186073 -44.095816) (xy 366.201558 -44.156973) (xy 366.209359 -44.219575) (xy 366.209834 -44.251118)
			(xy 366.209695 -44.265949) (xy 366.207917 -44.295559) (xy 366.206278 -44.3103) (xy 366.206278 -44.310554)
			(xy 366.205682 -44.319571) (xy 366.210052 -44.337089) (xy 366.220217 -44.352012) (xy 366.22736 -44.357544)
			(xy 366.300258 -44.40936) (xy 366.307905 -44.414257) (xy 366.325453 -44.418871) (xy 366.343508 -44.417079)
			(xy 366.35182 -44.413424) (xy 366.352074 -44.413424) (xy 366.366845 -44.406318) (xy 366.397366 -44.394363)
			(xy 366.413034 -44.389548) (xy 366.421439 -44.38677) (xy 366.435752 -44.376375) (xy 366.440974 -44.369228)
			(xy 366.457992 -44.344082) (xy 366.46269 -44.336366) (xy 366.466847 -44.318797) (xy 366.46612 -44.309792)
			(xy 366.464564 -44.295237) (xy 366.46291 -44.266009) (xy 366.462818 -44.251372) (xy 366.462818 -44.251118)
			(xy 366.46332 -44.219157) (xy 366.471331 -44.155739) (xy 366.487228 -44.093825) (xy 366.51076 -44.034392)
			(xy 366.541554 -43.978377) (xy 366.579127 -43.926662) (xy 366.622884 -43.880065) (xy 366.672137 -43.83932)
			(xy 366.726108 -43.805069) (xy 366.783947 -43.777852) (xy 366.84474 -43.758099) (xy 366.90753 -43.746121)
			(xy 366.971326 -43.742108) (xy 367.035122 -43.746121) (xy 367.097912 -43.758099) (xy 367.158705 -43.777852)
			(xy 367.216544 -43.805069) (xy 367.270515 -43.83932) (xy 367.319768 -43.880065) (xy 367.363525 -43.926662)
			(xy 367.401098 -43.978377) (xy 367.431892 -44.034392) (xy 367.455424 -44.093825) (xy 367.471321 -44.155739)
			(xy 367.479332 -44.219157) (xy 367.479834 -44.2511) (xy 367.732286 -44.2511) (xy 367.7363 -44.187302)
			(xy 367.748279 -44.124509) (xy 367.768034 -44.063714) (xy 367.795252 -44.005874) (xy 367.829506 -43.951901)
			(xy 367.870254 -43.902647) (xy 367.916854 -43.858889) (xy 367.968571 -43.821317) (xy 368.02459 -43.790523)
			(xy 368.084026 -43.766993) (xy 368.145943 -43.751098) (xy 368.209364 -43.743089) (xy 368.241326 -43.74261)
			(xy 368.272844 -43.743103) (xy 368.335398 -43.750875) (xy 368.396512 -43.766322) (xy 368.455247 -43.789206)
			(xy 368.510702 -43.819176) (xy 368.562026 -43.855772) (xy 368.608432 -43.898434) (xy 368.649207 -43.946505)
			(xy 368.683725 -43.999249) (xy 368.698018 -44.027344) (xy 368.704469 -44.03929) (xy 368.72247 -44.059595)
			(xy 368.745185 -44.074441) (xy 368.771007 -44.082781) (xy 368.798114 -44.084025) (xy 368.824591 -44.078085)
			(xy 368.84857 -44.065382) (xy 368.868356 -44.046811) (xy 368.875818 -44.035472) (xy 368.893236 -44.008075)
			(xy 368.933922 -43.957483) (xy 368.980718 -43.912482) (xy 369.032861 -43.873804) (xy 369.089503 -43.842078)
			(xy 369.149723 -43.81782) (xy 369.212541 -43.801426) (xy 369.276935 -43.793161) (xy 369.309396 -43.792648)
			(xy 369.341356 -43.793217) (xy 369.404771 -43.801227) (xy 369.466683 -43.817123) (xy 369.526114 -43.840653)
			(xy 369.582127 -43.871446) (xy 369.633839 -43.909017) (xy 369.680435 -43.952773) (xy 369.721179 -44.002023)
			(xy 369.755429 -44.055992) (xy 369.782644 -44.113828) (xy 369.802397 -44.174619) (xy 369.814374 -44.237407)
			(xy 369.818388 -44.3012) (xy 369.814374 -44.364993) (xy 369.802397 -44.427781) (xy 369.782644 -44.488572)
			(xy 369.755429 -44.546408) (xy 369.721179 -44.600377) (xy 369.680435 -44.649627) (xy 369.633839 -44.693383)
			(xy 369.582127 -44.730954) (xy 369.526114 -44.761747) (xy 369.466683 -44.785277) (xy 369.404771 -44.801173)
			(xy 369.341356 -44.809183) (xy 369.309396 -44.809664) (xy 369.277878 -44.809167) (xy 369.215323 -44.801397)
			(xy 369.154209 -44.785952) (xy 369.095473 -44.76307) (xy 369.040018 -44.7331) (xy 368.988694 -44.696504)
			(xy 368.942288 -44.653842) (xy 368.901514 -44.60577) (xy 368.866996 -44.553025) (xy 368.852704 -44.52493)
			(xy 368.846367 -44.512919) (xy 368.828343 -44.492611) (xy 368.805609 -44.477767) (xy 368.779767 -44.469433)
			(xy 368.752643 -44.468199) (xy 368.726152 -44.474151) (xy 368.702162 -44.486868) (xy 368.682369 -44.505455)
			(xy 368.674904 -44.516802) (xy 368.657497 -44.544206) (xy 368.616807 -44.594795) (xy 368.570008 -44.639793)
			(xy 368.517863 -44.678469) (xy 368.46122 -44.710193) (xy 368.400999 -44.73445) (xy 368.338181 -44.750845)
			(xy 368.273787 -44.759112) (xy 368.241326 -44.759626) (xy 368.209364 -44.759111) (xy 368.145943 -44.751102)
			(xy 368.084026 -44.735207) (xy 368.02459 -44.711677) (xy 367.968571 -44.680883) (xy 367.916854 -44.643311)
			(xy 367.870254 -44.599553) (xy 367.829506 -44.550299) (xy 367.795252 -44.496326) (xy 367.768034 -44.438486)
			(xy 367.748279 -44.377691) (xy 367.7363 -44.314898) (xy 367.732286 -44.2511) (xy 367.479834 -44.2511)
			(xy 367.479834 -44.251118) (xy 367.479362 -44.281839) (xy 367.471956 -44.342832) (xy 367.457256 -44.402489)
			(xy 367.435474 -44.459939) (xy 367.406929 -44.514347) (xy 367.372036 -44.564919) (xy 367.331303 -44.610918)
			(xy 367.285325 -44.651674) (xy 367.234772 -44.686593) (xy 367.180379 -44.715166) (xy 367.122939 -44.736978)
			(xy 367.06329 -44.751709) (xy 367.0023 -44.759146) (xy 366.97158 -44.759626) (xy 366.971072 -44.759626)
			(xy 366.969802 -44.759626) (xy 366.960739 -44.75987) (xy 366.943687 -44.765998) (xy 366.936528 -44.771564)
			(xy 366.91316 -44.791122) (xy 366.90669 -44.797202) (xy 366.897988 -44.812663) (xy 366.896142 -44.821348)
			(xy 366.891181 -44.847573) (xy 366.874751 -44.898355) (xy 366.851407 -44.946354) (xy 366.821605 -44.990634)
			(xy 366.785924 -45.030329) (xy 366.745062 -45.064667) (xy 366.699815 -45.092978) (xy 366.667571 -45.107352)
			(xy 439.130438 -45.107352) (xy 439.134509 -45.05173) (xy 439.146635 -44.997293) (xy 439.166558 -44.945202)
			(xy 439.193854 -44.896567) (xy 439.22794 -44.852424) (xy 439.268089 -44.813715) (xy 439.313447 -44.781264)
			(xy 439.363047 -44.755763) (xy 439.415831 -44.737756) (xy 439.470674 -44.727626) (xy 439.526408 -44.725589)
			(xy 439.581845 -44.731689) (xy 439.635802 -44.745795) (xy 439.687131 -44.767607) (xy 439.734737 -44.796661)
			(xy 439.777605 -44.832336) (xy 439.814822 -44.873873) (xy 439.845595 -44.920386) (xy 439.869267 -44.970883)
			(xy 439.885335 -45.02429) (xy 439.893455 -45.079466) (xy 439.893964 -45.107352) (xy 439.893455 -45.135238)
			(xy 439.885335 -45.190414) (xy 439.869267 -45.243821) (xy 439.845595 -45.294318) (xy 439.814822 -45.340831)
			(xy 439.777605 -45.382368) (xy 439.734737 -45.418043) (xy 439.687131 -45.447097) (xy 439.635802 -45.468909)
			(xy 439.581845 -45.483015) (xy 439.526408 -45.489115) (xy 439.470674 -45.487078) (xy 439.415831 -45.476948)
			(xy 439.363047 -45.458941) (xy 439.313447 -45.43344) (xy 439.268089 -45.400989) (xy 439.22794 -45.36228)
			(xy 439.193854 -45.318137) (xy 439.166558 -45.269502) (xy 439.146635 -45.217411) (xy 439.134509 -45.162974)
			(xy 439.130438 -45.107352) (xy 366.667571 -45.107352) (xy 366.651065 -45.11471) (xy 366.599763 -45.129439)
			(xy 366.546909 -45.136877) (xy 366.520222 -45.137324) (xy 366.493132 -45.13683) (xy 366.439497 -45.129168)
			(xy 366.387486 -45.113995) (xy 366.338144 -45.091616) (xy 366.292465 -45.062481) (xy 366.251367 -45.027177)
			(xy 366.215678 -44.986414) (xy 366.186114 -44.941011) (xy 366.163271 -44.891883) (xy 366.147609 -44.840016)
			(xy 366.139442 -44.786456) (xy 366.138714 -44.759372) (xy 366.138714 -44.745402) (xy 366.124236 -44.72178)
			(xy 366.020604 -44.666662) (xy 365.992918 -44.667932) (xy 365.981234 -44.675552) (xy 365.956254 -44.691534)
			(xy 365.903283 -44.718204) (xy 365.847573 -44.738539) (xy 365.789878 -44.752263) (xy 365.730978 -44.759192)
			(xy 365.701326 -44.759626) (xy 365.669783 -44.75916) (xy 365.60718 -44.75136) (xy 365.546024 -44.735876)
			(xy 365.487252 -44.712946) (xy 365.431768 -44.682922) (xy 365.380423 -44.646266) (xy 365.334008 -44.603541)
			(xy 365.293233 -44.555402) (xy 365.258726 -44.502589) (xy 365.231017 -44.445914) (xy 365.210532 -44.386246)
			(xy 365.197584 -44.324503) (xy 365.192372 -44.261632) (xy 354.447224 -44.261632) (xy 354.446854 -44.296041)
			(xy 354.438956 -44.38758) (xy 354.423217 -44.4781) (xy 354.399756 -44.566933) (xy 354.368745 -44.65342)
			(xy 354.330414 -44.73692) (xy 354.285046 -44.816817) (xy 354.232979 -44.892518) (xy 354.174596 -44.963462)
			(xy 354.110331 -45.029125) (xy 354.040659 -45.089021) (xy 353.966096 -45.142705) (xy 353.887194 -45.189781)
			(xy 353.804537 -45.2299) (xy 353.718738 -45.262765) (xy 353.63043 -45.288132) (xy 353.54027 -45.305814)
			(xy 353.448922 -45.31568) (xy 353.357065 -45.317657) (xy 353.265378 -45.31173) (xy 353.17454 -45.297944)
			(xy 353.085223 -45.276399) (xy 352.998089 -45.247256) (xy 352.913783 -45.21073) (xy 352.832929 -45.167092)
			(xy 352.756125 -45.116665) (xy 352.683941 -45.059823) (xy 352.61691 -44.996985) (xy 352.555529 -44.928618)
			(xy 352.500253 -44.855228) (xy 352.45149 -44.777357) (xy 352.409602 -44.695582) (xy 352.374899 -44.61051)
			(xy 352.347637 -44.522769) (xy 352.32802 -44.433009) (xy 352.31619 -44.341895) (xy 352.312238 -44.250102)
			(xy 351.907348 -44.250102) (xy 351.906854 -44.296041) (xy 351.898956 -44.38758) (xy 351.883217 -44.4781)
			(xy 351.859756 -44.566933) (xy 351.828745 -44.65342) (xy 351.790414 -44.73692) (xy 351.745046 -44.816817)
			(xy 351.692979 -44.892518) (xy 351.634596 -44.963462) (xy 351.570331 -45.029125) (xy 351.500659 -45.089021)
			(xy 351.426096 -45.142705) (xy 351.347194 -45.189781) (xy 351.264537 -45.2299) (xy 351.178738 -45.262765)
			(xy 351.09043 -45.288132) (xy 351.00027 -45.305814) (xy 350.908922 -45.31568) (xy 350.817065 -45.317657)
			(xy 350.725378 -45.31173) (xy 350.63454 -45.297944) (xy 350.545223 -45.276399) (xy 350.458089 -45.247256)
			(xy 350.373783 -45.21073) (xy 350.292929 -45.167092) (xy 350.216125 -45.116665) (xy 350.143941 -45.059823)
			(xy 350.07691 -44.996985) (xy 350.015529 -44.928618) (xy 349.960253 -44.855228) (xy 349.91149 -44.777357)
			(xy 349.869602 -44.695582) (xy 349.834899 -44.61051) (xy 349.807637 -44.522769) (xy 349.78802 -44.433009)
			(xy 349.77619 -44.341895) (xy 349.772238 -44.250102) (xy 349.367348 -44.250102) (xy 349.366854 -44.296041)
			(xy 349.358956 -44.38758) (xy 349.343217 -44.4781) (xy 349.319756 -44.566933) (xy 349.288745 -44.65342)
			(xy 349.250414 -44.73692) (xy 349.205046 -44.816817) (xy 349.152979 -44.892518) (xy 349.094596 -44.963462)
			(xy 349.030331 -45.029125) (xy 348.960659 -45.089021) (xy 348.886096 -45.142705) (xy 348.807194 -45.189781)
			(xy 348.724537 -45.2299) (xy 348.638738 -45.262765) (xy 348.55043 -45.288132) (xy 348.46027 -45.305814)
			(xy 348.368922 -45.31568) (xy 348.277065 -45.317657) (xy 348.185378 -45.31173) (xy 348.09454 -45.297944)
			(xy 348.005223 -45.276399) (xy 347.918089 -45.247256) (xy 347.833783 -45.21073) (xy 347.752929 -45.167092)
			(xy 347.676125 -45.116665) (xy 347.603941 -45.059823) (xy 347.53691 -44.996985) (xy 347.475529 -44.928618)
			(xy 347.420253 -44.855228) (xy 347.37149 -44.777357) (xy 347.329602 -44.695582) (xy 347.294899 -44.61051)
			(xy 347.267637 -44.522769) (xy 347.24802 -44.433009) (xy 347.23619 -44.341895) (xy 347.232238 -44.250102)
			(xy 346.827348 -44.250102) (xy 346.826854 -44.296041) (xy 346.818956 -44.38758) (xy 346.803217 -44.4781)
			(xy 346.779756 -44.566933) (xy 346.748745 -44.65342) (xy 346.710414 -44.73692) (xy 346.665046 -44.816817)
			(xy 346.612979 -44.892518) (xy 346.554596 -44.963462) (xy 346.490331 -45.029125) (xy 346.420659 -45.089021)
			(xy 346.346096 -45.142705) (xy 346.267194 -45.189781) (xy 346.184537 -45.2299) (xy 346.098738 -45.262765)
			(xy 346.01043 -45.288132) (xy 345.92027 -45.305814) (xy 345.828922 -45.31568) (xy 345.737065 -45.317657)
			(xy 345.645378 -45.31173) (xy 345.55454 -45.297944) (xy 345.465223 -45.276399) (xy 345.378089 -45.247256)
			(xy 345.293783 -45.21073) (xy 345.212929 -45.167092) (xy 345.136125 -45.116665) (xy 345.063941 -45.059823)
			(xy 344.99691 -44.996985) (xy 344.935529 -44.928618) (xy 344.880253 -44.855228) (xy 344.83149 -44.777357)
			(xy 344.789602 -44.695582) (xy 344.754899 -44.61051) (xy 344.727637 -44.522769) (xy 344.70802 -44.433009)
			(xy 344.69619 -44.341895) (xy 344.692238 -44.250102) (xy 344.287348 -44.250102) (xy 344.286854 -44.296041)
			(xy 344.278956 -44.38758) (xy 344.263217 -44.4781) (xy 344.239756 -44.566933) (xy 344.208745 -44.65342)
			(xy 344.170414 -44.73692) (xy 344.125046 -44.816817) (xy 344.072979 -44.892518) (xy 344.014596 -44.963462)
			(xy 343.950331 -45.029125) (xy 343.880659 -45.089021) (xy 343.806096 -45.142705) (xy 343.727194 -45.189781)
			(xy 343.644537 -45.2299) (xy 343.558738 -45.262765) (xy 343.47043 -45.288132) (xy 343.38027 -45.305814)
			(xy 343.288922 -45.31568) (xy 343.197065 -45.317657) (xy 343.105378 -45.31173) (xy 343.01454 -45.297944)
			(xy 342.925223 -45.276399) (xy 342.838089 -45.247256) (xy 342.753783 -45.21073) (xy 342.672929 -45.167092)
			(xy 342.596125 -45.116665) (xy 342.523941 -45.059823) (xy 342.45691 -44.996985) (xy 342.395529 -44.928618)
			(xy 342.340253 -44.855228) (xy 342.29149 -44.777357) (xy 342.249602 -44.695582) (xy 342.214899 -44.61051)
			(xy 342.187637 -44.522769) (xy 342.16802 -44.433009) (xy 342.15619 -44.341895) (xy 342.152238 -44.250102)
			(xy 324.847807 -44.250102) (xy 324.892016 -44.270905) (xy 324.945987 -44.305156) (xy 324.99524 -44.345901)
			(xy 325.038997 -44.392498) (xy 325.07657 -44.444213) (xy 325.107364 -44.500228) (xy 325.130896 -44.559661)
			(xy 325.146793 -44.621575) (xy 325.154804 -44.684993) (xy 325.155306 -44.716954) (xy 325.154804 -44.748915)
			(xy 325.146793 -44.812333) (xy 325.130896 -44.874247) (xy 325.107364 -44.93368) (xy 325.07657 -44.989695)
			(xy 325.038997 -45.04141) (xy 324.99524 -45.088007) (xy 324.945987 -45.128752) (xy 324.892016 -45.163003)
			(xy 324.834177 -45.19022) (xy 324.773384 -45.209973) (xy 324.710594 -45.221951) (xy 324.646798 -45.225965)
			(xy 324.583002 -45.221951) (xy 324.520212 -45.209973) (xy 324.459419 -45.19022) (xy 324.40158 -45.163003)
			(xy 324.347609 -45.128752) (xy 324.298356 -45.088007) (xy 324.254599 -45.04141) (xy 324.217026 -44.989695)
			(xy 324.186232 -44.93368) (xy 324.1627 -44.874247) (xy 324.146803 -44.812333) (xy 324.138792 -44.748915)
			(xy 322.244244 -44.748915) (xy 322.239231 -44.756814) (xy 322.198482 -44.80607) (xy 322.151881 -44.849832)
			(xy 322.100162 -44.887407) (xy 322.044142 -44.918204) (xy 321.984704 -44.941737) (xy 321.922785 -44.957635)
			(xy 321.859362 -44.965647) (xy 321.827398 -44.966128) (xy 321.794479 -44.965613) (xy 321.729193 -44.957105)
			(xy 321.665551 -44.940244) (xy 321.604617 -44.915312) (xy 321.547408 -44.882726) (xy 321.494883 -44.843031)
			(xy 321.471036 -44.820332) (xy 321.460467 -44.81058) (xy 321.435179 -44.796912) (xy 321.407082 -44.790842)
			(xy 321.378407 -44.79285) (xy 321.35143 -44.802777) (xy 321.328294 -44.819836) (xy 321.310834 -44.842671)
			(xy 321.305174 -44.855892) (xy 321.294265 -44.882316) (xy 321.265734 -44.931852) (xy 321.230132 -44.976577)
			(xy 321.188257 -45.015491) (xy 321.141046 -45.047722) (xy 321.089554 -45.07255) (xy 321.034935 -45.089419)
			(xy 320.97841 -45.097951) (xy 320.949828 -45.098462) (xy 320.922571 -45.098093) (xy 320.86861 -45.090338)
			(xy 320.816302 -45.074983) (xy 320.766713 -45.052339) (xy 320.720851 -45.022868) (xy 320.67965 -44.98717)
			(xy 320.643948 -44.945972) (xy 320.614474 -44.900112) (xy 320.591827 -44.850524) (xy 320.576468 -44.798217)
			(xy 320.568709 -44.744257) (xy 305.245492 -44.744257) (xy 305.269964 -44.788772) (xy 305.293496 -44.848205)
			(xy 305.309393 -44.910119) (xy 305.317404 -44.973537) (xy 305.317906 -45.005498) (xy 305.317425 -45.036981)
			(xy 305.309651 -45.099466) (xy 305.294222 -45.160512) (xy 305.271373 -45.219187) (xy 305.241454 -45.274591)
			(xy 305.204924 -45.325877) (xy 305.162341 -45.372261) (xy 305.114357 -45.413032) (xy 305.08829 -45.430694)
			(xy 305.078184 -45.43811) (xy 305.066196 -45.460092) (xy 305.06543 -45.472604) (xy 305.064922 -45.55744)
			(xy 305.065488 -45.570024) (xy 305.077211 -45.592282) (xy 305.087274 -45.599858) (xy 305.112782 -45.617624)
			(xy 305.159711 -45.658391) (xy 305.201319 -45.704576) (xy 305.236986 -45.755489) (xy 305.26618 -45.81037)
			(xy 305.288466 -45.868402) (xy 305.293169 -45.887257) (xy 320.568709 -45.887257) (xy 320.568709 -45.832743)
			(xy 320.576468 -45.778783) (xy 320.591827 -45.726476) (xy 320.614474 -45.676888) (xy 320.643948 -45.631028)
			(xy 320.67965 -45.58983) (xy 320.720851 -45.554132) (xy 320.766713 -45.524661) (xy 320.816302 -45.502017)
			(xy 320.86861 -45.486662) (xy 320.922571 -45.478907) (xy 320.949828 -45.478446) (xy 320.976665 -45.478894)
			(xy 321.029808 -45.486426) (xy 321.08137 -45.501336) (xy 321.130331 -45.523331) (xy 321.175723 -45.551976)
			(xy 321.216649 -45.586704) (xy 321.234816 -45.606462) (xy 321.234816 -45.606716) (xy 321.243203 -45.615179)
			(xy 321.265328 -45.62393) (xy 321.277234 -45.62348) (xy 321.370198 -45.615352) (xy 321.390518 -45.60316)
			(xy 321.396868 -45.593) (xy 321.41433 -45.566054) (xy 321.455056 -45.516409) (xy 321.501709 -45.472288)
			(xy 321.553549 -45.434395) (xy 321.609748 -45.403332) (xy 321.669411 -45.379595) (xy 321.731589 -45.363561)
			(xy 321.795292 -45.355486) (xy 321.827398 -45.355002) (xy 321.859361 -45.355463) (xy 321.922783 -45.363475)
			(xy 321.984701 -45.379372) (xy 322.044138 -45.402905) (xy 322.100157 -45.433701) (xy 322.151874 -45.471276)
			(xy 322.198475 -45.515036) (xy 322.239223 -45.564292) (xy 322.273476 -45.618267) (xy 322.300695 -45.676109)
			(xy 322.320449 -45.736906) (xy 322.332428 -45.7997) (xy 322.336442 -45.8635) (xy 322.334431 -45.895471)
			(xy 324.138792 -45.895471) (xy 324.138792 -45.831549) (xy 324.146803 -45.768131) (xy 324.1627 -45.706217)
			(xy 324.186232 -45.646784) (xy 324.217026 -45.590769) (xy 324.254599 -45.539054) (xy 324.298356 -45.492457)
			(xy 324.347609 -45.451712) (xy 324.40158 -45.417461) (xy 324.459419 -45.390244) (xy 324.520212 -45.370491)
			(xy 324.583002 -45.358513) (xy 324.646798 -45.3545) (xy 324.710594 -45.358513) (xy 324.773384 -45.370491)
			(xy 324.834177 -45.390244) (xy 324.892016 -45.417461) (xy 324.945987 -45.451712) (xy 324.99524 -45.492457)
			(xy 325.038997 -45.539054) (xy 325.07657 -45.590769) (xy 325.107364 -45.646784) (xy 325.129762 -45.703352)
			(xy 444.201536 -45.703352) (xy 444.201536 -45.648848) (xy 444.209292 -45.594899) (xy 444.224646 -45.542602)
			(xy 444.247286 -45.493023) (xy 444.276751 -45.44717) (xy 444.312441 -45.405976) (xy 444.35363 -45.370281)
			(xy 444.399479 -45.34081) (xy 444.449055 -45.318164) (xy 444.50135 -45.302802) (xy 444.555298 -45.295039)
			(xy 444.58255 -45.29455) (xy 444.610259 -45.29505) (xy 444.665093 -45.303079) (xy 444.718187 -45.31896)
			(xy 444.768423 -45.342359) (xy 444.814744 -45.372783) (xy 444.835788 -45.390816) (xy 444.842918 -45.396634)
			(xy 444.86012 -45.403135) (xy 444.869316 -45.403516) (xy 444.946786 -45.403516) (xy 444.963804 -45.397166)
			(xy 444.970916 -45.390816) (xy 444.991947 -45.372766) (xy 445.038268 -45.342337) (xy 445.088507 -45.318938)
			(xy 445.141605 -45.303062) (xy 445.196443 -45.295043) (xy 445.224154 -45.29455) (xy 445.251406 -45.295094)
			(xy 445.305356 -45.302845) (xy 445.357654 -45.318195) (xy 445.407234 -45.340833) (xy 445.453088 -45.370296)
			(xy 445.494282 -45.405986) (xy 445.529976 -45.447175) (xy 445.559445 -45.493026) (xy 445.582089 -45.542603)
			(xy 445.597445 -45.594899) (xy 445.605203 -45.648848) (xy 445.605203 -45.703352) (xy 445.602902 -45.719354)
			(xy 445.994738 -45.719354) (xy 445.994738 -45.664846) (xy 446.002495 -45.610894) (xy 446.017851 -45.558594)
			(xy 446.040494 -45.509013) (xy 446.069962 -45.463158) (xy 446.105657 -45.421964) (xy 446.14685 -45.386268)
			(xy 446.192704 -45.356799) (xy 446.242285 -45.334155) (xy 446.294584 -45.318797) (xy 446.348536 -45.311039)
			(xy 446.37579 -45.310552) (xy 446.403498 -45.311087) (xy 446.45833 -45.319108) (xy 446.511424 -45.33498)
			(xy 446.561661 -45.358372) (xy 446.607983 -45.388788) (xy 446.629028 -45.406818) (xy 446.636176 -45.412611)
			(xy 446.653364 -45.419127) (xy 446.662556 -45.419518) (xy 446.740026 -45.419518) (xy 446.757044 -45.413168)
			(xy 446.764156 -45.406818) (xy 446.78521 -45.388796) (xy 446.831525 -45.358364) (xy 446.881758 -45.334959)
			(xy 446.934851 -45.319076) (xy 446.989685 -45.31105) (xy 447.017394 -45.310552) (xy 447.044644 -45.311095)
			(xy 447.09859 -45.31885) (xy 447.150883 -45.334204) (xy 447.200459 -45.356844) (xy 447.246308 -45.386309)
			(xy 447.287497 -45.421999) (xy 447.323188 -45.463187) (xy 447.352653 -45.509036) (xy 447.375294 -45.558611)
			(xy 447.390648 -45.610904) (xy 447.398405 -45.66485) (xy 447.398405 -45.71935) (xy 447.398404 -45.719354)
			(xy 447.772738 -45.719354) (xy 447.772738 -45.664846) (xy 447.780495 -45.610894) (xy 447.795851 -45.558594)
			(xy 447.818494 -45.509013) (xy 447.847962 -45.463158) (xy 447.883657 -45.421964) (xy 447.92485 -45.386268)
			(xy 447.970704 -45.356799) (xy 448.020285 -45.334155) (xy 448.072584 -45.318797) (xy 448.126536 -45.311039)
			(xy 448.15379 -45.310552) (xy 448.181498 -45.311087) (xy 448.23633 -45.319108) (xy 448.289424 -45.33498)
			(xy 448.339661 -45.358372) (xy 448.385983 -45.388788) (xy 448.407028 -45.406818) (xy 448.414176 -45.412611)
			(xy 448.431364 -45.419127) (xy 448.440556 -45.419518) (xy 448.518026 -45.419518) (xy 448.535044 -45.413168)
			(xy 448.542156 -45.406818) (xy 448.56321 -45.388796) (xy 448.609525 -45.358364) (xy 448.659758 -45.334959)
			(xy 448.712851 -45.319076) (xy 448.767685 -45.31105) (xy 448.795394 -45.310552) (xy 448.822644 -45.311095)
			(xy 448.87659 -45.31885) (xy 448.928883 -45.334204) (xy 448.978459 -45.356844) (xy 449.024308 -45.386309)
			(xy 449.065497 -45.421999) (xy 449.101188 -45.463187) (xy 449.130653 -45.509036) (xy 449.153294 -45.558611)
			(xy 449.168648 -45.610904) (xy 449.176405 -45.66485) (xy 449.176405 -45.71935) (xy 449.176404 -45.719354)
			(xy 449.550738 -45.719354) (xy 449.550738 -45.664846) (xy 449.558495 -45.610894) (xy 449.573851 -45.558594)
			(xy 449.596494 -45.509013) (xy 449.625962 -45.463158) (xy 449.661657 -45.421964) (xy 449.70285 -45.386268)
			(xy 449.748704 -45.356799) (xy 449.798285 -45.334155) (xy 449.850584 -45.318797) (xy 449.904536 -45.311039)
			(xy 449.93179 -45.310552) (xy 449.959498 -45.311087) (xy 450.01433 -45.319108) (xy 450.067424 -45.33498)
			(xy 450.117661 -45.358372) (xy 450.163983 -45.388788) (xy 450.185028 -45.406818) (xy 450.192176 -45.412611)
			(xy 450.209364 -45.419127) (xy 450.218556 -45.419518) (xy 450.296026 -45.419518) (xy 450.313044 -45.413168)
			(xy 450.320156 -45.406818) (xy 450.34121 -45.388796) (xy 450.387525 -45.358364) (xy 450.437758 -45.334959)
			(xy 450.490851 -45.319076) (xy 450.545685 -45.31105) (xy 450.573394 -45.310552) (xy 450.573648 -45.310552)
			(xy 450.600809 -45.311047) (xy 450.654579 -45.318772) (xy 450.706714 -45.334033) (xy 450.731636 -45.344842)
			(xy 450.741034 -45.34916) (xy 450.762116 -45.349668) (xy 450.849492 -45.314362) (xy 450.864224 -45.299884)
			(xy 450.868034 -45.290232) (xy 450.881034 -45.259193) (xy 450.914029 -45.200543) (xy 450.954472 -45.146758)
			(xy 451.001657 -45.098777) (xy 451.054759 -45.057441) (xy 451.11285 -45.02347) (xy 451.174914 -44.99746)
			(xy 451.239866 -44.979863) (xy 451.306573 -44.970989) (xy 451.34022 -44.970446) (xy 451.372177 -44.971041)
			(xy 451.435588 -44.979054) (xy 451.497494 -44.994951) (xy 451.55692 -45.018481) (xy 451.612928 -45.049274)
			(xy 451.664635 -45.086843) (xy 451.711226 -45.130597) (xy 451.751966 -45.179845) (xy 451.78575 -45.233082)
			(xy 454.229976 -45.233082) (xy 454.234047 -45.17746) (xy 454.246173 -45.123023) (xy 454.266096 -45.070932)
			(xy 454.293392 -45.022297) (xy 454.327478 -44.978154) (xy 454.367627 -44.939445) (xy 454.412985 -44.906994)
			(xy 454.462585 -44.881493) (xy 454.515369 -44.863486) (xy 454.570212 -44.853356) (xy 454.625946 -44.851319)
			(xy 454.681383 -44.857419) (xy 454.73534 -44.871525) (xy 454.786669 -44.893337) (xy 454.834275 -44.922391)
			(xy 454.877143 -44.958066) (xy 454.91436 -44.999603) (xy 454.925341 -45.0162) (xy 456.450638 -45.0162)
			(xy 456.454668 -44.931593) (xy 456.466723 -44.847753) (xy 456.486693 -44.765438) (xy 456.514396 -44.685394)
			(xy 456.549584 -44.608346) (xy 456.591935 -44.534991) (xy 456.641068 -44.465995) (xy 456.696537 -44.401981)
			(xy 456.75784 -44.34353) (xy 456.824421 -44.291171) (xy 456.895678 -44.245378) (xy 456.970965 -44.206566)
			(xy 457.049601 -44.175087) (xy 457.130873 -44.151224) (xy 457.214045 -44.135195) (xy 457.298365 -44.127145)
			(xy 457.340716 -44.126658) (xy 457.381812 -44.12712) (xy 457.463652 -44.134713) (xy 457.544443 -44.149823)
			(xy 457.623495 -44.172321) (xy 457.700135 -44.202016) (xy 457.773709 -44.238654) (xy 457.843589 -44.281923)
			(xy 457.90918 -44.331453) (xy 457.969922 -44.386824) (xy 458.025297 -44.447561) (xy 458.074834 -44.513147)
			(xy 458.118109 -44.583024) (xy 458.154753 -44.656595) (xy 458.184454 -44.733232) (xy 458.206959 -44.812283)
			(xy 458.214984 -44.85259) (xy 458.244194 -44.851574) (xy 458.271446 -44.852073) (xy 458.325395 -44.859829)
			(xy 458.377691 -44.875184) (xy 458.42727 -44.897825) (xy 458.473121 -44.927291) (xy 458.514313 -44.962983)
			(xy 458.550005 -45.004174) (xy 458.579472 -45.050025) (xy 458.602114 -45.099603) (xy 458.61747 -45.151899)
			(xy 458.625227 -45.205848) (xy 458.625227 -45.233082) (xy 458.777086 -45.233082) (xy 458.777631 -45.204166)
			(xy 458.78635 -45.146994) (xy 458.8036 -45.091795) (xy 458.828987 -45.039832) (xy 458.861927 -44.992298)
			(xy 458.901667 -44.950282) (xy 458.924152 -44.932092) (xy 458.932962 -44.924488) (xy 458.943142 -44.903585)
			(xy 458.94371 -44.89196) (xy 458.94371 -44.812204) (xy 458.943151 -44.800575) (xy 458.932976 -44.779665)
			(xy 458.924152 -44.772072) (xy 458.901645 -44.753909) (xy 458.861914 -44.711882) (xy 458.828979 -44.664341)
			(xy 458.803595 -44.612374) (xy 458.786343 -44.557172) (xy 458.777619 -44.499999) (xy 458.777086 -44.471082)
			(xy 458.777572 -44.443831) (xy 458.785328 -44.389883) (xy 458.800683 -44.337588) (xy 458.823325 -44.288011)
			(xy 458.852791 -44.242161) (xy 458.888482 -44.20097) (xy 458.929673 -44.165279) (xy 458.975523 -44.135813)
			(xy 459.0251 -44.113171) (xy 459.077395 -44.097816) (xy 459.131343 -44.09006) (xy 459.185845 -44.09006)
			(xy 459.239793 -44.097816) (xy 459.292088 -44.113171) (xy 459.341665 -44.135813) (xy 459.387515 -44.165279)
			(xy 459.428706 -44.20097) (xy 459.464397 -44.242161) (xy 459.493863 -44.288011) (xy 459.516505 -44.337588)
			(xy 459.53186 -44.389883) (xy 459.539616 -44.443831) (xy 459.540102 -44.471082) (xy 459.53957 -44.499998)
			(xy 459.53298 -44.543175) (xy 461.474306 -44.543175) (xy 461.474306 -44.479253) (xy 461.482317 -44.415835)
			(xy 461.498214 -44.353921) (xy 461.521746 -44.294488) (xy 461.55254 -44.238473) (xy 461.590113 -44.186758)
			(xy 461.63387 -44.140161) (xy 461.683123 -44.099416) (xy 461.737094 -44.065165) (xy 461.794933 -44.037948)
			(xy 461.855726 -44.018195) (xy 461.918516 -44.006217) (xy 461.982312 -44.002204) (xy 462.046108 -44.006217)
			(xy 462.108898 -44.018195) (xy 462.169691 -44.037948) (xy 462.22753 -44.065165) (xy 462.281501 -44.099416)
			(xy 462.330754 -44.140161) (xy 462.374511 -44.186758) (xy 462.412084 -44.238473) (xy 462.442878 -44.294488)
			(xy 462.46641 -44.353921) (xy 462.482307 -44.415835) (xy 462.490318 -44.479253) (xy 462.49082 -44.511214)
			(xy 462.490318 -44.543175) (xy 462.482307 -44.606593) (xy 462.46641 -44.668507) (xy 462.442878 -44.72794)
			(xy 462.412084 -44.783955) (xy 462.374511 -44.83567) (xy 462.330754 -44.882267) (xy 462.281501 -44.923012)
			(xy 462.22753 -44.957263) (xy 462.169691 -44.98448) (xy 462.108898 -45.004233) (xy 462.046108 -45.016211)
			(xy 461.982312 -45.020225) (xy 461.918516 -45.016211) (xy 461.855726 -45.004233) (xy 461.794933 -44.98448)
			(xy 461.737094 -44.957263) (xy 461.683123 -44.923012) (xy 461.63387 -44.882267) (xy 461.590113 -44.83567)
			(xy 461.55254 -44.783955) (xy 461.521746 -44.72794) (xy 461.498214 -44.668507) (xy 461.482317 -44.606593)
			(xy 461.474306 -44.543175) (xy 459.53298 -44.543175) (xy 459.530844 -44.557169) (xy 459.513588 -44.612367)
			(xy 459.488199 -44.664329) (xy 459.455258 -44.711863) (xy 459.41552 -44.753881) (xy 459.393036 -44.772072)
			(xy 459.384241 -44.77969) (xy 459.374053 -44.800583) (xy 459.373478 -44.812204) (xy 459.373478 -44.89196)
			(xy 459.374004 -44.903593) (xy 459.384203 -44.924502) (xy 459.393036 -44.932092) (xy 459.415523 -44.950278)
			(xy 459.455256 -44.9923) (xy 459.488194 -45.039836) (xy 459.513581 -45.091798) (xy 459.530837 -45.146996)
			(xy 459.539567 -45.204166) (xy 459.540102 -45.233082) (xy 459.539616 -45.260333) (xy 459.53186 -45.314281)
			(xy 459.516505 -45.366576) (xy 459.493863 -45.416153) (xy 459.464397 -45.462003) (xy 459.428706 -45.503194)
			(xy 459.387515 -45.538885) (xy 459.341665 -45.568351) (xy 459.292088 -45.590993) (xy 459.239793 -45.606348)
			(xy 459.185845 -45.614104) (xy 459.131343 -45.614104) (xy 459.077395 -45.606348) (xy 459.0251 -45.590993)
			(xy 458.975523 -45.568351) (xy 458.929673 -45.538885) (xy 458.888482 -45.503194) (xy 458.852791 -45.462003)
			(xy 458.823325 -45.416153) (xy 458.800683 -45.366576) (xy 458.785328 -45.314281) (xy 458.777572 -45.260333)
			(xy 458.777086 -45.233082) (xy 458.625227 -45.233082) (xy 458.625227 -45.260352) (xy 458.61747 -45.314301)
			(xy 458.602114 -45.366597) (xy 458.579472 -45.416175) (xy 458.550005 -45.462026) (xy 458.514313 -45.503217)
			(xy 458.473121 -45.538909) (xy 458.42727 -45.568375) (xy 458.377691 -45.591016) (xy 458.325395 -45.606371)
			(xy 458.271446 -45.614127) (xy 458.244194 -45.61459) (xy 458.215954 -45.614059) (xy 458.160094 -45.605698)
			(xy 458.106079 -45.589191) (xy 458.080364 -45.577506) (xy 458.070034 -45.57329) (xy 458.047751 -45.573205)
			(xy 458.027528 -45.582562) (xy 458.019912 -45.590714) (xy 457.991813 -45.623188) (xy 457.930289 -45.683108)
			(xy 457.863273 -45.736816) (xy 457.791391 -45.783812) (xy 457.715312 -45.823658) (xy 457.635746 -45.855981)
			(xy 457.553433 -45.880482) (xy 457.469142 -45.896931) (xy 457.383657 -45.905175) (xy 457.340716 -45.905674)
			(xy 457.298365 -45.905255) (xy 457.214045 -45.897205) (xy 457.130873 -45.881176) (xy 457.049601 -45.857313)
			(xy 456.970965 -45.825834) (xy 456.895678 -45.787022) (xy 456.824421 -45.741229) (xy 456.75784 -45.68887)
			(xy 456.696537 -45.630419) (xy 456.641068 -45.566405) (xy 456.591935 -45.497409) (xy 456.549584 -45.424054)
			(xy 456.514396 -45.347006) (xy 456.486693 -45.266962) (xy 456.466723 -45.184647) (xy 456.454668 -45.100807)
			(xy 456.450638 -45.0162) (xy 454.925341 -45.0162) (xy 454.945133 -45.046116) (xy 454.968805 -45.096613)
			(xy 454.984873 -45.15002) (xy 454.992993 -45.205196) (xy 454.993502 -45.233082) (xy 454.992993 -45.260968)
			(xy 454.984873 -45.316144) (xy 454.968805 -45.369551) (xy 454.945133 -45.420048) (xy 454.91436 -45.466561)
			(xy 454.877143 -45.508098) (xy 454.834275 -45.543773) (xy 454.786669 -45.572827) (xy 454.73534 -45.594639)
			(xy 454.681383 -45.608745) (xy 454.625946 -45.614845) (xy 454.570212 -45.612808) (xy 454.515369 -45.602678)
			(xy 454.462585 -45.584671) (xy 454.412985 -45.55917) (xy 454.367627 -45.526719) (xy 454.327478 -45.48801)
			(xy 454.293392 -45.443867) (xy 454.266096 -45.395232) (xy 454.246173 -45.343141) (xy 454.234047 -45.288704)
			(xy 454.229976 -45.233082) (xy 451.78575 -45.233082) (xy 451.786212 -45.23381) (xy 451.813425 -45.291642)
			(xy 451.833175 -45.352429) (xy 451.845151 -45.415211) (xy 451.849165 -45.479) (xy 451.845151 -45.542789)
			(xy 451.833175 -45.605571) (xy 451.813425 -45.666358) (xy 451.786212 -45.72419) (xy 451.751966 -45.778155)
			(xy 451.711226 -45.827403) (xy 451.664635 -45.871157) (xy 451.612928 -45.908726) (xy 451.61209 -45.909187)
			(xy 461.079844 -45.909187) (xy 461.079844 -45.845265) (xy 461.087855 -45.781847) (xy 461.103752 -45.719933)
			(xy 461.127284 -45.6605) (xy 461.158078 -45.604485) (xy 461.195651 -45.55277) (xy 461.239408 -45.506173)
			(xy 461.288661 -45.465428) (xy 461.342632 -45.431177) (xy 461.400471 -45.40396) (xy 461.461264 -45.384207)
			(xy 461.524054 -45.372229) (xy 461.58785 -45.368216) (xy 461.651646 -45.372229) (xy 461.714436 -45.384207)
			(xy 461.775229 -45.40396) (xy 461.833068 -45.431177) (xy 461.887039 -45.465428) (xy 461.936292 -45.506173)
			(xy 461.980049 -45.55277) (xy 462.017622 -45.604485) (xy 462.048416 -45.6605) (xy 462.071948 -45.719933)
			(xy 462.087845 -45.781847) (xy 462.095856 -45.845265) (xy 462.096358 -45.877226) (xy 462.095856 -45.909187)
			(xy 462.087845 -45.972605) (xy 462.071948 -46.034519) (xy 462.048416 -46.093952) (xy 462.017622 -46.149967)
			(xy 461.980049 -46.201682) (xy 461.936292 -46.248279) (xy 461.887039 -46.289024) (xy 461.833068 -46.323275)
			(xy 461.775229 -46.350492) (xy 461.714436 -46.370245) (xy 461.651646 -46.382223) (xy 461.58785 -46.386237)
			(xy 461.524054 -46.382223) (xy 461.461264 -46.370245) (xy 461.400471 -46.350492) (xy 461.342632 -46.323275)
			(xy 461.288661 -46.289024) (xy 461.239408 -46.248279) (xy 461.195651 -46.201682) (xy 461.158078 -46.149967)
			(xy 461.127284 -46.093952) (xy 461.103752 -46.034519) (xy 461.087855 -45.972605) (xy 461.079844 -45.909187)
			(xy 451.61209 -45.909187) (xy 451.55692 -45.939519) (xy 451.497494 -45.963049) (xy 451.435588 -45.978946)
			(xy 451.372177 -45.986959) (xy 451.34022 -45.987462) (xy 451.30724 -45.986933) (xy 451.241834 -45.978412)
			(xy 451.178077 -45.961508) (xy 451.117039 -45.936507) (xy 451.059745 -45.903826) (xy 451.033134 -45.884338)
			(xy 451.024752 -45.877988) (xy 451.00494 -45.872908) (xy 450.911214 -45.888148) (xy 450.893942 -45.89907)
			(xy 450.8881 -45.907706) (xy 450.872777 -45.929265) (xy 450.837142 -45.968349) (xy 450.79645 -46.002136)
			(xy 450.75148 -46.029977) (xy 450.703095 -46.051339) (xy 450.652223 -46.065812) (xy 450.599839 -46.073118)
			(xy 450.573394 -46.073568) (xy 450.545686 -46.073037) (xy 450.490854 -46.065015) (xy 450.43776 -46.049141)
			(xy 450.387523 -46.025749) (xy 450.341201 -45.995332) (xy 450.320156 -45.977302) (xy 450.313011 -45.971504)
			(xy 450.29582 -45.96499) (xy 450.286628 -45.964602) (xy 450.209158 -45.964602) (xy 450.19214 -45.970952)
			(xy 450.185028 -45.977302) (xy 450.163983 -45.995334) (xy 450.117666 -46.025765) (xy 450.06743 -46.049167)
			(xy 450.014335 -46.065047) (xy 449.9595 -46.073072) (xy 449.93179 -46.073568) (xy 449.904536 -46.073161)
			(xy 449.850584 -46.065403) (xy 449.798285 -46.050045) (xy 449.748704 -46.027401) (xy 449.70285 -45.997932)
			(xy 449.661657 -45.962236) (xy 449.625962 -45.921042) (xy 449.596494 -45.875187) (xy 449.573851 -45.825606)
			(xy 449.558495 -45.773306) (xy 449.550738 -45.719354) (xy 449.176404 -45.719354) (xy 449.168648 -45.773296)
			(xy 449.153294 -45.825589) (xy 449.130653 -45.875164) (xy 449.101188 -45.921013) (xy 449.065497 -45.962201)
			(xy 449.024308 -45.997891) (xy 448.978459 -46.027356) (xy 448.928883 -46.049996) (xy 448.87659 -46.06535)
			(xy 448.822644 -46.073105) (xy 448.795394 -46.073568) (xy 448.767686 -46.073037) (xy 448.712854 -46.065015)
			(xy 448.65976 -46.049141) (xy 448.609523 -46.025749) (xy 448.563201 -45.995332) (xy 448.542156 -45.977302)
			(xy 448.535011 -45.971504) (xy 448.51782 -45.96499) (xy 448.508628 -45.964602) (xy 448.431158 -45.964602)
			(xy 448.41414 -45.970952) (xy 448.407028 -45.977302) (xy 448.385983 -45.995334) (xy 448.339666 -46.025765)
			(xy 448.28943 -46.049167) (xy 448.236335 -46.065047) (xy 448.1815 -46.073072) (xy 448.15379 -46.073568)
			(xy 448.126536 -46.073161) (xy 448.072584 -46.065403) (xy 448.020285 -46.050045) (xy 447.970704 -46.027401)
			(xy 447.92485 -45.997932) (xy 447.883657 -45.962236) (xy 447.847962 -45.921042) (xy 447.818494 -45.875187)
			(xy 447.795851 -45.825606) (xy 447.780495 -45.773306) (xy 447.772738 -45.719354) (xy 447.398404 -45.719354)
			(xy 447.390648 -45.773296) (xy 447.375294 -45.825589) (xy 447.352653 -45.875164) (xy 447.323188 -45.921013)
			(xy 447.287497 -45.962201) (xy 447.246308 -45.997891) (xy 447.200459 -46.027356) (xy 447.150883 -46.049996)
			(xy 447.09859 -46.06535) (xy 447.044644 -46.073105) (xy 447.017394 -46.073568) (xy 446.989686 -46.073037)
			(xy 446.934854 -46.065015) (xy 446.88176 -46.049141) (xy 446.831523 -46.025749) (xy 446.785201 -45.995332)
			(xy 446.764156 -45.977302) (xy 446.757011 -45.971504) (xy 446.73982 -45.96499) (xy 446.730628 -45.964602)
			(xy 446.653158 -45.964602) (xy 446.63614 -45.970952) (xy 446.629028 -45.977302) (xy 446.607983 -45.995334)
			(xy 446.561666 -46.025765) (xy 446.51143 -46.049167) (xy 446.458335 -46.065047) (xy 446.4035 -46.073072)
			(xy 446.37579 -46.073568) (xy 446.348536 -46.073161) (xy 446.294584 -46.065403) (xy 446.242285 -46.050045)
			(xy 446.192704 -46.027401) (xy 446.14685 -45.997932) (xy 446.105657 -45.962236) (xy 446.069962 -45.921042)
			(xy 446.040494 -45.875187) (xy 446.017851 -45.825606) (xy 446.002495 -45.773306) (xy 445.994738 -45.719354)
			(xy 445.602902 -45.719354) (xy 445.597445 -45.757301) (xy 445.582089 -45.809597) (xy 445.559445 -45.859174)
			(xy 445.529976 -45.905025) (xy 445.494282 -45.946214) (xy 445.453088 -45.981904) (xy 445.407234 -46.011367)
			(xy 445.357654 -46.034005) (xy 445.305356 -46.049355) (xy 445.251406 -46.057106) (xy 445.224154 -46.057566)
			(xy 445.196445 -46.057059) (xy 445.141612 -46.049031) (xy 445.088518 -46.033152) (xy 445.038282 -46.009754)
			(xy 444.991961 -45.979332) (xy 444.970916 -45.9613) (xy 444.963784 -45.955485) (xy 444.946583 -45.948981)
			(xy 444.937388 -45.9486) (xy 444.859918 -45.9486) (xy 444.8429 -45.95495) (xy 444.835788 -45.9613)
			(xy 444.814758 -45.979351) (xy 444.768437 -46.009779) (xy 444.718197 -46.033177) (xy 444.665099 -46.049053)
			(xy 444.610261 -46.057072) (xy 444.58255 -46.057566) (xy 444.555298 -46.057161) (xy 444.50135 -46.049398)
			(xy 444.449055 -46.034036) (xy 444.399479 -46.01139) (xy 444.35363 -45.981919) (xy 444.312441 -45.946224)
			(xy 444.276751 -45.90503) (xy 444.247286 -45.859177) (xy 444.224646 -45.809598) (xy 444.209292 -45.757301)
			(xy 444.201536 -45.703352) (xy 325.129762 -45.703352) (xy 325.130896 -45.706217) (xy 325.146793 -45.768131)
			(xy 325.154804 -45.831549) (xy 325.155306 -45.86351) (xy 325.154804 -45.895471) (xy 325.146793 -45.958889)
			(xy 325.130896 -46.020803) (xy 325.107364 -46.080236) (xy 325.07657 -46.136251) (xy 325.038997 -46.187966)
			(xy 324.99524 -46.234563) (xy 324.945987 -46.275308) (xy 324.892016 -46.309559) (xy 324.834177 -46.336776)
			(xy 324.773384 -46.356529) (xy 324.710594 -46.368507) (xy 324.646798 -46.372521) (xy 324.583002 -46.368507)
			(xy 324.520212 -46.356529) (xy 324.459419 -46.336776) (xy 324.40158 -46.309559) (xy 324.347609 -46.275308)
			(xy 324.298356 -46.234563) (xy 324.254599 -46.187966) (xy 324.217026 -46.136251) (xy 324.186232 -46.080236)
			(xy 324.1627 -46.020803) (xy 324.146803 -45.958889) (xy 324.138792 -45.895471) (xy 322.334431 -45.895471)
			(xy 322.332428 -45.9273) (xy 322.320449 -45.990094) (xy 322.300695 -46.050891) (xy 322.273476 -46.108733)
			(xy 322.239223 -46.162708) (xy 322.198475 -46.211964) (xy 322.151874 -46.255724) (xy 322.100157 -46.293299)
			(xy 322.044138 -46.324095) (xy 321.984701 -46.347628) (xy 321.922783 -46.363525) (xy 321.859361 -46.371537)
			(xy 321.827398 -46.372018) (xy 321.795026 -46.371569) (xy 321.730806 -46.36335) (xy 321.668148 -46.347045)
			(xy 321.608068 -46.322919) (xy 321.551536 -46.291361) (xy 321.499467 -46.252882) (xy 321.452704 -46.208104)
			(xy 321.412003 -46.157753) (xy 321.394582 -46.130464) (xy 321.388486 -46.120304) (xy 321.367912 -46.107604)
			(xy 321.26301 -46.098206) (xy 321.240912 -46.106842) (xy 321.232784 -46.115732) (xy 321.214613 -46.135137)
			(xy 321.173849 -46.16926) (xy 321.12874 -46.197389) (xy 321.080161 -46.218978) (xy 321.029053 -46.23361)
			(xy 320.976408 -46.240999) (xy 320.949828 -46.241462) (xy 320.922571 -46.241093) (xy 320.86861 -46.233338)
			(xy 320.816302 -46.217983) (xy 320.766713 -46.195339) (xy 320.720851 -46.165868) (xy 320.67965 -46.13017)
			(xy 320.643948 -46.088972) (xy 320.614474 -46.043112) (xy 320.591827 -45.993524) (xy 320.576468 -45.941217)
			(xy 320.568709 -45.887257) (xy 305.293169 -45.887257) (xy 305.30351 -45.928717) (xy 305.311089 -45.990416)
			(xy 305.311556 -46.021498) (xy 305.311054 -46.053459) (xy 305.303043 -46.116877) (xy 305.287146 -46.178791)
			(xy 305.263614 -46.238224) (xy 305.23282 -46.294239) (xy 305.195247 -46.345954) (xy 305.15149 -46.392551)
			(xy 305.102237 -46.433296) (xy 305.048266 -46.467547) (xy 304.990427 -46.494764) (xy 304.929634 -46.514517)
			(xy 304.866844 -46.526495) (xy 304.803048 -46.530509) (xy 304.739252 -46.526495) (xy 304.676462 -46.514517)
			(xy 304.615669 -46.494764) (xy 304.55783 -46.467547) (xy 304.503859 -46.433296) (xy 304.454606 -46.392551)
			(xy 304.410849 -46.345954) (xy 304.373276 -46.294239) (xy 304.342482 -46.238224) (xy 304.31895 -46.178791)
			(xy 304.303053 -46.116877) (xy 304.295042 -46.053459) (xy 304.29454 -46.021498) (xy 275.0947 -46.021498)
			(xy 275.0947 -47.037498) (xy 304.42103 -47.037498) (xy 304.425101 -46.981876) (xy 304.437227 -46.927439)
			(xy 304.45715 -46.875348) (xy 304.484446 -46.826713) (xy 304.518532 -46.78257) (xy 304.558681 -46.743861)
			(xy 304.604039 -46.71141) (xy 304.653639 -46.685909) (xy 304.706423 -46.667902) (xy 304.761266 -46.657772)
			(xy 304.817 -46.655735) (xy 304.872437 -46.661835) (xy 304.926394 -46.675941) (xy 304.977723 -46.697753)
			(xy 305.025329 -46.726807) (xy 305.068197 -46.762482) (xy 305.105414 -46.804019) (xy 305.136187 -46.850532)
			(xy 305.159859 -46.901029) (xy 305.175927 -46.954436) (xy 305.183067 -47.002954) (xy 320.56781 -47.002954)
			(xy 320.571881 -46.947332) (xy 320.584007 -46.892895) (xy 320.60393 -46.840804) (xy 320.631226 -46.792169)
			(xy 320.665312 -46.748026) (xy 320.705461 -46.709317) (xy 320.750819 -46.676866) (xy 320.800419 -46.651365)
			(xy 320.853203 -46.633358) (xy 320.908046 -46.623228) (xy 320.96378 -46.621191) (xy 321.019217 -46.627291)
			(xy 321.073174 -46.641397) (xy 321.124503 -46.663209) (xy 321.172109 -46.692263) (xy 321.214977 -46.727938)
			(xy 321.252194 -46.769475) (xy 321.282967 -46.815988) (xy 321.306639 -46.866485) (xy 321.322707 -46.919892)
			(xy 321.330827 -46.975068) (xy 321.331336 -47.002954) (xy 321.331049 -47.018659) (xy 324.138792 -47.018659)
			(xy 324.138792 -46.954737) (xy 324.146803 -46.891319) (xy 324.1627 -46.829405) (xy 324.186232 -46.769972)
			(xy 324.217026 -46.713957) (xy 324.254599 -46.662242) (xy 324.298356 -46.615645) (xy 324.347609 -46.5749)
			(xy 324.40158 -46.540649) (xy 324.459419 -46.513432) (xy 324.520212 -46.493679) (xy 324.583002 -46.481701)
			(xy 324.646798 -46.477688) (xy 324.710594 -46.481701) (xy 324.773384 -46.493679) (xy 324.834177 -46.513432)
			(xy 324.892016 -46.540649) (xy 324.945987 -46.5749) (xy 324.99524 -46.615645) (xy 325.038997 -46.662242)
			(xy 325.07657 -46.713957) (xy 325.095809 -46.748954) (xy 327.80681 -46.748954) (xy 327.810881 -46.693332)
			(xy 327.823007 -46.638895) (xy 327.84293 -46.586804) (xy 327.870226 -46.538169) (xy 327.904312 -46.494026)
			(xy 327.944461 -46.455317) (xy 327.989819 -46.422866) (xy 328.039419 -46.397365) (xy 328.092203 -46.379358)
			(xy 328.147046 -46.369228) (xy 328.20278 -46.367191) (xy 328.258217 -46.373291) (xy 328.312174 -46.387397)
			(xy 328.363503 -46.409209) (xy 328.411109 -46.438263) (xy 328.453977 -46.473938) (xy 328.491194 -46.515475)
			(xy 328.521967 -46.561988) (xy 328.545639 -46.612485) (xy 328.561707 -46.665892) (xy 328.569827 -46.721068)
			(xy 328.570336 -46.748954) (xy 328.569827 -46.77684) (xy 328.567699 -46.791302) (xy 329.712824 -46.791302)
			(xy 329.712824 -46.706606) (xy 329.720875 -46.622292) (xy 329.736904 -46.539126) (xy 329.760765 -46.457859)
			(xy 329.792244 -46.379229) (xy 329.831055 -46.303948) (xy 329.876845 -46.232696) (xy 329.929201 -46.16612)
			(xy 329.987649 -46.104822) (xy 330.051659 -46.049357) (xy 330.120651 -46.000228) (xy 330.194001 -45.957879)
			(xy 330.271044 -45.922695) (xy 330.351083 -45.894993) (xy 330.433392 -45.875025) (xy 330.517227 -45.862972)
			(xy 330.601828 -45.858942) (xy 330.686429 -45.862972) (xy 330.770264 -45.875025) (xy 330.852573 -45.894993)
			(xy 330.932612 -45.922695) (xy 331.009655 -45.957879) (xy 331.083005 -46.000228) (xy 331.151997 -46.049357)
			(xy 331.216007 -46.104822) (xy 331.274455 -46.16612) (xy 331.326811 -46.232696) (xy 331.372601 -46.303948)
			(xy 331.37834 -46.315079) (xy 365.19332 -46.315079) (xy 365.19332 -46.251157) (xy 365.201331 -46.187739)
			(xy 365.217228 -46.125825) (xy 365.24076 -46.066392) (xy 365.271554 -46.010377) (xy 365.309127 -45.958662)
			(xy 365.352884 -45.912065) (xy 365.402137 -45.87132) (xy 365.456108 -45.837069) (xy 365.513947 -45.809852)
			(xy 365.57474 -45.790099) (xy 365.63753 -45.778121) (xy 365.701326 -45.774108) (xy 365.765122 -45.778121)
			(xy 365.827912 -45.790099) (xy 365.888705 -45.809852) (xy 365.946544 -45.837069) (xy 366.000515 -45.87132)
			(xy 366.049768 -45.912065) (xy 366.093525 -45.958662) (xy 366.131098 -46.010377) (xy 366.161892 -46.066392)
			(xy 366.185424 -46.125825) (xy 366.201321 -46.187739) (xy 366.209332 -46.251157) (xy 366.209834 -46.283118)
			(xy 366.209332 -46.315079) (xy 367.73332 -46.315079) (xy 367.73332 -46.251157) (xy 367.741331 -46.187739)
			(xy 367.757228 -46.125825) (xy 367.78076 -46.066392) (xy 367.811554 -46.010377) (xy 367.849127 -45.958662)
			(xy 367.892884 -45.912065) (xy 367.942137 -45.87132) (xy 367.996108 -45.837069) (xy 368.053947 -45.809852)
			(xy 368.11474 -45.790099) (xy 368.17753 -45.778121) (xy 368.241326 -45.774108) (xy 368.305122 -45.778121)
			(xy 368.367912 -45.790099) (xy 368.428705 -45.809852) (xy 368.486544 -45.837069) (xy 368.540515 -45.87132)
			(xy 368.589768 -45.912065) (xy 368.633525 -45.958662) (xy 368.671098 -46.010377) (xy 368.701892 -46.066392)
			(xy 368.725424 -46.125825) (xy 368.741321 -46.187739) (xy 368.749332 -46.251157) (xy 368.749834 -46.283118)
			(xy 368.749332 -46.315079) (xy 368.741321 -46.378497) (xy 368.725424 -46.440411) (xy 368.701892 -46.499844)
			(xy 368.687149 -46.526661) (xy 409.707074 -46.526661) (xy 409.707074 -46.462739) (xy 409.715085 -46.399321)
			(xy 409.730982 -46.337407) (xy 409.754514 -46.277974) (xy 409.785308 -46.221959) (xy 409.822881 -46.170244)
			(xy 409.866638 -46.123647) (xy 409.915891 -46.082902) (xy 409.969862 -46.048651) (xy 410.027701 -46.021434)
			(xy 410.088494 -46.001681) (xy 410.151284 -45.989703) (xy 410.21508 -45.98569) (xy 410.278876 -45.989703)
			(xy 410.341666 -46.001681) (xy 410.402459 -46.021434) (xy 410.460298 -46.048651) (xy 410.514269 -46.082902)
			(xy 410.563522 -46.123647) (xy 410.607279 -46.170244) (xy 410.644852 -46.221959) (xy 410.675646 -46.277974)
			(xy 410.699178 -46.337407) (xy 410.715075 -46.399321) (xy 410.723086 -46.462739) (xy 410.723588 -46.4947)
			(xy 410.723086 -46.526661) (xy 410.715075 -46.590079) (xy 410.699178 -46.651993) (xy 410.687036 -46.68266)
			(xy 451.356982 -46.68266) (xy 451.361053 -46.627038) (xy 451.373179 -46.572601) (xy 451.393102 -46.52051)
			(xy 451.420398 -46.471875) (xy 451.454484 -46.427732) (xy 451.494633 -46.389023) (xy 451.539991 -46.356572)
			(xy 451.589591 -46.331071) (xy 451.642375 -46.313064) (xy 451.697218 -46.302934) (xy 451.752952 -46.300897)
			(xy 451.808389 -46.306997) (xy 451.862346 -46.321103) (xy 451.913675 -46.342915) (xy 451.961281 -46.371969)
			(xy 452.004149 -46.407644) (xy 452.041366 -46.449181) (xy 452.072139 -46.495694) (xy 452.095811 -46.546191)
			(xy 452.111879 -46.599598) (xy 452.119999 -46.654774) (xy 452.120508 -46.68266) (xy 452.119999 -46.710546)
			(xy 452.111879 -46.765722) (xy 452.095811 -46.819129) (xy 452.072139 -46.869626) (xy 452.041366 -46.916139)
			(xy 452.004149 -46.957676) (xy 451.961281 -46.993351) (xy 451.913675 -47.022405) (xy 451.862346 -47.044217)
			(xy 451.808389 -47.058323) (xy 451.752952 -47.064423) (xy 451.697218 -47.062386) (xy 451.642375 -47.052256)
			(xy 451.589591 -47.034249) (xy 451.539991 -47.008748) (xy 451.494633 -46.976297) (xy 451.454484 -46.937588)
			(xy 451.420398 -46.893445) (xy 451.393102 -46.84481) (xy 451.373179 -46.792719) (xy 451.361053 -46.738282)
			(xy 451.356982 -46.68266) (xy 410.687036 -46.68266) (xy 410.675646 -46.711426) (xy 410.644852 -46.767441)
			(xy 410.607279 -46.819156) (xy 410.563522 -46.865753) (xy 410.514269 -46.906498) (xy 410.460298 -46.940749)
			(xy 410.402459 -46.967966) (xy 410.341666 -46.987719) (xy 410.278876 -46.999697) (xy 410.21508 -47.003711)
			(xy 410.151284 -46.999697) (xy 410.088494 -46.987719) (xy 410.027701 -46.967966) (xy 409.969862 -46.940749)
			(xy 409.915891 -46.906498) (xy 409.866638 -46.865753) (xy 409.822881 -46.819156) (xy 409.785308 -46.767441)
			(xy 409.754514 -46.711426) (xy 409.730982 -46.651993) (xy 409.715085 -46.590079) (xy 409.707074 -46.526661)
			(xy 368.687149 -46.526661) (xy 368.671098 -46.555859) (xy 368.633525 -46.607574) (xy 368.589768 -46.654171)
			(xy 368.540515 -46.694916) (xy 368.486544 -46.729167) (xy 368.428705 -46.756384) (xy 368.367912 -46.776137)
			(xy 368.305122 -46.788115) (xy 368.241326 -46.792129) (xy 368.17753 -46.788115) (xy 368.11474 -46.776137)
			(xy 368.053947 -46.756384) (xy 367.996108 -46.729167) (xy 367.942137 -46.694916) (xy 367.892884 -46.654171)
			(xy 367.849127 -46.607574) (xy 367.811554 -46.555859) (xy 367.78076 -46.499844) (xy 367.757228 -46.440411)
			(xy 367.741331 -46.378497) (xy 367.73332 -46.315079) (xy 366.209332 -46.315079) (xy 366.201321 -46.378497)
			(xy 366.185424 -46.440411) (xy 366.161892 -46.499844) (xy 366.131098 -46.555859) (xy 366.093525 -46.607574)
			(xy 366.049768 -46.654171) (xy 366.000515 -46.694916) (xy 365.946544 -46.729167) (xy 365.888705 -46.756384)
			(xy 365.827912 -46.776137) (xy 365.765122 -46.788115) (xy 365.701326 -46.792129) (xy 365.63753 -46.788115)
			(xy 365.57474 -46.776137) (xy 365.513947 -46.756384) (xy 365.456108 -46.729167) (xy 365.402137 -46.694916)
			(xy 365.352884 -46.654171) (xy 365.309127 -46.607574) (xy 365.271554 -46.555859) (xy 365.24076 -46.499844)
			(xy 365.217228 -46.440411) (xy 365.201331 -46.378497) (xy 365.19332 -46.315079) (xy 331.37834 -46.315079)
			(xy 331.411412 -46.379229) (xy 331.442891 -46.457859) (xy 331.466752 -46.539126) (xy 331.482781 -46.622292)
			(xy 331.490832 -46.706606) (xy 331.491336 -46.748954) (xy 331.490832 -46.791302) (xy 331.482781 -46.875616)
			(xy 331.466752 -46.958782) (xy 331.442891 -47.040049) (xy 331.411412 -47.118679) (xy 331.372601 -47.19396)
			(xy 331.331792 -47.257462) (xy 452.605396 -47.257462) (xy 452.60944 -47.179008) (xy 452.621529 -47.101386)
			(xy 452.641536 -47.025418) (xy 452.669247 -46.95191) (xy 452.70437 -46.881641) (xy 452.746532 -46.815356)
			(xy 452.795286 -46.753757) (xy 452.850115 -46.697497) (xy 452.910438 -46.647173) (xy 452.975616 -46.603319)
			(xy 453.044957 -46.566398) (xy 453.117728 -46.536803) (xy 453.193155 -46.514848) (xy 453.27044 -46.500764)
			(xy 453.348764 -46.494701) (xy 453.427296 -46.496724) (xy 453.505204 -46.50681) (xy 453.581661 -46.524854)
			(xy 453.655859 -46.550664) (xy 453.727009 -46.583966) (xy 453.794358 -46.624407) (xy 453.857192 -46.671558)
			(xy 453.914844 -46.724921) (xy 453.966704 -46.783928) (xy 454.012223 -46.847955) (xy 454.050916 -46.916323)
			(xy 454.082375 -46.988307) (xy 454.106266 -47.063144) (xy 454.122335 -47.140041) (xy 454.130412 -47.218183)
			(xy 454.130801 -47.248351) (xy 455.604595 -47.248351) (xy 455.604595 -47.193849) (xy 455.612352 -47.139901)
			(xy 455.627708 -47.087607) (xy 455.65035 -47.03803) (xy 455.679817 -46.992181) (xy 455.71551 -46.950992)
			(xy 455.756701 -46.915302) (xy 455.802553 -46.885837) (xy 455.852131 -46.863199) (xy 455.904427 -46.847847)
			(xy 455.958375 -46.840093) (xy 455.985626 -46.839632) (xy 456.013546 -46.840075) (xy 456.06879 -46.848219)
			(xy 456.122256 -46.864328) (xy 456.172803 -46.88806) (xy 456.219351 -46.918906) (xy 456.260905 -46.956207)
			(xy 456.296578 -46.999168) (xy 456.311508 -47.022766) (xy 456.316832 -47.030757) (xy 456.332103 -47.042375)
			(xy 456.341226 -47.045372) (xy 456.417426 -47.066708) (xy 456.436476 -47.064676) (xy 456.445112 -47.060104)
			(xy 456.47235 -47.046662) (xy 456.530033 -47.027643) (xy 456.590003 -47.018017) (xy 456.620372 -47.017432)
			(xy 456.620626 -47.017432) (xy 456.647879 -47.01784) (xy 456.701829 -47.0256) (xy 456.754127 -47.040959)
			(xy 456.803706 -47.063604) (xy 456.849558 -47.093074) (xy 456.890749 -47.128769) (xy 456.926442 -47.169963)
			(xy 456.955909 -47.215817) (xy 456.97855 -47.265398) (xy 456.993906 -47.317696) (xy 457.001662 -47.371647)
			(xy 457.001662 -47.426153) (xy 456.99451 -47.4759) (xy 457.343791 -47.4759) (xy 457.347805 -47.412106)
			(xy 457.359782 -47.349318) (xy 457.379534 -47.288526) (xy 457.406749 -47.230689) (xy 457.440999 -47.176719)
			(xy 457.481742 -47.127467) (xy 457.528337 -47.083709) (xy 457.580049 -47.046137) (xy 457.636062 -47.015341)
			(xy 457.695492 -46.991809) (xy 457.757404 -46.975911) (xy 457.82082 -46.967897) (xy 457.85278 -46.967394)
			(xy 457.886769 -46.967913) (xy 457.95414 -46.976972) (xy 458.019703 -46.994931) (xy 458.082286 -47.021468)
			(xy 458.140774 -47.056111) (xy 458.194121 -47.098242) (xy 458.241377 -47.147107) (xy 458.261974 -47.17415)
			(xy 458.269694 -47.183444) (xy 458.291306 -47.194175) (xy 458.303376 -47.194724) (xy 458.38618 -47.193708)
			(xy 458.398251 -47.192933) (xy 458.419603 -47.181634) (xy 458.427074 -47.172118) (xy 458.444936 -47.147394)
			(xy 458.485662 -47.101985) (xy 458.53153 -47.061776) (xy 458.581879 -47.027345) (xy 458.635987 -46.999186)
			(xy 458.693075 -46.977705) (xy 458.752324 -46.963209) (xy 458.812882 -46.955908) (xy 458.84338 -46.955456)
			(xy 458.875341 -46.956008) (xy 458.938759 -46.964017) (xy 459.000673 -46.979912) (xy 459.060107 -47.003441)
			(xy 459.116123 -47.034234) (xy 459.167837 -47.071805) (xy 459.214435 -47.115562) (xy 459.255181 -47.164813)
			(xy 459.289433 -47.218784) (xy 459.31665 -47.276622) (xy 459.336404 -47.337415) (xy 459.348382 -47.400204)
			(xy 459.352396 -47.464) (xy 459.348382 -47.527796) (xy 459.336404 -47.590585) (xy 459.31665 -47.651378)
			(xy 459.289433 -47.709216) (xy 459.255181 -47.763187) (xy 459.214435 -47.812438) (xy 459.167837 -47.856195)
			(xy 459.116123 -47.893766) (xy 459.060107 -47.924559) (xy 459.000673 -47.948088) (xy 458.938759 -47.963983)
			(xy 458.875341 -47.971992) (xy 458.84338 -47.972472) (xy 458.809392 -47.971922) (xy 458.742022 -47.96287)
			(xy 458.676459 -47.944918) (xy 458.613875 -47.918386) (xy 458.555387 -47.883747) (xy 458.502039 -47.84162)
			(xy 458.454783 -47.792757) (xy 458.434186 -47.765716) (xy 458.426444 -47.756444) (xy 458.404849 -47.745702)
			(xy 458.392784 -47.745142) (xy 458.30998 -47.746158) (xy 458.297917 -47.746981) (xy 458.276564 -47.758247)
			(xy 458.269086 -47.767748) (xy 458.251238 -47.792483) (xy 458.210511 -47.837893) (xy 458.164642 -47.878102)
			(xy 458.114291 -47.912533) (xy 458.060181 -47.940691) (xy 458.00309 -47.96217) (xy 457.943839 -47.976663)
			(xy 457.883279 -47.983961) (xy 457.85278 -47.98441) (xy 457.82082 -47.983903) (xy 457.757404 -47.975889)
			(xy 457.695492 -47.959991) (xy 457.636062 -47.936459) (xy 457.580049 -47.905663) (xy 457.528337 -47.868091)
			(xy 457.481742 -47.824333) (xy 457.440999 -47.775081) (xy 457.406749 -47.721111) (xy 457.379534 -47.663274)
			(xy 457.359782 -47.602482) (xy 457.347805 -47.539694) (xy 457.343791 -47.4759) (xy 456.99451 -47.4759)
			(xy 456.993906 -47.480104) (xy 456.97855 -47.532402) (xy 456.955909 -47.581983) (xy 456.926442 -47.627837)
			(xy 456.890749 -47.669031) (xy 456.849558 -47.704726) (xy 456.803706 -47.734196) (xy 456.754127 -47.756841)
			(xy 456.701829 -47.7722) (xy 456.647879 -47.77996) (xy 456.620626 -47.780448) (xy 456.592707 -47.779974)
			(xy 456.537464 -47.771837) (xy 456.483998 -47.755734) (xy 456.433451 -47.732008) (xy 456.386903 -47.701166)
			(xy 456.345348 -47.663868) (xy 456.309674 -47.620911) (xy 456.294744 -47.597314) (xy 456.289443 -47.589305)
			(xy 456.274155 -47.577697) (xy 456.265026 -47.574708) (xy 456.188826 -47.553372) (xy 456.169776 -47.555404)
			(xy 456.16114 -47.559976) (xy 456.133893 -47.573399) (xy 456.076214 -47.592425) (xy 456.016248 -47.602059)
			(xy 455.98588 -47.602648) (xy 455.985626 -47.602648) (xy 455.958375 -47.602107) (xy 455.904427 -47.594353)
			(xy 455.852131 -47.579001) (xy 455.802553 -47.556363) (xy 455.756701 -47.526898) (xy 455.71551 -47.491208)
			(xy 455.679817 -47.450019) (xy 455.65035 -47.40417) (xy 455.627708 -47.354593) (xy 455.612352 -47.302299)
			(xy 455.604595 -47.248351) (xy 454.130801 -47.248351) (xy 454.130918 -47.257462) (xy 454.130412 -47.296741)
			(xy 454.122335 -47.374883) (xy 454.106266 -47.45178) (xy 454.082375 -47.526617) (xy 454.050916 -47.598601)
			(xy 454.012223 -47.666969) (xy 453.966704 -47.730996) (xy 453.914844 -47.790003) (xy 453.857192 -47.843366)
			(xy 453.794358 -47.890517) (xy 453.727009 -47.930958) (xy 453.655859 -47.96426) (xy 453.581661 -47.99007)
			(xy 453.505204 -48.008114) (xy 453.427296 -48.0182) (xy 453.348764 -48.020223) (xy 453.27044 -48.01416)
			(xy 453.193155 -48.000076) (xy 453.117728 -47.978121) (xy 453.044957 -47.948526) (xy 452.975616 -47.911605)
			(xy 452.910438 -47.867751) (xy 452.850115 -47.817427) (xy 452.795286 -47.761167) (xy 452.746532 -47.699568)
			(xy 452.70437 -47.633283) (xy 452.669247 -47.563014) (xy 452.641536 -47.489506) (xy 452.621529 -47.413538)
			(xy 452.60944 -47.335916) (xy 452.605396 -47.257462) (xy 331.331792 -47.257462) (xy 331.326811 -47.265212)
			(xy 331.274455 -47.331788) (xy 331.216007 -47.393086) (xy 331.151997 -47.448551) (xy 331.083005 -47.49768)
			(xy 331.009655 -47.540029) (xy 330.932612 -47.575213) (xy 330.852573 -47.602915) (xy 330.770264 -47.622883)
			(xy 330.686429 -47.634936) (xy 330.601828 -47.638967) (xy 330.517227 -47.634936) (xy 330.433392 -47.622883)
			(xy 330.351083 -47.602915) (xy 330.271044 -47.575213) (xy 330.194001 -47.540029) (xy 330.120651 -47.49768)
			(xy 330.051659 -47.448551) (xy 329.987649 -47.393086) (xy 329.929201 -47.331788) (xy 329.876845 -47.265212)
			(xy 329.831055 -47.19396) (xy 329.792244 -47.118679) (xy 329.760765 -47.040049) (xy 329.736904 -46.958782)
			(xy 329.720875 -46.875616) (xy 329.712824 -46.791302) (xy 328.567699 -46.791302) (xy 328.561707 -46.832016)
			(xy 328.545639 -46.885423) (xy 328.521967 -46.93592) (xy 328.491194 -46.982433) (xy 328.453977 -47.02397)
			(xy 328.411109 -47.059645) (xy 328.363503 -47.088699) (xy 328.312174 -47.110511) (xy 328.258217 -47.124617)
			(xy 328.20278 -47.130717) (xy 328.147046 -47.12868) (xy 328.092203 -47.11855) (xy 328.039419 -47.100543)
			(xy 327.989819 -47.075042) (xy 327.944461 -47.042591) (xy 327.904312 -47.003882) (xy 327.870226 -46.959739)
			(xy 327.84293 -46.911104) (xy 327.823007 -46.859013) (xy 327.810881 -46.804576) (xy 327.80681 -46.748954)
			(xy 325.095809 -46.748954) (xy 325.107364 -46.769972) (xy 325.130896 -46.829405) (xy 325.146793 -46.891319)
			(xy 325.154804 -46.954737) (xy 325.155306 -46.986698) (xy 325.154804 -47.018659) (xy 325.146793 -47.082077)
			(xy 325.130896 -47.143991) (xy 325.107364 -47.203424) (xy 325.07657 -47.259439) (xy 325.038997 -47.311154)
			(xy 324.99524 -47.357751) (xy 324.945987 -47.398496) (xy 324.892016 -47.432747) (xy 324.834177 -47.459964)
			(xy 324.773384 -47.479717) (xy 324.710594 -47.491695) (xy 324.646798 -47.495709) (xy 324.583002 -47.491695)
			(xy 324.520212 -47.479717) (xy 324.459419 -47.459964) (xy 324.40158 -47.432747) (xy 324.347609 -47.398496)
			(xy 324.298356 -47.357751) (xy 324.254599 -47.311154) (xy 324.217026 -47.259439) (xy 324.186232 -47.203424)
			(xy 324.1627 -47.143991) (xy 324.146803 -47.082077) (xy 324.138792 -47.018659) (xy 321.331049 -47.018659)
			(xy 321.330827 -47.03084) (xy 321.322707 -47.086016) (xy 321.306639 -47.139423) (xy 321.282967 -47.18992)
			(xy 321.252194 -47.236433) (xy 321.214977 -47.27797) (xy 321.172109 -47.313645) (xy 321.124503 -47.342699)
			(xy 321.073174 -47.364511) (xy 321.019217 -47.378617) (xy 320.96378 -47.384717) (xy 320.908046 -47.38268)
			(xy 320.853203 -47.37255) (xy 320.800419 -47.354543) (xy 320.750819 -47.329042) (xy 320.705461 -47.296591)
			(xy 320.665312 -47.257882) (xy 320.631226 -47.213739) (xy 320.60393 -47.165104) (xy 320.584007 -47.113013)
			(xy 320.571881 -47.058576) (xy 320.56781 -47.002954) (xy 305.183067 -47.002954) (xy 305.184047 -47.009612)
			(xy 305.184556 -47.037498) (xy 305.184047 -47.065384) (xy 305.175927 -47.12056) (xy 305.159859 -47.173967)
			(xy 305.136187 -47.224464) (xy 305.105414 -47.270977) (xy 305.068197 -47.312514) (xy 305.025329 -47.348189)
			(xy 304.977723 -47.377243) (xy 304.926394 -47.399055) (xy 304.872437 -47.413161) (xy 304.817 -47.419261)
			(xy 304.761266 -47.417224) (xy 304.706423 -47.407094) (xy 304.653639 -47.389087) (xy 304.604039 -47.363586)
			(xy 304.558681 -47.331135) (xy 304.518532 -47.292426) (xy 304.484446 -47.248283) (xy 304.45715 -47.199648)
			(xy 304.437227 -47.147557) (xy 304.425101 -47.09312) (xy 304.42103 -47.037498) (xy 275.0947 -47.037498)
			(xy 275.0947 -49.3065) (xy 449.338969 -49.3065) (xy 449.342983 -49.242704) (xy 449.35496 -49.179914)
			(xy 449.374713 -49.11912) (xy 449.401929 -49.061281) (xy 449.436179 -49.007309) (xy 449.476923 -48.958055)
			(xy 449.523519 -48.914296) (xy 449.575232 -48.876722) (xy 449.631246 -48.845925) (xy 449.690678 -48.822391)
			(xy 449.752591 -48.806491) (xy 449.816009 -48.798476) (xy 449.84797 -48.797972) (xy 449.879036 -48.798417)
			(xy 449.940706 -48.805989) (xy 450.000992 -48.821024) (xy 450.058996 -48.843298) (xy 450.11385 -48.872477)
			(xy 450.139562 -48.88992) (xy 450.148374 -48.895493) (xy 450.168772 -48.899709) (xy 450.18917 -48.895493)
			(xy 450.197982 -48.88992) (xy 450.223695 -48.872482) (xy 450.278553 -48.843313) (xy 450.336557 -48.821046)
			(xy 450.396841 -48.806014) (xy 450.458509 -48.79844) (xy 450.489574 -48.797972) (xy 450.521536 -48.798491)
			(xy 450.584957 -48.8065) (xy 450.646873 -48.822395) (xy 450.70631 -48.845925) (xy 450.762328 -48.876718)
			(xy 450.814045 -48.914291) (xy 450.860645 -48.958049) (xy 450.901393 -49.007302) (xy 450.935646 -49.061275)
			(xy 450.94081 -49.072249) (xy 452.963274 -49.072249) (xy 452.963274 -49.008327) (xy 452.971285 -48.944909)
			(xy 452.987182 -48.882995) (xy 453.010714 -48.823562) (xy 453.041508 -48.767547) (xy 453.079081 -48.715832)
			(xy 453.122838 -48.669235) (xy 453.172091 -48.62849) (xy 453.226062 -48.594239) (xy 453.283901 -48.567022)
			(xy 453.344694 -48.547269) (xy 453.407484 -48.535291) (xy 453.47128 -48.531278) (xy 453.535076 -48.535291)
			(xy 453.597866 -48.547269) (xy 453.658659 -48.567022) (xy 453.716498 -48.594239) (xy 453.770469 -48.62849)
			(xy 453.819722 -48.669235) (xy 453.863479 -48.715832) (xy 453.901052 -48.767547) (xy 453.931846 -48.823562)
			(xy 453.955378 -48.882995) (xy 453.971275 -48.944909) (xy 453.979286 -49.008327) (xy 453.979788 -49.040288)
			(xy 453.979286 -49.072249) (xy 453.971275 -49.135667) (xy 453.967582 -49.150052) (xy 454.696793 -49.150052)
			(xy 454.696793 -49.095548) (xy 454.70455 -49.0416) (xy 454.719906 -48.989305) (xy 454.742549 -48.939728)
			(xy 454.772017 -48.893878) (xy 454.80771 -48.852689) (xy 454.848902 -48.816999) (xy 454.894754 -48.787534)
			(xy 454.944333 -48.764896) (xy 454.99663 -48.749544) (xy 455.050578 -48.741791) (xy 455.07783 -48.74133)
			(xy 455.105735 -48.741815) (xy 455.160947 -48.749961) (xy 455.214385 -48.766061) (xy 455.264908 -48.789772)
			(xy 455.31144 -48.820587) (xy 455.352988 -48.85785) (xy 455.3712 -48.878998) (xy 455.379073 -48.887459)
			(xy 455.400039 -48.8971) (xy 455.411586 -48.89754) (xy 455.503026 -48.895) (xy 455.5236 -48.884332)
			(xy 455.530712 -48.874934) (xy 455.548883 -48.85172) (xy 455.591107 -48.810585) (xy 455.639157 -48.776436)
			(xy 455.691888 -48.750084) (xy 455.748045 -48.732159) (xy 455.806292 -48.723085) (xy 455.835766 -48.722534)
			(xy 455.865104 -48.723061) (xy 455.923087 -48.732066) (xy 455.979008 -48.749839) (xy 456.03155 -48.77596)
			(xy 456.079476 -48.809815) (xy 456.121655 -48.850606) (xy 456.139804 -48.873664) (xy 456.147218 -48.882564)
			(xy 456.167866 -48.89301) (xy 456.179428 -48.89373) (xy 456.271122 -48.895254) (xy 456.292204 -48.885348)
			(xy 456.29957 -48.876204) (xy 456.31781 -48.854604) (xy 456.359542 -48.816468) (xy 456.406442 -48.784904)
			(xy 456.457486 -48.760604) (xy 456.511555 -48.744099) (xy 456.567468 -48.735751) (xy 456.595734 -48.735234)
			(xy 456.622243 -48.735661) (xy 456.67475 -48.743013) (xy 456.725734 -48.757558) (xy 456.774217 -48.779015)
			(xy 456.819266 -48.806972) (xy 456.860014 -48.840892) (xy 456.878182 -48.860202) (xy 456.885496 -48.867588)
			(xy 456.904388 -48.87622) (xy 456.914758 -48.876966) (xy 456.99934 -48.87849) (xy 457.018644 -48.870616)
			(xy 457.02601 -48.862996) (xy 457.044015 -48.845162) (xy 457.083928 -48.813935) (xy 457.127625 -48.788267)
			(xy 457.174334 -48.76861) (xy 457.223236 -48.755311) (xy 457.273467 -48.748602) (xy 457.298806 -48.748188)
			(xy 457.327925 -48.748719) (xy 457.385487 -48.757566) (xy 457.441037 -48.775054) (xy 457.493286 -48.800776)
			(xy 457.541021 -48.834137) (xy 457.562458 -48.853852) (xy 457.569909 -48.86027) (xy 457.588192 -48.86746)
			(xy 457.598018 -48.867822) (xy 457.679044 -48.86706) (xy 457.697332 -48.85944) (xy 457.70419 -48.852582)
			(xy 457.72578 -48.831878) (xy 457.774218 -48.796786) (xy 457.827541 -48.769687) (xy 457.884441 -48.751244)
			(xy 457.943523 -48.741911) (xy 457.97343 -48.74133) (xy 458.000685 -48.741727) (xy 458.054641 -48.749489)
			(xy 458.106942 -48.764851) (xy 458.156525 -48.7875) (xy 458.20238 -48.816974) (xy 458.243573 -48.852675)
			(xy 458.279266 -48.893875) (xy 458.308733 -48.939735) (xy 458.331373 -48.989322) (xy 458.346725 -49.041626)
			(xy 458.354478 -49.095583) (xy 458.354938 -49.122838) (xy 458.354379 -49.151754) (xy 458.345653 -49.208924)
			(xy 458.328391 -49.26412) (xy 458.302991 -49.316076) (xy 458.270034 -49.363598) (xy 458.250544 -49.384966)
			(xy 458.25029 -49.38522) (xy 458.243763 -49.392951) (xy 458.236814 -49.411933) (xy 458.236828 -49.42205)
			(xy 458.240384 -49.505362) (xy 458.249274 -49.523904) (xy 458.256894 -49.530762) (xy 458.276717 -49.548948)
			(xy 458.311576 -49.589919) (xy 458.340333 -49.635381) (xy 458.362417 -49.684433) (xy 458.377389 -49.736102)
			(xy 458.384954 -49.789361) (xy 458.385418 -49.816258) (xy 458.384911 -49.844867) (xy 458.376339 -49.901438)
			(xy 458.359411 -49.956094) (xy 458.334508 -50.007608) (xy 458.302187 -50.054823) (xy 458.283056 -50.0761)
			(xy 458.276932 -50.08334) (xy 458.269887 -50.100924) (xy 458.26934 -50.11039) (xy 458.269086 -50.179224)
			(xy 458.269426 -50.188629) (xy 458.276094 -50.206216) (xy 458.28204 -50.213514) (xy 458.300464 -50.234628)
			(xy 458.331525 -50.281267) (xy 458.355425 -50.331951) (xy 458.371649 -50.385587) (xy 458.379846 -50.44102)
			(xy 458.380338 -50.469038) (xy 458.379852 -50.496289) (xy 458.372096 -50.550237) (xy 458.356741 -50.602532)
			(xy 458.334099 -50.652109) (xy 458.304633 -50.697959) (xy 458.268942 -50.73915) (xy 458.227751 -50.774841)
			(xy 458.181901 -50.804307) (xy 458.132324 -50.826949) (xy 458.080029 -50.842304) (xy 458.026081 -50.85006)
			(xy 457.971579 -50.85006) (xy 457.917631 -50.842304) (xy 457.865336 -50.826949) (xy 457.815759 -50.804307)
			(xy 457.769909 -50.774841) (xy 457.728718 -50.73915) (xy 457.693027 -50.697959) (xy 457.663561 -50.652109)
			(xy 457.640919 -50.602532) (xy 457.625564 -50.550237) (xy 457.617808 -50.496289) (xy 457.617322 -50.469038)
			(xy 457.617816 -50.440429) (xy 457.626389 -50.383856) (xy 457.64332 -50.329199) (xy 457.668226 -50.277686)
			(xy 457.700551 -50.230472) (xy 457.719684 -50.209196) (xy 457.725815 -50.201961) (xy 457.732855 -50.184373)
			(xy 457.7334 -50.174906) (xy 457.733654 -50.106072) (xy 457.733257 -50.096672) (xy 457.726628 -50.079086)
			(xy 457.7207 -50.071782) (xy 457.702265 -50.050678) (xy 457.671207 -50.004035) (xy 457.64731 -49.953349)
			(xy 457.631089 -49.899711) (xy 457.622894 -49.844277) (xy 457.622402 -49.816258) (xy 457.622948 -49.787341)
			(xy 457.631675 -49.73017) (xy 457.648939 -49.674973) (xy 457.674343 -49.623018) (xy 457.707304 -49.575497)
			(xy 457.726796 -49.55413) (xy 457.72705 -49.553876) (xy 457.733583 -49.54615) (xy 457.740527 -49.527164)
			(xy 457.740512 -49.517046) (xy 457.736956 -49.433734) (xy 457.728066 -49.415192) (xy 457.7207 -49.408588)
			(xy 457.720192 -49.40808) (xy 457.709778 -49.398682) (xy 457.702344 -49.392241) (xy 457.684049 -49.385063)
			(xy 457.674218 -49.384712) (xy 457.593192 -49.385474) (xy 457.574904 -49.393094) (xy 457.568046 -49.399952)
			(xy 457.54643 -49.420627) (xy 457.498 -49.455725) (xy 457.444683 -49.482832) (xy 457.387789 -49.501281)
			(xy 457.328712 -49.51062) (xy 457.298806 -49.511204) (xy 457.272298 -49.510738) (xy 457.219794 -49.503392)
			(xy 457.168811 -49.488854) (xy 457.120328 -49.467404) (xy 457.075278 -49.439455) (xy 457.034528 -49.405542)
			(xy 457.016358 -49.386236) (xy 457.009024 -49.378873) (xy 456.990147 -49.370226) (xy 456.979782 -49.369472)
			(xy 456.8952 -49.367948) (xy 456.875896 -49.375822) (xy 456.86853 -49.383442) (xy 456.850496 -49.401245)
			(xy 456.81059 -49.432478) (xy 456.7669 -49.458151) (xy 456.720196 -49.477814) (xy 456.671299 -49.491119)
			(xy 456.621071 -49.497833) (xy 456.595734 -49.49825) (xy 456.566395 -49.49773) (xy 456.508412 -49.488724)
			(xy 456.452491 -49.47095) (xy 456.399949 -49.444828) (xy 456.352023 -49.410971) (xy 456.309844 -49.370179)
			(xy 456.291696 -49.34712) (xy 456.284285 -49.338218) (xy 456.263634 -49.327773) (xy 456.252072 -49.327054)
			(xy 456.160378 -49.32553) (xy 456.139296 -49.335436) (xy 456.13193 -49.34458) (xy 456.113686 -49.366177)
			(xy 456.071956 -49.404314) (xy 456.025056 -49.435878) (xy 455.974013 -49.460179) (xy 455.919944 -49.476685)
			(xy 455.864032 -49.485033) (xy 455.835766 -49.48555) (xy 455.807861 -49.485075) (xy 455.752647 -49.476927)
			(xy 455.69921 -49.460826) (xy 455.648686 -49.437114) (xy 455.602155 -49.406297) (xy 455.560608 -49.369031)
			(xy 455.542396 -49.347882) (xy 455.534527 -49.339416) (xy 455.513558 -49.329779) (xy 455.50201 -49.32934)
			(xy 455.41057 -49.33188) (xy 455.389996 -49.342548) (xy 455.382884 -49.351946) (xy 455.364737 -49.375179)
			(xy 455.322505 -49.416309) (xy 455.274449 -49.450454) (xy 455.221714 -49.476801) (xy 455.165554 -49.494724)
			(xy 455.107305 -49.503795) (xy 455.07783 -49.504346) (xy 455.050578 -49.503809) (xy 454.99663 -49.496056)
			(xy 454.944333 -49.480704) (xy 454.894754 -49.458066) (xy 454.848902 -49.428601) (xy 454.80771 -49.392911)
			(xy 454.772017 -49.351722) (xy 454.742549 -49.305872) (xy 454.719906 -49.256295) (xy 454.70455 -49.204)
			(xy 454.696793 -49.150052) (xy 453.967582 -49.150052) (xy 453.955378 -49.197581) (xy 453.931846 -49.257014)
			(xy 453.901052 -49.313029) (xy 453.863479 -49.364744) (xy 453.819722 -49.411341) (xy 453.770469 -49.452086)
			(xy 453.716498 -49.486337) (xy 453.658659 -49.513554) (xy 453.597866 -49.533307) (xy 453.535076 -49.545285)
			(xy 453.47128 -49.549299) (xy 453.407484 -49.545285) (xy 453.344694 -49.533307) (xy 453.283901 -49.513554)
			(xy 453.226062 -49.486337) (xy 453.172091 -49.452086) (xy 453.122838 -49.411341) (xy 453.079081 -49.364744)
			(xy 453.041508 -49.313029) (xy 453.010714 -49.257014) (xy 452.987182 -49.197581) (xy 452.971285 -49.135667)
			(xy 452.963274 -49.072249) (xy 450.94081 -49.072249) (xy 450.962865 -49.119115) (xy 450.982619 -49.17991)
			(xy 450.994598 -49.242702) (xy 450.998612 -49.3065) (xy 450.994598 -49.370298) (xy 450.982619 -49.43309)
			(xy 450.962865 -49.493885) (xy 450.935646 -49.551725) (xy 450.901393 -49.605698) (xy 450.860645 -49.654951)
			(xy 450.814045 -49.698709) (xy 450.762328 -49.736282) (xy 450.70631 -49.767075) (xy 450.646873 -49.790605)
			(xy 450.584957 -49.8065) (xy 450.521536 -49.814509) (xy 450.489574 -49.814988) (xy 450.458508 -49.814528)
			(xy 450.396839 -49.80696) (xy 450.336552 -49.791929) (xy 450.278549 -49.769659) (xy 450.223694 -49.740482)
			(xy 450.197982 -49.72304) (xy 450.18917 -49.717467) (xy 450.168772 -49.713251) (xy 450.148374 -49.717467)
			(xy 450.139562 -49.72304) (xy 450.113833 -49.740454) (xy 450.05898 -49.769628) (xy 450.00098 -49.7919)
			(xy 449.940699 -49.806938) (xy 449.879034 -49.814518) (xy 449.84797 -49.814988) (xy 449.816009 -49.814524)
			(xy 449.752591 -49.806509) (xy 449.690678 -49.790609) (xy 449.631246 -49.767075) (xy 449.575232 -49.736278)
			(xy 449.523519 -49.698704) (xy 449.476923 -49.654945) (xy 449.436179 -49.605691) (xy 449.401929 -49.551719)
			(xy 449.374713 -49.49388) (xy 449.35496 -49.433086) (xy 449.342983 -49.370296) (xy 449.338969 -49.3065)
			(xy 275.0947 -49.3065) (xy 275.0947 -51.11623) (xy 388.081518 -51.11623) (xy 388.085589 -51.060608)
			(xy 388.097715 -51.006171) (xy 388.117638 -50.95408) (xy 388.144934 -50.905445) (xy 388.17902 -50.861302)
			(xy 388.219169 -50.822593) (xy 388.264527 -50.790142) (xy 388.314127 -50.764641) (xy 388.366911 -50.746634)
			(xy 388.421754 -50.736504) (xy 388.477488 -50.734467) (xy 388.532925 -50.740567) (xy 388.586882 -50.754673)
			(xy 388.638211 -50.776485) (xy 388.685817 -50.805539) (xy 388.716651 -50.831199) (xy 424.536356 -50.831199)
			(xy 424.536356 -50.767277) (xy 424.544367 -50.703859) (xy 424.560264 -50.641945) (xy 424.583796 -50.582512)
			(xy 424.61459 -50.526497) (xy 424.652163 -50.474782) (xy 424.69592 -50.428185) (xy 424.745173 -50.38744)
			(xy 424.799144 -50.353189) (xy 424.856983 -50.325972) (xy 424.917776 -50.306219) (xy 424.980566 -50.294241)
			(xy 425.044362 -50.290228) (xy 425.108158 -50.294241) (xy 425.170948 -50.306219) (xy 425.231741 -50.325972)
			(xy 425.28958 -50.353189) (xy 425.343551 -50.38744) (xy 425.392804 -50.428185) (xy 425.410893 -50.447448)
			(xy 431.109384 -50.447448) (xy 431.113364 -50.357565) (xy 431.125272 -50.268385) (xy 431.145015 -50.180607)
			(xy 431.172439 -50.094917) (xy 431.207328 -50.011986) (xy 431.249411 -49.932464) (xy 431.298357 -49.856971)
			(xy 431.353784 -49.7861) (xy 431.415257 -49.720405) (xy 431.482296 -49.6604) (xy 431.554376 -49.606555)
			(xy 431.630932 -49.559291) (xy 431.711367 -49.518978) (xy 431.795049 -49.485931) (xy 431.881324 -49.46041)
			(xy 431.969518 -49.442614) (xy 432.058939 -49.432681) (xy 432.148888 -49.430691) (xy 432.238661 -49.436658)
			(xy 432.327556 -49.450536) (xy 432.414876 -49.472216) (xy 432.499938 -49.501529) (xy 432.582077 -49.538245)
			(xy 432.660649 -49.582076) (xy 432.73504 -49.63268) (xy 432.804667 -49.689661) (xy 432.868986 -49.752573)
			(xy 432.927494 -49.820923) (xy 432.979731 -49.894176) (xy 433.02529 -49.971759) (xy 433.063814 -50.053066)
			(xy 433.095001 -50.137459) (xy 433.118608 -50.224278) (xy 433.134449 -50.312843) (xy 433.142401 -50.402462)
			(xy 433.142898 -50.447448) (xy 438.824634 -50.447448) (xy 438.828614 -50.357565) (xy 438.840522 -50.268385)
			(xy 438.860265 -50.180607) (xy 438.887689 -50.094917) (xy 438.922578 -50.011986) (xy 438.964661 -49.932464)
			(xy 439.013607 -49.856971) (xy 439.069034 -49.7861) (xy 439.130507 -49.720405) (xy 439.197546 -49.6604)
			(xy 439.269626 -49.606555) (xy 439.346182 -49.559291) (xy 439.426617 -49.518978) (xy 439.510299 -49.485931)
			(xy 439.596574 -49.46041) (xy 439.684768 -49.442614) (xy 439.774189 -49.432681) (xy 439.864138 -49.430691)
			(xy 439.953911 -49.436658) (xy 440.042806 -49.450536) (xy 440.130126 -49.472216) (xy 440.215188 -49.501529)
			(xy 440.297327 -49.538245) (xy 440.375899 -49.582076) (xy 440.45029 -49.63268) (xy 440.519917 -49.689661)
			(xy 440.584236 -49.752573) (xy 440.642744 -49.820923) (xy 440.694981 -49.894176) (xy 440.74054 -49.971759)
			(xy 440.779064 -50.053066) (xy 440.810251 -50.137459) (xy 440.817532 -50.164238) (xy 454.645012 -50.164238)
			(xy 454.649083 -50.108616) (xy 454.661209 -50.054179) (xy 454.681132 -50.002088) (xy 454.708428 -49.953453)
			(xy 454.742514 -49.90931) (xy 454.782663 -49.870601) (xy 454.828021 -49.83815) (xy 454.877621 -49.812649)
			(xy 454.930405 -49.794642) (xy 454.985248 -49.784512) (xy 455.040982 -49.782475) (xy 455.096419 -49.788575)
			(xy 455.150376 -49.802681) (xy 455.201705 -49.824493) (xy 455.249311 -49.853547) (xy 455.292179 -49.889222)
			(xy 455.329396 -49.930759) (xy 455.360169 -49.977272) (xy 455.383841 -50.027769) (xy 455.399909 -50.081176)
			(xy 455.408029 -50.136352) (xy 455.408538 -50.164238) (xy 455.408213 -50.182018) (xy 455.640692 -50.182018)
			(xy 455.644763 -50.126396) (xy 455.656889 -50.071959) (xy 455.676812 -50.019868) (xy 455.704108 -49.971233)
			(xy 455.738194 -49.92709) (xy 455.778343 -49.888381) (xy 455.823701 -49.85593) (xy 455.873301 -49.830429)
			(xy 455.926085 -49.812422) (xy 455.980928 -49.802292) (xy 456.036662 -49.800255) (xy 456.092099 -49.806355)
			(xy 456.146056 -49.820461) (xy 456.197385 -49.842273) (xy 456.244991 -49.871327) (xy 456.287859 -49.907002)
			(xy 456.325076 -49.948539) (xy 456.355849 -49.995052) (xy 456.379521 -50.045549) (xy 456.395589 -50.098956)
			(xy 456.403709 -50.154132) (xy 456.404218 -50.182018) (xy 456.403709 -50.209904) (xy 456.395589 -50.26508)
			(xy 456.379521 -50.318487) (xy 456.355849 -50.368984) (xy 456.325076 -50.415497) (xy 456.287859 -50.457034)
			(xy 456.244991 -50.492709) (xy 456.197385 -50.521763) (xy 456.146056 -50.543575) (xy 456.092099 -50.557681)
			(xy 456.036662 -50.563781) (xy 455.980928 -50.561744) (xy 455.926085 -50.551614) (xy 455.873301 -50.533607)
			(xy 455.823701 -50.508106) (xy 455.778343 -50.475655) (xy 455.738194 -50.436946) (xy 455.704108 -50.392803)
			(xy 455.676812 -50.344168) (xy 455.656889 -50.292077) (xy 455.644763 -50.23764) (xy 455.640692 -50.182018)
			(xy 455.408213 -50.182018) (xy 455.408029 -50.192124) (xy 455.399909 -50.2473) (xy 455.383841 -50.300707)
			(xy 455.360169 -50.351204) (xy 455.329396 -50.397717) (xy 455.292179 -50.439254) (xy 455.249311 -50.474929)
			(xy 455.201705 -50.503983) (xy 455.150376 -50.525795) (xy 455.096419 -50.539901) (xy 455.040982 -50.546001)
			(xy 454.985248 -50.543964) (xy 454.930405 -50.533834) (xy 454.877621 -50.515827) (xy 454.828021 -50.490326)
			(xy 454.782663 -50.457875) (xy 454.742514 -50.419166) (xy 454.708428 -50.375023) (xy 454.681132 -50.326388)
			(xy 454.661209 -50.274297) (xy 454.649083 -50.21986) (xy 454.645012 -50.164238) (xy 440.817532 -50.164238)
			(xy 440.833858 -50.224278) (xy 440.849699 -50.312843) (xy 440.857651 -50.402462) (xy 440.858148 -50.447448)
			(xy 440.857651 -50.492434) (xy 440.849699 -50.582053) (xy 440.833858 -50.670618) (xy 440.810251 -50.757437)
			(xy 440.779064 -50.84183) (xy 440.74054 -50.923137) (xy 440.694981 -51.00072) (xy 440.642744 -51.073973)
			(xy 440.584236 -51.142323) (xy 440.519917 -51.205235) (xy 440.45029 -51.262216) (xy 440.375899 -51.31282)
			(xy 440.297327 -51.356651) (xy 440.256725 -51.3748) (xy 445.38897 -51.3748) (xy 445.392985 -51.311)
			(xy 445.404963 -51.248207) (xy 445.424718 -51.18741) (xy 445.451937 -51.129569) (xy 445.48619 -51.075595)
			(xy 445.526939 -51.02634) (xy 445.573539 -50.98258) (xy 445.625257 -50.945007) (xy 445.681276 -50.914211)
			(xy 445.740713 -50.89068) (xy 445.802631 -50.874784) (xy 445.866053 -50.866774) (xy 445.898016 -50.866294)
			(xy 445.929082 -50.866763) (xy 445.990751 -50.874329) (xy 446.051037 -50.889358) (xy 446.10904 -50.911626)
			(xy 446.163896 -50.940801) (xy 446.189608 -50.958242) (xy 446.19842 -50.963815) (xy 446.218818 -50.968031)
			(xy 446.239216 -50.963815) (xy 446.248028 -50.958242) (xy 446.27373 -50.940786) (xy 446.328591 -50.91162)
			(xy 446.386597 -50.889357) (xy 446.446885 -50.874328) (xy 446.508554 -50.866759) (xy 446.53962 -50.866294)
			(xy 446.57158 -50.866793) (xy 446.634997 -50.874807) (xy 446.696909 -50.890705) (xy 446.75634 -50.914238)
			(xy 446.812353 -50.945033) (xy 446.864065 -50.982606) (xy 446.910661 -51.026364) (xy 446.951404 -51.075616)
			(xy 446.985654 -51.129587) (xy 447.01287 -51.187424) (xy 447.032622 -51.248217) (xy 447.044599 -51.311005)
			(xy 447.048613 -51.3748) (xy 447.047606 -51.3908) (xy 447.182293 -51.3908) (xy 447.186307 -51.327008)
			(xy 447.198283 -51.264222) (xy 447.218034 -51.203432) (xy 447.245247 -51.145597) (xy 447.279495 -51.091628)
			(xy 447.320236 -51.042376) (xy 447.366828 -50.998619) (xy 447.418537 -50.961047) (xy 447.474547 -50.930251)
			(xy 447.533975 -50.906717) (xy 447.595884 -50.890817) (xy 447.659297 -50.882801) (xy 447.691256 -50.882296)
			(xy 447.722322 -50.882744) (xy 447.783992 -50.890315) (xy 447.844279 -50.905349) (xy 447.902282 -50.927622)
			(xy 447.957137 -50.956801) (xy 447.982848 -50.974244) (xy 447.99166 -50.979817) (xy 448.012058 -50.984033)
			(xy 448.032456 -50.979817) (xy 448.041268 -50.974244) (xy 448.066987 -50.956815) (xy 448.121843 -50.927644)
			(xy 448.179845 -50.905375) (xy 448.240129 -50.890341) (xy 448.301795 -50.882765) (xy 448.33286 -50.882296)
			(xy 448.364824 -50.882767) (xy 448.428249 -50.890774) (xy 448.49017 -50.906669) (xy 448.549611 -50.930199)
			(xy 448.605633 -50.960993) (xy 448.657354 -50.998567) (xy 448.69477 -51.0337) (xy 448.919869 -51.0337)
			(xy 448.923883 -50.969904) (xy 448.93586 -50.907114) (xy 448.955613 -50.84632) (xy 448.982829 -50.788481)
			(xy 449.017079 -50.734509) (xy 449.057823 -50.685255) (xy 449.104419 -50.641496) (xy 449.156132 -50.603922)
			(xy 449.212146 -50.573125) (xy 449.271578 -50.549591) (xy 449.333491 -50.533691) (xy 449.396909 -50.525676)
			(xy 449.42887 -50.525172) (xy 449.459936 -50.525617) (xy 449.521606 -50.533189) (xy 449.581892 -50.548224)
			(xy 449.639896 -50.570498) (xy 449.69475 -50.599677) (xy 449.720462 -50.61712) (xy 449.729274 -50.622693)
			(xy 449.749672 -50.626909) (xy 449.77007 -50.622693) (xy 449.778882 -50.61712) (xy 449.804595 -50.599682)
			(xy 449.859453 -50.570513) (xy 449.917457 -50.548246) (xy 449.977741 -50.533214) (xy 450.039409 -50.52564)
			(xy 450.070474 -50.525172) (xy 450.099907 -50.525584) (xy 450.158376 -50.532426) (xy 450.215666 -50.545964)
			(xy 450.271013 -50.566017) (xy 450.323678 -50.592319) (xy 450.37296 -50.624517) (xy 450.395848 -50.643028)
			(xy 450.40489 -50.649811) (xy 450.426759 -50.655413) (xy 450.44891 -50.651052) (xy 450.458332 -50.644806)
			(xy 450.484615 -50.626107) (xy 450.541002 -50.594783) (xy 450.600897 -50.570839) (xy 450.663338 -50.554658)
			(xy 450.727324 -50.5465) (xy 450.759576 -50.546) (xy 450.790643 -50.546437) (xy 450.852313 -50.55401)
			(xy 450.912599 -50.569047) (xy 450.970603 -50.591322) (xy 451.025457 -50.620504) (xy 451.051168 -50.637948)
			(xy 451.05998 -50.643521) (xy 451.080378 -50.647737) (xy 451.100776 -50.643521) (xy 451.109588 -50.637948)
			(xy 451.135302 -50.62051) (xy 451.190159 -50.591341) (xy 451.248163 -50.569074) (xy 451.308447 -50.554041)
			(xy 451.370115 -50.546467) (xy 451.40118 -50.546) (xy 451.433144 -50.546464) (xy 451.496567 -50.554474)
			(xy 451.558487 -50.57037) (xy 451.617925 -50.593901) (xy 451.673946 -50.624697) (xy 451.725665 -50.662271)
			(xy 451.772267 -50.706031) (xy 451.813017 -50.755288) (xy 451.847272 -50.809263) (xy 451.874491 -50.867106)
			(xy 451.894246 -50.927904) (xy 451.906225 -50.990699) (xy 451.91024 -51.0545) (xy 451.906225 -51.118301)
			(xy 451.894246 -51.181096) (xy 451.874491 -51.241894) (xy 451.847272 -51.299737) (xy 451.837192 -51.31562)
			(xy 455.806808 -51.31562) (xy 455.810879 -51.259998) (xy 455.823005 -51.205561) (xy 455.842928 -51.15347)
			(xy 455.870224 -51.104835) (xy 455.90431 -51.060692) (xy 455.944459 -51.021983) (xy 455.989817 -50.989532)
			(xy 456.039417 -50.964031) (xy 456.092201 -50.946024) (xy 456.147044 -50.935894) (xy 456.202778 -50.933857)
			(xy 456.258215 -50.939957) (xy 456.312172 -50.954063) (xy 456.363501 -50.975875) (xy 456.411107 -51.004929)
			(xy 456.453975 -51.040604) (xy 456.491192 -51.082141) (xy 456.521965 -51.128654) (xy 456.545637 -51.179151)
			(xy 456.561705 -51.232558) (xy 456.569825 -51.287734) (xy 456.570334 -51.31562) (xy 456.569825 -51.343506)
			(xy 456.561705 -51.398682) (xy 456.545637 -51.452089) (xy 456.521965 -51.502586) (xy 456.491192 -51.549099)
			(xy 456.453975 -51.590636) (xy 456.411107 -51.626311) (xy 456.363501 -51.655365) (xy 456.312172 -51.677177)
			(xy 456.258215 -51.691283) (xy 456.202778 -51.697383) (xy 456.147044 -51.695346) (xy 456.092201 -51.685216)
			(xy 456.039417 -51.667209) (xy 455.989817 -51.641708) (xy 455.944459 -51.609257) (xy 455.90431 -51.570548)
			(xy 455.870224 -51.526405) (xy 455.842928 -51.47777) (xy 455.823005 -51.425679) (xy 455.810879 -51.371242)
			(xy 455.806808 -51.31562) (xy 451.837192 -51.31562) (xy 451.813017 -51.353712) (xy 451.772267 -51.402969)
			(xy 451.725665 -51.446729) (xy 451.673946 -51.484303) (xy 451.617925 -51.515099) (xy 451.558487 -51.53863)
			(xy 451.496567 -51.554526) (xy 451.433144 -51.562536) (xy 451.40118 -51.563016) (xy 451.370114 -51.562548)
			(xy 451.308445 -51.554981) (xy 451.248159 -51.539952) (xy 451.190156 -51.517684) (xy 451.1353 -51.488509)
			(xy 451.109588 -51.471068) (xy 451.100776 -51.465495) (xy 451.080378 -51.461279) (xy 451.05998 -51.465495)
			(xy 451.051168 -51.471068) (xy 451.025468 -51.488527) (xy 450.970606 -51.517692) (xy 450.912599 -51.539955)
			(xy 450.852312 -51.554983) (xy 450.790642 -51.562551) (xy 450.759576 -51.563016) (xy 450.730143 -51.562578)
			(xy 450.671675 -51.555742) (xy 450.614386 -51.542209) (xy 450.559039 -51.52216) (xy 450.506373 -51.495863)
			(xy 450.457091 -51.463669) (xy 450.434202 -51.44516) (xy 450.425131 -51.438422) (xy 450.40328 -51.432808)
			(xy 450.38114 -51.437148) (xy 450.371718 -51.443382) (xy 450.345419 -51.462057) (xy 450.289036 -51.493385)
			(xy 450.229146 -51.517335) (xy 450.166708 -51.533521) (xy 450.102725 -51.541684) (xy 450.070474 -51.542188)
			(xy 450.039408 -51.541728) (xy 449.977739 -51.53416) (xy 449.917452 -51.519129) (xy 449.859449 -51.496859)
			(xy 449.804594 -51.467682) (xy 449.778882 -51.45024) (xy 449.77007 -51.444667) (xy 449.749672 -51.440451)
			(xy 449.729274 -51.444667) (xy 449.720462 -51.45024) (xy 449.694733 -51.467654) (xy 449.63988 -51.496828)
			(xy 449.58188 -51.5191) (xy 449.521599 -51.534138) (xy 449.459934 -51.541718) (xy 449.42887 -51.542188)
			(xy 449.396909 -51.541724) (xy 449.333491 -51.533709) (xy 449.271578 -51.517809) (xy 449.212146 -51.494275)
			(xy 449.156132 -51.463478) (xy 449.104419 -51.425904) (xy 449.057823 -51.382145) (xy 449.017079 -51.332891)
			(xy 448.982829 -51.278919) (xy 448.955613 -51.22108) (xy 448.93586 -51.160286) (xy 448.923883 -51.097496)
			(xy 448.919869 -51.0337) (xy 448.69477 -51.0337) (xy 448.703958 -51.042327) (xy 448.744709 -51.091583)
			(xy 448.778965 -51.145559) (xy 448.806186 -51.203403) (xy 448.825942 -51.264202) (xy 448.837921 -51.326998)
			(xy 448.841936 -51.3908) (xy 448.837921 -51.454602) (xy 448.825942 -51.517398) (xy 448.806186 -51.578197)
			(xy 448.778965 -51.636041) (xy 448.744709 -51.690017) (xy 448.703958 -51.739273) (xy 448.657354 -51.783033)
			(xy 448.605633 -51.820607) (xy 448.549611 -51.851401) (xy 448.49017 -51.874931) (xy 448.428249 -51.890826)
			(xy 448.364824 -51.898833) (xy 448.33286 -51.899312) (xy 448.301794 -51.898854) (xy 448.240125 -51.891286)
			(xy 448.179838 -51.876254) (xy 448.121835 -51.853983) (xy 448.06698 -51.824806) (xy 448.041268 -51.807364)
			(xy 448.032456 -51.801791) (xy 448.012058 -51.797575) (xy 447.99166 -51.801791) (xy 447.982848 -51.807364)
			(xy 447.957125 -51.824787) (xy 447.90227 -51.853959) (xy 447.844269 -51.876229) (xy 447.783986 -51.891265)
			(xy 447.722321 -51.898843) (xy 447.691256 -51.899312) (xy 447.659297 -51.898799) (xy 447.595884 -51.890783)
			(xy 447.533975 -51.874883) (xy 447.474547 -51.851349) (xy 447.418537 -51.820553) (xy 447.366828 -51.782981)
			(xy 447.320236 -51.739224) (xy 447.279495 -51.689972) (xy 447.245247 -51.636003) (xy 447.218034 -51.578168)
			(xy 447.198283 -51.517378) (xy 447.186307 -51.454592) (xy 447.182293 -51.3908) (xy 447.047606 -51.3908)
			(xy 447.044599 -51.438595) (xy 447.032622 -51.501383) (xy 447.01287 -51.562176) (xy 446.985654 -51.620013)
			(xy 446.951404 -51.673984) (xy 446.910661 -51.723236) (xy 446.864065 -51.766994) (xy 446.812353 -51.804567)
			(xy 446.75634 -51.835362) (xy 446.696909 -51.858895) (xy 446.634997 -51.874793) (xy 446.57158 -51.882807)
			(xy 446.53962 -51.88331) (xy 446.508555 -51.882822) (xy 446.446887 -51.87526) (xy 446.386601 -51.860235)
			(xy 446.328597 -51.837971) (xy 446.273741 -51.8088) (xy 446.248028 -51.791362) (xy 446.239216 -51.785789)
			(xy 446.218818 -51.781573) (xy 446.19842 -51.785789) (xy 446.189608 -51.791362) (xy 446.163896 -51.808802)
			(xy 446.109038 -51.837971) (xy 446.051034 -51.860238) (xy 445.990749 -51.87527) (xy 445.929081 -51.882843)
			(xy 445.898016 -51.88331) (xy 445.866053 -51.882826) (xy 445.802631 -51.874816) (xy 445.740713 -51.85892)
			(xy 445.681276 -51.835389) (xy 445.625257 -51.804593) (xy 445.573539 -51.76702) (xy 445.526939 -51.72326)
			(xy 445.48619 -51.674005) (xy 445.451937 -51.620031) (xy 445.424718 -51.56219) (xy 445.404963 -51.501393)
			(xy 445.392985 -51.4386) (xy 445.38897 -51.3748) (xy 440.256725 -51.3748) (xy 440.215188 -51.393367)
			(xy 440.130126 -51.42268) (xy 440.042806 -51.44436) (xy 439.953911 -51.458238) (xy 439.864138 -51.464205)
			(xy 439.774189 -51.462215) (xy 439.684768 -51.452282) (xy 439.596574 -51.434486) (xy 439.510299 -51.408965)
			(xy 439.426617 -51.375918) (xy 439.346182 -51.335605) (xy 439.269626 -51.288341) (xy 439.197546 -51.234496)
			(xy 439.130507 -51.174491) (xy 439.069034 -51.108796) (xy 439.013607 -51.037925) (xy 438.964661 -50.962432)
			(xy 438.922578 -50.88291) (xy 438.887689 -50.799979) (xy 438.860265 -50.714289) (xy 438.840522 -50.626511)
			(xy 438.828614 -50.537331) (xy 438.824634 -50.447448) (xy 433.142898 -50.447448) (xy 433.142401 -50.492434)
			(xy 433.134449 -50.582053) (xy 433.118608 -50.670618) (xy 433.095001 -50.757437) (xy 433.063814 -50.84183)
			(xy 433.02529 -50.923137) (xy 432.979731 -51.00072) (xy 432.927494 -51.073973) (xy 432.868986 -51.142323)
			(xy 432.804667 -51.205235) (xy 432.73504 -51.262216) (xy 432.660649 -51.31282) (xy 432.582077 -51.356651)
			(xy 432.499938 -51.393367) (xy 432.414876 -51.42268) (xy 432.327556 -51.44436) (xy 432.238661 -51.458238)
			(xy 432.148888 -51.464205) (xy 432.058939 -51.462215) (xy 431.969518 -51.452282) (xy 431.881324 -51.434486)
			(xy 431.795049 -51.408965) (xy 431.711367 -51.375918) (xy 431.630932 -51.335605) (xy 431.554376 -51.288341)
			(xy 431.482296 -51.234496) (xy 431.415257 -51.174491) (xy 431.353784 -51.108796) (xy 431.298357 -51.037925)
			(xy 431.249411 -50.962432) (xy 431.207328 -50.88291) (xy 431.172439 -50.799979) (xy 431.145015 -50.714289)
			(xy 431.125272 -50.626511) (xy 431.113364 -50.537331) (xy 431.109384 -50.447448) (xy 425.410893 -50.447448)
			(xy 425.436561 -50.474782) (xy 425.474134 -50.526497) (xy 425.504928 -50.582512) (xy 425.52846 -50.641945)
			(xy 425.544357 -50.703859) (xy 425.552368 -50.767277) (xy 425.55287 -50.799238) (xy 425.552368 -50.831199)
			(xy 425.544357 -50.894617) (xy 425.52846 -50.956531) (xy 425.504928 -51.015964) (xy 425.474134 -51.071979)
			(xy 425.436561 -51.123694) (xy 425.392804 -51.170291) (xy 425.343551 -51.211036) (xy 425.28958 -51.245287)
			(xy 425.231741 -51.272504) (xy 425.170948 -51.292257) (xy 425.108158 -51.304235) (xy 425.044362 -51.308249)
			(xy 424.980566 -51.304235) (xy 424.917776 -51.292257) (xy 424.856983 -51.272504) (xy 424.799144 -51.245287)
			(xy 424.745173 -51.211036) (xy 424.69592 -51.170291) (xy 424.652163 -51.123694) (xy 424.61459 -51.071979)
			(xy 424.583796 -51.015964) (xy 424.560264 -50.956531) (xy 424.544367 -50.894617) (xy 424.536356 -50.831199)
			(xy 388.716651 -50.831199) (xy 388.728685 -50.841214) (xy 388.765902 -50.882751) (xy 388.796675 -50.929264)
			(xy 388.820347 -50.979761) (xy 388.836415 -51.033168) (xy 388.844535 -51.088344) (xy 388.845044 -51.11623)
			(xy 388.844535 -51.144116) (xy 388.836415 -51.199292) (xy 388.820347 -51.252699) (xy 388.796675 -51.303196)
			(xy 388.765902 -51.349709) (xy 388.728685 -51.391246) (xy 388.685817 -51.426921) (xy 388.638211 -51.455975)
			(xy 388.586882 -51.477787) (xy 388.532925 -51.491893) (xy 388.477488 -51.497993) (xy 388.421754 -51.495956)
			(xy 388.366911 -51.485826) (xy 388.314127 -51.467819) (xy 388.264527 -51.442318) (xy 388.219169 -51.409867)
			(xy 388.17902 -51.371158) (xy 388.144934 -51.327015) (xy 388.117638 -51.27838) (xy 388.097715 -51.226289)
			(xy 388.085589 -51.171852) (xy 388.081518 -51.11623) (xy 275.0947 -51.11623) (xy 275.0947 -52.697337)
			(xy 291.621966 -52.697337) (xy 291.621966 -52.633415) (xy 291.629977 -52.569997) (xy 291.645874 -52.508083)
			(xy 291.669406 -52.44865) (xy 291.7002 -52.392635) (xy 291.737773 -52.34092) (xy 291.78153 -52.294323)
			(xy 291.830783 -52.253578) (xy 291.884754 -52.219327) (xy 291.942593 -52.19211) (xy 292.003386 -52.172357)
			(xy 292.066176 -52.160379) (xy 292.129972 -52.156366) (xy 292.193768 -52.160379) (xy 292.256558 -52.172357)
			(xy 292.317351 -52.19211) (xy 292.37519 -52.219327) (xy 292.429161 -52.253578) (xy 292.478414 -52.294323)
			(xy 292.522171 -52.34092) (xy 292.559744 -52.392635) (xy 292.590538 -52.44865) (xy 292.61407 -52.508083)
			(xy 292.629967 -52.569997) (xy 292.637978 -52.633415) (xy 292.63848 -52.665376) (xy 292.637978 -52.697337)
			(xy 292.930066 -52.697337) (xy 292.930066 -52.633415) (xy 292.938077 -52.569997) (xy 292.953974 -52.508083)
			(xy 292.977506 -52.44865) (xy 293.0083 -52.392635) (xy 293.045873 -52.34092) (xy 293.08963 -52.294323)
			(xy 293.138883 -52.253578) (xy 293.192854 -52.219327) (xy 293.250693 -52.19211) (xy 293.311486 -52.172357)
			(xy 293.374276 -52.160379) (xy 293.438072 -52.156366) (xy 293.501868 -52.160379) (xy 293.564658 -52.172357)
			(xy 293.625451 -52.19211) (xy 293.68329 -52.219327) (xy 293.737261 -52.253578) (xy 293.786514 -52.294323)
			(xy 293.830271 -52.34092) (xy 293.867844 -52.392635) (xy 293.898638 -52.44865) (xy 293.92217 -52.508083)
			(xy 293.938067 -52.569997) (xy 293.945655 -52.63007) (xy 297.09213 -52.63007) (xy 297.096082 -52.538277)
			(xy 297.107912 -52.447163) (xy 297.127529 -52.357403) (xy 297.154791 -52.269662) (xy 297.189494 -52.18459)
			(xy 297.231382 -52.102815) (xy 297.280145 -52.024944) (xy 297.335421 -51.951554) (xy 297.396802 -51.883187)
			(xy 297.463833 -51.820349) (xy 297.536017 -51.763507) (xy 297.612821 -51.71308) (xy 297.693675 -51.669442)
			(xy 297.777981 -51.632916) (xy 297.865115 -51.603773) (xy 297.954432 -51.582228) (xy 298.04527 -51.568442)
			(xy 298.136957 -51.562515) (xy 298.228814 -51.564492) (xy 298.320162 -51.574358) (xy 298.410322 -51.59204)
			(xy 298.49863 -51.617407) (xy 298.584429 -51.650272) (xy 298.667086 -51.690391) (xy 298.745988 -51.737467)
			(xy 298.820551 -51.791151) (xy 298.890223 -51.851047) (xy 298.954488 -51.91671) (xy 299.012871 -51.987654)
			(xy 299.064938 -52.063355) (xy 299.110306 -52.143252) (xy 299.148637 -52.226752) (xy 299.179648 -52.313239)
			(xy 299.203109 -52.402072) (xy 299.218848 -52.492592) (xy 299.226746 -52.584131) (xy 299.22724 -52.63007)
			(xy 299.63213 -52.63007) (xy 299.636082 -52.538277) (xy 299.647912 -52.447163) (xy 299.667529 -52.357403)
			(xy 299.694791 -52.269662) (xy 299.729494 -52.18459) (xy 299.771382 -52.102815) (xy 299.820145 -52.024944)
			(xy 299.875421 -51.951554) (xy 299.936802 -51.883187) (xy 300.003833 -51.820349) (xy 300.076017 -51.763507)
			(xy 300.152821 -51.71308) (xy 300.233675 -51.669442) (xy 300.317981 -51.632916) (xy 300.405115 -51.603773)
			(xy 300.494432 -51.582228) (xy 300.58527 -51.568442) (xy 300.676957 -51.562515) (xy 300.768814 -51.564492)
			(xy 300.860162 -51.574358) (xy 300.950322 -51.59204) (xy 301.03863 -51.617407) (xy 301.124429 -51.650272)
			(xy 301.207086 -51.690391) (xy 301.285988 -51.737467) (xy 301.360551 -51.791151) (xy 301.430223 -51.851047)
			(xy 301.494488 -51.91671) (xy 301.552871 -51.987654) (xy 301.604938 -52.063355) (xy 301.650306 -52.143252)
			(xy 301.688637 -52.226752) (xy 301.719648 -52.313239) (xy 301.743109 -52.402072) (xy 301.758848 -52.492592)
			(xy 301.766746 -52.584131) (xy 301.76724 -52.63007) (xy 302.17213 -52.63007) (xy 302.176082 -52.538277)
			(xy 302.187912 -52.447163) (xy 302.207529 -52.357403) (xy 302.234791 -52.269662) (xy 302.269494 -52.18459)
			(xy 302.311382 -52.102815) (xy 302.360145 -52.024944) (xy 302.415421 -51.951554) (xy 302.476802 -51.883187)
			(xy 302.543833 -51.820349) (xy 302.616017 -51.763507) (xy 302.692821 -51.71308) (xy 302.773675 -51.669442)
			(xy 302.857981 -51.632916) (xy 302.945115 -51.603773) (xy 303.034432 -51.582228) (xy 303.12527 -51.568442)
			(xy 303.216957 -51.562515) (xy 303.308814 -51.564492) (xy 303.400162 -51.574358) (xy 303.490322 -51.59204)
			(xy 303.57863 -51.617407) (xy 303.664429 -51.650272) (xy 303.747086 -51.690391) (xy 303.825988 -51.737467)
			(xy 303.900551 -51.791151) (xy 303.970223 -51.851047) (xy 304.034488 -51.91671) (xy 304.092871 -51.987654)
			(xy 304.144938 -52.063355) (xy 304.190306 -52.143252) (xy 304.228637 -52.226752) (xy 304.259648 -52.313239)
			(xy 304.272071 -52.360279) (xy 321.803008 -52.360279) (xy 321.803008 -52.296357) (xy 321.811019 -52.232939)
			(xy 321.826916 -52.171025) (xy 321.850448 -52.111592) (xy 321.881242 -52.055577) (xy 321.918815 -52.003862)
			(xy 321.962572 -51.957265) (xy 322.011825 -51.91652) (xy 322.065796 -51.882269) (xy 322.123635 -51.855052)
			(xy 322.184428 -51.835299) (xy 322.247218 -51.823321) (xy 322.311014 -51.819308) (xy 322.37481 -51.823321)
			(xy 322.393461 -51.826879) (xy 331.292194 -51.826879) (xy 331.292194 -51.762957) (xy 331.300205 -51.699539)
			(xy 331.316102 -51.637625) (xy 331.339634 -51.578192) (xy 331.370428 -51.522177) (xy 331.408001 -51.470462)
			(xy 331.451758 -51.423865) (xy 331.501011 -51.38312) (xy 331.554982 -51.348869) (xy 331.612821 -51.321652)
			(xy 331.673614 -51.301899) (xy 331.736404 -51.289921) (xy 331.8002 -51.285908) (xy 331.863996 -51.289921)
			(xy 331.926786 -51.301899) (xy 331.987579 -51.321652) (xy 332.045418 -51.348869) (xy 332.099389 -51.38312)
			(xy 332.148642 -51.423865) (xy 332.192399 -51.470462) (xy 332.229972 -51.522177) (xy 332.260766 -51.578192)
			(xy 332.284298 -51.637625) (xy 332.300195 -51.699539) (xy 332.308206 -51.762957) (xy 332.308708 -51.794918)
			(xy 332.308206 -51.826879) (xy 332.300195 -51.890297) (xy 332.284298 -51.952211) (xy 332.260766 -52.011644)
			(xy 332.229972 -52.067659) (xy 332.192399 -52.119374) (xy 332.148642 -52.165971) (xy 332.099389 -52.206716)
			(xy 332.045418 -52.240967) (xy 331.987579 -52.268184) (xy 331.926786 -52.287937) (xy 331.863996 -52.299915)
			(xy 331.8002 -52.303929) (xy 331.736404 -52.299915) (xy 331.673614 -52.287937) (xy 331.612821 -52.268184)
			(xy 331.554982 -52.240967) (xy 331.501011 -52.206716) (xy 331.451758 -52.165971) (xy 331.408001 -52.119374)
			(xy 331.370428 -52.067659) (xy 331.339634 -52.011644) (xy 331.316102 -51.952211) (xy 331.300205 -51.890297)
			(xy 331.292194 -51.826879) (xy 322.393461 -51.826879) (xy 322.4376 -51.835299) (xy 322.498393 -51.855052)
			(xy 322.556232 -51.882269) (xy 322.610203 -51.91652) (xy 322.659456 -51.957265) (xy 322.703213 -52.003862)
			(xy 322.740786 -52.055577) (xy 322.77158 -52.111592) (xy 322.795112 -52.171025) (xy 322.811009 -52.232939)
			(xy 322.81902 -52.296357) (xy 322.819522 -52.328318) (xy 322.81902 -52.360279) (xy 322.811009 -52.423697)
			(xy 322.795112 -52.485611) (xy 322.77158 -52.545044) (xy 322.740786 -52.601059) (xy 322.703213 -52.652774)
			(xy 322.683548 -52.673715) (xy 394.299434 -52.673715) (xy 394.299434 -52.609793) (xy 394.307445 -52.546375)
			(xy 394.323342 -52.484461) (xy 394.346874 -52.425028) (xy 394.377668 -52.369013) (xy 394.415241 -52.317298)
			(xy 394.458998 -52.270701) (xy 394.508251 -52.229956) (xy 394.562222 -52.195705) (xy 394.620061 -52.168488)
			(xy 394.680854 -52.148735) (xy 394.743644 -52.136757) (xy 394.80744 -52.132744) (xy 394.871236 -52.136757)
			(xy 394.934026 -52.148735) (xy 394.994819 -52.168488) (xy 395.052658 -52.195705) (xy 395.106629 -52.229956)
			(xy 395.155882 -52.270701) (xy 395.199639 -52.317298) (xy 395.237212 -52.369013) (xy 395.268006 -52.425028)
			(xy 395.286016 -52.470515) (xy 425.90948 -52.470515) (xy 425.90948 -52.406593) (xy 425.917491 -52.343175)
			(xy 425.933388 -52.281261) (xy 425.95692 -52.221828) (xy 425.987714 -52.165813) (xy 426.025287 -52.114098)
			(xy 426.069044 -52.067501) (xy 426.118297 -52.026756) (xy 426.172268 -51.992505) (xy 426.230107 -51.965288)
			(xy 426.2909 -51.945535) (xy 426.35369 -51.933557) (xy 426.417486 -51.929544) (xy 426.481282 -51.933557)
			(xy 426.544072 -51.945535) (xy 426.604865 -51.965288) (xy 426.662704 -51.992505) (xy 426.716675 -52.026756)
			(xy 426.765928 -52.067501) (xy 426.809685 -52.114098) (xy 426.847258 -52.165813) (xy 426.878052 -52.221828)
			(xy 426.901584 -52.281261) (xy 426.917481 -52.343175) (xy 426.925492 -52.406593) (xy 426.925994 -52.438554)
			(xy 426.925492 -52.470515) (xy 426.917481 -52.533933) (xy 426.901584 -52.595847) (xy 426.878052 -52.65528)
			(xy 426.847258 -52.711295) (xy 426.809685 -52.76301) (xy 426.765928 -52.809607) (xy 426.716675 -52.850352)
			(xy 426.662704 -52.884603) (xy 426.604865 -52.91182) (xy 426.544072 -52.931573) (xy 426.481282 -52.943551)
			(xy 426.417486 -52.947565) (xy 426.35369 -52.943551) (xy 426.2909 -52.931573) (xy 426.230107 -52.91182)
			(xy 426.172268 -52.884603) (xy 426.118297 -52.850352) (xy 426.069044 -52.809607) (xy 426.025287 -52.76301)
			(xy 425.987714 -52.711295) (xy 425.95692 -52.65528) (xy 425.933388 -52.595847) (xy 425.917491 -52.533933)
			(xy 425.90948 -52.470515) (xy 395.286016 -52.470515) (xy 395.291538 -52.484461) (xy 395.307435 -52.546375)
			(xy 395.315446 -52.609793) (xy 395.315948 -52.641754) (xy 395.315446 -52.673715) (xy 395.307435 -52.737133)
			(xy 395.291538 -52.799047) (xy 395.268006 -52.85848) (xy 395.237212 -52.914495) (xy 395.199639 -52.96621)
			(xy 395.155882 -53.012807) (xy 395.106629 -53.053552) (xy 395.052658 -53.087803) (xy 394.994819 -53.11502)
			(xy 394.934026 -53.134773) (xy 394.871236 -53.146751) (xy 394.80744 -53.150765) (xy 394.743644 -53.146751)
			(xy 394.680854 -53.134773) (xy 394.620061 -53.11502) (xy 394.562222 -53.087803) (xy 394.508251 -53.053552)
			(xy 394.458998 -53.012807) (xy 394.415241 -52.96621) (xy 394.377668 -52.914495) (xy 394.346874 -52.85848)
			(xy 394.323342 -52.799047) (xy 394.307445 -52.737133) (xy 394.299434 -52.673715) (xy 322.683548 -52.673715)
			(xy 322.659456 -52.699371) (xy 322.610203 -52.740116) (xy 322.556232 -52.774367) (xy 322.498393 -52.801584)
			(xy 322.4376 -52.821337) (xy 322.37481 -52.833315) (xy 322.311014 -52.837329) (xy 322.247218 -52.833315)
			(xy 322.184428 -52.821337) (xy 322.123635 -52.801584) (xy 322.065796 -52.774367) (xy 322.011825 -52.740116)
			(xy 321.962572 -52.699371) (xy 321.918815 -52.652774) (xy 321.881242 -52.601059) (xy 321.850448 -52.545044)
			(xy 321.826916 -52.485611) (xy 321.811019 -52.423697) (xy 321.803008 -52.360279) (xy 304.272071 -52.360279)
			(xy 304.283109 -52.402072) (xy 304.298848 -52.492592) (xy 304.306746 -52.584131) (xy 304.30724 -52.63007)
			(xy 304.306746 -52.676009) (xy 304.298848 -52.767548) (xy 304.283109 -52.858068) (xy 304.259648 -52.946901)
			(xy 304.228637 -53.033388) (xy 304.190306 -53.116888) (xy 304.144938 -53.196785) (xy 304.092871 -53.272486)
			(xy 304.034488 -53.34343) (xy 303.970223 -53.409093) (xy 303.956983 -53.420475) (xy 422.233084 -53.420475)
			(xy 422.233084 -53.356553) (xy 422.241095 -53.293135) (xy 422.256992 -53.231221) (xy 422.280524 -53.171788)
			(xy 422.311318 -53.115773) (xy 422.348891 -53.064058) (xy 422.392648 -53.017461) (xy 422.441901 -52.976716)
			(xy 422.495872 -52.942465) (xy 422.553711 -52.915248) (xy 422.614504 -52.895495) (xy 422.677294 -52.883517)
			(xy 422.74109 -52.879504) (xy 422.804886 -52.883517) (xy 422.867676 -52.895495) (xy 422.928469 -52.915248)
			(xy 422.986308 -52.942465) (xy 423.040279 -52.976716) (xy 423.056238 -52.989918) (xy 431.237386 -52.989918)
			(xy 431.237386 -52.905222) (xy 431.245437 -52.820908) (xy 431.261466 -52.737742) (xy 431.285327 -52.656475)
			(xy 431.316806 -52.577845) (xy 431.355617 -52.502564) (xy 431.401407 -52.431312) (xy 431.453763 -52.364736)
			(xy 431.512211 -52.303438) (xy 431.576221 -52.247973) (xy 431.645213 -52.198844) (xy 431.718563 -52.156495)
			(xy 431.795606 -52.121311) (xy 431.875645 -52.093609) (xy 431.957954 -52.073641) (xy 432.041789 -52.061588)
			(xy 432.12639 -52.057558) (xy 432.210991 -52.061588) (xy 432.294826 -52.073641) (xy 432.377135 -52.093609)
			(xy 432.457174 -52.121311) (xy 432.534217 -52.156495) (xy 432.607567 -52.198844) (xy 432.676559 -52.247973)
			(xy 432.740569 -52.303438) (xy 432.799017 -52.364736) (xy 432.851373 -52.431312) (xy 432.897163 -52.502564)
			(xy 432.935974 -52.577845) (xy 432.967453 -52.656475) (xy 432.991314 -52.737742) (xy 433.007343 -52.820908)
			(xy 433.015394 -52.905222) (xy 433.015898 -52.94757) (xy 433.015394 -52.989918) (xy 438.952636 -52.989918)
			(xy 438.952636 -52.905222) (xy 438.960687 -52.820908) (xy 438.976716 -52.737742) (xy 439.000577 -52.656475)
			(xy 439.032056 -52.577845) (xy 439.070867 -52.502564) (xy 439.116657 -52.431312) (xy 439.169013 -52.364736)
			(xy 439.227461 -52.303438) (xy 439.291471 -52.247973) (xy 439.360463 -52.198844) (xy 439.433813 -52.156495)
			(xy 439.510856 -52.121311) (xy 439.590895 -52.093609) (xy 439.673204 -52.073641) (xy 439.757039 -52.061588)
			(xy 439.84164 -52.057558) (xy 439.926241 -52.061588) (xy 440.010076 -52.073641) (xy 440.092385 -52.093609)
			(xy 440.172424 -52.121311) (xy 440.249467 -52.156495) (xy 440.322817 -52.198844) (xy 440.391809 -52.247973)
			(xy 440.455819 -52.303438) (xy 440.514267 -52.364736) (xy 440.566623 -52.431312) (xy 440.612413 -52.502564)
			(xy 440.651224 -52.577845) (xy 440.682703 -52.656475) (xy 440.706564 -52.737742) (xy 440.722593 -52.820908)
			(xy 440.730644 -52.905222) (xy 440.731148 -52.94757) (xy 440.730644 -52.989918) (xy 440.722593 -53.074232)
			(xy 440.706564 -53.157398) (xy 440.682703 -53.238665) (xy 440.651224 -53.317295) (xy 440.612413 -53.392576)
			(xy 440.566623 -53.463828) (xy 440.514267 -53.530404) (xy 440.455819 -53.591702) (xy 440.391809 -53.647167)
			(xy 440.322817 -53.696296) (xy 440.249467 -53.738645) (xy 440.172424 -53.773829) (xy 440.092385 -53.801531)
			(xy 440.010076 -53.821499) (xy 439.926241 -53.833552) (xy 439.84164 -53.837583) (xy 439.757039 -53.833552)
			(xy 439.673204 -53.821499) (xy 439.590895 -53.801531) (xy 439.510856 -53.773829) (xy 439.433813 -53.738645)
			(xy 439.360463 -53.696296) (xy 439.291471 -53.647167) (xy 439.227461 -53.591702) (xy 439.169013 -53.530404)
			(xy 439.116657 -53.463828) (xy 439.070867 -53.392576) (xy 439.032056 -53.317295) (xy 439.000577 -53.238665)
			(xy 438.976716 -53.157398) (xy 438.960687 -53.074232) (xy 438.952636 -52.989918) (xy 433.015394 -52.989918)
			(xy 433.007343 -53.074232) (xy 432.991314 -53.157398) (xy 432.967453 -53.238665) (xy 432.935974 -53.317295)
			(xy 432.897163 -53.392576) (xy 432.851373 -53.463828) (xy 432.799017 -53.530404) (xy 432.740569 -53.591702)
			(xy 432.676559 -53.647167) (xy 432.607567 -53.696296) (xy 432.534217 -53.738645) (xy 432.457174 -53.773829)
			(xy 432.377135 -53.801531) (xy 432.294826 -53.821499) (xy 432.210991 -53.833552) (xy 432.12639 -53.837583)
			(xy 432.041789 -53.833552) (xy 431.957954 -53.821499) (xy 431.875645 -53.801531) (xy 431.795606 -53.773829)
			(xy 431.718563 -53.738645) (xy 431.645213 -53.696296) (xy 431.576221 -53.647167) (xy 431.512211 -53.591702)
			(xy 431.453763 -53.530404) (xy 431.401407 -53.463828) (xy 431.355617 -53.392576) (xy 431.316806 -53.317295)
			(xy 431.285327 -53.238665) (xy 431.261466 -53.157398) (xy 431.245437 -53.074232) (xy 431.237386 -52.989918)
			(xy 423.056238 -52.989918) (xy 423.089532 -53.017461) (xy 423.133289 -53.064058) (xy 423.170862 -53.115773)
			(xy 423.201656 -53.171788) (xy 423.225188 -53.231221) (xy 423.241085 -53.293135) (xy 423.249096 -53.356553)
			(xy 423.249598 -53.388514) (xy 423.249096 -53.420475) (xy 423.241085 -53.483893) (xy 423.225188 -53.545807)
			(xy 423.201656 -53.60524) (xy 423.170862 -53.661255) (xy 423.133289 -53.71297) (xy 423.089532 -53.759567)
			(xy 423.040279 -53.800312) (xy 422.986308 -53.834563) (xy 422.928469 -53.86178) (xy 422.867676 -53.881533)
			(xy 422.804886 -53.893511) (xy 422.74109 -53.897525) (xy 422.677294 -53.893511) (xy 422.614504 -53.881533)
			(xy 422.553711 -53.86178) (xy 422.495872 -53.834563) (xy 422.441901 -53.800312) (xy 422.392648 -53.759567)
			(xy 422.348891 -53.71297) (xy 422.311318 -53.661255) (xy 422.280524 -53.60524) (xy 422.256992 -53.545807)
			(xy 422.241095 -53.483893) (xy 422.233084 -53.420475) (xy 303.956983 -53.420475) (xy 303.900551 -53.468989)
			(xy 303.825988 -53.522673) (xy 303.747086 -53.569749) (xy 303.664429 -53.609868) (xy 303.57863 -53.642733)
			(xy 303.490322 -53.6681) (xy 303.400162 -53.685782) (xy 303.308814 -53.695648) (xy 303.216957 -53.697625)
			(xy 303.12527 -53.691698) (xy 303.034432 -53.677912) (xy 302.945115 -53.656367) (xy 302.857981 -53.627224)
			(xy 302.773675 -53.590698) (xy 302.692821 -53.54706) (xy 302.616017 -53.496633) (xy 302.543833 -53.439791)
			(xy 302.476802 -53.376953) (xy 302.415421 -53.308586) (xy 302.360145 -53.235196) (xy 302.311382 -53.157325)
			(xy 302.269494 -53.07555) (xy 302.234791 -52.990478) (xy 302.207529 -52.902737) (xy 302.187912 -52.812977)
			(xy 302.176082 -52.721863) (xy 302.17213 -52.63007) (xy 301.76724 -52.63007) (xy 301.766746 -52.676009)
			(xy 301.758848 -52.767548) (xy 301.743109 -52.858068) (xy 301.719648 -52.946901) (xy 301.688637 -53.033388)
			(xy 301.650306 -53.116888) (xy 301.604938 -53.196785) (xy 301.552871 -53.272486) (xy 301.494488 -53.34343)
			(xy 301.430223 -53.409093) (xy 301.360551 -53.468989) (xy 301.285988 -53.522673) (xy 301.207086 -53.569749)
			(xy 301.124429 -53.609868) (xy 301.03863 -53.642733) (xy 300.950322 -53.6681) (xy 300.860162 -53.685782)
			(xy 300.768814 -53.695648) (xy 300.676957 -53.697625) (xy 300.58527 -53.691698) (xy 300.494432 -53.677912)
			(xy 300.405115 -53.656367) (xy 300.317981 -53.627224) (xy 300.233675 -53.590698) (xy 300.152821 -53.54706)
			(xy 300.076017 -53.496633) (xy 300.003833 -53.439791) (xy 299.936802 -53.376953) (xy 299.875421 -53.308586)
			(xy 299.820145 -53.235196) (xy 299.771382 -53.157325) (xy 299.729494 -53.07555) (xy 299.694791 -52.990478)
			(xy 299.667529 -52.902737) (xy 299.647912 -52.812977) (xy 299.636082 -52.721863) (xy 299.63213 -52.63007)
			(xy 299.22724 -52.63007) (xy 299.226746 -52.676009) (xy 299.218848 -52.767548) (xy 299.203109 -52.858068)
			(xy 299.179648 -52.946901) (xy 299.148637 -53.033388) (xy 299.110306 -53.116888) (xy 299.064938 -53.196785)
			(xy 299.012871 -53.272486) (xy 298.954488 -53.34343) (xy 298.890223 -53.409093) (xy 298.820551 -53.468989)
			(xy 298.745988 -53.522673) (xy 298.667086 -53.569749) (xy 298.584429 -53.609868) (xy 298.49863 -53.642733)
			(xy 298.410322 -53.6681) (xy 298.320162 -53.685782) (xy 298.228814 -53.695648) (xy 298.136957 -53.697625)
			(xy 298.04527 -53.691698) (xy 297.954432 -53.677912) (xy 297.865115 -53.656367) (xy 297.777981 -53.627224)
			(xy 297.693675 -53.590698) (xy 297.612821 -53.54706) (xy 297.536017 -53.496633) (xy 297.463833 -53.439791)
			(xy 297.396802 -53.376953) (xy 297.335421 -53.308586) (xy 297.280145 -53.235196) (xy 297.231382 -53.157325)
			(xy 297.189494 -53.07555) (xy 297.154791 -52.990478) (xy 297.127529 -52.902737) (xy 297.107912 -52.812977)
			(xy 297.096082 -52.721863) (xy 297.09213 -52.63007) (xy 293.945655 -52.63007) (xy 293.946078 -52.633415)
			(xy 293.94658 -52.665376) (xy 293.946078 -52.697337) (xy 293.938067 -52.760755) (xy 293.92217 -52.822669)
			(xy 293.898638 -52.882102) (xy 293.867844 -52.938117) (xy 293.830271 -52.989832) (xy 293.786514 -53.036429)
			(xy 293.737261 -53.077174) (xy 293.68329 -53.111425) (xy 293.625451 -53.138642) (xy 293.564658 -53.158395)
			(xy 293.501868 -53.170373) (xy 293.438072 -53.174387) (xy 293.374276 -53.170373) (xy 293.311486 -53.158395)
			(xy 293.250693 -53.138642) (xy 293.192854 -53.111425) (xy 293.138883 -53.077174) (xy 293.08963 -53.036429)
			(xy 293.045873 -52.989832) (xy 293.0083 -52.938117) (xy 292.977506 -52.882102) (xy 292.953974 -52.822669)
			(xy 292.938077 -52.760755) (xy 292.930066 -52.697337) (xy 292.637978 -52.697337) (xy 292.629967 -52.760755)
			(xy 292.61407 -52.822669) (xy 292.590538 -52.882102) (xy 292.559744 -52.938117) (xy 292.522171 -52.989832)
			(xy 292.478414 -53.036429) (xy 292.429161 -53.077174) (xy 292.37519 -53.111425) (xy 292.317351 -53.138642)
			(xy 292.256558 -53.158395) (xy 292.193768 -53.170373) (xy 292.129972 -53.174387) (xy 292.066176 -53.170373)
			(xy 292.003386 -53.158395) (xy 291.942593 -53.138642) (xy 291.884754 -53.111425) (xy 291.830783 -53.077174)
			(xy 291.78153 -53.036429) (xy 291.737773 -52.989832) (xy 291.7002 -52.938117) (xy 291.669406 -52.882102)
			(xy 291.645874 -52.822669) (xy 291.629977 -52.760755) (xy 291.621966 -52.697337) (xy 275.0947 -52.697337)
			(xy 275.0947 -53.967337) (xy 291.621966 -53.967337) (xy 291.621966 -53.903415) (xy 291.629977 -53.839997)
			(xy 291.645874 -53.778083) (xy 291.669406 -53.71865) (xy 291.7002 -53.662635) (xy 291.737773 -53.61092)
			(xy 291.78153 -53.564323) (xy 291.830783 -53.523578) (xy 291.884754 -53.489327) (xy 291.942593 -53.46211)
			(xy 292.003386 -53.442357) (xy 292.066176 -53.430379) (xy 292.129972 -53.426366) (xy 292.193768 -53.430379)
			(xy 292.256558 -53.442357) (xy 292.317351 -53.46211) (xy 292.37519 -53.489327) (xy 292.429161 -53.523578)
			(xy 292.478414 -53.564323) (xy 292.522171 -53.61092) (xy 292.559744 -53.662635) (xy 292.590538 -53.71865)
			(xy 292.61407 -53.778083) (xy 292.629967 -53.839997) (xy 292.637978 -53.903415) (xy 292.63848 -53.935376)
			(xy 292.637978 -53.967337) (xy 292.930066 -53.967337) (xy 292.930066 -53.903415) (xy 292.938077 -53.839997)
			(xy 292.953974 -53.778083) (xy 292.977506 -53.71865) (xy 293.0083 -53.662635) (xy 293.045873 -53.61092)
			(xy 293.08963 -53.564323) (xy 293.138883 -53.523578) (xy 293.192854 -53.489327) (xy 293.250693 -53.46211)
			(xy 293.311486 -53.442357) (xy 293.374276 -53.430379) (xy 293.438072 -53.426366) (xy 293.501868 -53.430379)
			(xy 293.564658 -53.442357) (xy 293.625451 -53.46211) (xy 293.68329 -53.489327) (xy 293.737261 -53.523578)
			(xy 293.786514 -53.564323) (xy 293.830271 -53.61092) (xy 293.867844 -53.662635) (xy 293.898638 -53.71865)
			(xy 293.92217 -53.778083) (xy 293.938067 -53.839997) (xy 293.946078 -53.903415) (xy 293.94658 -53.935376)
			(xy 293.946078 -53.967337) (xy 293.938067 -54.030755) (xy 293.92217 -54.092669) (xy 293.898638 -54.152102)
			(xy 293.867844 -54.208117) (xy 293.867835 -54.208129) (xy 324.471532 -54.208129) (xy 324.471532 -54.144207)
			(xy 324.479543 -54.080789) (xy 324.49544 -54.018875) (xy 324.518972 -53.959442) (xy 324.549766 -53.903427)
			(xy 324.587339 -53.851712) (xy 324.631096 -53.805115) (xy 324.680349 -53.76437) (xy 324.73432 -53.730119)
			(xy 324.792159 -53.702902) (xy 324.852952 -53.683149) (xy 324.915742 -53.671171) (xy 324.979538 -53.667158)
			(xy 325.043334 -53.671171) (xy 325.106124 -53.683149) (xy 325.166917 -53.702902) (xy 325.224756 -53.730119)
			(xy 325.278727 -53.76437) (xy 325.32798 -53.805115) (xy 325.371737 -53.851712) (xy 325.40931 -53.903427)
			(xy 325.440104 -53.959442) (xy 325.463636 -54.018875) (xy 325.479533 -54.080789) (xy 325.480833 -54.091078)
			(xy 452.613774 -54.091078) (xy 452.617845 -54.035456) (xy 452.629971 -53.981019) (xy 452.649894 -53.928928)
			(xy 452.67719 -53.880293) (xy 452.711276 -53.83615) (xy 452.751425 -53.797441) (xy 452.796783 -53.76499)
			(xy 452.846383 -53.739489) (xy 452.899167 -53.721482) (xy 452.95401 -53.711352) (xy 453.009744 -53.709315)
			(xy 453.065181 -53.715415) (xy 453.119138 -53.729521) (xy 453.170467 -53.751333) (xy 453.218073 -53.780387)
			(xy 453.260941 -53.816062) (xy 453.298158 -53.857599) (xy 453.328931 -53.904112) (xy 453.352603 -53.954609)
			(xy 453.368671 -54.008016) (xy 453.376791 -54.063192) (xy 453.3773 -54.091078) (xy 453.376791 -54.118964)
			(xy 453.368671 -54.17414) (xy 453.352603 -54.227547) (xy 453.328931 -54.278044) (xy 453.298158 -54.324557)
			(xy 453.260941 -54.366094) (xy 453.218073 -54.401769) (xy 453.170467 -54.430823) (xy 453.119138 -54.452635)
			(xy 453.065181 -54.466741) (xy 453.009744 -54.472841) (xy 452.95401 -54.470804) (xy 452.899167 -54.460674)
			(xy 452.846383 -54.442667) (xy 452.796783 -54.417166) (xy 452.751425 -54.384715) (xy 452.711276 -54.346006)
			(xy 452.67719 -54.301863) (xy 452.649894 -54.253228) (xy 452.629971 -54.201137) (xy 452.617845 -54.1467)
			(xy 452.613774 -54.091078) (xy 325.480833 -54.091078) (xy 325.487544 -54.144207) (xy 325.488046 -54.176168)
			(xy 325.487544 -54.208129) (xy 325.479533 -54.271547) (xy 325.463636 -54.333461) (xy 325.440104 -54.392894)
			(xy 325.40931 -54.448909) (xy 325.371737 -54.500624) (xy 325.32798 -54.547221) (xy 325.278727 -54.587966)
			(xy 325.224756 -54.622217) (xy 325.166917 -54.649434) (xy 325.106124 -54.669187) (xy 325.043334 -54.681165)
			(xy 324.979538 -54.685179) (xy 324.915742 -54.681165) (xy 324.852952 -54.669187) (xy 324.792159 -54.649434)
			(xy 324.73432 -54.622217) (xy 324.680349 -54.587966) (xy 324.631096 -54.547221) (xy 324.587339 -54.500624)
			(xy 324.549766 -54.448909) (xy 324.518972 -54.392894) (xy 324.49544 -54.333461) (xy 324.479543 -54.271547)
			(xy 324.471532 -54.208129) (xy 293.867835 -54.208129) (xy 293.830271 -54.259832) (xy 293.786514 -54.306429)
			(xy 293.737261 -54.347174) (xy 293.68329 -54.381425) (xy 293.625451 -54.408642) (xy 293.564658 -54.428395)
			(xy 293.501868 -54.440373) (xy 293.438072 -54.444387) (xy 293.374276 -54.440373) (xy 293.311486 -54.428395)
			(xy 293.250693 -54.408642) (xy 293.192854 -54.381425) (xy 293.138883 -54.347174) (xy 293.08963 -54.306429)
			(xy 293.045873 -54.259832) (xy 293.0083 -54.208117) (xy 292.977506 -54.152102) (xy 292.953974 -54.092669)
			(xy 292.938077 -54.030755) (xy 292.930066 -53.967337) (xy 292.637978 -53.967337) (xy 292.629967 -54.030755)
			(xy 292.61407 -54.092669) (xy 292.590538 -54.152102) (xy 292.559744 -54.208117) (xy 292.522171 -54.259832)
			(xy 292.478414 -54.306429) (xy 292.429161 -54.347174) (xy 292.37519 -54.381425) (xy 292.317351 -54.408642)
			(xy 292.256558 -54.428395) (xy 292.193768 -54.440373) (xy 292.129972 -54.444387) (xy 292.066176 -54.440373)
			(xy 292.003386 -54.428395) (xy 291.942593 -54.408642) (xy 291.884754 -54.381425) (xy 291.830783 -54.347174)
			(xy 291.78153 -54.306429) (xy 291.737773 -54.259832) (xy 291.7002 -54.208117) (xy 291.669406 -54.152102)
			(xy 291.645874 -54.092669) (xy 291.629977 -54.030755) (xy 291.621966 -53.967337) (xy 275.0947 -53.967337)
			(xy 275.0947 -55.21352) (xy 297.220126 -55.21352) (xy 297.220126 -55.12662) (xy 297.228144 -55.040091)
			(xy 297.244112 -54.954671) (xy 297.267893 -54.871089) (xy 297.299285 -54.790057) (xy 297.338019 -54.712268)
			(xy 297.383766 -54.638384) (xy 297.436135 -54.569037) (xy 297.494679 -54.504817) (xy 297.558899 -54.446273)
			(xy 297.628246 -54.393904) (xy 297.70213 -54.348157) (xy 297.779919 -54.309423) (xy 297.860951 -54.278031)
			(xy 297.944533 -54.25425) (xy 298.029953 -54.238282) (xy 298.116482 -54.230264) (xy 298.203382 -54.230264)
			(xy 298.289911 -54.238282) (xy 298.375331 -54.25425) (xy 298.458913 -54.278031) (xy 298.539945 -54.309423)
			(xy 298.617734 -54.348157) (xy 298.691618 -54.393904) (xy 298.760965 -54.446273) (xy 298.825185 -54.504817)
			(xy 298.883729 -54.569037) (xy 298.936098 -54.638384) (xy 298.981845 -54.712268) (xy 299.020579 -54.790057)
			(xy 299.051971 -54.871089) (xy 299.075752 -54.954671) (xy 299.09172 -55.040091) (xy 299.099738 -55.12662)
			(xy 299.10024 -55.17007) (xy 299.099738 -55.21352) (xy 299.760126 -55.21352) (xy 299.760126 -55.12662)
			(xy 299.768144 -55.040091) (xy 299.784112 -54.954671) (xy 299.807893 -54.871089) (xy 299.839285 -54.790057)
			(xy 299.878019 -54.712268) (xy 299.923766 -54.638384) (xy 299.976135 -54.569037) (xy 300.034679 -54.504817)
			(xy 300.098899 -54.446273) (xy 300.168246 -54.393904) (xy 300.24213 -54.348157) (xy 300.319919 -54.309423)
			(xy 300.400951 -54.278031) (xy 300.484533 -54.25425) (xy 300.569953 -54.238282) (xy 300.656482 -54.230264)
			(xy 300.743382 -54.230264) (xy 300.829911 -54.238282) (xy 300.915331 -54.25425) (xy 300.998913 -54.278031)
			(xy 301.079945 -54.309423) (xy 301.157734 -54.348157) (xy 301.231618 -54.393904) (xy 301.300965 -54.446273)
			(xy 301.365185 -54.504817) (xy 301.423729 -54.569037) (xy 301.476098 -54.638384) (xy 301.521845 -54.712268)
			(xy 301.560579 -54.790057) (xy 301.591971 -54.871089) (xy 301.615752 -54.954671) (xy 301.63172 -55.040091)
			(xy 301.639738 -55.12662) (xy 301.64024 -55.17007) (xy 301.639738 -55.21352) (xy 302.300126 -55.21352)
			(xy 302.300126 -55.12662) (xy 302.308144 -55.040091) (xy 302.324112 -54.954671) (xy 302.347893 -54.871089)
			(xy 302.379285 -54.790057) (xy 302.418019 -54.712268) (xy 302.463766 -54.638384) (xy 302.516135 -54.569037)
			(xy 302.574679 -54.504817) (xy 302.638899 -54.446273) (xy 302.708246 -54.393904) (xy 302.78213 -54.348157)
			(xy 302.859919 -54.309423) (xy 302.940951 -54.278031) (xy 303.024533 -54.25425) (xy 303.109953 -54.238282)
			(xy 303.196482 -54.230264) (xy 303.283382 -54.230264) (xy 303.369911 -54.238282) (xy 303.455331 -54.25425)
			(xy 303.538913 -54.278031) (xy 303.619945 -54.309423) (xy 303.697734 -54.348157) (xy 303.771618 -54.393904)
			(xy 303.840965 -54.446273) (xy 303.905185 -54.504817) (xy 303.963729 -54.569037) (xy 304.016098 -54.638384)
			(xy 304.061845 -54.712268) (xy 304.100579 -54.790057) (xy 304.131971 -54.871089) (xy 304.155752 -54.954671)
			(xy 304.168755 -55.024231) (xy 384.989826 -55.024231) (xy 384.989826 -54.960309) (xy 384.997837 -54.896891)
			(xy 385.013734 -54.834977) (xy 385.037266 -54.775544) (xy 385.06806 -54.719529) (xy 385.105633 -54.667814)
			(xy 385.14939 -54.621217) (xy 385.198643 -54.580472) (xy 385.252614 -54.546221) (xy 385.310453 -54.519004)
			(xy 385.371246 -54.499251) (xy 385.434036 -54.487273) (xy 385.497832 -54.48326) (xy 385.561628 -54.487273)
			(xy 385.624418 -54.499251) (xy 385.685211 -54.519004) (xy 385.74305 -54.546221) (xy 385.797021 -54.580472)
			(xy 385.846274 -54.621217) (xy 385.890031 -54.667814) (xy 385.927604 -54.719529) (xy 385.958398 -54.775544)
			(xy 385.98193 -54.834977) (xy 385.997827 -54.896891) (xy 386.005838 -54.960309) (xy 386.00634 -54.99227)
			(xy 386.006222 -54.999752) (xy 443.693536 -54.999752) (xy 443.693536 -54.945248) (xy 443.701292 -54.891299)
			(xy 443.716646 -54.839002) (xy 443.739286 -54.789423) (xy 443.768751 -54.74357) (xy 443.804441 -54.702376)
			(xy 443.84563 -54.666681) (xy 443.891479 -54.63721) (xy 443.941055 -54.614564) (xy 443.99335 -54.599202)
			(xy 444.047298 -54.591439) (xy 444.07455 -54.59095) (xy 444.102259 -54.59145) (xy 444.157093 -54.599479)
			(xy 444.210187 -54.61536) (xy 444.260423 -54.638759) (xy 444.306744 -54.669183) (xy 444.327788 -54.687216)
			(xy 444.334918 -54.693034) (xy 444.35212 -54.699535) (xy 444.361316 -54.699916) (xy 444.438786 -54.699916)
			(xy 444.455804 -54.693566) (xy 444.462916 -54.687216) (xy 444.483947 -54.669166) (xy 444.530268 -54.638737)
			(xy 444.580507 -54.615338) (xy 444.633605 -54.599462) (xy 444.688443 -54.591443) (xy 444.716154 -54.59095)
			(xy 444.743406 -54.591494) (xy 444.797356 -54.599245) (xy 444.849654 -54.614595) (xy 444.899234 -54.637233)
			(xy 444.945088 -54.666696) (xy 444.986282 -54.702386) (xy 445.021976 -54.743575) (xy 445.051445 -54.789426)
			(xy 445.074089 -54.839003) (xy 445.089445 -54.891299) (xy 445.097203 -54.945248) (xy 445.097203 -54.999752)
			(xy 445.496936 -54.999752) (xy 445.496936 -54.945248) (xy 445.504692 -54.891299) (xy 445.520046 -54.839002)
			(xy 445.542686 -54.789423) (xy 445.572151 -54.74357) (xy 445.607841 -54.702376) (xy 445.64903 -54.666681)
			(xy 445.694879 -54.63721) (xy 445.744455 -54.614564) (xy 445.79675 -54.599202) (xy 445.850698 -54.591439)
			(xy 445.87795 -54.59095) (xy 445.905659 -54.59145) (xy 445.960493 -54.599479) (xy 446.013587 -54.61536)
			(xy 446.063823 -54.638759) (xy 446.110144 -54.669183) (xy 446.131188 -54.687216) (xy 446.138318 -54.693034)
			(xy 446.15552 -54.699535) (xy 446.164716 -54.699916) (xy 446.242186 -54.699916) (xy 446.259204 -54.693566)
			(xy 446.266316 -54.687216) (xy 446.287347 -54.669166) (xy 446.333668 -54.638737) (xy 446.383907 -54.615338)
			(xy 446.437005 -54.599462) (xy 446.491843 -54.591443) (xy 446.519554 -54.59095) (xy 446.546806 -54.591494)
			(xy 446.600756 -54.599245) (xy 446.653054 -54.614595) (xy 446.702634 -54.637233) (xy 446.748488 -54.666696)
			(xy 446.789682 -54.702386) (xy 446.825376 -54.743575) (xy 446.854845 -54.789426) (xy 446.877489 -54.839003)
			(xy 446.892845 -54.891299) (xy 446.900603 -54.945248) (xy 446.900603 -54.999752) (xy 446.898302 -55.015754)
			(xy 447.290138 -55.015754) (xy 447.290138 -54.961246) (xy 447.297895 -54.907294) (xy 447.313251 -54.854994)
			(xy 447.335894 -54.805413) (xy 447.365362 -54.759558) (xy 447.401057 -54.718364) (xy 447.44225 -54.682668)
			(xy 447.488104 -54.653199) (xy 447.537685 -54.630555) (xy 447.589984 -54.615197) (xy 447.643936 -54.607439)
			(xy 447.67119 -54.606952) (xy 447.698898 -54.607487) (xy 447.75373 -54.615508) (xy 447.806824 -54.63138)
			(xy 447.857061 -54.654772) (xy 447.903383 -54.685188) (xy 447.924428 -54.703218) (xy 447.931576 -54.709011)
			(xy 447.948764 -54.715527) (xy 447.957956 -54.715918) (xy 448.035426 -54.715918) (xy 448.052444 -54.709568)
			(xy 448.059556 -54.703218) (xy 448.08061 -54.685196) (xy 448.126925 -54.654764) (xy 448.177158 -54.631359)
			(xy 448.230251 -54.615476) (xy 448.285085 -54.60745) (xy 448.312794 -54.606952) (xy 448.340044 -54.607495)
			(xy 448.39399 -54.61525) (xy 448.446283 -54.630604) (xy 448.495859 -54.653244) (xy 448.506611 -54.660154)
			(xy 449.093538 -54.660154) (xy 449.093538 -54.605646) (xy 449.101295 -54.551694) (xy 449.116651 -54.499394)
			(xy 449.139294 -54.449813) (xy 449.168762 -54.403958) (xy 449.204457 -54.362764) (xy 449.24565 -54.327068)
			(xy 449.291504 -54.297599) (xy 449.341085 -54.274955) (xy 449.393384 -54.259597) (xy 449.447336 -54.251839)
			(xy 449.47459 -54.251352) (xy 449.502298 -54.251887) (xy 449.55713 -54.259908) (xy 449.610224 -54.27578)
			(xy 449.660461 -54.299172) (xy 449.706783 -54.329588) (xy 449.727828 -54.347618) (xy 449.734976 -54.353411)
			(xy 449.752164 -54.359927) (xy 449.761356 -54.360318) (xy 449.838826 -54.360318) (xy 449.855844 -54.353968)
			(xy 449.862956 -54.347618) (xy 449.88401 -54.329596) (xy 449.930325 -54.299164) (xy 449.980558 -54.275759)
			(xy 450.033651 -54.259876) (xy 450.088485 -54.25185) (xy 450.116194 -54.251352) (xy 450.143444 -54.251895)
			(xy 450.19739 -54.25965) (xy 450.249683 -54.275004) (xy 450.299259 -54.297644) (xy 450.345108 -54.327109)
			(xy 450.386297 -54.362799) (xy 450.421988 -54.403987) (xy 450.451453 -54.449836) (xy 450.474094 -54.499411)
			(xy 450.489448 -54.551704) (xy 450.497205 -54.60565) (xy 450.497205 -54.66015) (xy 450.497204 -54.660154)
			(xy 450.871538 -54.660154) (xy 450.871538 -54.605646) (xy 450.879295 -54.551694) (xy 450.894651 -54.499394)
			(xy 450.917294 -54.449813) (xy 450.946762 -54.403958) (xy 450.982457 -54.362764) (xy 451.02365 -54.327068)
			(xy 451.069504 -54.297599) (xy 451.119085 -54.274955) (xy 451.171384 -54.259597) (xy 451.225336 -54.251839)
			(xy 451.25259 -54.251352) (xy 451.280298 -54.251887) (xy 451.33513 -54.259908) (xy 451.388224 -54.27578)
			(xy 451.438461 -54.299172) (xy 451.484783 -54.329588) (xy 451.505828 -54.347618) (xy 451.512976 -54.353411)
			(xy 451.530164 -54.359927) (xy 451.539356 -54.360318) (xy 451.616826 -54.360318) (xy 451.633844 -54.353968)
			(xy 451.640956 -54.347618) (xy 451.66201 -54.329596) (xy 451.708325 -54.299164) (xy 451.758558 -54.275759)
			(xy 451.811651 -54.259876) (xy 451.866485 -54.25185) (xy 451.894194 -54.251352) (xy 451.921444 -54.251895)
			(xy 451.97539 -54.25965) (xy 452.027683 -54.275004) (xy 452.077259 -54.297644) (xy 452.123108 -54.327109)
			(xy 452.164297 -54.362799) (xy 452.199988 -54.403987) (xy 452.229453 -54.449836) (xy 452.252094 -54.499411)
			(xy 452.267448 -54.551704) (xy 452.275205 -54.60565) (xy 452.275205 -54.66015) (xy 452.267448 -54.714096)
			(xy 452.252094 -54.766389) (xy 452.229453 -54.815964) (xy 452.199988 -54.861813) (xy 452.164297 -54.903001)
			(xy 452.123108 -54.938691) (xy 452.077259 -54.968156) (xy 452.027683 -54.990796) (xy 451.97539 -55.00615)
			(xy 451.921444 -55.013905) (xy 451.894194 -55.014368) (xy 451.866486 -55.013837) (xy 451.811654 -55.005815)
			(xy 451.75856 -54.989941) (xy 451.708323 -54.966549) (xy 451.662001 -54.936132) (xy 451.640956 -54.918102)
			(xy 451.633811 -54.912304) (xy 451.61662 -54.90579) (xy 451.607428 -54.905402) (xy 451.529958 -54.905402)
			(xy 451.51294 -54.911752) (xy 451.505828 -54.918102) (xy 451.484783 -54.936134) (xy 451.438466 -54.966565)
			(xy 451.38823 -54.989967) (xy 451.335135 -55.005847) (xy 451.2803 -55.013872) (xy 451.25259 -55.014368)
			(xy 451.225336 -55.013961) (xy 451.171384 -55.006203) (xy 451.119085 -54.990845) (xy 451.069504 -54.968201)
			(xy 451.02365 -54.938732) (xy 450.982457 -54.903036) (xy 450.946762 -54.861842) (xy 450.917294 -54.815987)
			(xy 450.894651 -54.766406) (xy 450.879295 -54.714106) (xy 450.871538 -54.660154) (xy 450.497204 -54.660154)
			(xy 450.489448 -54.714096) (xy 450.474094 -54.766389) (xy 450.451453 -54.815964) (xy 450.421988 -54.861813)
			(xy 450.386297 -54.903001) (xy 450.345108 -54.938691) (xy 450.299259 -54.968156) (xy 450.249683 -54.990796)
			(xy 450.19739 -55.00615) (xy 450.143444 -55.013905) (xy 450.116194 -55.014368) (xy 450.088486 -55.013837)
			(xy 450.033654 -55.005815) (xy 449.98056 -54.989941) (xy 449.930323 -54.966549) (xy 449.884001 -54.936132)
			(xy 449.862956 -54.918102) (xy 449.855811 -54.912304) (xy 449.83862 -54.90579) (xy 449.829428 -54.905402)
			(xy 449.751958 -54.905402) (xy 449.73494 -54.911752) (xy 449.727828 -54.918102) (xy 449.706783 -54.936134)
			(xy 449.660466 -54.966565) (xy 449.61023 -54.989967) (xy 449.557135 -55.005847) (xy 449.5023 -55.013872)
			(xy 449.47459 -55.014368) (xy 449.447336 -55.013961) (xy 449.393384 -55.006203) (xy 449.341085 -54.990845)
			(xy 449.291504 -54.968201) (xy 449.24565 -54.938732) (xy 449.204457 -54.903036) (xy 449.168762 -54.861842)
			(xy 449.139294 -54.815987) (xy 449.116651 -54.766406) (xy 449.101295 -54.714106) (xy 449.093538 -54.660154)
			(xy 448.506611 -54.660154) (xy 448.541708 -54.682709) (xy 448.582897 -54.718399) (xy 448.618588 -54.759587)
			(xy 448.648053 -54.805436) (xy 448.670694 -54.855011) (xy 448.686048 -54.907304) (xy 448.693805 -54.96125)
			(xy 448.693805 -55.01575) (xy 448.686048 -55.069696) (xy 448.670694 -55.121989) (xy 448.648053 -55.171564)
			(xy 448.618588 -55.217413) (xy 448.582897 -55.258601) (xy 448.541708 -55.294291) (xy 448.495859 -55.323756)
			(xy 448.446283 -55.346396) (xy 448.39399 -55.36175) (xy 448.340044 -55.369505) (xy 448.312794 -55.369968)
			(xy 448.285086 -55.369437) (xy 448.230254 -55.361415) (xy 448.17716 -55.345541) (xy 448.126923 -55.322149)
			(xy 448.080601 -55.291732) (xy 448.059556 -55.273702) (xy 448.052411 -55.267904) (xy 448.03522 -55.26139)
			(xy 448.026028 -55.261002) (xy 447.948558 -55.261002) (xy 447.93154 -55.267352) (xy 447.924428 -55.273702)
			(xy 447.903383 -55.291734) (xy 447.857066 -55.322165) (xy 447.80683 -55.345567) (xy 447.753735 -55.361447)
			(xy 447.6989 -55.369472) (xy 447.67119 -55.369968) (xy 447.643936 -55.369561) (xy 447.589984 -55.361803)
			(xy 447.537685 -55.346445) (xy 447.488104 -55.323801) (xy 447.44225 -55.294332) (xy 447.401057 -55.258636)
			(xy 447.365362 -55.217442) (xy 447.335894 -55.171587) (xy 447.313251 -55.122006) (xy 447.297895 -55.069706)
			(xy 447.290138 -55.015754) (xy 446.898302 -55.015754) (xy 446.892845 -55.053701) (xy 446.877489 -55.105997)
			(xy 446.854845 -55.155574) (xy 446.825376 -55.201425) (xy 446.789682 -55.242614) (xy 446.748488 -55.278304)
			(xy 446.702634 -55.307767) (xy 446.653054 -55.330405) (xy 446.600756 -55.345755) (xy 446.546806 -55.353506)
			(xy 446.519554 -55.353966) (xy 446.491845 -55.353459) (xy 446.437012 -55.345431) (xy 446.383918 -55.329552)
			(xy 446.333682 -55.306154) (xy 446.287361 -55.275732) (xy 446.266316 -55.2577) (xy 446.259184 -55.251885)
			(xy 446.241983 -55.245381) (xy 446.232788 -55.245) (xy 446.155318 -55.245) (xy 446.1383 -55.25135)
			(xy 446.131188 -55.2577) (xy 446.110158 -55.275751) (xy 446.063837 -55.306179) (xy 446.013597 -55.329577)
			(xy 445.960499 -55.345453) (xy 445.905661 -55.353472) (xy 445.87795 -55.353966) (xy 445.850698 -55.353561)
			(xy 445.79675 -55.345798) (xy 445.744455 -55.330436) (xy 445.694879 -55.30779) (xy 445.64903 -55.278319)
			(xy 445.607841 -55.242624) (xy 445.572151 -55.20143) (xy 445.542686 -55.155577) (xy 445.520046 -55.105998)
			(xy 445.504692 -55.053701) (xy 445.496936 -54.999752) (xy 445.097203 -54.999752) (xy 445.089445 -55.053701)
			(xy 445.074089 -55.105997) (xy 445.051445 -55.155574) (xy 445.021976 -55.201425) (xy 444.986282 -55.242614)
			(xy 444.945088 -55.278304) (xy 444.899234 -55.307767) (xy 444.849654 -55.330405) (xy 444.797356 -55.345755)
			(xy 444.743406 -55.353506) (xy 444.716154 -55.353966) (xy 444.688445 -55.353459) (xy 444.633612 -55.345431)
			(xy 444.580518 -55.329552) (xy 444.530282 -55.306154) (xy 444.483961 -55.275732) (xy 444.462916 -55.2577)
			(xy 444.455784 -55.251885) (xy 444.438583 -55.245381) (xy 444.429388 -55.245) (xy 444.351918 -55.245)
			(xy 444.3349 -55.25135) (xy 444.327788 -55.2577) (xy 444.306758 -55.275751) (xy 444.260437 -55.306179)
			(xy 444.210197 -55.329577) (xy 444.157099 -55.345453) (xy 444.102261 -55.353472) (xy 444.07455 -55.353966)
			(xy 444.047298 -55.353561) (xy 443.99335 -55.345798) (xy 443.941055 -55.330436) (xy 443.891479 -55.30779)
			(xy 443.84563 -55.278319) (xy 443.804441 -55.242624) (xy 443.768751 -55.20143) (xy 443.739286 -55.155577)
			(xy 443.716646 -55.105998) (xy 443.701292 -55.053701) (xy 443.693536 -54.999752) (xy 386.006222 -54.999752)
			(xy 386.005838 -55.024231) (xy 385.997827 -55.087649) (xy 385.98193 -55.149563) (xy 385.958398 -55.208996)
			(xy 385.927604 -55.265011) (xy 385.890031 -55.316726) (xy 385.846274 -55.363323) (xy 385.797021 -55.404068)
			(xy 385.74305 -55.438319) (xy 385.708018 -55.454804) (xy 394.710156 -55.454804) (xy 394.714227 -55.399182)
			(xy 394.726353 -55.344745) (xy 394.746276 -55.292654) (xy 394.773572 -55.244019) (xy 394.807658 -55.199876)
			(xy 394.847807 -55.161167) (xy 394.893165 -55.128716) (xy 394.942765 -55.103215) (xy 394.995549 -55.085208)
			(xy 395.050392 -55.075078) (xy 395.106126 -55.073041) (xy 395.161563 -55.079141) (xy 395.21552 -55.093247)
			(xy 395.266849 -55.115059) (xy 395.314455 -55.144113) (xy 395.357323 -55.179788) (xy 395.39454 -55.221325)
			(xy 395.425313 -55.267838) (xy 395.448985 -55.318335) (xy 395.465053 -55.371742) (xy 395.473173 -55.426918)
			(xy 395.473682 -55.454804) (xy 395.473173 -55.48269) (xy 395.465053 -55.537866) (xy 395.448985 -55.591273)
			(xy 395.425313 -55.64177) (xy 395.39454 -55.688283) (xy 395.357323 -55.72982) (xy 395.314455 -55.765495)
			(xy 395.266849 -55.794549) (xy 395.21552 -55.816361) (xy 395.161563 -55.830467) (xy 395.106126 -55.836567)
			(xy 395.050392 -55.83453) (xy 394.995549 -55.8244) (xy 394.942765 -55.806393) (xy 394.893165 -55.780892)
			(xy 394.847807 -55.748441) (xy 394.807658 -55.709732) (xy 394.773572 -55.665589) (xy 394.746276 -55.616954)
			(xy 394.726353 -55.564863) (xy 394.714227 -55.510426) (xy 394.710156 -55.454804) (xy 385.708018 -55.454804)
			(xy 385.685211 -55.465536) (xy 385.624418 -55.485289) (xy 385.561628 -55.497267) (xy 385.497832 -55.501281)
			(xy 385.434036 -55.497267) (xy 385.371246 -55.485289) (xy 385.310453 -55.465536) (xy 385.252614 -55.438319)
			(xy 385.198643 -55.404068) (xy 385.14939 -55.363323) (xy 385.105633 -55.316726) (xy 385.06806 -55.265011)
			(xy 385.037266 -55.208996) (xy 385.013734 -55.149563) (xy 384.997837 -55.087649) (xy 384.989826 -55.024231)
			(xy 304.168755 -55.024231) (xy 304.17172 -55.040091) (xy 304.179738 -55.12662) (xy 304.18024 -55.17007)
			(xy 304.179738 -55.21352) (xy 304.17172 -55.300049) (xy 304.155752 -55.385469) (xy 304.131971 -55.469051)
			(xy 304.100579 -55.550083) (xy 304.061845 -55.627872) (xy 304.016098 -55.701756) (xy 303.963729 -55.771103)
			(xy 303.949938 -55.786231) (xy 320.03212 -55.786231) (xy 320.03212 -55.722309) (xy 320.040131 -55.658891)
			(xy 320.056028 -55.596977) (xy 320.07956 -55.537544) (xy 320.110354 -55.481529) (xy 320.147927 -55.429814)
			(xy 320.191684 -55.383217) (xy 320.240937 -55.342472) (xy 320.294908 -55.308221) (xy 320.352747 -55.281004)
			(xy 320.41354 -55.261251) (xy 320.47633 -55.249273) (xy 320.540126 -55.24526) (xy 320.603922 -55.249273)
			(xy 320.666712 -55.261251) (xy 320.727505 -55.281004) (xy 320.785344 -55.308221) (xy 320.839315 -55.342472)
			(xy 320.888568 -55.383217) (xy 320.932325 -55.429814) (xy 320.969898 -55.481529) (xy 321.000692 -55.537544)
			(xy 321.024224 -55.596977) (xy 321.040121 -55.658891) (xy 321.048132 -55.722309) (xy 321.048634 -55.75427)
			(xy 321.048132 -55.786231) (xy 321.044057 -55.818489) (xy 321.909434 -55.818489) (xy 321.909434 -55.754567)
			(xy 321.917445 -55.691149) (xy 321.933342 -55.629235) (xy 321.956874 -55.569802) (xy 321.987668 -55.513787)
			(xy 322.025241 -55.462072) (xy 322.068998 -55.415475) (xy 322.118251 -55.37473) (xy 322.172222 -55.340479)
			(xy 322.230061 -55.313262) (xy 322.290854 -55.293509) (xy 322.353644 -55.281531) (xy 322.41744 -55.277518)
			(xy 322.481236 -55.281531) (xy 322.544026 -55.293509) (xy 322.604819 -55.313262) (xy 322.662658 -55.340479)
			(xy 322.716629 -55.37473) (xy 322.765882 -55.415475) (xy 322.809639 -55.462072) (xy 322.847212 -55.513787)
			(xy 322.878006 -55.569802) (xy 322.901538 -55.629235) (xy 322.917435 -55.691149) (xy 322.925446 -55.754567)
			(xy 322.925948 -55.786528) (xy 322.925557 -55.81142) (xy 384.320286 -55.81142) (xy 384.324357 -55.755798)
			(xy 384.336483 -55.701361) (xy 384.356406 -55.64927) (xy 384.383702 -55.600635) (xy 384.417788 -55.556492)
			(xy 384.457937 -55.517783) (xy 384.503295 -55.485332) (xy 384.552895 -55.459831) (xy 384.605679 -55.441824)
			(xy 384.660522 -55.431694) (xy 384.716256 -55.429657) (xy 384.771693 -55.435757) (xy 384.82565 -55.449863)
			(xy 384.876979 -55.471675) (xy 384.924585 -55.500729) (xy 384.967453 -55.536404) (xy 385.00467 -55.577941)
			(xy 385.035443 -55.624454) (xy 385.059115 -55.674951) (xy 385.075183 -55.728358) (xy 385.083303 -55.783534)
			(xy 385.083812 -55.81142) (xy 385.083303 -55.839306) (xy 385.075183 -55.894482) (xy 385.059115 -55.947889)
			(xy 385.035443 -55.998386) (xy 385.00467 -56.044899) (xy 384.967453 -56.086436) (xy 384.963406 -56.089804)
			(xy 394.075156 -56.089804) (xy 394.079227 -56.034182) (xy 394.091353 -55.979745) (xy 394.111276 -55.927654)
			(xy 394.138572 -55.879019) (xy 394.172658 -55.834876) (xy 394.212807 -55.796167) (xy 394.258165 -55.763716)
			(xy 394.307765 -55.738215) (xy 394.360549 -55.720208) (xy 394.415392 -55.710078) (xy 394.471126 -55.708041)
			(xy 394.526563 -55.714141) (xy 394.58052 -55.728247) (xy 394.631849 -55.750059) (xy 394.679455 -55.779113)
			(xy 394.722323 -55.814788) (xy 394.75954 -55.856325) (xy 394.790313 -55.902838) (xy 394.813985 -55.953335)
			(xy 394.830053 -56.006742) (xy 394.838173 -56.061918) (xy 394.838682 -56.089804) (xy 394.838173 -56.11769)
			(xy 394.830053 -56.172866) (xy 394.813985 -56.226273) (xy 394.790313 -56.27677) (xy 394.75954 -56.323283)
			(xy 394.722323 -56.36482) (xy 394.679455 -56.400495) (xy 394.631849 -56.429549) (xy 394.58052 -56.451361)
			(xy 394.526563 -56.465467) (xy 394.471126 -56.471567) (xy 394.415392 -56.46953) (xy 394.360549 -56.4594)
			(xy 394.307765 -56.441393) (xy 394.258165 -56.415892) (xy 394.212807 -56.383441) (xy 394.172658 -56.344732)
			(xy 394.138572 -56.300589) (xy 394.111276 -56.251954) (xy 394.091353 -56.199863) (xy 394.079227 -56.145426)
			(xy 394.075156 -56.089804) (xy 384.963406 -56.089804) (xy 384.924585 -56.122111) (xy 384.876979 -56.151165)
			(xy 384.82565 -56.172977) (xy 384.771693 -56.187083) (xy 384.716256 -56.193183) (xy 384.660522 -56.191146)
			(xy 384.605679 -56.181016) (xy 384.552895 -56.163009) (xy 384.503295 -56.137508) (xy 384.457937 -56.105057)
			(xy 384.417788 -56.066348) (xy 384.383702 -56.022205) (xy 384.356406 -55.97357) (xy 384.336483 -55.921479)
			(xy 384.324357 -55.867042) (xy 384.320286 -55.81142) (xy 322.925557 -55.81142) (xy 322.925446 -55.818489)
			(xy 322.917435 -55.881907) (xy 322.901538 -55.943821) (xy 322.878006 -56.003254) (xy 322.847212 -56.059269)
			(xy 322.809639 -56.110984) (xy 322.765882 -56.157581) (xy 322.716629 -56.198326) (xy 322.662658 -56.232577)
			(xy 322.604819 -56.259794) (xy 322.544026 -56.279547) (xy 322.481236 -56.291525) (xy 322.41744 -56.295539)
			(xy 322.353644 -56.291525) (xy 322.290854 -56.279547) (xy 322.230061 -56.259794) (xy 322.172222 -56.232577)
			(xy 322.118251 -56.198326) (xy 322.068998 -56.157581) (xy 322.025241 -56.110984) (xy 321.987668 -56.059269)
			(xy 321.956874 -56.003254) (xy 321.933342 -55.943821) (xy 321.917445 -55.881907) (xy 321.909434 -55.818489)
			(xy 321.044057 -55.818489) (xy 321.040121 -55.849649) (xy 321.024224 -55.911563) (xy 321.000692 -55.970996)
			(xy 320.969898 -56.027011) (xy 320.932325 -56.078726) (xy 320.888568 -56.125323) (xy 320.839315 -56.166068)
			(xy 320.785344 -56.200319) (xy 320.727505 -56.227536) (xy 320.666712 -56.247289) (xy 320.603922 -56.259267)
			(xy 320.540126 -56.263281) (xy 320.47633 -56.259267) (xy 320.41354 -56.247289) (xy 320.352747 -56.227536)
			(xy 320.294908 -56.200319) (xy 320.240937 -56.166068) (xy 320.191684 -56.125323) (xy 320.147927 -56.078726)
			(xy 320.110354 -56.027011) (xy 320.07956 -55.970996) (xy 320.056028 -55.911563) (xy 320.040131 -55.849649)
			(xy 320.03212 -55.786231) (xy 303.949938 -55.786231) (xy 303.905185 -55.835323) (xy 303.840965 -55.893867)
			(xy 303.771618 -55.946236) (xy 303.697734 -55.991983) (xy 303.619945 -56.030717) (xy 303.538913 -56.062109)
			(xy 303.455331 -56.08589) (xy 303.369911 -56.101858) (xy 303.283382 -56.109876) (xy 303.196482 -56.109876)
			(xy 303.109953 -56.101858) (xy 303.024533 -56.08589) (xy 302.940951 -56.062109) (xy 302.859919 -56.030717)
			(xy 302.78213 -55.991983) (xy 302.708246 -55.946236) (xy 302.638899 -55.893867) (xy 302.574679 -55.835323)
			(xy 302.516135 -55.771103) (xy 302.463766 -55.701756) (xy 302.418019 -55.627872) (xy 302.379285 -55.550083)
			(xy 302.347893 -55.469051) (xy 302.324112 -55.385469) (xy 302.308144 -55.300049) (xy 302.300126 -55.21352)
			(xy 301.639738 -55.21352) (xy 301.63172 -55.300049) (xy 301.615752 -55.385469) (xy 301.591971 -55.469051)
			(xy 301.560579 -55.550083) (xy 301.521845 -55.627872) (xy 301.476098 -55.701756) (xy 301.423729 -55.771103)
			(xy 301.365185 -55.835323) (xy 301.300965 -55.893867) (xy 301.231618 -55.946236) (xy 301.157734 -55.991983)
			(xy 301.079945 -56.030717) (xy 300.998913 -56.062109) (xy 300.915331 -56.08589) (xy 300.829911 -56.101858)
			(xy 300.743382 -56.109876) (xy 300.656482 -56.109876) (xy 300.569953 -56.101858) (xy 300.484533 -56.08589)
			(xy 300.400951 -56.062109) (xy 300.319919 -56.030717) (xy 300.24213 -55.991983) (xy 300.168246 -55.946236)
			(xy 300.098899 -55.893867) (xy 300.034679 -55.835323) (xy 299.976135 -55.771103) (xy 299.923766 -55.701756)
			(xy 299.878019 -55.627872) (xy 299.839285 -55.550083) (xy 299.807893 -55.469051) (xy 299.784112 -55.385469)
			(xy 299.768144 -55.300049) (xy 299.760126 -55.21352) (xy 299.099738 -55.21352) (xy 299.09172 -55.300049)
			(xy 299.075752 -55.385469) (xy 299.051971 -55.469051) (xy 299.020579 -55.550083) (xy 298.981845 -55.627872)
			(xy 298.936098 -55.701756) (xy 298.883729 -55.771103) (xy 298.825185 -55.835323) (xy 298.760965 -55.893867)
			(xy 298.691618 -55.946236) (xy 298.617734 -55.991983) (xy 298.539945 -56.030717) (xy 298.458913 -56.062109)
			(xy 298.375331 -56.08589) (xy 298.289911 -56.101858) (xy 298.203382 -56.109876) (xy 298.116482 -56.109876)
			(xy 298.029953 -56.101858) (xy 297.944533 -56.08589) (xy 297.860951 -56.062109) (xy 297.779919 -56.030717)
			(xy 297.70213 -55.991983) (xy 297.628246 -55.946236) (xy 297.558899 -55.893867) (xy 297.494679 -55.835323)
			(xy 297.436135 -55.771103) (xy 297.383766 -55.701756) (xy 297.338019 -55.627872) (xy 297.299285 -55.550083)
			(xy 297.267893 -55.469051) (xy 297.244112 -55.385469) (xy 297.228144 -55.300049) (xy 297.220126 -55.21352)
			(xy 275.0947 -55.21352) (xy 275.0947 -56.662785) (xy 406.900374 -56.662785) (xy 406.900374 -56.598863)
			(xy 406.908385 -56.535445) (xy 406.924282 -56.473531) (xy 406.947814 -56.414098) (xy 406.978608 -56.358083)
			(xy 407.016181 -56.306368) (xy 407.059938 -56.259771) (xy 407.109191 -56.219026) (xy 407.163162 -56.184775)
			(xy 407.221001 -56.157558) (xy 407.281794 -56.137805) (xy 407.344584 -56.125827) (xy 407.40838 -56.121814)
			(xy 407.472176 -56.125827) (xy 407.534966 -56.137805) (xy 407.595759 -56.157558) (xy 407.653598 -56.184775)
			(xy 407.707569 -56.219026) (xy 407.756822 -56.259771) (xy 407.800579 -56.306368) (xy 407.83073 -56.347868)
			(xy 413.53562 -56.347868) (xy 413.539691 -56.292246) (xy 413.551817 -56.237809) (xy 413.57174 -56.185718)
			(xy 413.599036 -56.137083) (xy 413.633122 -56.09294) (xy 413.673271 -56.054231) (xy 413.718629 -56.02178)
			(xy 413.768229 -55.996279) (xy 413.821013 -55.978272) (xy 413.875856 -55.968142) (xy 413.93159 -55.966105)
			(xy 413.987027 -55.972205) (xy 414.040984 -55.986311) (xy 414.092313 -56.008123) (xy 414.139919 -56.037177)
			(xy 414.182787 -56.072852) (xy 414.220004 -56.114389) (xy 414.250777 -56.160902) (xy 414.274449 -56.211399)
			(xy 414.290517 -56.264806) (xy 414.298637 -56.319982) (xy 414.299146 -56.347868) (xy 414.298637 -56.375754)
			(xy 414.298037 -56.379829) (xy 418.597836 -56.379829) (xy 418.597836 -56.315907) (xy 418.605847 -56.252489)
			(xy 418.621744 -56.190575) (xy 418.645276 -56.131142) (xy 418.67607 -56.075127) (xy 418.713643 -56.023412)
			(xy 418.7574 -55.976815) (xy 418.806653 -55.93607) (xy 418.860624 -55.901819) (xy 418.918463 -55.874602)
			(xy 418.979256 -55.854849) (xy 419.042046 -55.842871) (xy 419.105842 -55.838858) (xy 419.169638 -55.842871)
			(xy 419.232428 -55.854849) (xy 419.293221 -55.874602) (xy 419.35106 -55.901819) (xy 419.405031 -55.93607)
			(xy 419.454284 -55.976815) (xy 419.498041 -56.023412) (xy 419.535614 -56.075127) (xy 419.548011 -56.097678)
			(xy 424.616624 -56.097678) (xy 424.620695 -56.042056) (xy 424.632821 -55.987619) (xy 424.652744 -55.935528)
			(xy 424.68004 -55.886893) (xy 424.714126 -55.84275) (xy 424.754275 -55.804041) (xy 424.799633 -55.77159)
			(xy 424.849233 -55.746089) (xy 424.902017 -55.728082) (xy 424.95686 -55.717952) (xy 425.012594 -55.715915)
			(xy 425.068031 -55.722015) (xy 425.121988 -55.736121) (xy 425.173317 -55.757933) (xy 425.220923 -55.786987)
			(xy 425.263791 -55.822662) (xy 425.301008 -55.864199) (xy 425.331781 -55.910712) (xy 425.355453 -55.961209)
			(xy 425.371521 -56.014616) (xy 425.379641 -56.069792) (xy 425.38015 -56.097678) (xy 425.379641 -56.125564)
			(xy 425.379041 -56.129639) (xy 426.829976 -56.129639) (xy 426.829976 -56.065717) (xy 426.837987 -56.002299)
			(xy 426.853884 -55.940385) (xy 426.877416 -55.880952) (xy 426.90821 -55.824937) (xy 426.945783 -55.773222)
			(xy 426.98954 -55.726625) (xy 427.038793 -55.68588) (xy 427.092764 -55.651629) (xy 427.150603 -55.624412)
			(xy 427.211396 -55.604659) (xy 427.274186 -55.592681) (xy 427.337982 -55.588668) (xy 427.401778 -55.592681)
			(xy 427.464568 -55.604659) (xy 427.525361 -55.624412) (xy 427.5832 -55.651629) (xy 427.637171 -55.68588)
			(xy 427.686424 -55.726625) (xy 427.730181 -55.773222) (xy 427.767754 -55.824937) (xy 427.798548 -55.880952)
			(xy 427.82208 -55.940385) (xy 427.837977 -56.002299) (xy 427.845988 -56.065717) (xy 427.84649 -56.097678)
			(xy 427.845988 -56.129639) (xy 427.837977 -56.193057) (xy 427.82208 -56.254971) (xy 427.798548 -56.314404)
			(xy 427.767754 -56.370419) (xy 427.730181 -56.422134) (xy 427.686424 -56.468731) (xy 427.637171 -56.509476)
			(xy 427.5832 -56.543727) (xy 427.525361 -56.570944) (xy 427.464568 -56.590697) (xy 427.401778 -56.602675)
			(xy 427.337982 -56.606689) (xy 427.274186 -56.602675) (xy 427.211396 -56.590697) (xy 427.150603 -56.570944)
			(xy 427.092764 -56.543727) (xy 427.038793 -56.509476) (xy 426.98954 -56.468731) (xy 426.945783 -56.422134)
			(xy 426.90821 -56.370419) (xy 426.877416 -56.314404) (xy 426.853884 -56.254971) (xy 426.837987 -56.193057)
			(xy 426.829976 -56.129639) (xy 425.379041 -56.129639) (xy 425.371521 -56.18074) (xy 425.355453 -56.234147)
			(xy 425.331781 -56.284644) (xy 425.301008 -56.331157) (xy 425.263791 -56.372694) (xy 425.220923 -56.408369)
			(xy 425.173317 -56.437423) (xy 425.121988 -56.459235) (xy 425.068031 -56.473341) (xy 425.012594 -56.479441)
			(xy 424.95686 -56.477404) (xy 424.902017 -56.467274) (xy 424.849233 -56.449267) (xy 424.799633 -56.423766)
			(xy 424.754275 -56.391315) (xy 424.714126 -56.352606) (xy 424.68004 -56.308463) (xy 424.652744 -56.259828)
			(xy 424.632821 -56.207737) (xy 424.620695 -56.1533) (xy 424.616624 -56.097678) (xy 419.548011 -56.097678)
			(xy 419.566408 -56.131142) (xy 419.58994 -56.190575) (xy 419.605837 -56.252489) (xy 419.613848 -56.315907)
			(xy 419.61435 -56.347868) (xy 419.613848 -56.379829) (xy 419.605837 -56.443247) (xy 419.58994 -56.505161)
			(xy 419.566408 -56.564594) (xy 419.535614 -56.620609) (xy 419.498041 -56.672324) (xy 419.454284 -56.718921)
			(xy 419.405031 -56.759666) (xy 419.35106 -56.793917) (xy 419.293221 -56.821134) (xy 419.232428 -56.840887)
			(xy 419.169638 -56.852865) (xy 419.105842 -56.856879) (xy 419.042046 -56.852865) (xy 418.979256 -56.840887)
			(xy 418.918463 -56.821134) (xy 418.860624 -56.793917) (xy 418.806653 -56.759666) (xy 418.7574 -56.718921)
			(xy 418.713643 -56.672324) (xy 418.67607 -56.620609) (xy 418.645276 -56.564594) (xy 418.621744 -56.505161)
			(xy 418.605847 -56.443247) (xy 418.597836 -56.379829) (xy 414.298037 -56.379829) (xy 414.290517 -56.43093)
			(xy 414.274449 -56.484337) (xy 414.250777 -56.534834) (xy 414.220004 -56.581347) (xy 414.182787 -56.622884)
			(xy 414.139919 -56.658559) (xy 414.092313 -56.687613) (xy 414.040984 -56.709425) (xy 413.987027 -56.723531)
			(xy 413.93159 -56.729631) (xy 413.875856 -56.727594) (xy 413.821013 -56.717464) (xy 413.768229 -56.699457)
			(xy 413.718629 -56.673956) (xy 413.673271 -56.641505) (xy 413.633122 -56.602796) (xy 413.599036 -56.558653)
			(xy 413.57174 -56.510018) (xy 413.551817 -56.457927) (xy 413.539691 -56.40349) (xy 413.53562 -56.347868)
			(xy 407.83073 -56.347868) (xy 407.838152 -56.358083) (xy 407.868946 -56.414098) (xy 407.892478 -56.473531)
			(xy 407.908375 -56.535445) (xy 407.916386 -56.598863) (xy 407.916888 -56.630824) (xy 407.916386 -56.662785)
			(xy 407.908375 -56.726203) (xy 407.892478 -56.788117) (xy 407.868946 -56.84755) (xy 407.838152 -56.903565)
			(xy 407.800579 -56.95528) (xy 407.756822 -57.001877) (xy 407.707569 -57.042622) (xy 407.653598 -57.076873)
			(xy 407.647805 -57.079599) (xy 415.047932 -57.079599) (xy 415.047932 -57.015677) (xy 415.055943 -56.952259)
			(xy 415.07184 -56.890345) (xy 415.095372 -56.830912) (xy 415.126166 -56.774897) (xy 415.163739 -56.723182)
			(xy 415.207496 -56.676585) (xy 415.256749 -56.63584) (xy 415.31072 -56.601589) (xy 415.368559 -56.574372)
			(xy 415.429352 -56.554619) (xy 415.492142 -56.542641) (xy 415.555938 -56.538628) (xy 415.619734 -56.542641)
			(xy 415.682524 -56.554619) (xy 415.743317 -56.574372) (xy 415.801156 -56.601589) (xy 415.855127 -56.63584)
			(xy 415.90438 -56.676585) (xy 415.948137 -56.723182) (xy 415.98571 -56.774897) (xy 416.016504 -56.830912)
			(xy 416.040036 -56.890345) (xy 416.055933 -56.952259) (xy 416.063944 -57.015677) (xy 416.064446 -57.047638)
			(xy 416.063944 -57.079599) (xy 419.71442 -57.079599) (xy 419.71442 -57.015677) (xy 419.722431 -56.952259)
			(xy 419.738328 -56.890345) (xy 419.76186 -56.830912) (xy 419.792654 -56.774897) (xy 419.830227 -56.723182)
			(xy 419.873984 -56.676585) (xy 419.923237 -56.63584) (xy 419.977208 -56.601589) (xy 420.035047 -56.574372)
			(xy 420.09584 -56.554619) (xy 420.15863 -56.542641) (xy 420.222426 -56.538628) (xy 420.286222 -56.542641)
			(xy 420.349012 -56.554619) (xy 420.409805 -56.574372) (xy 420.467644 -56.601589) (xy 420.521615 -56.63584)
			(xy 420.570868 -56.676585) (xy 420.614625 -56.723182) (xy 420.652198 -56.774897) (xy 420.682992 -56.830912)
			(xy 420.706524 -56.890345) (xy 420.722421 -56.952259) (xy 420.730432 -57.015677) (xy 420.730934 -57.047638)
			(xy 420.730432 -57.079599) (xy 420.98442 -57.079599) (xy 420.98442 -57.015677) (xy 420.992431 -56.952259)
			(xy 421.008328 -56.890345) (xy 421.03186 -56.830912) (xy 421.062654 -56.774897) (xy 421.100227 -56.723182)
			(xy 421.143984 -56.676585) (xy 421.193237 -56.63584) (xy 421.247208 -56.601589) (xy 421.305047 -56.574372)
			(xy 421.36584 -56.554619) (xy 421.42863 -56.542641) (xy 421.492426 -56.538628) (xy 421.556222 -56.542641)
			(xy 421.619012 -56.554619) (xy 421.679805 -56.574372) (xy 421.737644 -56.601589) (xy 421.791615 -56.63584)
			(xy 421.840868 -56.676585) (xy 421.884625 -56.723182) (xy 421.922198 -56.774897) (xy 421.952992 -56.830912)
			(xy 421.976524 -56.890345) (xy 421.992421 -56.952259) (xy 422.000432 -57.015677) (xy 422.000934 -57.047638)
			(xy 422.000432 -57.079599) (xy 421.992421 -57.143017) (xy 421.976524 -57.204931) (xy 421.952992 -57.264364)
			(xy 421.922198 -57.320379) (xy 421.884625 -57.372094) (xy 421.840868 -57.418691) (xy 421.791615 -57.459436)
			(xy 421.737644 -57.493687) (xy 421.679805 -57.520904) (xy 421.619012 -57.540657) (xy 421.556222 -57.552635)
			(xy 421.492426 -57.556649) (xy 421.42863 -57.552635) (xy 421.36584 -57.540657) (xy 421.305047 -57.520904)
			(xy 421.247208 -57.493687) (xy 421.193237 -57.459436) (xy 421.143984 -57.418691) (xy 421.100227 -57.372094)
			(xy 421.062654 -57.320379) (xy 421.03186 -57.264364) (xy 421.008328 -57.204931) (xy 420.992431 -57.143017)
			(xy 420.98442 -57.079599) (xy 420.730432 -57.079599) (xy 420.722421 -57.143017) (xy 420.706524 -57.204931)
			(xy 420.682992 -57.264364) (xy 420.652198 -57.320379) (xy 420.614625 -57.372094) (xy 420.570868 -57.418691)
			(xy 420.521615 -57.459436) (xy 420.467644 -57.493687) (xy 420.409805 -57.520904) (xy 420.349012 -57.540657)
			(xy 420.286222 -57.552635) (xy 420.222426 -57.556649) (xy 420.15863 -57.552635) (xy 420.09584 -57.540657)
			(xy 420.035047 -57.520904) (xy 419.977208 -57.493687) (xy 419.923237 -57.459436) (xy 419.873984 -57.418691)
			(xy 419.830227 -57.372094) (xy 419.792654 -57.320379) (xy 419.76186 -57.264364) (xy 419.738328 -57.204931)
			(xy 419.722431 -57.143017) (xy 419.71442 -57.079599) (xy 416.063944 -57.079599) (xy 416.055933 -57.143017)
			(xy 416.040036 -57.204931) (xy 416.016504 -57.264364) (xy 415.98571 -57.320379) (xy 415.948137 -57.372094)
			(xy 415.90438 -57.418691) (xy 415.855127 -57.459436) (xy 415.801156 -57.493687) (xy 415.743317 -57.520904)
			(xy 415.682524 -57.540657) (xy 415.619734 -57.552635) (xy 415.555938 -57.556649) (xy 415.492142 -57.552635)
			(xy 415.429352 -57.540657) (xy 415.368559 -57.520904) (xy 415.31072 -57.493687) (xy 415.256749 -57.459436)
			(xy 415.207496 -57.418691) (xy 415.163739 -57.372094) (xy 415.126166 -57.320379) (xy 415.095372 -57.264364)
			(xy 415.07184 -57.204931) (xy 415.055943 -57.143017) (xy 415.047932 -57.079599) (xy 407.647805 -57.079599)
			(xy 407.595759 -57.10409) (xy 407.534966 -57.123843) (xy 407.472176 -57.135821) (xy 407.40838 -57.139835)
			(xy 407.344584 -57.135821) (xy 407.281794 -57.123843) (xy 407.221001 -57.10409) (xy 407.163162 -57.076873)
			(xy 407.109191 -57.042622) (xy 407.059938 -57.001877) (xy 407.016181 -56.95528) (xy 406.978608 -56.903565)
			(xy 406.947814 -56.84755) (xy 406.924282 -56.788117) (xy 406.908385 -56.726203) (xy 406.900374 -56.662785)
			(xy 275.0947 -56.662785) (xy 275.0947 -57.510383) (xy 390.004294 -57.510383) (xy 390.004294 -57.446461)
			(xy 390.012305 -57.383043) (xy 390.028202 -57.321129) (xy 390.051734 -57.261696) (xy 390.082528 -57.205681)
			(xy 390.120101 -57.153966) (xy 390.163858 -57.107369) (xy 390.213111 -57.066624) (xy 390.267082 -57.032373)
			(xy 390.324921 -57.005156) (xy 390.385714 -56.985403) (xy 390.448504 -56.973425) (xy 390.5123 -56.969412)
			(xy 390.576096 -56.973425) (xy 390.638886 -56.985403) (xy 390.699679 -57.005156) (xy 390.757518 -57.032373)
			(xy 390.811489 -57.066624) (xy 390.860742 -57.107369) (xy 390.904499 -57.153966) (xy 390.942072 -57.205681)
			(xy 390.972866 -57.261696) (xy 390.996398 -57.321129) (xy 391.012295 -57.383043) (xy 391.020306 -57.446461)
			(xy 391.020808 -57.478422) (xy 391.020306 -57.510383) (xy 391.012295 -57.573801) (xy 390.996398 -57.635715)
			(xy 390.972866 -57.695148) (xy 390.953795 -57.729839) (xy 413.409632 -57.729839) (xy 413.409632 -57.665917)
			(xy 413.417643 -57.602499) (xy 413.43354 -57.540585) (xy 413.457072 -57.481152) (xy 413.487866 -57.425137)
			(xy 413.525439 -57.373422) (xy 413.569196 -57.326825) (xy 413.618449 -57.28608) (xy 413.67242 -57.251829)
			(xy 413.730259 -57.224612) (xy 413.791052 -57.204859) (xy 413.853842 -57.192881) (xy 413.917638 -57.188868)
			(xy 413.981434 -57.192881) (xy 414.044224 -57.204859) (xy 414.105017 -57.224612) (xy 414.162856 -57.251829)
			(xy 414.216827 -57.28608) (xy 414.26608 -57.326825) (xy 414.309837 -57.373422) (xy 414.34741 -57.425137)
			(xy 414.378204 -57.481152) (xy 414.401736 -57.540585) (xy 414.417633 -57.602499) (xy 414.425644 -57.665917)
			(xy 414.426146 -57.697878) (xy 414.425644 -57.729839) (xy 418.597836 -57.729839) (xy 418.597836 -57.665917)
			(xy 418.605847 -57.602499) (xy 418.621744 -57.540585) (xy 418.645276 -57.481152) (xy 418.67607 -57.425137)
			(xy 418.713643 -57.373422) (xy 418.7574 -57.326825) (xy 418.806653 -57.28608) (xy 418.860624 -57.251829)
			(xy 418.918463 -57.224612) (xy 418.979256 -57.204859) (xy 419.042046 -57.192881) (xy 419.105842 -57.188868)
			(xy 419.169638 -57.192881) (xy 419.232428 -57.204859) (xy 419.293221 -57.224612) (xy 419.35106 -57.251829)
			(xy 419.405031 -57.28608) (xy 419.454284 -57.326825) (xy 419.498041 -57.373422) (xy 419.535614 -57.425137)
			(xy 419.566408 -57.481152) (xy 419.58994 -57.540585) (xy 419.605837 -57.602499) (xy 419.613848 -57.665917)
			(xy 419.61435 -57.697878) (xy 419.613848 -57.729839) (xy 419.605837 -57.793257) (xy 419.58994 -57.855171)
			(xy 419.566408 -57.914604) (xy 419.535614 -57.970619) (xy 419.498041 -58.022334) (xy 419.454284 -58.068931)
			(xy 419.405031 -58.109676) (xy 419.35106 -58.143927) (xy 419.293221 -58.171144) (xy 419.232428 -58.190897)
			(xy 419.169638 -58.202875) (xy 419.105842 -58.206889) (xy 419.042046 -58.202875) (xy 418.979256 -58.190897)
			(xy 418.918463 -58.171144) (xy 418.860624 -58.143927) (xy 418.806653 -58.109676) (xy 418.7574 -58.068931)
			(xy 418.713643 -58.022334) (xy 418.67607 -57.970619) (xy 418.645276 -57.914604) (xy 418.621744 -57.855171)
			(xy 418.605847 -57.793257) (xy 418.597836 -57.729839) (xy 414.425644 -57.729839) (xy 414.417633 -57.793257)
			(xy 414.401736 -57.855171) (xy 414.378204 -57.914604) (xy 414.34741 -57.970619) (xy 414.309837 -58.022334)
			(xy 414.26608 -58.068931) (xy 414.216827 -58.109676) (xy 414.162856 -58.143927) (xy 414.105017 -58.171144)
			(xy 414.044224 -58.190897) (xy 413.981434 -58.202875) (xy 413.917638 -58.206889) (xy 413.853842 -58.202875)
			(xy 413.791052 -58.190897) (xy 413.730259 -58.171144) (xy 413.67242 -58.143927) (xy 413.618449 -58.109676)
			(xy 413.569196 -58.068931) (xy 413.525439 -58.022334) (xy 413.487866 -57.970619) (xy 413.457072 -57.914604)
			(xy 413.43354 -57.855171) (xy 413.417643 -57.793257) (xy 413.409632 -57.729839) (xy 390.953795 -57.729839)
			(xy 390.942072 -57.751163) (xy 390.904499 -57.802878) (xy 390.860742 -57.849475) (xy 390.811489 -57.89022)
			(xy 390.757518 -57.924471) (xy 390.699679 -57.951688) (xy 390.638886 -57.971441) (xy 390.576096 -57.983419)
			(xy 390.5123 -57.987433) (xy 390.448504 -57.983419) (xy 390.385714 -57.971441) (xy 390.324921 -57.951688)
			(xy 390.267082 -57.924471) (xy 390.213111 -57.89022) (xy 390.163858 -57.849475) (xy 390.120101 -57.802878)
			(xy 390.082528 -57.751163) (xy 390.051734 -57.695148) (xy 390.028202 -57.635715) (xy 390.012305 -57.573801)
			(xy 390.004294 -57.510383) (xy 275.0947 -57.510383) (xy 275.0947 -58.625994) (xy 275.094278 -58.636065)
			(xy 275.086565 -58.654671) (xy 275.079714 -58.662062) (xy 274.972315 -58.769461) (xy 388.914634 -58.769461)
			(xy 388.914634 -58.705539) (xy 388.922645 -58.642121) (xy 388.938542 -58.580207) (xy 388.962074 -58.520774)
			(xy 388.992868 -58.464759) (xy 389.030441 -58.413044) (xy 389.074198 -58.366447) (xy 389.123451 -58.325702)
			(xy 389.177422 -58.291451) (xy 389.235261 -58.264234) (xy 389.296054 -58.244481) (xy 389.358844 -58.232503)
			(xy 389.42264 -58.22849) (xy 389.486436 -58.232503) (xy 389.549226 -58.244481) (xy 389.610019 -58.264234)
			(xy 389.667858 -58.291451) (xy 389.721829 -58.325702) (xy 389.771082 -58.366447) (xy 389.801295 -58.398621)
			(xy 404.993342 -58.398621) (xy 404.993342 -58.334699) (xy 405.001353 -58.271281) (xy 405.01725 -58.209367)
			(xy 405.040782 -58.149934) (xy 405.071576 -58.093919) (xy 405.109149 -58.042204) (xy 405.152906 -57.995607)
			(xy 405.202159 -57.954862) (xy 405.25613 -57.920611) (xy 405.313969 -57.893394) (xy 405.374762 -57.873641)
			(xy 405.437552 -57.861663) (xy 405.501348 -57.85765) (xy 405.565144 -57.861663) (xy 405.627934 -57.873641)
			(xy 405.688727 -57.893394) (xy 405.746566 -57.920611) (xy 405.800537 -57.954862) (xy 405.84979 -57.995607)
			(xy 405.893547 -58.042204) (xy 405.93112 -58.093919) (xy 405.961914 -58.149934) (xy 405.985446 -58.209367)
			(xy 406.001343 -58.271281) (xy 406.005049 -58.30062) (xy 406.594562 -58.30062) (xy 406.598633 -58.244998)
			(xy 406.610759 -58.190561) (xy 406.630682 -58.13847) (xy 406.657978 -58.089835) (xy 406.692064 -58.045692)
			(xy 406.732213 -58.006983) (xy 406.777571 -57.974532) (xy 406.827171 -57.949031) (xy 406.879955 -57.931024)
			(xy 406.934798 -57.920894) (xy 406.990532 -57.918857) (xy 407.045969 -57.924957) (xy 407.099926 -57.939063)
			(xy 407.151255 -57.960875) (xy 407.198861 -57.989929) (xy 407.241729 -58.025604) (xy 407.278946 -58.067141)
			(xy 407.309719 -58.113654) (xy 407.333391 -58.164151) (xy 407.349459 -58.217558) (xy 407.357579 -58.272734)
			(xy 407.358088 -58.30062) (xy 407.357579 -58.328506) (xy 407.349459 -58.383682) (xy 407.335641 -58.429609)
			(xy 415.047932 -58.429609) (xy 415.047932 -58.365687) (xy 415.055943 -58.302269) (xy 415.07184 -58.240355)
			(xy 415.095372 -58.180922) (xy 415.126166 -58.124907) (xy 415.163739 -58.073192) (xy 415.207496 -58.026595)
			(xy 415.256749 -57.98585) (xy 415.31072 -57.951599) (xy 415.368559 -57.924382) (xy 415.429352 -57.904629)
			(xy 415.492142 -57.892651) (xy 415.555938 -57.888638) (xy 415.619734 -57.892651) (xy 415.682524 -57.904629)
			(xy 415.743317 -57.924382) (xy 415.801156 -57.951599) (xy 415.855127 -57.98585) (xy 415.90438 -58.026595)
			(xy 415.948137 -58.073192) (xy 415.98571 -58.124907) (xy 416.016504 -58.180922) (xy 416.040036 -58.240355)
			(xy 416.055933 -58.302269) (xy 416.063944 -58.365687) (xy 416.064446 -58.397648) (xy 416.063944 -58.429609)
			(xy 416.055933 -58.493027) (xy 416.05526 -58.495649) (xy 421.621706 -58.495649) (xy 421.621706 -58.431727)
			(xy 421.629717 -58.368309) (xy 421.645614 -58.306395) (xy 421.669146 -58.246962) (xy 421.69994 -58.190947)
			(xy 421.737513 -58.139232) (xy 421.78127 -58.092635) (xy 421.830523 -58.05189) (xy 421.884494 -58.017639)
			(xy 421.942333 -57.990422) (xy 422.003126 -57.970669) (xy 422.065916 -57.958691) (xy 422.129712 -57.954678)
			(xy 422.193508 -57.958691) (xy 422.256298 -57.970669) (xy 422.317091 -57.990422) (xy 422.37493 -58.017639)
			(xy 422.393713 -58.029559) (xy 426.823626 -58.029559) (xy 426.823626 -57.965637) (xy 426.831637 -57.902219)
			(xy 426.847534 -57.840305) (xy 426.871066 -57.780872) (xy 426.90186 -57.724857) (xy 426.939433 -57.673142)
			(xy 426.98319 -57.626545) (xy 427.032443 -57.5858) (xy 427.086414 -57.551549) (xy 427.144253 -57.524332)
			(xy 427.205046 -57.504579) (xy 427.267836 -57.492601) (xy 427.331632 -57.488588) (xy 427.395428 -57.492601)
			(xy 427.458218 -57.504579) (xy 427.519011 -57.524332) (xy 427.57685 -57.551549) (xy 427.630821 -57.5858)
			(xy 427.680074 -57.626545) (xy 427.723831 -57.673142) (xy 427.761404 -57.724857) (xy 427.792198 -57.780872)
			(xy 427.81573 -57.840305) (xy 427.831627 -57.902219) (xy 427.839638 -57.965637) (xy 427.84014 -57.997598)
			(xy 427.839638 -58.029559) (xy 427.831627 -58.092977) (xy 427.81573 -58.154891) (xy 427.792198 -58.214324)
			(xy 427.761404 -58.270339) (xy 427.723831 -58.322054) (xy 427.680074 -58.368651) (xy 427.630821 -58.409396)
			(xy 427.57685 -58.443647) (xy 427.519011 -58.470864) (xy 427.458218 -58.490617) (xy 427.395428 -58.502595)
			(xy 427.331632 -58.506609) (xy 427.267836 -58.502595) (xy 427.205046 -58.490617) (xy 427.144253 -58.470864)
			(xy 427.086414 -58.443647) (xy 427.032443 -58.409396) (xy 426.98319 -58.368651) (xy 426.939433 -58.322054)
			(xy 426.90186 -58.270339) (xy 426.871066 -58.214324) (xy 426.847534 -58.154891) (xy 426.831637 -58.092977)
			(xy 426.823626 -58.029559) (xy 422.393713 -58.029559) (xy 422.428901 -58.05189) (xy 422.478154 -58.092635)
			(xy 422.521911 -58.139232) (xy 422.559484 -58.190947) (xy 422.590278 -58.246962) (xy 422.61381 -58.306395)
			(xy 422.629707 -58.368309) (xy 422.637718 -58.431727) (xy 422.63822 -58.463688) (xy 422.637718 -58.495649)
			(xy 422.629707 -58.559067) (xy 422.61381 -58.620981) (xy 422.590278 -58.680414) (xy 422.559484 -58.736429)
			(xy 422.521911 -58.788144) (xy 422.478154 -58.834741) (xy 422.428901 -58.875486) (xy 422.37493 -58.909737)
			(xy 422.317091 -58.936954) (xy 422.256298 -58.956707) (xy 422.193508 -58.968685) (xy 422.129712 -58.972699)
			(xy 422.065916 -58.968685) (xy 422.003126 -58.956707) (xy 421.942333 -58.936954) (xy 421.884494 -58.909737)
			(xy 421.830523 -58.875486) (xy 421.78127 -58.834741) (xy 421.737513 -58.788144) (xy 421.69994 -58.736429)
			(xy 421.669146 -58.680414) (xy 421.645614 -58.620981) (xy 421.629717 -58.559067) (xy 421.621706 -58.495649)
			(xy 416.05526 -58.495649) (xy 416.040036 -58.554941) (xy 416.016504 -58.614374) (xy 415.98571 -58.670389)
			(xy 415.948137 -58.722104) (xy 415.90438 -58.768701) (xy 415.855127 -58.809446) (xy 415.801156 -58.843697)
			(xy 415.743317 -58.870914) (xy 415.682524 -58.890667) (xy 415.619734 -58.902645) (xy 415.555938 -58.906659)
			(xy 415.492142 -58.902645) (xy 415.429352 -58.890667) (xy 415.368559 -58.870914) (xy 415.31072 -58.843697)
			(xy 415.256749 -58.809446) (xy 415.207496 -58.768701) (xy 415.163739 -58.722104) (xy 415.126166 -58.670389)
			(xy 415.095372 -58.614374) (xy 415.07184 -58.554941) (xy 415.055943 -58.493027) (xy 415.047932 -58.429609)
			(xy 407.335641 -58.429609) (xy 407.333391 -58.437089) (xy 407.309719 -58.487586) (xy 407.278946 -58.534099)
			(xy 407.241729 -58.575636) (xy 407.198861 -58.611311) (xy 407.151255 -58.640365) (xy 407.099926 -58.662177)
			(xy 407.045969 -58.676283) (xy 406.990532 -58.682383) (xy 406.934798 -58.680346) (xy 406.879955 -58.670216)
			(xy 406.827171 -58.652209) (xy 406.777571 -58.626708) (xy 406.732213 -58.594257) (xy 406.692064 -58.555548)
			(xy 406.657978 -58.511405) (xy 406.630682 -58.46277) (xy 406.610759 -58.410679) (xy 406.598633 -58.356242)
			(xy 406.594562 -58.30062) (xy 406.005049 -58.30062) (xy 406.009354 -58.334699) (xy 406.009856 -58.36666)
			(xy 406.009354 -58.398621) (xy 406.001343 -58.462039) (xy 405.985446 -58.523953) (xy 405.961914 -58.583386)
			(xy 405.93112 -58.639401) (xy 405.893547 -58.691116) (xy 405.84979 -58.737713) (xy 405.800537 -58.778458)
			(xy 405.746566 -58.812709) (xy 405.688727 -58.839926) (xy 405.627934 -58.859679) (xy 405.565144 -58.871657)
			(xy 405.501348 -58.875671) (xy 405.437552 -58.871657) (xy 405.374762 -58.859679) (xy 405.313969 -58.839926)
			(xy 405.25613 -58.812709) (xy 405.202159 -58.778458) (xy 405.152906 -58.737713) (xy 405.109149 -58.691116)
			(xy 405.071576 -58.639401) (xy 405.040782 -58.583386) (xy 405.01725 -58.523953) (xy 405.001353 -58.462039)
			(xy 404.993342 -58.398621) (xy 389.801295 -58.398621) (xy 389.814839 -58.413044) (xy 389.852412 -58.464759)
			(xy 389.883206 -58.520774) (xy 389.906738 -58.580207) (xy 389.922635 -58.642121) (xy 389.930646 -58.705539)
			(xy 389.931148 -58.7375) (xy 389.930646 -58.769461) (xy 389.922635 -58.832879) (xy 389.906738 -58.894793)
			(xy 389.883206 -58.954226) (xy 389.852412 -59.010241) (xy 389.814839 -59.061956) (xy 389.771082 -59.108553)
			(xy 389.721829 -59.149298) (xy 389.667858 -59.183549) (xy 389.610019 -59.210766) (xy 389.549226 -59.230519)
			(xy 389.486436 -59.242497) (xy 389.42264 -59.246511) (xy 389.358844 -59.242497) (xy 389.296054 -59.230519)
			(xy 389.235261 -59.210766) (xy 389.177422 -59.183549) (xy 389.123451 -59.149298) (xy 389.074198 -59.108553)
			(xy 389.030441 -59.061956) (xy 388.992868 -59.010241) (xy 388.962074 -58.954226) (xy 388.938542 -58.894793)
			(xy 388.922645 -58.832879) (xy 388.914634 -58.769461) (xy 274.972315 -58.769461) (xy 274.210315 -59.531461)
			(xy 404.190956 -59.531461) (xy 404.190956 -59.467539) (xy 404.198967 -59.404121) (xy 404.214864 -59.342207)
			(xy 404.238396 -59.282774) (xy 404.26919 -59.226759) (xy 404.306763 -59.175044) (xy 404.35052 -59.128447)
			(xy 404.399773 -59.087702) (xy 404.453744 -59.053451) (xy 404.511583 -59.026234) (xy 404.572376 -59.006481)
			(xy 404.635166 -58.994503) (xy 404.698962 -58.99049) (xy 404.762758 -58.994503) (xy 404.825548 -59.006481)
			(xy 404.886341 -59.026234) (xy 404.94418 -59.053451) (xy 404.998151 -59.087702) (xy 405.047404 -59.128447)
			(xy 405.091161 -59.175044) (xy 405.128734 -59.226759) (xy 405.159528 -59.282774) (xy 405.18306 -59.342207)
			(xy 405.198957 -59.404121) (xy 405.206968 -59.467539) (xy 405.20747 -59.4995) (xy 405.206968 -59.531461)
			(xy 405.460956 -59.531461) (xy 405.460956 -59.467539) (xy 405.468967 -59.404121) (xy 405.484864 -59.342207)
			(xy 405.508396 -59.282774) (xy 405.53919 -59.226759) (xy 405.576763 -59.175044) (xy 405.62052 -59.128447)
			(xy 405.669773 -59.087702) (xy 405.723744 -59.053451) (xy 405.781583 -59.026234) (xy 405.842376 -59.006481)
			(xy 405.905166 -58.994503) (xy 405.968962 -58.99049) (xy 406.032758 -58.994503) (xy 406.095548 -59.006481)
			(xy 406.156341 -59.026234) (xy 406.21418 -59.053451) (xy 406.268151 -59.087702) (xy 406.317404 -59.128447)
			(xy 406.361161 -59.175044) (xy 406.377656 -59.197748) (xy 419.840408 -59.197748) (xy 419.844479 -59.142126)
			(xy 419.856605 -59.087689) (xy 419.876528 -59.035598) (xy 419.903824 -58.986963) (xy 419.93791 -58.94282)
			(xy 419.978059 -58.904111) (xy 420.023417 -58.87166) (xy 420.073017 -58.846159) (xy 420.125801 -58.828152)
			(xy 420.180644 -58.818022) (xy 420.236378 -58.815985) (xy 420.291815 -58.822085) (xy 420.345772 -58.836191)
			(xy 420.397101 -58.858003) (xy 420.444707 -58.887057) (xy 420.487575 -58.922732) (xy 420.524792 -58.964269)
			(xy 420.555565 -59.010782) (xy 420.579237 -59.061279) (xy 420.595305 -59.114686) (xy 420.603425 -59.169862)
			(xy 420.603934 -59.197748) (xy 420.603425 -59.225634) (xy 420.595305 -59.28081) (xy 420.579237 -59.334217)
			(xy 420.555565 -59.384714) (xy 420.524792 -59.431227) (xy 420.520515 -59.436) (xy 427.59325 -59.436)
			(xy 427.597321 -59.380378) (xy 427.609447 -59.325941) (xy 427.62937 -59.27385) (xy 427.656666 -59.225215)
			(xy 427.690752 -59.181072) (xy 427.730901 -59.142363) (xy 427.776259 -59.109912) (xy 427.825859 -59.084411)
			(xy 427.878643 -59.066404) (xy 427.933486 -59.056274) (xy 427.98922 -59.054237) (xy 428.044657 -59.060337)
			(xy 428.098614 -59.074443) (xy 428.149943 -59.096255) (xy 428.197549 -59.125309) (xy 428.240417 -59.160984)
			(xy 428.277634 -59.202521) (xy 428.308407 -59.249034) (xy 428.332079 -59.299531) (xy 428.348147 -59.352938)
			(xy 428.356267 -59.408114) (xy 428.356776 -59.436) (xy 428.356267 -59.463886) (xy 428.355667 -59.467961)
			(xy 428.497994 -59.467961) (xy 428.497994 -59.404039) (xy 428.506005 -59.340621) (xy 428.521902 -59.278707)
			(xy 428.545434 -59.219274) (xy 428.576228 -59.163259) (xy 428.613801 -59.111544) (xy 428.657558 -59.064947)
			(xy 428.706811 -59.024202) (xy 428.760782 -58.989951) (xy 428.818621 -58.962734) (xy 428.879414 -58.942981)
			(xy 428.942204 -58.931003) (xy 429.006 -58.92699) (xy 429.069796 -58.931003) (xy 429.132586 -58.942981)
			(xy 429.193379 -58.962734) (xy 429.251218 -58.989951) (xy 429.305189 -59.024202) (xy 429.354442 -59.064947)
			(xy 429.398199 -59.111544) (xy 429.435772 -59.163259) (xy 429.466566 -59.219274) (xy 429.490098 -59.278707)
			(xy 429.505995 -59.340621) (xy 429.514006 -59.404039) (xy 429.514508 -59.436) (xy 429.514006 -59.467961)
			(xy 429.505995 -59.531379) (xy 429.490098 -59.593293) (xy 429.466566 -59.652726) (xy 429.435772 -59.708741)
			(xy 429.398199 -59.760456) (xy 429.354442 -59.807053) (xy 429.305189 -59.847798) (xy 429.251218 -59.882049)
			(xy 429.193379 -59.909266) (xy 429.132586 -59.929019) (xy 429.069796 -59.940997) (xy 429.006 -59.945011)
			(xy 428.942204 -59.940997) (xy 428.879414 -59.929019) (xy 428.818621 -59.909266) (xy 428.760782 -59.882049)
			(xy 428.706811 -59.847798) (xy 428.657558 -59.807053) (xy 428.613801 -59.760456) (xy 428.576228 -59.708741)
			(xy 428.545434 -59.652726) (xy 428.521902 -59.593293) (xy 428.506005 -59.531379) (xy 428.497994 -59.467961)
			(xy 428.355667 -59.467961) (xy 428.348147 -59.519062) (xy 428.332079 -59.572469) (xy 428.308407 -59.622966)
			(xy 428.277634 -59.669479) (xy 428.240417 -59.711016) (xy 428.197549 -59.746691) (xy 428.149943 -59.775745)
			(xy 428.098614 -59.797557) (xy 428.044657 -59.811663) (xy 427.98922 -59.817763) (xy 427.933486 -59.815726)
			(xy 427.878643 -59.805596) (xy 427.825859 -59.787589) (xy 427.776259 -59.762088) (xy 427.730901 -59.729637)
			(xy 427.690752 -59.690928) (xy 427.656666 -59.646785) (xy 427.62937 -59.59815) (xy 427.609447 -59.546059)
			(xy 427.597321 -59.491622) (xy 427.59325 -59.436) (xy 420.520515 -59.436) (xy 420.487575 -59.472764)
			(xy 420.444707 -59.508439) (xy 420.397101 -59.537493) (xy 420.345772 -59.559305) (xy 420.291815 -59.573411)
			(xy 420.236378 -59.579511) (xy 420.180644 -59.577474) (xy 420.125801 -59.567344) (xy 420.073017 -59.549337)
			(xy 420.023417 -59.523836) (xy 419.978059 -59.491385) (xy 419.93791 -59.452676) (xy 419.903824 -59.408533)
			(xy 419.876528 -59.359898) (xy 419.856605 -59.307807) (xy 419.844479 -59.25337) (xy 419.840408 -59.197748)
			(xy 406.377656 -59.197748) (xy 406.398734 -59.226759) (xy 406.429528 -59.282774) (xy 406.45306 -59.342207)
			(xy 406.468957 -59.404121) (xy 406.476968 -59.467539) (xy 406.47747 -59.4995) (xy 406.476968 -59.531461)
			(xy 406.468957 -59.594879) (xy 406.45306 -59.656793) (xy 406.429528 -59.716226) (xy 406.398734 -59.772241)
			(xy 406.361161 -59.823956) (xy 406.317404 -59.870553) (xy 406.268151 -59.911298) (xy 406.21418 -59.945549)
			(xy 406.156341 -59.972766) (xy 406.095548 -59.992519) (xy 406.032758 -60.004497) (xy 405.968962 -60.008511)
			(xy 405.905166 -60.004497) (xy 405.842376 -59.992519) (xy 405.781583 -59.972766) (xy 405.723744 -59.945549)
			(xy 405.669773 -59.911298) (xy 405.62052 -59.870553) (xy 405.576763 -59.823956) (xy 405.53919 -59.772241)
			(xy 405.508396 -59.716226) (xy 405.484864 -59.656793) (xy 405.468967 -59.594879) (xy 405.460956 -59.531461)
			(xy 405.206968 -59.531461) (xy 405.198957 -59.594879) (xy 405.18306 -59.656793) (xy 405.159528 -59.716226)
			(xy 405.128734 -59.772241) (xy 405.091161 -59.823956) (xy 405.047404 -59.870553) (xy 404.998151 -59.911298)
			(xy 404.94418 -59.945549) (xy 404.886341 -59.972766) (xy 404.825548 -59.992519) (xy 404.762758 -60.004497)
			(xy 404.698962 -60.008511) (xy 404.635166 -60.004497) (xy 404.572376 -59.992519) (xy 404.511583 -59.972766)
			(xy 404.453744 -59.945549) (xy 404.399773 -59.911298) (xy 404.35052 -59.870553) (xy 404.306763 -59.823956)
			(xy 404.26919 -59.772241) (xy 404.238396 -59.716226) (xy 404.214864 -59.656793) (xy 404.198967 -59.594879)
			(xy 404.190956 -59.531461) (xy 274.210315 -59.531461) (xy 273.614939 -60.126837) (xy 316.754504 -60.126837)
			(xy 316.754504 -60.062915) (xy 316.762515 -59.999497) (xy 316.778412 -59.937583) (xy 316.801944 -59.87815)
			(xy 316.832738 -59.822135) (xy 316.870311 -59.77042) (xy 316.914068 -59.723823) (xy 316.963321 -59.683078)
			(xy 317.017292 -59.648827) (xy 317.075131 -59.62161) (xy 317.135924 -59.601857) (xy 317.198714 -59.589879)
			(xy 317.26251 -59.585866) (xy 317.326306 -59.589879) (xy 317.389096 -59.601857) (xy 317.449889 -59.62161)
			(xy 317.507728 -59.648827) (xy 317.561699 -59.683078) (xy 317.610952 -59.723823) (xy 317.654709 -59.77042)
			(xy 317.692282 -59.822135) (xy 317.723076 -59.87815) (xy 317.746608 -59.937583) (xy 317.762505 -59.999497)
			(xy 317.770516 -60.062915) (xy 317.771018 -60.094876) (xy 324.16191 -60.094876) (xy 324.165981 -60.039254)
			(xy 324.178107 -59.984817) (xy 324.19803 -59.932726) (xy 324.225326 -59.884091) (xy 324.259412 -59.839948)
			(xy 324.299561 -59.801239) (xy 324.344919 -59.768788) (xy 324.394519 -59.743287) (xy 324.447303 -59.72528)
			(xy 324.502146 -59.71515) (xy 324.55788 -59.713113) (xy 324.613317 -59.719213) (xy 324.667274 -59.733319)
			(xy 324.718603 -59.755131) (xy 324.766209 -59.784185) (xy 324.809077 -59.81986) (xy 324.846294 -59.861397)
			(xy 324.877067 -59.90791) (xy 324.900739 -59.958407) (xy 324.916807 -60.011814) (xy 324.924927 -60.06699)
			(xy 324.925436 -60.094876) (xy 338.774022 -60.094876) (xy 338.778093 -60.039254) (xy 338.790219 -59.984817)
			(xy 338.810142 -59.932726) (xy 338.837438 -59.884091) (xy 338.871524 -59.839948) (xy 338.911673 -59.801239)
			(xy 338.957031 -59.768788) (xy 339.006631 -59.743287) (xy 339.059415 -59.72528) (xy 339.114258 -59.71515)
			(xy 339.169992 -59.713113) (xy 339.225429 -59.719213) (xy 339.279386 -59.733319) (xy 339.330715 -59.755131)
			(xy 339.378321 -59.784185) (xy 339.421189 -59.81986) (xy 339.458406 -59.861397) (xy 339.489179 -59.90791)
			(xy 339.512851 -59.958407) (xy 339.528919 -60.011814) (xy 339.537039 -60.06699) (xy 339.537548 -60.094876)
			(xy 339.537039 -60.122762) (xy 339.536439 -60.126837) (xy 350.955604 -60.126837) (xy 350.955604 -60.062915)
			(xy 350.963615 -59.999497) (xy 350.979512 -59.937583) (xy 351.003044 -59.87815) (xy 351.033838 -59.822135)
			(xy 351.071411 -59.77042) (xy 351.115168 -59.723823) (xy 351.164421 -59.683078) (xy 351.218392 -59.648827)
			(xy 351.276231 -59.62161) (xy 351.337024 -59.601857) (xy 351.399814 -59.589879) (xy 351.46361 -59.585866)
			(xy 351.527406 -59.589879) (xy 351.590196 -59.601857) (xy 351.650989 -59.62161) (xy 351.708828 -59.648827)
			(xy 351.762799 -59.683078) (xy 351.812052 -59.723823) (xy 351.855809 -59.77042) (xy 351.893382 -59.822135)
			(xy 351.924176 -59.87815) (xy 351.947708 -59.937583) (xy 351.963605 -59.999497) (xy 351.971616 -60.062915)
			(xy 351.972118 -60.094876) (xy 351.971616 -60.126837) (xy 351.963605 -60.190255) (xy 351.947708 -60.252169)
			(xy 351.924176 -60.311602) (xy 351.893382 -60.367617) (xy 351.855809 -60.419332) (xy 351.812052 -60.465929)
			(xy 351.785035 -60.488279) (xy 387.449562 -60.488279) (xy 387.449562 -60.424357) (xy 387.457573 -60.360939)
			(xy 387.47347 -60.299025) (xy 387.497002 -60.239592) (xy 387.527796 -60.183577) (xy 387.565369 -60.131862)
			(xy 387.609126 -60.085265) (xy 387.658379 -60.04452) (xy 387.71235 -60.010269) (xy 387.770189 -59.983052)
			(xy 387.830982 -59.963299) (xy 387.893772 -59.951321) (xy 387.957568 -59.947308) (xy 388.021364 -59.951321)
			(xy 388.084154 -59.963299) (xy 388.144947 -59.983052) (xy 388.202786 -60.010269) (xy 388.256757 -60.04452)
			(xy 388.30601 -60.085265) (xy 388.349767 -60.131862) (xy 388.38734 -60.183577) (xy 388.418134 -60.239592)
			(xy 388.441666 -60.299025) (xy 388.457563 -60.360939) (xy 388.465574 -60.424357) (xy 388.466076 -60.456318)
			(xy 388.465574 -60.488279) (xy 388.457563 -60.551697) (xy 388.441666 -60.613611) (xy 388.418134 -60.673044)
			(xy 388.38734 -60.729059) (xy 388.349767 -60.780774) (xy 388.330341 -60.801461) (xy 404.190956 -60.801461)
			(xy 404.190956 -60.737539) (xy 404.198967 -60.674121) (xy 404.214864 -60.612207) (xy 404.238396 -60.552774)
			(xy 404.26919 -60.496759) (xy 404.306763 -60.445044) (xy 404.35052 -60.398447) (xy 404.399773 -60.357702)
			(xy 404.453744 -60.323451) (xy 404.511583 -60.296234) (xy 404.572376 -60.276481) (xy 404.635166 -60.264503)
			(xy 404.698962 -60.26049) (xy 404.762758 -60.264503) (xy 404.825548 -60.276481) (xy 404.886341 -60.296234)
			(xy 404.94418 -60.323451) (xy 404.998151 -60.357702) (xy 405.047404 -60.398447) (xy 405.091161 -60.445044)
			(xy 405.128734 -60.496759) (xy 405.159528 -60.552774) (xy 405.162755 -60.560923) (xy 412.789618 -60.560923)
			(xy 412.789618 -60.497001) (xy 412.797629 -60.433583) (xy 412.813526 -60.371669) (xy 412.837058 -60.312236)
			(xy 412.867852 -60.256221) (xy 412.905425 -60.204506) (xy 412.949182 -60.157909) (xy 412.998435 -60.117164)
			(xy 413.052406 -60.082913) (xy 413.110245 -60.055696) (xy 413.171038 -60.035943) (xy 413.233828 -60.023965)
			(xy 413.297624 -60.019952) (xy 413.36142 -60.023965) (xy 413.42421 -60.035943) (xy 413.485003 -60.055696)
			(xy 413.542842 -60.082913) (xy 413.596813 -60.117164) (xy 413.646066 -60.157909) (xy 413.689823 -60.204506)
			(xy 413.727396 -60.256221) (xy 413.75819 -60.312236) (xy 413.781722 -60.371669) (xy 413.797619 -60.433583)
			(xy 413.80563 -60.497001) (xy 413.806132 -60.528962) (xy 413.80563 -60.560923) (xy 413.797619 -60.624341)
			(xy 413.781722 -60.686255) (xy 413.75819 -60.745688) (xy 413.727396 -60.801703) (xy 413.689823 -60.853418)
			(xy 413.646066 -60.900015) (xy 413.596813 -60.94076) (xy 413.542842 -60.975011) (xy 413.485003 -61.002228)
			(xy 413.42421 -61.021981) (xy 413.36142 -61.033959) (xy 413.297624 -61.037973) (xy 413.233828 -61.033959)
			(xy 413.171038 -61.021981) (xy 413.110245 -61.002228) (xy 413.052406 -60.975011) (xy 412.998435 -60.94076)
			(xy 412.949182 -60.900015) (xy 412.905425 -60.853418) (xy 412.867852 -60.801703) (xy 412.837058 -60.745688)
			(xy 412.813526 -60.686255) (xy 412.797629 -60.624341) (xy 412.789618 -60.560923) (xy 405.162755 -60.560923)
			(xy 405.18306 -60.612207) (xy 405.198957 -60.674121) (xy 405.206968 -60.737539) (xy 405.20747 -60.7695)
			(xy 405.206968 -60.801461) (xy 405.198957 -60.864879) (xy 405.18306 -60.926793) (xy 405.159528 -60.986226)
			(xy 405.128734 -61.042241) (xy 405.091161 -61.093956) (xy 405.047404 -61.140553) (xy 404.998151 -61.181298)
			(xy 404.94418 -61.215549) (xy 404.886341 -61.242766) (xy 404.825548 -61.262519) (xy 404.762758 -61.274497)
			(xy 404.698962 -61.278511) (xy 404.635166 -61.274497) (xy 404.572376 -61.262519) (xy 404.511583 -61.242766)
			(xy 404.453744 -61.215549) (xy 404.399773 -61.181298) (xy 404.35052 -61.140553) (xy 404.306763 -61.093956)
			(xy 404.26919 -61.042241) (xy 404.238396 -60.986226) (xy 404.214864 -60.926793) (xy 404.198967 -60.864879)
			(xy 404.190956 -60.801461) (xy 388.330341 -60.801461) (xy 388.30601 -60.827371) (xy 388.256757 -60.868116)
			(xy 388.202786 -60.902367) (xy 388.144947 -60.929584) (xy 388.084154 -60.949337) (xy 388.021364 -60.961315)
			(xy 387.957568 -60.965329) (xy 387.893772 -60.961315) (xy 387.830982 -60.949337) (xy 387.770189 -60.929584)
			(xy 387.71235 -60.902367) (xy 387.658379 -60.868116) (xy 387.609126 -60.827371) (xy 387.565369 -60.780774)
			(xy 387.527796 -60.729059) (xy 387.497002 -60.673044) (xy 387.47347 -60.613611) (xy 387.457573 -60.551697)
			(xy 387.449562 -60.488279) (xy 351.785035 -60.488279) (xy 351.762799 -60.506674) (xy 351.708828 -60.540925)
			(xy 351.650989 -60.568142) (xy 351.590196 -60.587895) (xy 351.527406 -60.599873) (xy 351.46361 -60.603887)
			(xy 351.399814 -60.599873) (xy 351.337024 -60.587895) (xy 351.276231 -60.568142) (xy 351.218392 -60.540925)
			(xy 351.164421 -60.506674) (xy 351.115168 -60.465929) (xy 351.071411 -60.419332) (xy 351.033838 -60.367617)
			(xy 351.003044 -60.311602) (xy 350.979512 -60.252169) (xy 350.963615 -60.190255) (xy 350.955604 -60.126837)
			(xy 339.536439 -60.126837) (xy 339.528919 -60.177938) (xy 339.512851 -60.231345) (xy 339.489179 -60.281842)
			(xy 339.458406 -60.328355) (xy 339.421189 -60.369892) (xy 339.378321 -60.405567) (xy 339.330715 -60.434621)
			(xy 339.279386 -60.456433) (xy 339.225429 -60.470539) (xy 339.169992 -60.476639) (xy 339.114258 -60.474602)
			(xy 339.059415 -60.464472) (xy 339.006631 -60.446465) (xy 338.957031 -60.420964) (xy 338.911673 -60.388513)
			(xy 338.871524 -60.349804) (xy 338.837438 -60.305661) (xy 338.810142 -60.257026) (xy 338.790219 -60.204935)
			(xy 338.778093 -60.150498) (xy 338.774022 -60.094876) (xy 324.925436 -60.094876) (xy 324.924927 -60.122762)
			(xy 324.916807 -60.177938) (xy 324.900739 -60.231345) (xy 324.877067 -60.281842) (xy 324.846294 -60.328355)
			(xy 324.809077 -60.369892) (xy 324.766209 -60.405567) (xy 324.718603 -60.434621) (xy 324.667274 -60.456433)
			(xy 324.613317 -60.470539) (xy 324.55788 -60.476639) (xy 324.502146 -60.474602) (xy 324.447303 -60.464472)
			(xy 324.394519 -60.446465) (xy 324.344919 -60.420964) (xy 324.299561 -60.388513) (xy 324.259412 -60.349804)
			(xy 324.225326 -60.305661) (xy 324.19803 -60.257026) (xy 324.178107 -60.204935) (xy 324.165981 -60.150498)
			(xy 324.16191 -60.094876) (xy 317.771018 -60.094876) (xy 317.770516 -60.126837) (xy 317.762505 -60.190255)
			(xy 317.746608 -60.252169) (xy 317.723076 -60.311602) (xy 317.692282 -60.367617) (xy 317.654709 -60.419332)
			(xy 317.610952 -60.465929) (xy 317.561699 -60.506674) (xy 317.507728 -60.540925) (xy 317.449889 -60.568142)
			(xy 317.389096 -60.587895) (xy 317.326306 -60.599873) (xy 317.26251 -60.603887) (xy 317.198714 -60.599873)
			(xy 317.135924 -60.587895) (xy 317.075131 -60.568142) (xy 317.017292 -60.540925) (xy 316.963321 -60.506674)
			(xy 316.914068 -60.465929) (xy 316.870311 -60.419332) (xy 316.832738 -60.367617) (xy 316.801944 -60.311602)
			(xy 316.778412 -60.252169) (xy 316.762515 -60.190255) (xy 316.754504 -60.126837) (xy 273.614939 -60.126837)
			(xy 272.11655 -61.625226) (xy 272.109152 -61.632073) (xy 272.090553 -61.639801) (xy 272.080482 -61.640212)
			(xy 264.061448 -61.640212) (xy 264.051382 -61.63978) (xy 264.03279 -61.632054) (xy 264.02538 -61.625226)
			(xy 261.24789 -58.847736) (xy 261.245039 -58.845031) (xy 261.23866 -58.840439) (xy 261.23519 -58.838592)
			(xy 261.229764 -58.836006) (xy 261.218084 -58.833175) (xy 261.212076 -58.833004) (xy 259.403088 -58.833004)
			(xy 259.399024 -58.833258) (xy 259.398516 -58.833258) (xy 259.3848 -58.836306) (xy 259.362702 -58.846974)
			(xy 259.351018 -58.854594) (xy 259.346192 -58.85942) (xy 259.345938 -58.859674) (xy 259.325183 -58.882986)
			(xy 259.278918 -58.924883) (xy 259.227874 -58.960806) (xy 259.172819 -58.990214) (xy 259.11458 -59.012665)
			(xy 259.054031 -59.027823) (xy 258.992083 -59.035459) (xy 258.929665 -59.035459) (xy 258.867717 -59.027823)
			(xy 258.807168 -59.012665) (xy 258.748929 -58.990214) (xy 258.693874 -58.960806) (xy 258.64283 -58.924883)
			(xy 258.596565 -58.882986) (xy 258.57581 -58.859674) (xy 258.568698 -58.851546) (xy 258.554982 -58.844942)
			(xy 258.536948 -58.836306) (xy 258.523232 -58.833258) (xy 258.522724 -58.833258) (xy 258.51866 -58.833004)
			(xy 257.414268 -58.833004) (xy 257.404041 -58.833624) (xy 257.385308 -58.841879) (xy 257.377946 -58.849006)
			(xy 257.374997 -58.852239) (xy 257.370148 -58.859521) (xy 257.368294 -58.863484) (xy 257.36804 -58.863992)
			(xy 257.330702 -58.952384) (xy 257.328564 -58.958825) (xy 257.327407 -58.972343) (xy 257.328416 -58.979054)
			(xy 257.32994 -58.986928) (xy 257.336798 -58.999882) (xy 257.342132 -59.00547) (xy 257.364506 -59.029256)
			(xy 257.403602 -59.081562) (xy 257.435678 -59.138444) (xy 257.460207 -59.198965) (xy 257.476786 -59.262128)
			(xy 257.485141 -59.326895) (xy 257.485642 -59.359546) (xy 257.48514 -59.391507) (xy 257.477129 -59.454925)
			(xy 257.461232 -59.516839) (xy 257.4377 -59.576272) (xy 257.406906 -59.632287) (xy 257.369333 -59.684002)
			(xy 257.325576 -59.730599) (xy 257.276323 -59.771344) (xy 257.222352 -59.805595) (xy 257.164513 -59.832812)
			(xy 257.10372 -59.852565) (xy 257.04093 -59.864543) (xy 256.977134 -59.868557) (xy 256.913338 -59.864543)
			(xy 256.850548 -59.852565) (xy 256.789755 -59.832812) (xy 256.731916 -59.805595) (xy 256.677945 -59.771344)
			(xy 256.628692 -59.730599) (xy 256.584935 -59.684002) (xy 256.547362 -59.632287) (xy 256.516568 -59.576272)
			(xy 256.493036 -59.516839) (xy 256.477139 -59.454925) (xy 256.469128 -59.391507) (xy 256.468626 -59.359546)
			(xy 256.469132 -59.326896) (xy 256.477497 -59.262134) (xy 256.494082 -59.198976) (xy 256.518616 -59.13846)
			(xy 256.550693 -59.081582) (xy 256.589786 -59.029277) (xy 256.612136 -59.00547) (xy 256.612898 -59.004708)
			(xy 256.617702 -58.99921) (xy 256.624286 -58.986185) (xy 256.625852 -58.979054) (xy 256.627122 -58.971942)
			(xy 256.62636 -58.96483) (xy 256.625928 -58.961175) (xy 256.624145 -58.954034) (xy 256.622804 -58.950606)
			(xy 256.616962 -58.93689) (xy 256.612611 -58.927869) (xy 256.598352 -58.913835) (xy 256.579808 -58.906326)
			(xy 256.559802 -58.906483) (xy 256.550414 -58.909966) (xy 256.543556 -58.91276) (xy 256.537714 -58.917586)
			(xy 256.514796 -58.936186) (xy 256.465429 -58.96854) (xy 256.412648 -58.994962) (xy 256.357162 -59.015094)
			(xy 256.299719 -59.028667) (xy 256.241091 -59.035499) (xy 256.211578 -59.03595) (xy 256.180394 -59.035482)
			(xy 256.118492 -59.027864) (xy 256.057986 -59.012733) (xy 255.999785 -58.990316) (xy 255.944762 -58.96095)
			(xy 255.893744 -58.925075) (xy 255.847496 -58.883231) (xy 255.826768 -58.859928) (xy 255.826514 -58.859674)
			(xy 255.819402 -58.852816) (xy 255.809496 -58.846466) (xy 255.790954 -58.83783) (xy 255.786636 -58.836052)
			(xy 255.780286 -58.834274) (xy 255.769364 -58.833004) (xy 240.487708 -58.833004) (xy 240.477025 -58.833474)
			(xy 240.457508 -58.842166) (xy 240.443218 -58.858048) (xy 240.439448 -58.868056) (xy 240.40846 -58.962544)
			(xy 240.406939 -58.969134) (xy 240.407073 -58.982653) (xy 240.408714 -58.989214) (xy 240.411 -58.996326)
			(xy 240.411762 -58.998866) (xy 240.42116 -59.011566) (xy 240.42751 -59.016392) (xy 240.454638 -59.037005)
			(xy 240.503664 -59.084318) (xy 240.545938 -59.137749) (xy 240.580704 -59.196345) (xy 240.60734 -59.259055)
			(xy 240.625368 -59.324759) (xy 240.634467 -59.392282) (xy 240.635028 -59.426348) (xy 240.634526 -59.458309)
			(xy 240.626515 -59.521727) (xy 240.610618 -59.583641) (xy 240.587086 -59.643074) (xy 240.561033 -59.690465)
			(xy 252.806194 -59.690465) (xy 252.806194 -59.626543) (xy 252.814205 -59.563125) (xy 252.830102 -59.501211)
			(xy 252.853634 -59.441778) (xy 252.884428 -59.385763) (xy 252.922001 -59.334048) (xy 252.965758 -59.287451)
			(xy 253.015011 -59.246706) (xy 253.068982 -59.212455) (xy 253.126821 -59.185238) (xy 253.187614 -59.165485)
			(xy 253.250404 -59.153507) (xy 253.3142 -59.149494) (xy 253.377996 -59.153507) (xy 253.440786 -59.165485)
			(xy 253.501579 -59.185238) (xy 253.559418 -59.212455) (xy 253.613389 -59.246706) (xy 253.662642 -59.287451)
			(xy 253.706399 -59.334048) (xy 253.743972 -59.385763) (xy 253.774766 -59.441778) (xy 253.798298 -59.501211)
			(xy 253.814195 -59.563125) (xy 253.822206 -59.626543) (xy 253.822708 -59.658504) (xy 253.822206 -59.690465)
			(xy 253.814195 -59.753883) (xy 253.798298 -59.815797) (xy 253.774766 -59.87523) (xy 253.743972 -59.931245)
			(xy 253.706399 -59.98296) (xy 253.662642 -60.029557) (xy 253.613389 -60.070302) (xy 253.559418 -60.104553)
			(xy 253.501579 -60.13177) (xy 253.440786 -60.151523) (xy 253.377996 -60.163501) (xy 253.3142 -60.167515)
			(xy 253.250404 -60.163501) (xy 253.187614 -60.151523) (xy 253.126821 -60.13177) (xy 253.068982 -60.104553)
			(xy 253.015011 -60.070302) (xy 252.965758 -60.029557) (xy 252.922001 -59.98296) (xy 252.884428 -59.931245)
			(xy 252.853634 -59.87523) (xy 252.830102 -59.815797) (xy 252.814205 -59.753883) (xy 252.806194 -59.690465)
			(xy 240.561033 -59.690465) (xy 240.556292 -59.699089) (xy 240.518719 -59.750804) (xy 240.474962 -59.797401)
			(xy 240.425709 -59.838146) (xy 240.371738 -59.872397) (xy 240.313899 -59.899614) (xy 240.253106 -59.919367)
			(xy 240.190316 -59.931345) (xy 240.12652 -59.935359) (xy 240.062724 -59.931345) (xy 239.999934 -59.919367)
			(xy 239.939141 -59.899614) (xy 239.881302 -59.872397) (xy 239.827331 -59.838146) (xy 239.778078 -59.797401)
			(xy 239.734321 -59.750804) (xy 239.696748 -59.699089) (xy 239.665954 -59.643074) (xy 239.642422 -59.583641)
			(xy 239.626525 -59.521727) (xy 239.618514 -59.458309) (xy 239.618012 -59.426348) (xy 239.618092 -59.413626)
			(xy 239.619363 -59.388214) (xy 239.620552 -59.375548) (xy 239.620298 -59.375548) (xy 239.623795 -59.345309)
			(xy 239.637088 -59.285903) (xy 239.657374 -59.228507) (xy 239.684364 -59.173942) (xy 239.717672 -59.122988)
			(xy 239.756823 -59.076373) (xy 239.801257 -59.034762) (xy 239.82553 -59.016392) (xy 239.83188 -59.011566)
			(xy 239.841278 -58.998866) (xy 239.84204 -58.996326) (xy 239.844326 -58.989214) (xy 239.845949 -58.982651)
			(xy 239.846079 -58.969136) (xy 239.84458 -58.962544) (xy 239.813592 -58.868056) (xy 239.809748 -58.858102)
			(xy 239.795461 -58.842289) (xy 239.775987 -58.833631) (xy 239.765332 -58.833004) (xy 238.935514 -58.833004)
			(xy 238.929418 -58.833512) (xy 238.92891 -58.833512) (xy 238.917619 -58.835536) (xy 238.898454 -58.848103)
			(xy 238.89208 -58.857642) (xy 238.846106 -58.934096) (xy 238.843712 -58.938671) (xy 238.840647 -58.94853)
			(xy 238.84001 -58.953654) (xy 238.84001 -58.95848) (xy 238.844328 -58.97626) (xy 238.848646 -58.987182)
			(xy 238.862167 -59.014326) (xy 238.883382 -59.071138) (xy 238.897687 -59.13007) (xy 238.904878 -59.190286)
			(xy 238.905288 -59.220608) (xy 238.904786 -59.252569) (xy 238.896775 -59.315987) (xy 238.880878 -59.377901)
			(xy 238.857346 -59.437334) (xy 238.826552 -59.493349) (xy 238.788979 -59.545064) (xy 238.745222 -59.591661)
			(xy 238.695969 -59.632406) (xy 238.641998 -59.666657) (xy 238.584159 -59.693874) (xy 238.523366 -59.713627)
			(xy 238.460576 -59.725605) (xy 238.39678 -59.729619) (xy 238.332984 -59.725605) (xy 238.270194 -59.713627)
			(xy 238.209401 -59.693874) (xy 238.151562 -59.666657) (xy 238.097591 -59.632406) (xy 238.048338 -59.591661)
			(xy 238.004581 -59.545064) (xy 237.967008 -59.493349) (xy 237.936214 -59.437334) (xy 237.912682 -59.377901)
			(xy 237.896785 -59.315987) (xy 237.888774 -59.252569) (xy 237.888272 -59.220608) (xy 237.888272 -59.217052)
			(xy 237.888105 -59.211042) (xy 237.88528 -59.199361) (xy 237.882684 -59.193938) (xy 237.87989 -59.188604)
			(xy 237.876334 -59.184286) (xy 237.866682 -59.175904) (xy 237.816898 -59.141106) (xy 237.787434 -59.120532)
			(xy 237.774988 -59.119008) (xy 237.769617 -59.118441) (xy 237.758856 -59.119339) (xy 237.753652 -59.120786)
			(xy 237.750858 -59.121802) (xy 237.718394 -59.133283) (xy 237.650664 -59.145674) (xy 237.616238 -59.14644)
			(xy 237.58885 -59.145963) (xy 237.534638 -59.138123) (xy 237.482104 -59.122613) (xy 237.432327 -59.099752)
			(xy 237.386329 -59.070009) (xy 237.345057 -59.033995) (xy 237.309357 -58.992451) (xy 237.279963 -58.946229)
			(xy 237.25748 -58.89628) (xy 237.249462 -58.870088) (xy 237.249462 -58.869834) (xy 237.248446 -58.866278)
			(xy 237.245692 -58.859582) (xy 237.23706 -58.847966) (xy 237.231428 -58.843418) (xy 237.224316 -58.838084)
			(xy 237.21695 -58.835544) (xy 237.206282 -58.833258) (xy 237.201202 -58.833004) (xy 231.382824 -58.833004)
			(xy 231.374629 -58.83331) (xy 231.359079 -58.838486) (xy 231.352344 -58.843164) (xy 231.345232 -58.848498)
			(xy 231.336596 -58.861452) (xy 231.334056 -58.869834) (xy 231.326067 -58.896045) (xy 231.303617 -58.94603)
			(xy 231.274248 -58.992289) (xy 231.238564 -59.033872) (xy 231.197298 -59.069923) (xy 231.151301 -59.0997)
			(xy 231.101517 -59.122592) (xy 231.04897 -59.138126) (xy 230.994741 -59.145985) (xy 230.939947 -59.146006)
			(xy 230.885712 -59.138188) (xy 230.833154 -59.122693) (xy 230.783352 -59.099839) (xy 230.737332 -59.070097)
			(xy 230.69604 -59.034077) (xy 230.660324 -58.992521) (xy 230.63092 -58.946284) (xy 230.608432 -58.896316)
			(xy 230.600504 -58.870088) (xy 230.600504 -58.869834) (xy 230.599488 -58.866278) (xy 230.596731 -58.859585)
			(xy 230.588093 -58.847976) (xy 230.58247 -58.843418) (xy 230.575358 -58.838084) (xy 230.567992 -58.835544)
			(xy 230.557324 -58.833258) (xy 230.552244 -58.833004) (xy 221.490032 -58.833004) (xy 221.479967 -58.832568)
			(xy 221.46138 -58.824837) (xy 221.453964 -58.818018) (xy 220.22689 -57.590944) (xy 220.220043 -57.583547)
			(xy 220.212315 -57.564948) (xy 220.211904 -57.554876) (xy 220.211904 -56.350408) (xy 220.212326 -56.340337)
			(xy 220.220039 -56.321731) (xy 220.22689 -56.31434) (xy 225.099626 -51.441604) (xy 225.10496 -51.435254)
			(xy 225.107964 -51.430805) (xy 225.112188 -51.420939) (xy 225.113342 -51.415696) (xy 225.113342 -51.415188)
			(xy 225.114358 -51.40579) (xy 225.114358 -47.016162) (xy 225.114104 -47.010828) (xy 225.112469 -46.999922)
			(xy 225.101272 -46.980953) (xy 225.092514 -46.974252) (xy 225.087942 -46.971458) (xy 225.059988 -46.955699)
			(xy 225.007921 -46.918188) (xy 224.960989 -46.874423) (xy 224.919938 -46.825098) (xy 224.885422 -46.770999)
			(xy 224.857989 -46.712987) (xy 224.838076 -46.651982) (xy 224.826 -46.588957) (xy 224.821952 -46.524912)
			(xy 224.825997 -46.460868) (xy 224.83807 -46.397842) (xy 224.85798 -46.336837) (xy 224.88541 -46.278822)
			(xy 224.919923 -46.224722) (xy 224.960972 -46.175395) (xy 225.007902 -46.131627) (xy 225.059967 -46.094114)
			(xy 225.087942 -46.078394) (xy 225.092514 -46.0756) (xy 225.101241 -46.068872) (xy 225.112429 -46.049915)
			(xy 225.114104 -46.039024) (xy 225.114358 -46.03369) (xy 225.114358 -45.355256) (xy 225.114218 -45.350224)
			(xy 225.112173 -45.340368) (xy 225.110294 -45.335698) (xy 225.103944 -45.320204) (xy 225.102353 -45.31665)
			(xy 225.098277 -45.310014) (xy 225.095816 -45.306996) (xy 225.09099 -45.301916) (xy 225.066832 -45.279575)
			(xy 225.023895 -45.229715) (xy 224.987742 -45.174736) (xy 224.958977 -45.115556) (xy 224.93808 -45.053162)
			(xy 224.925399 -44.988595) (xy 224.921145 -44.922932) (xy 224.92539 -44.857269) (xy 224.938064 -44.7927)
			(xy 224.958953 -44.730304) (xy 224.987711 -44.67112) (xy 225.023856 -44.616137) (xy 225.066788 -44.56627)
			(xy 225.09099 -44.54398) (xy 225.095816 -44.5389) (xy 225.098295 -44.535895) (xy 225.10237 -44.529256)
			(xy 225.103944 -44.525692) (xy 225.110294 -44.510198) (xy 225.112137 -44.505517) (xy 225.114181 -44.495668)
			(xy 225.114358 -44.49064) (xy 225.114358 -43.948096) (xy 225.114358 -43.946318) (xy 225.113533 -43.936364)
			(xy 225.105306 -43.918184) (xy 225.098356 -43.911012) (xy 225.075468 -43.890692) (xy 225.034227 -43.845466)
			(xy 224.998713 -43.795616) (xy 224.969442 -43.741862) (xy 224.946835 -43.684984) (xy 224.93122 -43.625802)
			(xy 224.922823 -43.565175) (xy 224.921826 -43.534584) (xy 224.921572 -43.52417) (xy 224.918016 -43.515788)
			(xy 224.91601 -43.51128) (xy 224.910518 -43.503084) (xy 224.907094 -43.499532) (xy 221.735396 -40.327834)
			(xy 221.72856 -40.320432) (xy 221.72085 -40.301834) (xy 221.72041 -40.291766) (xy 221.72041 -33.944306)
			(xy 221.719965 -33.934494) (xy 221.712614 -33.9163) (xy 221.698982 -33.902185) (xy 221.690184 -33.897824)
			(xy 221.601792 -33.858962) (xy 221.596081 -33.857112) (xy 221.584146 -33.855838) (xy 221.57817 -33.856422)
			(xy 221.573852 -33.857184) (xy 221.567724 -33.858737) (xy 221.556421 -33.864391) (xy 221.5515 -33.86836)
			(xy 221.55023 -33.869376) (xy 221.526721 -33.890278) (xy 221.475451 -33.926729) (xy 221.420077 -33.95658)
			(xy 221.361445 -33.979376) (xy 221.30045 -33.994768) (xy 221.238022 -34.002521) (xy 221.206568 -34.00298)
			(xy 221.17461 -34.002476) (xy 221.111199 -33.994462) (xy 221.049291 -33.978563) (xy 220.989865 -33.955031)
			(xy 220.933856 -33.924237) (xy 220.882149 -33.886666) (xy 220.835557 -33.842911) (xy 220.794817 -33.793662)
			(xy 220.76057 -33.739695) (xy 220.733357 -33.681862) (xy 220.713607 -33.621074) (xy 220.701631 -33.55829)
			(xy 220.697617 -33.4945) (xy 220.701631 -33.43071) (xy 220.713607 -33.367926) (xy 220.733357 -33.307138)
			(xy 220.76057 -33.249305) (xy 220.794817 -33.195338) (xy 220.835557 -33.146089) (xy 220.882149 -33.102334)
			(xy 220.933856 -33.064763) (xy 220.989865 -33.033969) (xy 221.049291 -33.010437) (xy 221.111199 -32.994538)
			(xy 221.17461 -32.986524) (xy 221.206568 -32.985964) (xy 221.238022 -32.986431) (xy 221.300451 -32.994182)
			(xy 221.361448 -33.00957) (xy 221.420083 -33.03236) (xy 221.475462 -33.062204) (xy 221.526739 -33.098647)
			(xy 221.55023 -33.119568) (xy 221.5515 -33.120584) (xy 221.556389 -33.124604) (xy 221.567702 -33.130269)
			(xy 221.573852 -33.13176) (xy 221.57817 -33.132522) (xy 221.584146 -33.133142) (xy 221.596087 -33.131864)
			(xy 221.601792 -33.129982) (xy 221.690184 -33.09112) (xy 221.69898 -33.086745) (xy 221.712641 -33.07265)
			(xy 221.719999 -33.054453) (xy 221.72041 -33.044638) (xy 221.72041 -14.251432) (xy 221.720241 -14.245423)
			(xy 221.717414 -14.233742) (xy 221.714822 -14.228318) (xy 221.712985 -14.224842) (xy 221.708396 -14.218458)
			(xy 221.705678 -14.215618) (xy 221.076012 -13.585952) (xy 221.073162 -13.583245) (xy 221.066785 -13.578649)
			(xy 221.063312 -13.576808) (xy 221.057884 -13.574229) (xy 221.046205 -13.571415) (xy 221.040198 -13.57122)
			(xy 210.571842 -13.57122) (xy 210.565833 -13.571388) (xy 210.554152 -13.574215) (xy 210.548728 -13.576808)
			(xy 210.545252 -13.578645) (xy 210.53887 -13.583235) (xy 210.536028 -13.585952) (xy 208.80758 -15.3144)
			(xy 217.58299 -15.3144) (xy 217.587004 -15.250603) (xy 217.598983 -15.187811) (xy 217.618737 -15.127017)
			(xy 217.645955 -15.069177) (xy 217.680207 -15.015205) (xy 217.720955 -14.965952) (xy 217.767554 -14.922194)
			(xy 217.81927 -14.884622) (xy 217.875287 -14.853828) (xy 217.934723 -14.830298) (xy 217.996638 -14.814403)
			(xy 218.060058 -14.806394) (xy 218.09202 -14.805914) (xy 218.123614 -14.806352) (xy 218.186312 -14.814206)
			(xy 218.247554 -14.829766) (xy 218.306397 -14.852792) (xy 218.361935 -14.882929) (xy 218.413312 -14.919713)
			(xy 218.459737 -14.962578) (xy 218.500495 -15.010864) (xy 218.534958 -15.063826) (xy 218.562595 -15.120649)
			(xy 218.582981 -15.180458) (xy 218.58986 -15.211298) (xy 218.58986 -15.211552) (xy 218.592425 -15.221142)
			(xy 218.603663 -15.237481) (xy 218.611704 -15.243302) (xy 218.671648 -15.282926) (xy 218.680002 -15.287948)
			(xy 218.699076 -15.291871) (xy 218.708732 -15.290546) (xy 218.709494 -15.290546) (xy 218.727719 -15.287136)
			(xy 218.764615 -15.283449) (xy 218.783154 -15.28318) (xy 218.810408 -15.283664) (xy 218.864362 -15.291416)
			(xy 218.916664 -15.306767) (xy 218.966248 -15.329406) (xy 219.012106 -15.358872) (xy 219.053303 -15.394565)
			(xy 219.089 -15.435757) (xy 219.118472 -15.481611) (xy 219.141117 -15.531193) (xy 219.156475 -15.583493)
			(xy 219.164233 -15.637446) (xy 219.164233 -15.691954) (xy 219.156475 -15.745907) (xy 219.141117 -15.798207)
			(xy 219.118472 -15.847789) (xy 219.089 -15.893643) (xy 219.053303 -15.934835) (xy 219.012106 -15.970528)
			(xy 218.966248 -15.999994) (xy 218.916664 -16.022633) (xy 218.864362 -16.037984) (xy 218.810408 -16.045736)
			(xy 218.783154 -16.046196) (xy 218.756107 -16.045729) (xy 218.702554 -16.038107) (xy 218.650615 -16.022996)
			(xy 218.601333 -16.000697) (xy 218.555695 -15.971659) (xy 218.514618 -15.936464) (xy 218.478926 -15.895818)
			(xy 218.449336 -15.850536) (xy 218.43746 -15.826232) (xy 218.433396 -15.817342) (xy 218.418664 -15.803626)
			(xy 218.341956 -15.775432) (xy 218.33245 -15.772497) (xy 218.312589 -15.773273) (xy 218.303348 -15.776956)
			(xy 218.270032 -15.791481) (xy 218.200298 -15.811963) (xy 218.12836 -15.822311) (xy 218.09202 -15.82293)
			(xy 218.060058 -15.822406) (xy 217.996638 -15.814397) (xy 217.934723 -15.798502) (xy 217.875287 -15.774972)
			(xy 217.81927 -15.744178) (xy 217.767554 -15.706606) (xy 217.720955 -15.662848) (xy 217.680207 -15.613595)
			(xy 217.645955 -15.559623) (xy 217.618737 -15.501783) (xy 217.598983 -15.440989) (xy 217.587004 -15.378197)
			(xy 217.58299 -15.3144) (xy 208.80758 -15.3144) (xy 208.553812 -15.568168) (xy 208.551106 -15.571019)
			(xy 208.546511 -15.577396) (xy 208.544668 -15.580868) (xy 208.542089 -15.586296) (xy 208.539273 -15.597975)
			(xy 208.53908 -15.603982) (xy 208.53908 -15.920974) (xy 211.99424 -15.920974) (xy 211.998311 -15.865352)
			(xy 212.010437 -15.810915) (xy 212.03036 -15.758824) (xy 212.057656 -15.710189) (xy 212.091742 -15.666046)
			(xy 212.131891 -15.627337) (xy 212.177249 -15.594886) (xy 212.226849 -15.569385) (xy 212.279633 -15.551378)
			(xy 212.334476 -15.541248) (xy 212.39021 -15.539211) (xy 212.445647 -15.545311) (xy 212.499604 -15.559417)
			(xy 212.550933 -15.581229) (xy 212.598539 -15.610283) (xy 212.641407 -15.645958) (xy 212.678624 -15.687495)
			(xy 212.709397 -15.734008) (xy 212.733069 -15.784505) (xy 212.749137 -15.837912) (xy 212.757257 -15.893088)
			(xy 212.757766 -15.920974) (xy 212.757257 -15.94886) (xy 212.749137 -16.004036) (xy 212.733069 -16.057443)
			(xy 212.709397 -16.10794) (xy 212.678624 -16.154453) (xy 212.641407 -16.19599) (xy 212.598539 -16.231665)
			(xy 212.550933 -16.260719) (xy 212.499604 -16.282531) (xy 212.445647 -16.296637) (xy 212.39021 -16.302737)
			(xy 212.334476 -16.3007) (xy 212.279633 -16.29057) (xy 212.226849 -16.272563) (xy 212.177249 -16.247062)
			(xy 212.131891 -16.214611) (xy 212.091742 -16.175902) (xy 212.057656 -16.131759) (xy 212.03036 -16.083124)
			(xy 212.010437 -16.031033) (xy 211.998311 -15.976596) (xy 211.99424 -15.920974) (xy 208.53908 -15.920974)
			(xy 208.53908 -17.305993) (xy 212.034114 -17.305993) (xy 212.034114 -17.242071) (xy 212.042125 -17.178653)
			(xy 212.058022 -17.116739) (xy 212.081554 -17.057306) (xy 212.112348 -17.001291) (xy 212.149921 -16.949576)
			(xy 212.193678 -16.902979) (xy 212.242931 -16.862234) (xy 212.296902 -16.827983) (xy 212.354741 -16.800766)
			(xy 212.415534 -16.781013) (xy 212.478324 -16.769035) (xy 212.54212 -16.765022) (xy 212.605916 -16.769035)
			(xy 212.668706 -16.781013) (xy 212.729499 -16.800766) (xy 212.787338 -16.827983) (xy 212.841309 -16.862234)
			(xy 212.890562 -16.902979) (xy 212.934319 -16.949576) (xy 212.971892 -17.001291) (xy 213.002686 -17.057306)
			(xy 213.026218 -17.116739) (xy 213.042115 -17.178653) (xy 213.050126 -17.242071) (xy 213.050628 -17.274032)
			(xy 213.050126 -17.305993) (xy 213.042115 -17.369411) (xy 213.026218 -17.431325) (xy 213.002686 -17.490758)
			(xy 212.971892 -17.546773) (xy 212.934319 -17.598488) (xy 212.890562 -17.645085) (xy 212.841309 -17.68583)
			(xy 212.787338 -17.720081) (xy 212.729499 -17.747298) (xy 212.668706 -17.767051) (xy 212.605916 -17.779029)
			(xy 212.54212 -17.783043) (xy 212.478324 -17.779029) (xy 212.415534 -17.767051) (xy 212.354741 -17.747298)
			(xy 212.296902 -17.720081) (xy 212.242931 -17.68583) (xy 212.193678 -17.645085) (xy 212.149921 -17.598488)
			(xy 212.112348 -17.546773) (xy 212.081554 -17.490758) (xy 212.058022 -17.431325) (xy 212.042125 -17.369411)
			(xy 212.034114 -17.305993) (xy 208.53908 -17.305993) (xy 208.53908 -21.122132) (xy 208.54035 -21.133308)
			(xy 208.561617 -21.229008) (xy 208.597889 -21.421692) (xy 208.626968 -21.615592) (xy 208.629396 -21.637244)
			(xy 212.41766 -21.637244) (xy 212.418196 -21.609994) (xy 212.425946 -21.556047) (xy 212.441295 -21.503752)
			(xy 212.46393 -21.454175) (xy 212.493391 -21.408323) (xy 212.529077 -21.36713) (xy 212.570262 -21.331436)
			(xy 212.616108 -21.301967) (xy 212.665681 -21.279322) (xy 212.717973 -21.263962) (xy 212.771918 -21.256202)
			(xy 212.799168 -21.255736) (xy 212.825838 -21.256143) (xy 212.878658 -21.263561) (xy 212.929929 -21.278269)
			(xy 212.978648 -21.299981) (xy 213.023865 -21.328273) (xy 213.064697 -21.362593) (xy 213.100345 -21.402269)
			(xy 213.130115 -21.446528) (xy 213.153423 -21.494504) (xy 213.169816 -21.545261) (xy 213.174834 -21.571458)
			(xy 213.174834 -21.571712) (xy 213.176899 -21.580926) (xy 213.18683 -21.596973) (xy 213.194138 -21.602954)
			(xy 213.256876 -21.650706) (xy 213.275164 -21.655786) (xy 213.284816 -21.65477) (xy 213.297169 -21.653676)
			(xy 213.321945 -21.65253) (xy 213.334346 -21.652484) (xy 213.365884 -21.653016) (xy 213.428474 -21.660824)
			(xy 213.489618 -21.676313) (xy 213.548376 -21.699247) (xy 213.603847 -21.729272) (xy 213.655178 -21.765928)
			(xy 213.701581 -21.808651) (xy 213.742342 -21.856786) (xy 213.776837 -21.909593) (xy 213.804536 -21.966261)
			(xy 213.825012 -22.025921) (xy 213.837952 -22.087655) (xy 213.843156 -22.150515) (xy 213.840546 -22.213536)
			(xy 213.840039 -22.216575) (xy 215.396058 -22.216575) (xy 215.396058 -22.152653) (xy 215.404069 -22.089235)
			(xy 215.419966 -22.027321) (xy 215.443498 -21.967888) (xy 215.474292 -21.911873) (xy 215.511865 -21.860158)
			(xy 215.555622 -21.813561) (xy 215.604875 -21.772816) (xy 215.658846 -21.738565) (xy 215.716685 -21.711348)
			(xy 215.777478 -21.691595) (xy 215.840268 -21.679617) (xy 215.904064 -21.675604) (xy 215.96786 -21.679617)
			(xy 216.03065 -21.691595) (xy 216.091443 -21.711348) (xy 216.149282 -21.738565) (xy 216.203253 -21.772816)
			(xy 216.252506 -21.813561) (xy 216.296263 -21.860158) (xy 216.333836 -21.911873) (xy 216.36463 -21.967888)
			(xy 216.388162 -22.027321) (xy 216.404059 -22.089235) (xy 216.41207 -22.152653) (xy 216.412572 -22.184614)
			(xy 216.41207 -22.216575) (xy 216.404059 -22.279993) (xy 216.388162 -22.341907) (xy 216.36463 -22.40134)
			(xy 216.333836 -22.457355) (xy 216.296263 -22.50907) (xy 216.252506 -22.555667) (xy 216.203253 -22.596412)
			(xy 216.149282 -22.630663) (xy 216.091443 -22.65788) (xy 216.03065 -22.677633) (xy 215.96786 -22.689611)
			(xy 215.904064 -22.693625) (xy 215.840268 -22.689611) (xy 215.777478 -22.677633) (xy 215.716685 -22.65788)
			(xy 215.658846 -22.630663) (xy 215.604875 -22.596412) (xy 215.555622 -22.555667) (xy 215.511865 -22.50907)
			(xy 215.474292 -22.457355) (xy 215.443498 -22.40134) (xy 215.419966 -22.341907) (xy 215.404069 -22.279993)
			(xy 215.396058 -22.216575) (xy 213.840039 -22.216575) (xy 213.83016 -22.275751) (xy 213.812159 -22.336203)
			(xy 213.786818 -22.393964) (xy 213.754528 -22.448147) (xy 213.715783 -22.49792) (xy 213.67118 -22.542519)
			(xy 213.621403 -22.581258) (xy 213.567216 -22.613543) (xy 213.509452 -22.638877) (xy 213.448998 -22.656872)
			(xy 213.386782 -22.667251) (xy 213.323761 -22.669855) (xy 213.260901 -22.664644) (xy 213.199169 -22.651698)
			(xy 213.139512 -22.631215) (xy 213.082846 -22.603511) (xy 213.030043 -22.56901) (xy 212.981912 -22.528243)
			(xy 212.939193 -22.481836) (xy 212.902543 -22.430501) (xy 212.872524 -22.375027) (xy 212.849597 -22.316266)
			(xy 212.834114 -22.255121) (xy 212.826313 -22.19253) (xy 212.825838 -22.160992) (xy 212.827362 -22.122384)
			(xy 212.828124 -22.112732) (xy 212.822536 -22.094698) (xy 212.767418 -22.025356) (xy 212.750908 -22.015958)
			(xy 212.74151 -22.014434) (xy 212.71481 -22.00987) (xy 212.662967 -21.99418) (xy 212.613862 -21.971317)
			(xy 212.568484 -21.941741) (xy 212.527743 -21.906046) (xy 212.492459 -21.86495) (xy 212.46334 -21.819277)
			(xy 212.440971 -21.769946) (xy 212.425801 -21.717948) (xy 212.418137 -21.664327) (xy 212.41766 -21.637244)
			(xy 208.629396 -21.637244) (xy 208.648815 -21.810439) (xy 208.663398 -22.005964) (xy 208.670698 -22.201896)
			(xy 208.67116 -22.29993) (xy 208.670698 -22.397964) (xy 208.663386 -22.593895) (xy 208.648795 -22.789419)
			(xy 208.626947 -22.984265) (xy 208.59787 -23.178165) (xy 208.561605 -23.370849) (xy 208.54035 -23.466552)
			(xy 208.53908 -23.477728) (xy 208.53908 -23.98555) (xy 211.611474 -23.98555) (xy 211.611474 -23.93105)
			(xy 211.619229 -23.877105) (xy 211.634583 -23.824813) (xy 211.657222 -23.775237) (xy 211.686685 -23.729388)
			(xy 211.722373 -23.688198) (xy 211.763559 -23.652506) (xy 211.809406 -23.623039) (xy 211.858979 -23.600395)
			(xy 211.91127 -23.585037) (xy 211.965214 -23.577276) (xy 211.992464 -23.576788) (xy 212.010547 -23.576997)
			(xy 212.04655 -23.580429) (xy 212.064346 -23.583646) (xy 212.07349 -23.585424) (xy 212.09127 -23.582376)
			(xy 212.157056 -23.544022) (xy 212.164798 -23.539018) (xy 212.176385 -23.524698) (xy 212.179662 -23.516082)
			(xy 212.190225 -23.486182) (xy 212.217755 -23.429056) (xy 212.252174 -23.375796) (xy 212.292948 -23.327228)
			(xy 212.339443 -23.284106) (xy 212.390938 -23.2471) (xy 212.446635 -23.216782) (xy 212.505669 -23.193624)
			(xy 212.567124 -23.177985) (xy 212.630047 -23.170108) (xy 212.661754 -23.169626) (xy 212.69372 -23.170036)
			(xy 212.716627 -23.172928) (xy 216.561414 -23.172928) (xy 216.565485 -23.117306) (xy 216.577611 -23.062869)
			(xy 216.597534 -23.010778) (xy 216.62483 -22.962143) (xy 216.658916 -22.918) (xy 216.699065 -22.879291)
			(xy 216.744423 -22.84684) (xy 216.794023 -22.821339) (xy 216.846807 -22.803332) (xy 216.90165 -22.793202)
			(xy 216.957384 -22.791165) (xy 217.012821 -22.797265) (xy 217.066778 -22.811371) (xy 217.118107 -22.833183)
			(xy 217.165713 -22.862237) (xy 217.169394 -22.8653) (xy 218.780102 -22.8653) (xy 218.784116 -22.801504)
			(xy 218.796094 -22.738714) (xy 218.815848 -22.677921) (xy 218.843065 -22.620082) (xy 218.877318 -22.566112)
			(xy 218.918064 -22.51686) (xy 218.964662 -22.473103) (xy 219.016377 -22.435532) (xy 219.072394 -22.404739)
			(xy 219.131828 -22.381209) (xy 219.193742 -22.365315) (xy 219.257161 -22.357306) (xy 219.289122 -22.356826)
			(xy 219.289376 -22.356826) (xy 219.32016 -22.357299) (xy 219.381273 -22.364779) (xy 219.441038 -22.379572)
			(xy 219.46997 -22.3901) (xy 219.480624 -22.393476) (xy 219.502884 -22.391861) (xy 219.522391 -22.381017)
			(xy 219.529406 -22.37232) (xy 219.547346 -22.348203) (xy 219.588033 -22.303955) (xy 219.633653 -22.264815)
			(xy 219.683571 -22.231327) (xy 219.73709 -22.203959) (xy 219.793462 -22.183094) (xy 219.851902 -22.169021)
			(xy 219.911593 -22.161939) (xy 219.941648 -22.1615) (xy 219.973608 -22.161989) (xy 220.037022 -22.170006)
			(xy 220.098932 -22.185907) (xy 220.158361 -22.209441) (xy 220.214372 -22.240238) (xy 220.266081 -22.277812)
			(xy 220.312674 -22.32157) (xy 220.353416 -22.370822) (xy 220.387664 -22.424792) (xy 220.414878 -22.482629)
			(xy 220.434629 -22.54342) (xy 220.446605 -22.606207) (xy 220.450619 -22.67) (xy 220.446605 -22.733793)
			(xy 220.434629 -22.79658) (xy 220.414878 -22.857371) (xy 220.387664 -22.915208) (xy 220.353416 -22.969178)
			(xy 220.312674 -23.01843) (xy 220.266081 -23.062188) (xy 220.214372 -23.099762) (xy 220.158361 -23.130559)
			(xy 220.098932 -23.154093) (xy 220.037022 -23.169994) (xy 219.973608 -23.178011) (xy 219.941648 -23.178516)
			(xy 219.941394 -23.178516) (xy 219.91061 -23.178049) (xy 219.849497 -23.170566) (xy 219.789732 -23.155771)
			(xy 219.7608 -23.145242) (xy 219.750156 -23.141822) (xy 219.727884 -23.143449) (xy 219.708375 -23.154314)
			(xy 219.701364 -23.163022) (xy 219.683394 -23.187116) (xy 219.64271 -23.231362) (xy 219.597094 -23.270503)
			(xy 219.54718 -23.303992) (xy 219.493666 -23.331363) (xy 219.437299 -23.352232) (xy 219.378863 -23.36631)
			(xy 219.319176 -23.3734) (xy 219.289122 -23.373842) (xy 219.257161 -23.373294) (xy 219.193742 -23.365285)
			(xy 219.131828 -23.349391) (xy 219.072394 -23.325861) (xy 219.016377 -23.295068) (xy 218.964662 -23.257497)
			(xy 218.918064 -23.21374) (xy 218.877318 -23.164488) (xy 218.843065 -23.110518) (xy 218.815848 -23.052679)
			(xy 218.796094 -22.991886) (xy 218.784116 -22.929096) (xy 218.780102 -22.8653) (xy 217.169394 -22.8653)
			(xy 217.208581 -22.897912) (xy 217.245798 -22.939449) (xy 217.276571 -22.985962) (xy 217.300243 -23.036459)
			(xy 217.316311 -23.089866) (xy 217.324431 -23.145042) (xy 217.32494 -23.172928) (xy 217.324431 -23.200814)
			(xy 217.316311 -23.25599) (xy 217.300243 -23.309397) (xy 217.276571 -23.359894) (xy 217.245798 -23.406407)
			(xy 217.208581 -23.447944) (xy 217.165713 -23.483619) (xy 217.118107 -23.512673) (xy 217.066778 -23.534485)
			(xy 217.012821 -23.548591) (xy 216.957384 -23.554691) (xy 216.90165 -23.552654) (xy 216.846807 -23.542524)
			(xy 216.794023 -23.524517) (xy 216.744423 -23.499016) (xy 216.699065 -23.466565) (xy 216.658916 -23.427856)
			(xy 216.62483 -23.383713) (xy 216.597534 -23.335078) (xy 216.577611 -23.282987) (xy 216.565485 -23.22855)
			(xy 216.561414 -23.172928) (xy 212.716627 -23.172928) (xy 212.75715 -23.178044) (xy 212.819075 -23.193939)
			(xy 212.87852 -23.21747) (xy 212.934546 -23.248266) (xy 212.986271 -23.285842) (xy 213.032878 -23.329605)
			(xy 213.073632 -23.378864) (xy 213.10789 -23.432843) (xy 213.135113 -23.49069) (xy 213.15487 -23.551493)
			(xy 213.166851 -23.614294) (xy 213.170866 -23.6781) (xy 213.166851 -23.741906) (xy 213.15487 -23.804707)
			(xy 213.135113 -23.86551) (xy 213.10789 -23.923357) (xy 213.088484 -23.953935) (xy 213.254584 -23.953935)
			(xy 213.254584 -23.890013) (xy 213.262595 -23.826595) (xy 213.278492 -23.764681) (xy 213.302024 -23.705248)
			(xy 213.332818 -23.649233) (xy 213.370391 -23.597518) (xy 213.414148 -23.550921) (xy 213.463401 -23.510176)
			(xy 213.517372 -23.475925) (xy 213.575211 -23.448708) (xy 213.636004 -23.428955) (xy 213.698794 -23.416977)
			(xy 213.76259 -23.412964) (xy 213.826386 -23.416977) (xy 213.889176 -23.428955) (xy 213.949969 -23.448708)
			(xy 214.007808 -23.475925) (xy 214.061779 -23.510176) (xy 214.111032 -23.550921) (xy 214.154789 -23.597518)
			(xy 214.192362 -23.649233) (xy 214.223156 -23.705248) (xy 214.246688 -23.764681) (xy 214.262585 -23.826595)
			(xy 214.270596 -23.890013) (xy 214.271098 -23.921974) (xy 214.270596 -23.953935) (xy 214.262585 -24.017353)
			(xy 214.246688 -24.079267) (xy 214.238686 -24.099477) (xy 214.750136 -24.099477) (xy 214.750136 -24.035555)
			(xy 214.758147 -23.972137) (xy 214.774044 -23.910223) (xy 214.797576 -23.85079) (xy 214.82837 -23.794775)
			(xy 214.865943 -23.74306) (xy 214.9097 -23.696463) (xy 214.958953 -23.655718) (xy 215.012924 -23.621467)
			(xy 215.070763 -23.59425) (xy 215.131556 -23.574497) (xy 215.194346 -23.562519) (xy 215.258142 -23.558506)
			(xy 215.321938 -23.562519) (xy 215.384728 -23.574497) (xy 215.445521 -23.59425) (xy 215.50336 -23.621467)
			(xy 215.557331 -23.655718) (xy 215.606584 -23.696463) (xy 215.650341 -23.74306) (xy 215.687914 -23.794775)
			(xy 215.718708 -23.85079) (xy 215.74224 -23.910223) (xy 215.758137 -23.972137) (xy 215.766148 -24.035555)
			(xy 215.76665 -24.067516) (xy 215.766148 -24.099477) (xy 215.758137 -24.162895) (xy 215.74224 -24.224809)
			(xy 215.718708 -24.284242) (xy 215.687914 -24.340257) (xy 215.650341 -24.391972) (xy 215.606584 -24.438569)
			(xy 215.557331 -24.479314) (xy 215.50336 -24.513565) (xy 215.445521 -24.540782) (xy 215.384728 -24.560535)
			(xy 215.321938 -24.572513) (xy 215.258142 -24.576527) (xy 215.194346 -24.572513) (xy 215.131556 -24.560535)
			(xy 215.070763 -24.540782) (xy 215.012924 -24.513565) (xy 214.958953 -24.479314) (xy 214.9097 -24.438569)
			(xy 214.865943 -24.391972) (xy 214.82837 -24.340257) (xy 214.797576 -24.284242) (xy 214.774044 -24.224809)
			(xy 214.758147 -24.162895) (xy 214.750136 -24.099477) (xy 214.238686 -24.099477) (xy 214.223156 -24.1387)
			(xy 214.192362 -24.194715) (xy 214.154789 -24.24643) (xy 214.111032 -24.293027) (xy 214.061779 -24.333772)
			(xy 214.007808 -24.368023) (xy 213.949969 -24.39524) (xy 213.889176 -24.414993) (xy 213.826386 -24.426971)
			(xy 213.76259 -24.430985) (xy 213.698794 -24.426971) (xy 213.636004 -24.414993) (xy 213.575211 -24.39524)
			(xy 213.517372 -24.368023) (xy 213.463401 -24.333772) (xy 213.414148 -24.293027) (xy 213.370391 -24.24643)
			(xy 213.332818 -24.194715) (xy 213.302024 -24.1387) (xy 213.278492 -24.079267) (xy 213.262595 -24.017353)
			(xy 213.254584 -23.953935) (xy 213.088484 -23.953935) (xy 213.073632 -23.977336) (xy 213.032878 -24.026595)
			(xy 212.986271 -24.070358) (xy 212.934546 -24.107934) (xy 212.87852 -24.13873) (xy 212.819075 -24.162261)
			(xy 212.75715 -24.178156) (xy 212.69372 -24.186164) (xy 212.661754 -24.186642) (xy 212.632887 -24.186242)
			(xy 212.575528 -24.179675) (xy 212.519279 -24.166664) (xy 212.464862 -24.147377) (xy 212.438742 -24.13508)
			(xy 212.430614 -24.131016) (xy 212.412072 -24.129238) (xy 212.338666 -24.14905) (xy 212.329923 -24.151766)
			(xy 212.315079 -24.162461) (xy 212.30971 -24.169878) (xy 212.30971 -24.170132) (xy 212.294456 -24.192139)
			(xy 212.258799 -24.232086) (xy 212.217905 -24.266651) (xy 212.172577 -24.295155) (xy 212.123707 -24.317037)
			(xy 212.072256 -24.331868) (xy 212.019237 -24.339354) (xy 211.992464 -24.339804) (xy 211.965214 -24.339324)
			(xy 211.91127 -24.331563) (xy 211.858979 -24.316205) (xy 211.809406 -24.293561) (xy 211.763559 -24.264094)
			(xy 211.722373 -24.228402) (xy 211.686685 -24.187212) (xy 211.657222 -24.141363) (xy 211.634583 -24.091787)
			(xy 211.619229 -24.039495) (xy 211.611474 -23.98555) (xy 208.53908 -23.98555) (xy 208.53908 -25.311354)
			(xy 216.680794 -25.311354) (xy 216.684865 -25.255732) (xy 216.696991 -25.201295) (xy 216.716914 -25.149204)
			(xy 216.74421 -25.100569) (xy 216.778296 -25.056426) (xy 216.818445 -25.017717) (xy 216.863803 -24.985266)
			(xy 216.913403 -24.959765) (xy 216.966187 -24.941758) (xy 217.02103 -24.931628) (xy 217.076764 -24.929591)
			(xy 217.132201 -24.935691) (xy 217.186158 -24.949797) (xy 217.237487 -24.971609) (xy 217.285093 -25.000663)
			(xy 217.327961 -25.036338) (xy 217.365178 -25.077875) (xy 217.395951 -25.124388) (xy 217.419623 -25.174885)
			(xy 217.435691 -25.228292) (xy 217.443811 -25.283468) (xy 217.44432 -25.311354) (xy 217.443811 -25.33924)
			(xy 217.435691 -25.394416) (xy 217.419623 -25.447823) (xy 217.395951 -25.49832) (xy 217.365178 -25.544833)
			(xy 217.327961 -25.58637) (xy 217.285093 -25.622045) (xy 217.237487 -25.651099) (xy 217.186158 -25.672911)
			(xy 217.132201 -25.687017) (xy 217.076764 -25.693117) (xy 217.02103 -25.69108) (xy 216.966187 -25.68095)
			(xy 216.913403 -25.662943) (xy 216.863803 -25.637442) (xy 216.818445 -25.604991) (xy 216.778296 -25.566282)
			(xy 216.74421 -25.522139) (xy 216.716914 -25.473504) (xy 216.696991 -25.421413) (xy 216.684865 -25.366976)
			(xy 216.680794 -25.311354) (xy 208.53908 -25.311354) (xy 208.53908 -26.468324) (xy 210.767674 -26.468324)
			(xy 210.771745 -26.412702) (xy 210.783871 -26.358265) (xy 210.803794 -26.306174) (xy 210.83109 -26.257539)
			(xy 210.865176 -26.213396) (xy 210.905325 -26.174687) (xy 210.950683 -26.142236) (xy 211.000283 -26.116735)
			(xy 211.053067 -26.098728) (xy 211.10791 -26.088598) (xy 211.163644 -26.086561) (xy 211.219081 -26.092661)
			(xy 211.273038 -26.106767) (xy 211.324367 -26.128579) (xy 211.371973 -26.157633) (xy 211.414841 -26.193308)
			(xy 211.452058 -26.234845) (xy 211.482831 -26.281358) (xy 211.506503 -26.331855) (xy 211.522571 -26.385262)
			(xy 211.530691 -26.440438) (xy 211.5312 -26.468324) (xy 211.530691 -26.49621) (xy 211.522571 -26.551386)
			(xy 211.506503 -26.604793) (xy 211.482831 -26.65529) (xy 211.452058 -26.701803) (xy 211.414841 -26.74334)
			(xy 211.371973 -26.779015) (xy 211.324367 -26.808069) (xy 211.273038 -26.829881) (xy 211.219081 -26.843987)
			(xy 211.163644 -26.850087) (xy 211.10791 -26.84805) (xy 211.053067 -26.83792) (xy 211.000283 -26.819913)
			(xy 210.950683 -26.794412) (xy 210.905325 -26.761961) (xy 210.865176 -26.723252) (xy 210.83109 -26.679109)
			(xy 210.803794 -26.630474) (xy 210.783871 -26.578383) (xy 210.771745 -26.523946) (xy 210.767674 -26.468324)
			(xy 208.53908 -26.468324) (xy 208.53908 -28.015184) (xy 213.705692 -28.015184) (xy 213.709763 -27.959562)
			(xy 213.721889 -27.905125) (xy 213.741812 -27.853034) (xy 213.769108 -27.804399) (xy 213.803194 -27.760256)
			(xy 213.843343 -27.721547) (xy 213.888701 -27.689096) (xy 213.938301 -27.663595) (xy 213.991085 -27.645588)
			(xy 214.045928 -27.635458) (xy 214.101662 -27.633421) (xy 214.157099 -27.639521) (xy 214.211056 -27.653627)
			(xy 214.262385 -27.675439) (xy 214.309991 -27.704493) (xy 214.352859 -27.740168) (xy 214.390076 -27.781705)
			(xy 214.420849 -27.828218) (xy 214.444521 -27.878715) (xy 214.460589 -27.932122) (xy 214.468709 -27.987298)
			(xy 214.469218 -28.015184) (xy 214.468709 -28.04307) (xy 214.460589 -28.098246) (xy 214.444521 -28.151653)
			(xy 214.420849 -28.20215) (xy 214.390076 -28.248663) (xy 214.352859 -28.2902) (xy 214.309991 -28.325875)
			(xy 214.262385 -28.354929) (xy 214.211056 -28.376741) (xy 214.157099 -28.390847) (xy 214.101662 -28.396947)
			(xy 214.045928 -28.39491) (xy 213.991085 -28.38478) (xy 213.938301 -28.366773) (xy 213.888701 -28.341272)
			(xy 213.843343 -28.308821) (xy 213.803194 -28.270112) (xy 213.769108 -28.225969) (xy 213.741812 -28.177334)
			(xy 213.721889 -28.125243) (xy 213.709763 -28.070806) (xy 213.705692 -28.015184) (xy 208.53908 -28.015184)
			(xy 208.53908 -28.195778) (xy 208.538642 -28.205841) (xy 208.530906 -28.224423) (xy 208.524094 -28.231846)
			(xy 208.040732 -28.715208) (xy 208.034308 -28.722232) (xy 208.02673 -28.739678) (xy 208.026009 -28.758686)
			(xy 208.028794 -28.767786) (xy 208.059782 -28.857448) (xy 208.06209 -28.862454) (xy 208.068487 -28.87143)
			(xy 208.072482 -28.875228) (xy 208.073498 -28.87599) (xy 208.080864 -28.882086) (xy 208.09331 -28.886912)
			(xy 208.100676 -28.887928) (xy 208.12811 -28.891726) (xy 208.181564 -28.90622) (xy 208.23236 -28.928289)
			(xy 208.279433 -28.957469) (xy 208.321793 -28.993147) (xy 208.35855 -29.034574) (xy 208.388933 -29.080879)
			(xy 208.412303 -29.13109) (xy 208.428169 -29.184152) (xy 208.436198 -29.238951) (xy 208.436718 -29.266642)
			(xy 210.721192 -29.266642) (xy 210.725263 -29.21102) (xy 210.737389 -29.156583) (xy 210.757312 -29.104492)
			(xy 210.784608 -29.055857) (xy 210.818694 -29.011714) (xy 210.858843 -28.973005) (xy 210.904201 -28.940554)
			(xy 210.953801 -28.915053) (xy 211.006585 -28.897046) (xy 211.061428 -28.886916) (xy 211.117162 -28.884879)
			(xy 211.172599 -28.890979) (xy 211.226556 -28.905085) (xy 211.277885 -28.926897) (xy 211.325491 -28.955951)
			(xy 211.368359 -28.991626) (xy 211.405576 -29.033163) (xy 211.436349 -29.079676) (xy 211.460021 -29.130173)
			(xy 211.476089 -29.18358) (xy 211.484209 -29.238756) (xy 211.484718 -29.266642) (xy 211.484209 -29.294528)
			(xy 211.483609 -29.298603) (xy 211.611204 -29.298603) (xy 211.611204 -29.234681) (xy 211.619215 -29.171263)
			(xy 211.635112 -29.109349) (xy 211.658644 -29.049916) (xy 211.689438 -28.993901) (xy 211.727011 -28.942186)
			(xy 211.770768 -28.895589) (xy 211.820021 -28.854844) (xy 211.873992 -28.820593) (xy 211.931831 -28.793376)
			(xy 211.992624 -28.773623) (xy 212.055414 -28.761645) (xy 212.11921 -28.757632) (xy 212.183006 -28.761645)
			(xy 212.245796 -28.773623) (xy 212.306589 -28.793376) (xy 212.364428 -28.820593) (xy 212.418399 -28.854844)
			(xy 212.467652 -28.895589) (xy 212.511409 -28.942186) (xy 212.548982 -28.993901) (xy 212.579776 -29.049916)
			(xy 212.603308 -29.109349) (xy 212.619205 -29.171263) (xy 212.627216 -29.234681) (xy 212.627718 -29.266642)
			(xy 212.627216 -29.298603) (xy 212.619205 -29.362021) (xy 212.603308 -29.423935) (xy 212.579776 -29.483368)
			(xy 212.548982 -29.539383) (xy 212.511409 -29.591098) (xy 212.467652 -29.637695) (xy 212.418399 -29.67844)
			(xy 212.364428 -29.712691) (xy 212.306589 -29.739908) (xy 212.245796 -29.759661) (xy 212.183006 -29.771639)
			(xy 212.11921 -29.775653) (xy 212.055414 -29.771639) (xy 211.992624 -29.759661) (xy 211.931831 -29.739908)
			(xy 211.873992 -29.712691) (xy 211.820021 -29.67844) (xy 211.770768 -29.637695) (xy 211.727011 -29.591098)
			(xy 211.689438 -29.539383) (xy 211.658644 -29.483368) (xy 211.635112 -29.423935) (xy 211.619215 -29.362021)
			(xy 211.611204 -29.298603) (xy 211.483609 -29.298603) (xy 211.476089 -29.349704) (xy 211.460021 -29.403111)
			(xy 211.436349 -29.453608) (xy 211.405576 -29.500121) (xy 211.368359 -29.541658) (xy 211.325491 -29.577333)
			(xy 211.277885 -29.606387) (xy 211.226556 -29.628199) (xy 211.172599 -29.642305) (xy 211.117162 -29.648405)
			(xy 211.061428 -29.646368) (xy 211.006585 -29.636238) (xy 210.953801 -29.618231) (xy 210.904201 -29.59273)
			(xy 210.858843 -29.560279) (xy 210.818694 -29.52157) (xy 210.784608 -29.477427) (xy 210.757312 -29.428792)
			(xy 210.737389 -29.376701) (xy 210.725263 -29.322264) (xy 210.721192 -29.266642) (xy 208.436718 -29.266642)
			(xy 208.436229 -29.293892) (xy 208.428468 -29.347835) (xy 208.413109 -29.400126) (xy 208.390466 -29.449698)
			(xy 208.360999 -29.495544) (xy 208.325307 -29.53673) (xy 208.284118 -29.572418) (xy 208.23827 -29.601881)
			(xy 208.188696 -29.624521) (xy 208.136404 -29.639875) (xy 208.08246 -29.647632) (xy 208.05521 -29.64815)
			(xy 208.027516 -29.647655) (xy 207.972711 -29.639644) (xy 207.919641 -29.623788) (xy 207.869423 -29.600422)
			(xy 207.823113 -29.570037) (xy 207.781687 -29.533273) (xy 207.746015 -29.490902) (xy 207.716847 -29.443816)
			(xy 207.694799 -29.393006) (xy 207.680332 -29.33954) (xy 207.676496 -29.312108) (xy 207.676242 -29.310076)
			(xy 207.675194 -29.304297) (xy 207.670827 -29.293397) (xy 207.667606 -29.288486) (xy 207.665574 -29.2862)
			(xy 207.663796 -29.283914) (xy 207.661002 -29.280612) (xy 207.655414 -29.276548) (xy 207.652448 -29.274574)
			(xy 207.646071 -29.271393) (xy 207.642714 -29.270198) (xy 207.633824 -29.266896) (xy 207.556354 -29.240226)
			(xy 207.547247 -29.23746) (xy 207.52824 -29.23816) (xy 207.510794 -29.245735) (xy 207.503776 -29.252164)
			(xy 203.866031 -32.889909) (xy 214.178128 -32.889909) (xy 214.178128 -32.825987) (xy 214.186139 -32.762569)
			(xy 214.202036 -32.700655) (xy 214.225568 -32.641222) (xy 214.256362 -32.585207) (xy 214.293935 -32.533492)
			(xy 214.337692 -32.486895) (xy 214.386945 -32.44615) (xy 214.440916 -32.411899) (xy 214.498755 -32.384682)
			(xy 214.559548 -32.364929) (xy 214.622338 -32.352951) (xy 214.686134 -32.348938) (xy 214.74993 -32.352951)
			(xy 214.81272 -32.364929) (xy 214.873513 -32.384682) (xy 214.931352 -32.411899) (xy 214.985323 -32.44615)
			(xy 215.034576 -32.486895) (xy 215.078333 -32.533492) (xy 215.115906 -32.585207) (xy 215.1467 -32.641222)
			(xy 215.170232 -32.700655) (xy 215.186129 -32.762569) (xy 215.19414 -32.825987) (xy 215.194642 -32.857948)
			(xy 215.19414 -32.889909) (xy 216.464128 -32.889909) (xy 216.464128 -32.825987) (xy 216.472139 -32.762569)
			(xy 216.488036 -32.700655) (xy 216.511568 -32.641222) (xy 216.542362 -32.585207) (xy 216.579935 -32.533492)
			(xy 216.623692 -32.486895) (xy 216.672945 -32.44615) (xy 216.726916 -32.411899) (xy 216.784755 -32.384682)
			(xy 216.845548 -32.364929) (xy 216.908338 -32.352951) (xy 216.972134 -32.348938) (xy 217.03593 -32.352951)
			(xy 217.09872 -32.364929) (xy 217.159513 -32.384682) (xy 217.217352 -32.411899) (xy 217.271323 -32.44615)
			(xy 217.320576 -32.486895) (xy 217.364333 -32.533492) (xy 217.401906 -32.585207) (xy 217.4327 -32.641222)
			(xy 217.456232 -32.700655) (xy 217.472129 -32.762569) (xy 217.48014 -32.825987) (xy 217.480642 -32.857948)
			(xy 217.48014 -32.889909) (xy 217.472129 -32.953327) (xy 217.456232 -33.015241) (xy 217.4327 -33.074674)
			(xy 217.401906 -33.130689) (xy 217.364333 -33.182404) (xy 217.320576 -33.229001) (xy 217.271323 -33.269746)
			(xy 217.217352 -33.303997) (xy 217.159513 -33.331214) (xy 217.09872 -33.350967) (xy 217.03593 -33.362945)
			(xy 216.972134 -33.366959) (xy 216.908338 -33.362945) (xy 216.845548 -33.350967) (xy 216.784755 -33.331214)
			(xy 216.726916 -33.303997) (xy 216.672945 -33.269746) (xy 216.623692 -33.229001) (xy 216.579935 -33.182404)
			(xy 216.542362 -33.130689) (xy 216.511568 -33.074674) (xy 216.488036 -33.015241) (xy 216.472139 -32.953327)
			(xy 216.464128 -32.889909) (xy 215.19414 -32.889909) (xy 215.186129 -32.953327) (xy 215.170232 -33.015241)
			(xy 215.1467 -33.074674) (xy 215.115906 -33.130689) (xy 215.078333 -33.182404) (xy 215.034576 -33.229001)
			(xy 214.985323 -33.269746) (xy 214.931352 -33.303997) (xy 214.873513 -33.331214) (xy 214.81272 -33.350967)
			(xy 214.74993 -33.362945) (xy 214.686134 -33.366959) (xy 214.622338 -33.362945) (xy 214.559548 -33.350967)
			(xy 214.498755 -33.331214) (xy 214.440916 -33.303997) (xy 214.386945 -33.269746) (xy 214.337692 -33.229001)
			(xy 214.293935 -33.182404) (xy 214.256362 -33.130689) (xy 214.225568 -33.074674) (xy 214.202036 -33.015241)
			(xy 214.186139 -32.953327) (xy 214.178128 -32.889909) (xy 203.866031 -32.889909) (xy 202.851766 -33.904174)
			(xy 202.844367 -33.911018) (xy 202.825769 -33.918744) (xy 202.815698 -33.91916) (xy 188.923422 -33.91916)
			(xy 188.917413 -33.91933) (xy 188.905733 -33.922158) (xy 188.900308 -33.924748) (xy 188.896834 -33.926588)
			(xy 188.890456 -33.931182) (xy 188.887608 -33.933892) (xy 188.624972 -34.196528) (xy 208.182208 -34.196528)
			(xy 208.186279 -34.140906) (xy 208.198405 -34.086469) (xy 208.218328 -34.034378) (xy 208.245624 -33.985743)
			(xy 208.27971 -33.9416) (xy 208.319859 -33.902891) (xy 208.365217 -33.87044) (xy 208.414817 -33.844939)
			(xy 208.467601 -33.826932) (xy 208.522444 -33.816802) (xy 208.578178 -33.814765) (xy 208.633615 -33.820865)
			(xy 208.687572 -33.834971) (xy 208.738901 -33.856783) (xy 208.786507 -33.885837) (xy 208.829375 -33.921512)
			(xy 208.866592 -33.963049) (xy 208.897365 -34.009562) (xy 208.921037 -34.060059) (xy 208.937105 -34.113466)
			(xy 208.945225 -34.168642) (xy 208.945734 -34.196528) (xy 208.945225 -34.224414) (xy 208.937105 -34.27959)
			(xy 208.921037 -34.332997) (xy 208.897365 -34.383494) (xy 208.866592 -34.430007) (xy 208.829375 -34.471544)
			(xy 208.786507 -34.507219) (xy 208.738901 -34.536273) (xy 208.727991 -34.540909) (xy 214.178128 -34.540909)
			(xy 214.178128 -34.476987) (xy 214.186139 -34.413569) (xy 214.202036 -34.351655) (xy 214.225568 -34.292222)
			(xy 214.256362 -34.236207) (xy 214.293935 -34.184492) (xy 214.337692 -34.137895) (xy 214.386945 -34.09715)
			(xy 214.440916 -34.062899) (xy 214.498755 -34.035682) (xy 214.559548 -34.015929) (xy 214.622338 -34.003951)
			(xy 214.686134 -33.999938) (xy 214.74993 -34.003951) (xy 214.81272 -34.015929) (xy 214.873513 -34.035682)
			(xy 214.931352 -34.062899) (xy 214.985323 -34.09715) (xy 215.034576 -34.137895) (xy 215.078333 -34.184492)
			(xy 215.115906 -34.236207) (xy 215.1467 -34.292222) (xy 215.170232 -34.351655) (xy 215.186129 -34.413569)
			(xy 215.19414 -34.476987) (xy 215.194642 -34.508948) (xy 215.19414 -34.540909) (xy 216.464128 -34.540909)
			(xy 216.464128 -34.476987) (xy 216.472139 -34.413569) (xy 216.488036 -34.351655) (xy 216.511568 -34.292222)
			(xy 216.542362 -34.236207) (xy 216.579935 -34.184492) (xy 216.623692 -34.137895) (xy 216.672945 -34.09715)
			(xy 216.726916 -34.062899) (xy 216.784755 -34.035682) (xy 216.845548 -34.015929) (xy 216.908338 -34.003951)
			(xy 216.972134 -33.999938) (xy 217.03593 -34.003951) (xy 217.09872 -34.015929) (xy 217.159513 -34.035682)
			(xy 217.217352 -34.062899) (xy 217.271323 -34.09715) (xy 217.320576 -34.137895) (xy 217.364333 -34.184492)
			(xy 217.401906 -34.236207) (xy 217.4327 -34.292222) (xy 217.456232 -34.351655) (xy 217.472129 -34.413569)
			(xy 217.48014 -34.476987) (xy 217.480642 -34.508948) (xy 217.48014 -34.540909) (xy 217.472129 -34.604327)
			(xy 217.456232 -34.666241) (xy 217.4327 -34.725674) (xy 217.401906 -34.781689) (xy 217.364333 -34.833404)
			(xy 217.320576 -34.880001) (xy 217.271323 -34.920746) (xy 217.217352 -34.954997) (xy 217.159513 -34.982214)
			(xy 217.09872 -35.001967) (xy 217.03593 -35.013945) (xy 216.972134 -35.017959) (xy 216.908338 -35.013945)
			(xy 216.845548 -35.001967) (xy 216.784755 -34.982214) (xy 216.726916 -34.954997) (xy 216.672945 -34.920746)
			(xy 216.623692 -34.880001) (xy 216.579935 -34.833404) (xy 216.542362 -34.781689) (xy 216.511568 -34.725674)
			(xy 216.488036 -34.666241) (xy 216.472139 -34.604327) (xy 216.464128 -34.540909) (xy 215.19414 -34.540909)
			(xy 215.186129 -34.604327) (xy 215.170232 -34.666241) (xy 215.1467 -34.725674) (xy 215.115906 -34.781689)
			(xy 215.078333 -34.833404) (xy 215.034576 -34.880001) (xy 214.985323 -34.920746) (xy 214.931352 -34.954997)
			(xy 214.873513 -34.982214) (xy 214.81272 -35.001967) (xy 214.74993 -35.013945) (xy 214.686134 -35.017959)
			(xy 214.622338 -35.013945) (xy 214.559548 -35.001967) (xy 214.498755 -34.982214) (xy 214.440916 -34.954997)
			(xy 214.386945 -34.920746) (xy 214.337692 -34.880001) (xy 214.293935 -34.833404) (xy 214.256362 -34.781689)
			(xy 214.225568 -34.725674) (xy 214.202036 -34.666241) (xy 214.186139 -34.604327) (xy 214.178128 -34.540909)
			(xy 208.727991 -34.540909) (xy 208.687572 -34.558085) (xy 208.633615 -34.572191) (xy 208.578178 -34.578291)
			(xy 208.522444 -34.576254) (xy 208.467601 -34.566124) (xy 208.414817 -34.548117) (xy 208.365217 -34.522616)
			(xy 208.319859 -34.490165) (xy 208.27971 -34.451456) (xy 208.245624 -34.407313) (xy 208.218328 -34.358678)
			(xy 208.198405 -34.306587) (xy 208.186279 -34.25215) (xy 208.182208 -34.196528) (xy 188.624972 -34.196528)
			(xy 187.437311 -35.384189) (xy 188.226694 -35.384189) (xy 188.226694 -35.320267) (xy 188.234705 -35.256849)
			(xy 188.250602 -35.194935) (xy 188.274134 -35.135502) (xy 188.304928 -35.079487) (xy 188.342501 -35.027772)
			(xy 188.386258 -34.981175) (xy 188.435511 -34.94043) (xy 188.489482 -34.906179) (xy 188.547321 -34.878962)
			(xy 188.608114 -34.859209) (xy 188.670904 -34.847231) (xy 188.7347 -34.843218) (xy 188.798496 -34.847231)
			(xy 188.861286 -34.859209) (xy 188.922079 -34.878962) (xy 188.979918 -34.906179) (xy 189.033889 -34.94043)
			(xy 189.083142 -34.981175) (xy 189.126899 -35.027772) (xy 189.164472 -35.079487) (xy 189.195266 -35.135502)
			(xy 189.218798 -35.194935) (xy 189.234695 -35.256849) (xy 189.242706 -35.320267) (xy 189.243208 -35.352228)
			(xy 189.242706 -35.384189) (xy 189.234695 -35.447607) (xy 189.218798 -35.509521) (xy 189.201141 -35.554115)
			(xy 206.383122 -35.554115) (xy 206.383122 -35.490193) (xy 206.391133 -35.426775) (xy 206.40703 -35.364861)
			(xy 206.430562 -35.305428) (xy 206.461356 -35.249413) (xy 206.498929 -35.197698) (xy 206.542686 -35.151101)
			(xy 206.591939 -35.110356) (xy 206.64591 -35.076105) (xy 206.703749 -35.048888) (xy 206.764542 -35.029135)
			(xy 206.827332 -35.017157) (xy 206.891128 -35.013144) (xy 206.954924 -35.017157) (xy 207.017714 -35.029135)
			(xy 207.078507 -35.048888) (xy 207.136346 -35.076105) (xy 207.190317 -35.110356) (xy 207.23957 -35.151101)
			(xy 207.283327 -35.197698) (xy 207.3209 -35.249413) (xy 207.351694 -35.305428) (xy 207.358156 -35.321748)
			(xy 209.345528 -35.321748) (xy 209.349599 -35.266126) (xy 209.361725 -35.211689) (xy 209.381648 -35.159598)
			(xy 209.408944 -35.110963) (xy 209.44303 -35.06682) (xy 209.483179 -35.028111) (xy 209.528537 -34.99566)
			(xy 209.578137 -34.970159) (xy 209.630921 -34.952152) (xy 209.685764 -34.942022) (xy 209.741498 -34.939985)
			(xy 209.796935 -34.946085) (xy 209.850892 -34.960191) (xy 209.902221 -34.982003) (xy 209.949827 -35.011057)
			(xy 209.992695 -35.046732) (xy 210.029912 -35.088269) (xy 210.060685 -35.134782) (xy 210.084357 -35.185279)
			(xy 210.100425 -35.238686) (xy 210.108545 -35.293862) (xy 210.109054 -35.321748) (xy 210.108545 -35.349634)
			(xy 210.100425 -35.40481) (xy 210.084357 -35.458217) (xy 210.060685 -35.508714) (xy 210.029912 -35.555227)
			(xy 209.992695 -35.596764) (xy 209.949827 -35.632439) (xy 209.902221 -35.661493) (xy 209.850892 -35.683305)
			(xy 209.796935 -35.697411) (xy 209.741498 -35.703511) (xy 209.685764 -35.701474) (xy 209.630921 -35.691344)
			(xy 209.578137 -35.673337) (xy 209.528537 -35.647836) (xy 209.483179 -35.615385) (xy 209.44303 -35.576676)
			(xy 209.408944 -35.532533) (xy 209.381648 -35.483898) (xy 209.361725 -35.431807) (xy 209.349599 -35.37737)
			(xy 209.345528 -35.321748) (xy 207.358156 -35.321748) (xy 207.375226 -35.364861) (xy 207.391123 -35.426775)
			(xy 207.399134 -35.490193) (xy 207.399636 -35.522154) (xy 207.399134 -35.554115) (xy 207.391123 -35.617533)
			(xy 207.375226 -35.679447) (xy 207.351694 -35.73888) (xy 207.3209 -35.794895) (xy 207.283327 -35.84661)
			(xy 207.23957 -35.893207) (xy 207.190317 -35.933952) (xy 207.136346 -35.968203) (xy 207.078507 -35.99542)
			(xy 207.017714 -36.015173) (xy 206.954924 -36.027151) (xy 206.891128 -36.031165) (xy 206.827332 -36.027151)
			(xy 206.764542 -36.015173) (xy 206.703749 -35.99542) (xy 206.64591 -35.968203) (xy 206.591939 -35.933952)
			(xy 206.542686 -35.893207) (xy 206.498929 -35.84661) (xy 206.461356 -35.794895) (xy 206.430562 -35.73888)
			(xy 206.40703 -35.679447) (xy 206.391133 -35.617533) (xy 206.383122 -35.554115) (xy 189.201141 -35.554115)
			(xy 189.195266 -35.568954) (xy 189.164472 -35.624969) (xy 189.126899 -35.676684) (xy 189.083142 -35.723281)
			(xy 189.033889 -35.764026) (xy 188.979918 -35.798277) (xy 188.922079 -35.825494) (xy 188.861286 -35.845247)
			(xy 188.798496 -35.857225) (xy 188.7347 -35.861239) (xy 188.670904 -35.857225) (xy 188.608114 -35.845247)
			(xy 188.547321 -35.825494) (xy 188.489482 -35.798277) (xy 188.435511 -35.764026) (xy 188.386258 -35.723281)
			(xy 188.342501 -35.676684) (xy 188.304928 -35.624969) (xy 188.274134 -35.568954) (xy 188.250602 -35.509521)
			(xy 188.234705 -35.447607) (xy 188.226694 -35.384189) (xy 187.437311 -35.384189) (xy 187.080652 -35.740848)
			(xy 187.073095 -35.749308) (xy 187.065559 -35.770671) (xy 187.066174 -35.781996) (xy 187.074048 -35.859974)
			(xy 187.075572 -35.868356) (xy 187.08116 -35.88131) (xy 187.084208 -35.886136) (xy 187.091574 -35.89401)
			(xy 187.096654 -35.897312) (xy 187.122643 -35.914986) (xy 187.170475 -35.955758) (xy 187.212918 -36.002114)
			(xy 187.249324 -36.053348) (xy 187.279138 -36.108678) (xy 187.301905 -36.16726) (xy 187.317279 -36.228202)
			(xy 187.325026 -36.290574) (xy 187.325508 -36.322) (xy 187.325044 -36.352731) (xy 187.317635 -36.413745)
			(xy 187.312827 -36.433252) (xy 195.216524 -36.433252) (xy 195.220595 -36.37763) (xy 195.232721 -36.323193)
			(xy 195.252644 -36.271102) (xy 195.27994 -36.222467) (xy 195.314026 -36.178324) (xy 195.354175 -36.139615)
			(xy 195.399533 -36.107164) (xy 195.449133 -36.081663) (xy 195.501917 -36.063656) (xy 195.55676 -36.053526)
			(xy 195.612494 -36.051489) (xy 195.667931 -36.057589) (xy 195.721888 -36.071695) (xy 195.773217 -36.093507)
			(xy 195.820823 -36.122561) (xy 195.863691 -36.158236) (xy 195.900908 -36.199773) (xy 195.931681 -36.246286)
			(xy 195.955353 -36.296783) (xy 195.971421 -36.35019) (xy 195.974294 -36.369709) (xy 216.459048 -36.369709)
			(xy 216.459048 -36.305787) (xy 216.467059 -36.242369) (xy 216.482956 -36.180455) (xy 216.506488 -36.121022)
			(xy 216.537282 -36.065007) (xy 216.574855 -36.013292) (xy 216.618612 -35.966695) (xy 216.667865 -35.92595)
			(xy 216.721836 -35.891699) (xy 216.779675 -35.864482) (xy 216.840468 -35.844729) (xy 216.903258 -35.832751)
			(xy 216.967054 -35.828738) (xy 217.03085 -35.832751) (xy 217.09364 -35.844729) (xy 217.154433 -35.864482)
			(xy 217.212272 -35.891699) (xy 217.266243 -35.92595) (xy 217.315496 -35.966695) (xy 217.359253 -36.013292)
			(xy 217.396826 -36.065007) (xy 217.42762 -36.121022) (xy 217.451152 -36.180455) (xy 217.467049 -36.242369)
			(xy 217.47506 -36.305787) (xy 217.475562 -36.337748) (xy 217.47506 -36.369709) (xy 217.467049 -36.433127)
			(xy 217.451152 -36.495041) (xy 217.42762 -36.554474) (xy 217.396826 -36.610489) (xy 217.359253 -36.662204)
			(xy 217.315496 -36.708801) (xy 217.266243 -36.749546) (xy 217.212272 -36.783797) (xy 217.154433 -36.811014)
			(xy 217.09364 -36.830767) (xy 217.03085 -36.842745) (xy 216.967054 -36.846759) (xy 216.903258 -36.842745)
			(xy 216.840468 -36.830767) (xy 216.779675 -36.811014) (xy 216.721836 -36.783797) (xy 216.667865 -36.749546)
			(xy 216.618612 -36.708801) (xy 216.574855 -36.662204) (xy 216.537282 -36.610489) (xy 216.506488 -36.554474)
			(xy 216.482956 -36.495041) (xy 216.467059 -36.433127) (xy 216.459048 -36.369709) (xy 195.974294 -36.369709)
			(xy 195.979541 -36.405366) (xy 195.98005 -36.433252) (xy 195.979541 -36.461138) (xy 195.971421 -36.516314)
			(xy 195.955353 -36.569721) (xy 195.931681 -36.620218) (xy 195.900908 -36.666731) (xy 195.863691 -36.708268)
			(xy 195.820823 -36.743943) (xy 195.773217 -36.772997) (xy 195.721888 -36.794809) (xy 195.667931 -36.808915)
			(xy 195.612494 -36.815015) (xy 195.55676 -36.812978) (xy 195.501917 -36.802848) (xy 195.449133 -36.784841)
			(xy 195.399533 -36.75934) (xy 195.354175 -36.726889) (xy 195.314026 -36.68818) (xy 195.27994 -36.644037)
			(xy 195.252644 -36.595402) (xy 195.232721 -36.543311) (xy 195.220595 -36.488874) (xy 195.216524 -36.433252)
			(xy 187.312827 -36.433252) (xy 187.302927 -36.473421) (xy 187.281132 -36.530889) (xy 187.252569 -36.585311)
			(xy 187.217655 -36.635893) (xy 187.176898 -36.681898) (xy 187.130893 -36.722655) (xy 187.080311 -36.757569)
			(xy 187.025889 -36.786132) (xy 186.968421 -36.807927) (xy 186.908745 -36.822635) (xy 186.847731 -36.830044)
			(xy 186.817 -36.830508) (xy 186.785919 -36.830041) (xy 186.72422 -36.822462) (xy 186.663906 -36.807417)
			(xy 186.605876 -36.78513) (xy 186.550996 -36.755934) (xy 186.500086 -36.720265) (xy 186.453904 -36.678655)
			(xy 186.41314 -36.631724) (xy 186.39536 -36.606226) (xy 186.388248 -36.597844) (xy 186.379866 -36.589716)
			(xy 186.371738 -36.583366) (xy 186.366658 -36.580318) (xy 186.276996 -36.571174) (xy 186.265676 -36.570598)
			(xy 186.244328 -36.578128) (xy 186.235848 -36.585652) (xy 185.832539 -36.988961) (xy 191.515994 -36.988961)
			(xy 191.515994 -36.925039) (xy 191.524005 -36.861621) (xy 191.539902 -36.799707) (xy 191.563434 -36.740274)
			(xy 191.594228 -36.684259) (xy 191.631801 -36.632544) (xy 191.675558 -36.585947) (xy 191.724811 -36.545202)
			(xy 191.778782 -36.510951) (xy 191.836621 -36.483734) (xy 191.897414 -36.463981) (xy 191.960204 -36.452003)
			(xy 192.024 -36.44799) (xy 192.087796 -36.452003) (xy 192.150586 -36.463981) (xy 192.211379 -36.483734)
			(xy 192.269218 -36.510951) (xy 192.323189 -36.545202) (xy 192.372442 -36.585947) (xy 192.416199 -36.632544)
			(xy 192.453772 -36.684259) (xy 192.484566 -36.740274) (xy 192.508098 -36.799707) (xy 192.523995 -36.861621)
			(xy 192.532006 -36.925039) (xy 192.532508 -36.957) (xy 192.532006 -36.988961) (xy 192.523995 -37.052379)
			(xy 192.508098 -37.114293) (xy 192.484566 -37.173726) (xy 192.453772 -37.229741) (xy 192.416199 -37.281456)
			(xy 192.372442 -37.328053) (xy 192.372392 -37.328094) (xy 197.270878 -37.328094) (xy 197.271361 -37.286992)
			(xy 197.278946 -37.205138) (xy 197.294052 -37.124334) (xy 197.316548 -37.045267) (xy 197.346244 -36.968614)
			(xy 197.382885 -36.895028) (xy 197.42616 -36.825136) (xy 197.475699 -36.759536) (xy 197.53108 -36.698786)
			(xy 197.591829 -36.643405) (xy 197.65743 -36.593865) (xy 197.727321 -36.550589) (xy 197.800907 -36.513947)
			(xy 197.87756 -36.484251) (xy 197.956626 -36.461753) (xy 198.03743 -36.446647) (xy 198.119284 -36.439061)
			(xy 198.160386 -36.438586) (xy 198.203951 -36.43914) (xy 198.290664 -36.447658) (xy 198.376129 -36.464614)
			(xy 198.459526 -36.489845) (xy 198.540057 -36.52311) (xy 198.616949 -36.56409) (xy 198.689465 -36.612392)
			(xy 198.756911 -36.667553) (xy 198.81864 -36.729045) (xy 198.874061 -36.796278) (xy 198.922643 -36.868607)
			(xy 198.963919 -36.94534) (xy 198.997494 -37.025742) (xy 199.010778 -37.067236) (xy 199.013725 -37.075494)
			(xy 199.024282 -37.089481) (xy 199.038926 -37.099106) (xy 199.047354 -37.101526) (xy 199.056043 -37.103769)
			(xy 206.393028 -37.103769) (xy 206.393028 -37.039847) (xy 206.401039 -36.976429) (xy 206.416936 -36.914515)
			(xy 206.440468 -36.855082) (xy 206.471262 -36.799067) (xy 206.508835 -36.747352) (xy 206.552592 -36.700755)
			(xy 206.601845 -36.66001) (xy 206.655816 -36.625759) (xy 206.713655 -36.598542) (xy 206.774448 -36.578789)
			(xy 206.837238 -36.566811) (xy 206.901034 -36.562798) (xy 206.96483 -36.566811) (xy 207.02762 -36.578789)
			(xy 207.088413 -36.598542) (xy 207.146252 -36.625759) (xy 207.200223 -36.66001) (xy 207.249476 -36.700755)
			(xy 207.293233 -36.747352) (xy 207.330806 -36.799067) (xy 207.3616 -36.855082) (xy 207.385132 -36.914515)
			(xy 207.401029 -36.976429) (xy 207.40904 -37.039847) (xy 207.409542 -37.071808) (xy 207.40904 -37.103769)
			(xy 207.401029 -37.167187) (xy 207.385132 -37.229101) (xy 207.3616 -37.288534) (xy 207.330806 -37.344549)
			(xy 207.325076 -37.352436) (xy 207.619045 -37.352436) (xy 207.624308 -37.268757) (xy 207.637423 -37.185945)
			(xy 207.658272 -37.104734) (xy 207.686671 -37.025846) (xy 207.722369 -36.949981) (xy 207.765047 -36.877811)
			(xy 207.814327 -36.809978) (xy 207.869772 -36.747084) (xy 207.93089 -36.689686) (xy 207.997138 -36.638295)
			(xy 208.067928 -36.593366) (xy 208.142633 -36.555299) (xy 208.220588 -36.52443) (xy 208.301102 -36.501035)
			(xy 208.38346 -36.48532) (xy 208.466932 -36.477426) (xy 208.508854 -36.47694) (xy 208.548777 -36.47736)
			(xy 208.6283 -36.484525) (xy 208.706861 -36.498791) (xy 208.783825 -36.520045) (xy 208.858574 -36.548114)
			(xy 208.930505 -36.582774) (xy 208.999038 -36.623743) (xy 209.031586 -36.646866) (xy 209.03975 -36.652233)
			(xy 209.058691 -36.656942) (xy 209.068416 -36.65601) (xy 209.09915 -36.651946) (xy 209.108418 -36.650301)
			(xy 209.124861 -36.641166) (xy 209.131154 -36.634166) (xy 209.149359 -36.613327) (xy 209.1908 -36.576659)
			(xy 209.237102 -36.546359) (xy 209.287293 -36.523062) (xy 209.340323 -36.507256) (xy 209.395079 -36.499273)
			(xy 209.422746 -36.498784) (xy 209.449998 -36.499235) (xy 209.503947 -36.506998) (xy 209.556241 -36.522358)
			(xy 209.605818 -36.545004) (xy 209.651668 -36.574474) (xy 209.692858 -36.610169) (xy 209.728548 -36.651362)
			(xy 209.758014 -36.697215) (xy 209.780655 -36.746794) (xy 209.796011 -36.799091) (xy 209.803768 -36.85304)
			(xy 209.804254 -36.880292) (xy 209.803709 -36.908222) (xy 209.795556 -36.963485) (xy 209.779438 -37.016969)
			(xy 209.755698 -37.067534) (xy 209.724844 -37.1141) (xy 209.687534 -37.155674) (xy 209.644564 -37.191367)
			(xy 209.596852 -37.220418) (xy 209.545416 -37.242207) (xy 209.491354 -37.256268) (xy 209.46364 -37.259768)
			(xy 209.45437 -37.261241) (xy 209.437697 -37.269828) (xy 209.431128 -37.276532) (xy 209.410554 -37.299392)
			(xy 209.404415 -37.306932) (xy 209.397885 -37.325228) (xy 209.397854 -37.334952) (xy 209.398362 -37.366448)
			(xy 209.397874 -37.40837) (xy 209.38998 -37.491842) (xy 209.374265 -37.5742) (xy 209.350869 -37.654714)
			(xy 209.32 -37.732669) (xy 209.281933 -37.807373) (xy 209.237004 -37.878164) (xy 209.185612 -37.944412)
			(xy 209.128215 -38.005529) (xy 209.06532 -38.060974) (xy 208.997487 -38.110254) (xy 208.925318 -38.152932)
			(xy 208.890442 -38.169342) (xy 210.213192 -38.169342) (xy 210.217263 -38.11372) (xy 210.229389 -38.059283)
			(xy 210.249312 -38.007192) (xy 210.276608 -37.958557) (xy 210.310694 -37.914414) (xy 210.350843 -37.875705)
			(xy 210.396201 -37.843254) (xy 210.445801 -37.817753) (xy 210.498585 -37.799746) (xy 210.553428 -37.789616)
			(xy 210.609162 -37.787579) (xy 210.664599 -37.793679) (xy 210.718556 -37.807785) (xy 210.769885 -37.829597)
			(xy 210.817491 -37.858651) (xy 210.860359 -37.894326) (xy 210.897576 -37.935863) (xy 210.928349 -37.982376)
			(xy 210.952021 -38.032873) (xy 210.968089 -38.08628) (xy 210.976209 -38.141456) (xy 210.976718 -38.169342)
			(xy 210.976209 -38.197228) (xy 210.968089 -38.252404) (xy 210.952021 -38.305811) (xy 210.928349 -38.356308)
			(xy 210.897576 -38.402821) (xy 210.860359 -38.444358) (xy 210.817491 -38.480033) (xy 210.769885 -38.509087)
			(xy 210.718556 -38.530899) (xy 210.664599 -38.545005) (xy 210.609162 -38.551105) (xy 210.553428 -38.549068)
			(xy 210.498585 -38.538938) (xy 210.445801 -38.520931) (xy 210.396201 -38.49543) (xy 210.350843 -38.462979)
			(xy 210.310694 -38.42427) (xy 210.276608 -38.380127) (xy 210.249312 -38.331492) (xy 210.229389 -38.279401)
			(xy 210.217263 -38.224964) (xy 210.213192 -38.169342) (xy 208.890442 -38.169342) (xy 208.849452 -38.188629)
			(xy 208.770564 -38.217029) (xy 208.689353 -38.237878) (xy 208.606541 -38.250992) (xy 208.522862 -38.256255)
			(xy 208.439059 -38.25362) (xy 208.355876 -38.24311) (xy 208.274051 -38.224819) (xy 208.194311 -38.198909)
			(xy 208.117363 -38.165609) (xy 208.04389 -38.125216) (xy 207.974544 -38.078089) (xy 207.909941 -38.024644)
			(xy 207.850655 -37.965357) (xy 207.79721 -37.900754) (xy 207.750082 -37.831408) (xy 207.70969 -37.757935)
			(xy 207.676391 -37.680987) (xy 207.650481 -37.601247) (xy 207.63219 -37.519422) (xy 207.62168 -37.436239)
			(xy 207.619045 -37.352436) (xy 207.325076 -37.352436) (xy 207.293233 -37.396264) (xy 207.249476 -37.442861)
			(xy 207.200223 -37.483606) (xy 207.146252 -37.517857) (xy 207.088413 -37.545074) (xy 207.02762 -37.564827)
			(xy 206.96483 -37.576805) (xy 206.901034 -37.580819) (xy 206.837238 -37.576805) (xy 206.774448 -37.564827)
			(xy 206.713655 -37.545074) (xy 206.655816 -37.517857) (xy 206.601845 -37.483606) (xy 206.552592 -37.442861)
			(xy 206.508835 -37.396264) (xy 206.471262 -37.344549) (xy 206.440468 -37.288534) (xy 206.416936 -37.229101)
			(xy 206.401039 -37.167187) (xy 206.393028 -37.103769) (xy 199.056043 -37.103769) (xy 199.088304 -37.112097)
			(xy 199.168181 -37.139906) (xy 199.245057 -37.175171) (xy 199.31824 -37.217572) (xy 199.387067 -37.266729)
			(xy 199.450919 -37.322195) (xy 199.509218 -37.383472) (xy 199.561438 -37.450005) (xy 199.607108 -37.521194)
			(xy 199.645814 -37.596396) (xy 199.677209 -37.674933) (xy 199.701008 -37.756094) (xy 199.716997 -37.839148)
			(xy 199.72503 -37.923345) (xy 199.725534 -37.965634) (xy 199.725066 -38.006736) (xy 199.717478 -38.08859)
			(xy 199.702371 -38.169394) (xy 199.679872 -38.24846) (xy 199.650175 -38.325113) (xy 199.613532 -38.398699)
			(xy 199.570256 -38.46859) (xy 199.520716 -38.53419) (xy 199.465334 -38.59494) (xy 199.404584 -38.650321)
			(xy 199.338984 -38.69986) (xy 199.269092 -38.743136) (xy 199.195506 -38.779778) (xy 199.118853 -38.809475)
			(xy 199.039787 -38.831972) (xy 198.958982 -38.847079) (xy 198.877128 -38.854666) (xy 198.836026 -38.855142)
			(xy 198.792462 -38.854558) (xy 198.70575 -38.846041) (xy 198.620287 -38.829087) (xy 198.536891 -38.803857)
			(xy 198.456361 -38.770595) (xy 198.37947 -38.729617) (xy 198.306954 -38.681318) (xy 198.239508 -38.626159)
			(xy 198.177778 -38.564671) (xy 198.122357 -38.497441) (xy 198.073774 -38.425114) (xy 198.032496 -38.348384)
			(xy 197.998919 -38.267985) (xy 197.985634 -38.226492) (xy 197.982666 -38.218242) (xy 197.97212 -38.204253)
			(xy 197.957484 -38.194625) (xy 197.949058 -38.192202) (xy 197.908117 -38.181597) (xy 197.828242 -38.15379)
			(xy 197.751366 -38.118528) (xy 197.678184 -38.076129) (xy 197.609357 -38.026975) (xy 197.545505 -37.971511)
			(xy 197.487206 -37.910237) (xy 197.434985 -37.843707) (xy 197.389315 -37.772521) (xy 197.350607 -37.697321)
			(xy 197.319211 -37.618788) (xy 197.29541 -37.537629) (xy 197.279419 -37.454577) (xy 197.271383 -37.370382)
			(xy 197.270878 -37.328094) (xy 192.372392 -37.328094) (xy 192.323189 -37.368798) (xy 192.269218 -37.403049)
			(xy 192.211379 -37.430266) (xy 192.150586 -37.450019) (xy 192.087796 -37.461997) (xy 192.024 -37.466011)
			(xy 191.960204 -37.461997) (xy 191.897414 -37.450019) (xy 191.836621 -37.430266) (xy 191.778782 -37.403049)
			(xy 191.724811 -37.368798) (xy 191.675558 -37.328053) (xy 191.631801 -37.281456) (xy 191.594228 -37.229741)
			(xy 191.563434 -37.173726) (xy 191.539902 -37.114293) (xy 191.524005 -37.052379) (xy 191.515994 -36.988961)
			(xy 185.832539 -36.988961) (xy 185.272977 -37.548523) (xy 188.352932 -37.548523) (xy 188.352932 -37.484601)
			(xy 188.360943 -37.421183) (xy 188.37684 -37.359269) (xy 188.400372 -37.299836) (xy 188.431166 -37.243821)
			(xy 188.468739 -37.192106) (xy 188.512496 -37.145509) (xy 188.561749 -37.104764) (xy 188.61572 -37.070513)
			(xy 188.673559 -37.043296) (xy 188.734352 -37.023543) (xy 188.797142 -37.011565) (xy 188.860938 -37.007552)
			(xy 188.924734 -37.011565) (xy 188.987524 -37.023543) (xy 189.048317 -37.043296) (xy 189.106156 -37.070513)
			(xy 189.160127 -37.104764) (xy 189.20938 -37.145509) (xy 189.253137 -37.192106) (xy 189.29071 -37.243821)
			(xy 189.321504 -37.299836) (xy 189.345036 -37.359269) (xy 189.360933 -37.421183) (xy 189.368944 -37.484601)
			(xy 189.369446 -37.516562) (xy 189.368944 -37.548523) (xy 189.360933 -37.611941) (xy 189.345036 -37.673855)
			(xy 189.321504 -37.733288) (xy 189.29071 -37.789303) (xy 189.253137 -37.841018) (xy 189.20938 -37.887615)
			(xy 189.160127 -37.92836) (xy 189.106156 -37.962611) (xy 189.048317 -37.989828) (xy 188.987524 -38.009581)
			(xy 188.924734 -38.021559) (xy 188.860938 -38.025573) (xy 188.797142 -38.021559) (xy 188.734352 -38.009581)
			(xy 188.673559 -37.989828) (xy 188.61572 -37.962611) (xy 188.561749 -37.92836) (xy 188.512496 -37.887615)
			(xy 188.468739 -37.841018) (xy 188.431166 -37.789303) (xy 188.400372 -37.733288) (xy 188.37684 -37.673855)
			(xy 188.360943 -37.611941) (xy 188.352932 -37.548523) (xy 185.272977 -37.548523) (xy 184.45099 -38.37051)
			(xy 184.443595 -38.377365) (xy 184.424996 -38.38511) (xy 184.414922 -38.385496) (xy 176.823878 -38.385496)
			(xy 176.81381 -38.385069) (xy 176.795211 -38.377348) (xy 176.78781 -38.37051) (xy 173.88459 -35.46729)
			(xy 173.877735 -35.459895) (xy 173.86999 -35.441296) (xy 173.869604 -35.431222) (xy 173.869604 -31.982156)
			(xy 173.869367 -31.975785) (xy 173.866143 -31.963456) (xy 173.863254 -31.957772) (xy 173.855126 -31.942786)
			(xy 173.848014 -31.93288) (xy 173.839886 -31.924244) (xy 173.830996 -31.91637) (xy 173.805672 -31.898586)
			(xy 173.759111 -31.857823) (xy 173.717842 -31.811711) (xy 173.682474 -31.76093) (xy 173.653532 -31.706233)
			(xy 173.631442 -31.648427) (xy 173.616531 -31.588367) (xy 173.60902 -31.526941) (xy 173.60902 -31.465059)
			(xy 173.616531 -31.403633) (xy 173.631442 -31.343573) (xy 173.653532 -31.285767) (xy 173.682474 -31.23107)
			(xy 173.717842 -31.180289) (xy 173.759111 -31.134177) (xy 173.805672 -31.093414) (xy 173.830996 -31.07563)
			(xy 173.839886 -31.067756) (xy 173.848014 -31.05912) (xy 173.855126 -31.049214) (xy 173.863254 -31.034228)
			(xy 173.86619 -31.028563) (xy 173.869407 -31.016221) (xy 173.869604 -31.009844) (xy 173.869604 -27.0637)
			(xy 173.869346 -27.056055) (xy 173.864824 -27.041449) (xy 173.860714 -27.034998) (xy 173.856904 -27.02941)
			(xy 173.85157 -27.0256) (xy 173.838362 -27.02052) (xy 173.832266 -27.018742) (xy 173.829472 -27.01798)
			(xy 173.814486 -27.015186) (xy 173.802802 -27.016456) (xy 173.787816 -27.021282) (xy 173.784768 -27.022298)
			(xy 173.780925 -27.023579) (xy 173.773657 -27.027157) (xy 173.77029 -27.02941) (xy 173.751748 -27.044396)
			(xy 173.74489 -27.052778) (xy 173.722871 -27.087571) (xy 173.673332 -27.153348) (xy 173.617926 -27.214266)
			(xy 173.557128 -27.269803) (xy 173.491459 -27.319484) (xy 173.421479 -27.362885) (xy 173.347789 -27.399634)
			(xy 173.271017 -27.429415) (xy 173.191823 -27.451976) (xy 173.110882 -27.467121) (xy 173.028889 -27.474723)
			(xy 172.987716 -27.47518) (xy 172.945368 -27.474693) (xy 172.861054 -27.466643) (xy 172.777888 -27.450615)
			(xy 172.696621 -27.426755) (xy 172.617991 -27.395277) (xy 172.542709 -27.356468) (xy 172.471457 -27.310678)
			(xy 172.404881 -27.258323) (xy 172.343582 -27.199876) (xy 172.288117 -27.135867) (xy 172.238988 -27.066875)
			(xy 172.196639 -26.993526) (xy 172.161454 -26.916483) (xy 172.133752 -26.836445) (xy 172.113784 -26.754136)
			(xy 172.10173 -26.670301) (xy 172.0977 -26.5857) (xy 172.10173 -26.501099) (xy 172.113784 -26.417264)
			(xy 172.133752 -26.334955) (xy 172.161454 -26.254917) (xy 172.196639 -26.177874) (xy 172.238988 -26.104525)
			(xy 172.288117 -26.035533) (xy 172.343582 -25.971524) (xy 172.404881 -25.913077) (xy 172.471457 -25.860722)
			(xy 172.542709 -25.814932) (xy 172.617991 -25.776123) (xy 172.696621 -25.744645) (xy 172.777888 -25.720785)
			(xy 172.861054 -25.704757) (xy 172.945368 -25.696707) (xy 172.987716 -25.696164) (xy 173.028037 -25.696617)
			(xy 173.108348 -25.703919) (xy 173.187668 -25.718461) (xy 173.265345 -25.740123) (xy 173.340743 -25.768729)
			(xy 173.413242 -25.804043) (xy 173.482246 -25.845775) (xy 173.547189 -25.893582) (xy 173.607538 -25.947072)
			(xy 173.662797 -26.005805) (xy 173.687994 -26.037286) (xy 173.688248 -26.03754) (xy 173.69332 -26.043492)
			(xy 173.706251 -26.052273) (xy 173.713648 -26.054812) (xy 173.721268 -26.057098) (xy 173.72838 -26.057098)
			(xy 173.732402 -26.056871) (xy 173.740309 -26.055334) (xy 173.744128 -26.05405) (xy 173.80585 -26.032714)
			(xy 173.815502 -26.029412) (xy 173.836584 -26.022046) (xy 173.846059 -26.017985) (xy 173.860958 -26.003766)
			(xy 173.869089 -25.984844) (xy 173.869604 -25.974548) (xy 173.869604 -20.944332) (xy 173.87004 -20.934267)
			(xy 173.877772 -20.915681) (xy 173.88459 -20.908264) (xy 174.231808 -20.561046) (xy 174.238353 -20.553835)
			(xy 174.245924 -20.535911) (xy 174.246266 -20.516456) (xy 174.243238 -20.507198) (xy 174.210472 -20.420838)
			(xy 174.20766 -20.414018) (xy 174.198762 -20.402261) (xy 174.192946 -20.397724) (xy 174.180754 -20.388834)
			(xy 174.179738 -20.388834) (xy 174.171864 -20.388326) (xy 174.145435 -20.386672) (xy 174.093376 -20.376981)
			(xy 174.043155 -20.360189) (xy 173.995736 -20.336618) (xy 173.95203 -20.306721) (xy 173.912874 -20.271071)
			(xy 173.87902 -20.230352) (xy 173.851118 -20.185346) (xy 173.829703 -20.136916) (xy 173.815185 -20.085991)
			(xy 173.807844 -20.033549) (xy 173.807374 -20.007072) (xy 173.807862 -19.979822) (xy 173.815621 -19.925876)
			(xy 173.830979 -19.873584) (xy 173.853621 -19.824009) (xy 173.883088 -19.77816) (xy 173.918779 -19.736972)
			(xy 173.959968 -19.701282) (xy 174.005817 -19.671816) (xy 174.055393 -19.649175) (xy 174.107686 -19.633819)
			(xy 174.161632 -19.626061) (xy 174.188882 -19.625564) (xy 174.215289 -19.62601) (xy 174.2676 -19.633291)
			(xy 174.318407 -19.647714) (xy 174.366739 -19.669006) (xy 174.411674 -19.696759) (xy 174.452353 -19.730443)
			(xy 174.487999 -19.769415) (xy 174.503334 -19.790918) (xy 174.503588 -19.791172) (xy 174.506167 -19.794884)
			(xy 174.512432 -19.801395) (xy 174.516034 -19.804126) (xy 174.51832 -19.805396) (xy 174.522513 -19.807848)
			(xy 174.531591 -19.8113) (xy 174.536354 -19.812254) (xy 174.574962 -19.817842) (xy 174.6123 -19.823176)
			(xy 174.616417 -19.823692) (xy 174.624712 -19.823571) (xy 174.62881 -19.822922) (xy 174.63135 -19.82216)
			(xy 174.63262 -19.821906) (xy 174.637199 -19.820545) (xy 174.645768 -19.816325) (xy 174.649638 -19.813524)
			(xy 174.651162 -19.812254) (xy 174.651416 -19.812) (xy 174.67178 -19.79602) (xy 174.716008 -19.769123)
			(xy 174.763468 -19.748457) (xy 174.813287 -19.734401) (xy 174.86455 -19.727214) (xy 174.89043 -19.726656)
			(xy 174.898304 -19.726656) (xy 174.909324 -19.726928) (xy 174.931309 -19.728583) (xy 174.942246 -19.729958)
			(xy 174.959151 -19.7324) (xy 174.992474 -19.739906) (xy 175.008794 -19.744944) (xy 175.009048 -19.744944)
			(xy 175.009556 -19.745198) (xy 175.00981 -19.745198) (xy 175.010572 -19.745452) (xy 175.016877 -19.747021)
			(xy 175.029865 -19.747283) (xy 175.036226 -19.74596) (xy 175.038512 -19.745452) (xy 175.043592 -19.744182)
			(xy 175.04918 -19.74088) (xy 175.060102 -19.732752) (xy 175.697134 -19.09572) (xy 175.705283 -19.08648)
			(xy 175.712586 -19.062992) (xy 175.711104 -19.050762) (xy 175.695102 -18.967704) (xy 175.693965 -18.962246)
			(xy 175.689612 -18.951986) (xy 175.686466 -18.947384) (xy 175.685958 -18.946876) (xy 175.681894 -18.941542)
			(xy 175.680878 -18.940526) (xy 175.671734 -18.933414) (xy 175.669448 -18.932398) (xy 175.665384 -18.93062)
			(xy 175.635415 -18.917111) (xy 175.578931 -18.88348) (xy 175.527252 -18.84285) (xy 175.481242 -18.795897)
			(xy 175.441667 -18.743406) (xy 175.409188 -18.686251) (xy 175.384348 -18.625387) (xy 175.367559 -18.561829)
			(xy 175.359103 -18.496637) (xy 175.358552 -18.463768) (xy 175.359568 -18.432272) (xy 175.360076 -18.421858)
			(xy 175.355504 -18.40865) (xy 175.3537 -18.404981) (xy 175.349106 -18.398217) (xy 175.34636 -18.395188)
			(xy 175.344074 -18.392648) (xy 175.309276 -18.355056) (xy 175.29429 -18.3388) (xy 175.291591 -18.336271)
			(xy 175.285599 -18.331936) (xy 175.282352 -18.330164) (xy 175.27016 -18.324576) (xy 175.255936 -18.324576)
			(xy 175.243744 -18.324068) (xy 175.230028 -18.330672) (xy 175.225589 -18.333327) (xy 175.217783 -18.34011)
			(xy 175.214534 -18.344134) (xy 175.210978 -18.348706) (xy 175.20412 -18.357596) (xy 175.164496 -18.409412)
			(xy 175.161051 -18.414147) (xy 175.156174 -18.424791) (xy 175.154844 -18.430494) (xy 175.152558 -18.442178)
			(xy 175.15586 -18.453862) (xy 175.164985 -18.488) (xy 175.174802 -18.557977) (xy 175.175418 -18.593308)
			(xy 175.174916 -18.625269) (xy 175.166905 -18.688687) (xy 175.151008 -18.750601) (xy 175.127476 -18.810034)
			(xy 175.096682 -18.866049) (xy 175.059109 -18.917764) (xy 175.015352 -18.964361) (xy 174.966099 -19.005106)
			(xy 174.912128 -19.039357) (xy 174.854289 -19.066574) (xy 174.793496 -19.086327) (xy 174.730706 -19.098305)
			(xy 174.66691 -19.102319) (xy 174.603114 -19.098305) (xy 174.540324 -19.086327) (xy 174.479531 -19.066574)
			(xy 174.421692 -19.039357) (xy 174.367721 -19.005106) (xy 174.318468 -18.964361) (xy 174.274711 -18.917764)
			(xy 174.237138 -18.866049) (xy 174.206344 -18.810034) (xy 174.182812 -18.750601) (xy 174.166915 -18.688687)
			(xy 174.158904 -18.625269) (xy 174.158402 -18.593308) (xy 174.158816 -18.564239) (xy 174.165482 -18.506485)
			(xy 174.178706 -18.449872) (xy 174.18812 -18.422366) (xy 174.19193 -18.411444) (xy 174.19066 -18.400268)
			(xy 174.190001 -18.394856) (xy 174.186667 -18.38448) (xy 174.184056 -18.379694) (xy 174.144178 -18.31213)
			(xy 174.141384 -18.307812) (xy 174.138732 -18.304382) (xy 174.132475 -18.298382) (xy 174.128938 -18.295874)
			(xy 174.11954 -18.289524) (xy 174.108364 -18.287746) (xy 174.071851 -18.281244) (xy 174.001087 -18.259051)
			(xy 173.967394 -18.24355) (xy 173.96714 -18.24355) (xy 173.966886 -18.243296) (xy 173.964854 -18.24228)
			(xy 173.959632 -18.240264) (xy 173.948607 -18.238347) (xy 173.94301 -18.23847) (xy 173.941486 -18.238724)
			(xy 173.933612 -18.239486) (xy 173.932342 -18.23974) (xy 173.926754 -18.242026) (xy 173.923287 -18.243513)
			(xy 173.916785 -18.247339) (xy 173.9138 -18.249646) (xy 173.876462 -18.279872) (xy 173.856396 -18.296128)
			(xy 173.841918 -18.307812) (xy 173.836439 -18.31261) (xy 173.828193 -18.324605) (xy 173.825662 -18.331434)
			(xy 173.824138 -18.335752) (xy 173.823376 -18.338038) (xy 173.822868 -18.352008) (xy 173.824646 -18.359374)
			(xy 173.82988 -18.381935) (xy 173.835486 -18.42791) (xy 173.835822 -18.451068) (xy 173.835361 -18.478323)
			(xy 173.827608 -18.532278) (xy 173.812255 -18.58458) (xy 173.789615 -18.634166) (xy 173.760148 -18.680024)
			(xy 173.724454 -18.721221) (xy 173.683261 -18.75692) (xy 173.637406 -18.786392) (xy 173.587824 -18.809039)
			(xy 173.535523 -18.824398) (xy 173.481569 -18.832158) (xy 173.454314 -18.832576) (xy 173.427353 -18.832105)
			(xy 173.37397 -18.824502) (xy 173.322189 -18.809459) (xy 173.273042 -18.787276) (xy 173.227507 -18.758395)
			(xy 173.186491 -18.723392) (xy 173.150811 -18.682962) (xy 173.121179 -18.637913) (xy 173.098184 -18.58914)
			(xy 173.082284 -18.537616) (xy 173.073796 -18.484366) (xy 173.072806 -18.457418) (xy 173.072806 -18.45056)
			(xy 173.073409 -18.420245) (xy 173.083037 -18.360384) (xy 173.102011 -18.3028) (xy 173.129855 -18.248941)
			(xy 173.165867 -18.200165) (xy 173.187106 -18.178526) (xy 173.191932 -18.173954) (xy 173.194472 -18.171414)
			(xy 173.198282 -18.162524) (xy 173.199908 -18.158757) (xy 173.202078 -18.150845) (xy 173.2026 -18.146776)
			(xy 173.202854 -18.127472) (xy 173.203108 -18.109438) (xy 173.203108 -18.10893) (xy 173.20387 -18.072354)
			(xy 173.20386 -18.067485) (xy 173.202202 -18.057891) (xy 173.200568 -18.053304) (xy 173.197012 -18.043906)
			(xy 173.190154 -18.03654) (xy 173.170845 -18.015202) (xy 173.138211 -17.967804) (xy 173.113065 -17.916043)
			(xy 173.095975 -17.861094) (xy 173.08733 -17.804201) (xy 173.086776 -17.775428) (xy 173.087237 -17.748173)
			(xy 173.094991 -17.694219) (xy 173.110344 -17.641916) (xy 173.132985 -17.592332) (xy 173.162452 -17.546474)
			(xy 173.198145 -17.505276) (xy 173.239338 -17.469578) (xy 173.285193 -17.440106) (xy 173.334775 -17.417459)
			(xy 173.387075 -17.4021) (xy 173.441029 -17.39434) (xy 173.468284 -17.39392) (xy 173.468792 -17.39392)
			(xy 173.496921 -17.394442) (xy 173.552565 -17.402739) (xy 173.60639 -17.41911) (xy 173.65723 -17.4432)
			(xy 173.680882 -17.458436) (xy 173.681136 -17.45869) (xy 173.688756 -17.46377) (xy 173.697392 -17.465802)
			(xy 173.701071 -17.466682) (xy 173.708597 -17.467444) (xy 173.712378 -17.467326) (xy 173.778926 -17.459198)
			(xy 173.78172 -17.458944) (xy 173.795436 -17.455388) (xy 173.806104 -17.450054) (xy 173.812708 -17.442942)
			(xy 173.833373 -17.420907) (xy 173.879071 -17.381393) (xy 173.929132 -17.347577) (xy 173.982849 -17.319934)
			(xy 174.039465 -17.298856) (xy 174.098181 -17.28464) (xy 174.158168 -17.277485) (xy 174.188374 -17.27708)
			(xy 174.219838 -17.27755) (xy 174.282284 -17.285314) (xy 174.343295 -17.300727) (xy 174.401937 -17.323553)
			(xy 174.457312 -17.353443) (xy 174.508575 -17.38994) (xy 174.55494 -17.432485) (xy 174.595699 -17.480428)
			(xy 174.630229 -17.533036) (xy 174.644558 -17.561052) (xy 174.644812 -17.561306) (xy 174.644812 -17.56156)
			(xy 174.646336 -17.564862) (xy 174.64958 -17.569789) (xy 174.657919 -17.578127) (xy 174.662846 -17.581372)
			(xy 174.66564 -17.583404) (xy 174.667926 -17.584674) (xy 174.668688 -17.585182) (xy 174.67453 -17.58696)
			(xy 174.685706 -17.589246) (xy 174.71517 -17.590262) (xy 174.716186 -17.590262) (xy 174.733458 -17.590516)
			(xy 174.733966 -17.590516) (xy 174.77867 -17.591786) (xy 174.785641 -17.591761) (xy 174.79917 -17.588424)
			(xy 174.80534 -17.585182) (xy 174.811182 -17.58188) (xy 174.820326 -17.572736) (xy 174.824136 -17.566132)
			(xy 174.841138 -17.537132) (xy 174.881619 -17.483463) (xy 174.928815 -17.435591) (xy 174.981903 -17.394351)
			(xy 175.039959 -17.36046) (xy 175.101972 -17.334508) (xy 175.166862 -17.316948) (xy 175.2335 -17.308085)
			(xy 175.267112 -17.30756) (xy 175.297843 -17.308025) (xy 175.358857 -17.315434) (xy 175.418534 -17.330144)
			(xy 175.476002 -17.351939) (xy 175.530425 -17.380502) (xy 175.581007 -17.415416) (xy 175.627013 -17.456172)
			(xy 175.667772 -17.502177) (xy 175.702688 -17.552758) (xy 175.731253 -17.60718) (xy 175.75305 -17.664647)
			(xy 175.767762 -17.724323) (xy 175.775174 -17.785337) (xy 175.77562 -17.816068) (xy 175.774604 -17.847564)
			(xy 175.774096 -17.857978) (xy 175.777906 -17.868646) (xy 175.779772 -17.873037) (xy 175.784888 -17.88109)
			(xy 175.788066 -17.884648) (xy 175.838104 -17.939004) (xy 175.844454 -17.944846) (xy 175.855122 -17.951196)
			(xy 175.863758 -17.955006) (xy 175.87468 -17.95526) (xy 175.875696 -17.95526) (xy 175.885856 -17.955514)
			(xy 175.887888 -17.955514) (xy 175.897032 -17.954752) (xy 175.904543 -17.953065) (xy 175.918121 -17.945829)
			(xy 175.923702 -17.940528) (xy 175.924464 -17.939766) (xy 175.94453 -17.918938) (xy 175.946308 -17.91716)
			(xy 175.946562 -17.916906) (xy 175.948086 -17.914874) (xy 175.952404 -17.90954) (xy 175.952404 -17.909032)
			(xy 175.954449 -17.905766) (xy 175.957636 -17.89875) (xy 175.958754 -17.895062) (xy 175.959747 -17.891013)
			(xy 175.960518 -17.882714) (xy 175.960278 -17.878552) (xy 175.960278 -17.87779) (xy 175.9585 -17.833848)
			(xy 175.958943 -17.803114) (xy 175.966347 -17.742094) (xy 175.981052 -17.682412) (xy 176.002845 -17.624937)
			(xy 176.031407 -17.570508) (xy 176.066322 -17.51992) (xy 176.107081 -17.473909) (xy 176.153088 -17.433147)
			(xy 176.203674 -17.398228) (xy 176.2581 -17.369661) (xy 176.315573 -17.347864) (xy 176.375255 -17.333154)
			(xy 176.436274 -17.325745) (xy 176.467008 -17.32534) (xy 176.467008 -17.325086) (xy 176.500668 -17.325633)
			(xy 176.5674 -17.334526) (xy 176.632371 -17.352155) (xy 176.694446 -17.37821) (xy 176.752535 -17.412237)
			(xy 176.805621 -17.453637) (xy 176.852773 -17.501686) (xy 176.873408 -17.528286) (xy 176.893976 -17.556546)
			(xy 176.928003 -17.617598) (xy 176.941226 -17.649952) (xy 176.94148 -17.65046) (xy 176.941734 -17.651222)
			(xy 176.944138 -17.656645) (xy 176.951077 -17.666263) (xy 176.95545 -17.670272) (xy 176.955704 -17.670526)
			(xy 176.96053 -17.67459) (xy 176.965864 -17.67713) (xy 176.977548 -17.681194) (xy 177.064416 -17.699482)
			(xy 177.076235 -17.700591) (xy 177.098755 -17.693178) (xy 177.107596 -17.685258) (xy 177.187606 -17.605248)
			(xy 177.191416 -17.595088) (xy 177.202747 -17.566517) (xy 177.231309 -17.512093) (xy 177.266223 -17.461509)
			(xy 177.306979 -17.415501) (xy 177.352984 -17.374742) (xy 177.403567 -17.339825) (xy 177.457989 -17.31126)
			(xy 177.486564 -17.29994) (xy 177.496724 -17.29613) (xy 177.516536 -17.276318) (xy 177.523936 -17.269475)
			(xy 177.542534 -17.261751) (xy 177.552604 -17.261332) (xy 179.035456 -17.261332) (xy 179.044854 -17.260316)
			(xy 179.045362 -17.260316) (xy 179.050594 -17.259128) (xy 179.060455 -17.254907) (xy 179.06492 -17.251934)
			(xy 179.07127 -17.2466) (xy 179.074318 -17.243552) (xy 179.09286 -17.235932) (xy 179.107338 -17.235932)
			(xy 180.265832 -16.077438) (xy 180.271166 -16.071088) (xy 180.274178 -16.066642) (xy 180.278417 -16.056779)
			(xy 180.279548 -16.05153) (xy 180.279548 -16.051022) (xy 180.280564 -16.041624) (xy 180.280564 -11.548364)
			(xy 180.280082 -11.5384) (xy 180.272498 -11.519971) (xy 180.265832 -11.51255) (xy 179.237894 -10.484358)
			(xy 179.231055 -10.476957) (xy 179.223337 -10.458359) (xy 179.222908 -10.44829) (xy 179.222908 -7.78891)
			(xy 179.222736 -7.782902) (xy 179.219905 -7.771223) (xy 179.21732 -7.765796) (xy 179.215482 -7.762321)
			(xy 179.210891 -7.755939) (xy 179.208176 -7.753096) (xy 178.929792 -7.474712) (xy 178.92694 -7.472007)
			(xy 178.92056 -7.467417) (xy 178.917092 -7.465568) (xy 178.911666 -7.462983) (xy 178.899986 -7.460153)
			(xy 178.893978 -7.45998) (xy 166.691818 -7.45998) (xy 166.687737 -7.460096) (xy 166.679695 -7.461499)
			(xy 166.675816 -7.462774) (xy 166.675308 -7.462774) (xy 166.671798 -7.464054) (xy 166.66517 -7.467502)
			(xy 166.6621 -7.469632) (xy 166.661592 -7.469886) (xy 166.658798 -7.472172) (xy 166.65602 -7.474771)
			(xy 166.651179 -7.48064) (xy 166.649146 -7.483856) (xy 166.644574 -7.490968) (xy 166.642542 -7.499858)
			(xy 166.635066 -7.531528) (xy 166.613129 -7.592793) (xy 166.583557 -7.650758) (xy 166.546831 -7.704478)
			(xy 166.503553 -7.753074) (xy 166.45443 -7.795752) (xy 166.400263 -7.831815) (xy 166.341939 -7.860673)
			(xy 166.280409 -7.881856) (xy 166.216681 -7.895016) (xy 166.151794 -7.89994) (xy 166.086809 -7.896545)
			(xy 166.022788 -7.884889) (xy 165.960777 -7.865161) (xy 165.901789 -7.837684) (xy 165.846789 -7.802907)
			(xy 165.796674 -7.761397) (xy 165.752263 -7.713834) (xy 165.714283 -7.660994) (xy 165.683354 -7.603741)
			(xy 165.659981 -7.54301) (xy 165.651688 -7.511542) (xy 165.649148 -7.503922) (xy 165.645846 -7.496302)
			(xy 165.64229 -7.489444) (xy 165.631114 -7.471156) (xy 165.62451 -7.465822) (xy 165.616636 -7.463028)
			(xy 165.612457 -7.461618) (xy 165.603773 -7.460087) (xy 165.599364 -7.45998) (xy 165.42131 -7.45998)
			(xy 165.412293 -7.460338) (xy 165.395373 -7.46658) (xy 165.38829 -7.472172) (xy 165.387528 -7.472934)
			(xy 165.381432 -7.478014) (xy 165.372796 -7.493508) (xy 165.371272 -7.502652) (xy 165.366234 -7.530544)
			(xy 165.349004 -7.584537) (xy 165.323977 -7.635389) (xy 165.291703 -7.681979) (xy 165.252893 -7.723283)
			(xy 165.208401 -7.758392) (xy 165.159205 -7.786534) (xy 165.106387 -7.80709) (xy 165.05111 -7.819607)
			(xy 164.99459 -7.82381) (xy 164.93807 -7.819607) (xy 164.882793 -7.80709) (xy 164.829975 -7.786534)
			(xy 164.780779 -7.758392) (xy 164.736287 -7.723283) (xy 164.697477 -7.681979) (xy 164.665203 -7.635389)
			(xy 164.640176 -7.584537) (xy 164.622946 -7.530544) (xy 164.617908 -7.502652) (xy 164.617146 -7.498588)
			(xy 164.614963 -7.490993) (xy 164.606692 -7.477537) (xy 164.60089 -7.472172) (xy 164.594032 -7.46633)
			(xy 164.58565 -7.463282) (xy 164.581363 -7.461758) (xy 164.572418 -7.460103) (xy 164.56787 -7.45998)
			(xy 164.368988 -7.45998) (xy 164.360298 -7.460329) (xy 164.343933 -7.46618) (xy 164.336984 -7.47141)
			(xy 164.33038 -7.476998) (xy 164.321236 -7.491984) (xy 164.319458 -7.500874) (xy 164.31281 -7.531985)
			(xy 164.292791 -7.592371) (xy 164.265396 -7.649789) (xy 164.231052 -7.703341) (xy 164.190296 -7.75219)
			(xy 164.143765 -7.795574) (xy 164.092186 -7.832815) (xy 164.036364 -7.86333) (xy 163.977171 -7.886644)
			(xy 163.915533 -7.902392) (xy 163.852411 -7.910328) (xy 163.788793 -7.910328) (xy 163.725671 -7.902392)
			(xy 163.664033 -7.886644) (xy 163.60484 -7.86333) (xy 163.549018 -7.832815) (xy 163.497439 -7.795574)
			(xy 163.450908 -7.75219) (xy 163.410152 -7.703341) (xy 163.375808 -7.649789) (xy 163.348413 -7.592371)
			(xy 163.328394 -7.531985) (xy 163.321746 -7.500874) (xy 163.321238 -7.498588) (xy 163.319162 -7.491192)
			(xy 163.311266 -7.478023) (xy 163.305744 -7.47268) (xy 163.29787 -7.46633) (xy 163.297362 -7.465822)
			(xy 163.289488 -7.463028) (xy 163.28531 -7.461614) (xy 163.276626 -7.460074) (xy 163.272216 -7.45998)
			(xy 160.946592 -7.45998) (xy 160.935569 -7.460515) (xy 160.915562 -7.469769) (xy 160.90132 -7.486594)
			(xy 160.897824 -7.497064) (xy 160.870138 -7.594854) (xy 160.868982 -7.602093) (xy 160.870401 -7.616677)
			(xy 160.872932 -7.623556) (xy 160.87598 -7.631176) (xy 160.886394 -7.643876) (xy 160.893506 -7.648194)
			(xy 160.930448 -7.671426) (xy 161.000303 -7.723744) (xy 161.065009 -7.78231) (xy 161.124009 -7.846619)
			(xy 161.176796 -7.91612) (xy 161.222916 -7.990213) (xy 161.261972 -8.068261) (xy 161.293627 -8.149592)
			(xy 161.317609 -8.233506) (xy 161.33029 -8.30105) (xy 168.199574 -8.30105) (xy 168.199574 -8.24655)
			(xy 168.207329 -8.192605) (xy 168.222683 -8.140313) (xy 168.245321 -8.090738) (xy 168.274784 -8.044889)
			(xy 168.310472 -8.003699) (xy 168.351658 -7.968007) (xy 168.397504 -7.938539) (xy 168.447077 -7.915896)
			(xy 168.499368 -7.900537) (xy 168.553312 -7.892776) (xy 168.580562 -7.892288) (xy 168.610591 -7.892863)
			(xy 168.669907 -7.902286) (xy 168.727012 -7.920888) (xy 168.780497 -7.94821) (xy 168.805098 -7.96544)
			(xy 168.805352 -7.965694) (xy 168.812765 -7.970525) (xy 168.829781 -7.975334) (xy 168.838626 -7.975092)
			(xy 168.913556 -7.969504) (xy 168.929558 -7.962138) (xy 168.936162 -7.955788) (xy 168.960013 -7.933093)
			(xy 169.012532 -7.893388) (xy 169.069738 -7.860797) (xy 169.130673 -7.835865) (xy 169.194317 -7.819008)
			(xy 169.259605 -7.810511) (xy 169.292524 -7.809992) (xy 169.324484 -7.810495) (xy 169.3879 -7.818509)
			(xy 169.449811 -7.834408) (xy 169.509242 -7.857941) (xy 169.565254 -7.888736) (xy 169.616966 -7.926309)
			(xy 169.663561 -7.970067) (xy 169.704304 -8.019319) (xy 169.738553 -8.073289) (xy 169.765768 -8.131126)
			(xy 169.78552 -8.191918) (xy 169.797497 -8.254706) (xy 169.800456 -8.301736) (xy 174.872396 -8.301736)
			(xy 174.872871 -8.271004) (xy 174.880276 -8.209989) (xy 174.894982 -8.150311) (xy 174.916774 -8.092841)
			(xy 174.945334 -8.038417) (xy 174.980247 -7.987833) (xy 175.021003 -7.941826) (xy 175.067008 -7.901067)
			(xy 175.11759 -7.866151) (xy 175.172012 -7.837587) (xy 175.229481 -7.815791) (xy 175.289158 -7.801082)
			(xy 175.350173 -7.793673) (xy 175.380904 -7.793228) (xy 175.381158 -7.793228) (xy 175.415171 -7.793786)
			(xy 175.482589 -7.802862) (xy 175.548196 -7.820844) (xy 175.610819 -7.847412) (xy 175.669342 -7.882091)
			(xy 175.72272 -7.924262) (xy 175.77 -7.973172) (xy 175.790606 -8.000238) (xy 175.796956 -8.009128)
			(xy 175.815498 -8.019796) (xy 175.91151 -8.029702) (xy 175.931576 -8.023352) (xy 175.939704 -8.01624)
			(xy 175.960733 -7.998243) (xy 176.007022 -7.967897) (xy 176.057211 -7.944561) (xy 176.110246 -7.928726)
			(xy 176.165014 -7.920723) (xy 176.192688 -7.920228) (xy 176.219942 -7.920667) (xy 176.273896 -7.928423)
			(xy 176.326196 -7.943779) (xy 176.375779 -7.966423) (xy 176.421634 -7.995893) (xy 176.462828 -8.031589)
			(xy 176.498521 -8.072785) (xy 176.527989 -8.118642) (xy 176.550629 -8.168226) (xy 176.565982 -8.220528)
			(xy 176.573735 -8.274482) (xy 176.574196 -8.301736) (xy 176.573622 -8.3305) (xy 176.56498 -8.387377)
			(xy 176.547897 -8.442311) (xy 176.522761 -8.494058) (xy 176.49014 -8.541444) (xy 176.450775 -8.583397)
			(xy 176.405558 -8.618964) (xy 176.355514 -8.647339) (xy 176.328832 -8.658098) (xy 176.317402 -8.662416)
			(xy 176.301146 -8.680196) (xy 176.276254 -8.771128) (xy 176.27368 -8.782751) (xy 176.27833 -8.806069)
			(xy 176.285144 -8.815832) (xy 176.285398 -8.816086) (xy 176.306058 -8.84311) (xy 176.340728 -8.901637)
			(xy 176.367287 -8.964263) (xy 176.385261 -9.02987) (xy 176.394329 -9.097288) (xy 176.394872 -9.1313)
			(xy 176.39437 -9.163261) (xy 176.756816 -9.163261) (xy 176.756816 -9.099339) (xy 176.764827 -9.035921)
			(xy 176.780724 -8.974007) (xy 176.804256 -8.914574) (xy 176.83505 -8.858559) (xy 176.872623 -8.806844)
			(xy 176.91638 -8.760247) (xy 176.965633 -8.719502) (xy 177.019604 -8.685251) (xy 177.077443 -8.658034)
			(xy 177.138236 -8.638281) (xy 177.201026 -8.626303) (xy 177.264822 -8.62229) (xy 177.328618 -8.626303)
			(xy 177.391408 -8.638281) (xy 177.452201 -8.658034) (xy 177.51004 -8.685251) (xy 177.564011 -8.719502)
			(xy 177.613264 -8.760247) (xy 177.657021 -8.806844) (xy 177.694594 -8.858559) (xy 177.725388 -8.914574)
			(xy 177.74892 -8.974007) (xy 177.764817 -9.035921) (xy 177.772828 -9.099339) (xy 177.77333 -9.1313)
			(xy 177.772828 -9.163261) (xy 177.764817 -9.226679) (xy 177.74892 -9.288593) (xy 177.725388 -9.348026)
			(xy 177.694594 -9.404041) (xy 177.657021 -9.455756) (xy 177.613264 -9.502353) (xy 177.564011 -9.543098)
			(xy 177.51004 -9.577349) (xy 177.452201 -9.604566) (xy 177.391408 -9.624319) (xy 177.328618 -9.636297)
			(xy 177.264822 -9.640311) (xy 177.201026 -9.636297) (xy 177.138236 -9.624319) (xy 177.077443 -9.604566)
			(xy 177.019604 -9.577349) (xy 176.965633 -9.543098) (xy 176.91638 -9.502353) (xy 176.872623 -9.455756)
			(xy 176.83505 -9.404041) (xy 176.804256 -9.348026) (xy 176.780724 -9.288593) (xy 176.764827 -9.226679)
			(xy 176.756816 -9.163261) (xy 176.39437 -9.163261) (xy 176.386359 -9.226679) (xy 176.370462 -9.288593)
			(xy 176.34693 -9.348026) (xy 176.316136 -9.404041) (xy 176.278563 -9.455756) (xy 176.234806 -9.502353)
			(xy 176.185553 -9.543098) (xy 176.131582 -9.577349) (xy 176.073743 -9.604566) (xy 176.01295 -9.624319)
			(xy 175.95016 -9.636297) (xy 175.886364 -9.640311) (xy 175.822568 -9.636297) (xy 175.759778 -9.624319)
			(xy 175.698985 -9.604566) (xy 175.641146 -9.577349) (xy 175.587175 -9.543098) (xy 175.537922 -9.502353)
			(xy 175.494165 -9.455756) (xy 175.456592 -9.404041) (xy 175.425798 -9.348026) (xy 175.402266 -9.288593)
			(xy 175.386369 -9.226679) (xy 175.378358 -9.163261) (xy 175.377856 -9.1313) (xy 175.377856 -9.131046)
			(xy 175.378344 -9.099402) (xy 175.386224 -9.036605) (xy 175.401819 -8.975268) (xy 175.412908 -8.945626)
			(xy 175.417226 -8.93445) (xy 175.415194 -8.911082) (xy 175.360584 -8.82142) (xy 175.340772 -8.80872)
			(xy 175.329088 -8.80745) (xy 175.32858 -8.80745) (xy 175.297689 -8.803769) (xy 175.237046 -8.789886)
			(xy 175.178551 -8.768705) (xy 175.123079 -8.740543) (xy 175.071458 -8.705822) (xy 175.02446 -8.66506)
			(xy 174.982789 -8.618866) (xy 174.947067 -8.567933) (xy 174.917828 -8.51302) (xy 174.89551 -8.45495)
			(xy 174.880446 -8.394589) (xy 174.872861 -8.332842) (xy 174.872396 -8.301736) (xy 169.800456 -8.301736)
			(xy 169.801511 -8.3185) (xy 169.797497 -8.382294) (xy 169.78552 -8.445082) (xy 169.765768 -8.505874)
			(xy 169.738553 -8.563711) (xy 169.704304 -8.617681) (xy 169.663561 -8.666933) (xy 169.616966 -8.710691)
			(xy 169.565254 -8.748264) (xy 169.509242 -8.779059) (xy 169.449811 -8.802592) (xy 169.3879 -8.818491)
			(xy 169.324484 -8.826505) (xy 169.292524 -8.827008) (xy 169.259741 -8.826487) (xy 169.194719 -8.818063)
			(xy 169.131319 -8.801351) (xy 169.070594 -8.776628) (xy 169.013549 -8.744305) (xy 168.961132 -8.704919)
			(xy 168.914213 -8.659121) (xy 168.89349 -8.633714) (xy 168.887902 -8.626602) (xy 168.872916 -8.617458)
			(xy 168.799256 -8.602472) (xy 168.790491 -8.601086) (xy 168.77295 -8.603679) (xy 168.764966 -8.607552)
			(xy 168.764966 -8.607806) (xy 168.764458 -8.607806) (xy 168.736113 -8.622696) (xy 168.675682 -8.643837)
			(xy 168.612572 -8.654606) (xy 168.580562 -8.655304) (xy 168.553312 -8.654824) (xy 168.499368 -8.647063)
			(xy 168.447077 -8.631704) (xy 168.397504 -8.609061) (xy 168.351658 -8.579593) (xy 168.310472 -8.543901)
			(xy 168.274784 -8.502711) (xy 168.245321 -8.456862) (xy 168.222683 -8.407287) (xy 168.207329 -8.354995)
			(xy 168.199574 -8.30105) (xy 161.33029 -8.30105) (xy 161.333713 -8.319282) (xy 161.341798 -8.406181)
			(xy 161.342324 -8.449818) (xy 161.341822 -8.493268) (xy 161.333804 -8.579797) (xy 161.317836 -8.665217)
			(xy 161.294055 -8.748799) (xy 161.262663 -8.829831) (xy 161.223929 -8.90762) (xy 161.178182 -8.981504)
			(xy 161.125813 -9.050851) (xy 161.067269 -9.115071) (xy 161.003049 -9.173615) (xy 160.933702 -9.225984)
			(xy 160.859818 -9.271731) (xy 160.782029 -9.310465) (xy 160.700997 -9.341857) (xy 160.617415 -9.365638)
			(xy 160.531995 -9.381606) (xy 160.445466 -9.389624) (xy 160.358566 -9.389624) (xy 160.272037 -9.381606)
			(xy 160.186617 -9.365638) (xy 160.103035 -9.341857) (xy 160.022003 -9.310465) (xy 159.944214 -9.271731)
			(xy 159.87033 -9.225984) (xy 159.800983 -9.173615) (xy 159.736763 -9.115071) (xy 159.678219 -9.050851)
			(xy 159.62585 -8.981504) (xy 159.580103 -8.90762) (xy 159.541369 -8.829831) (xy 159.509977 -8.748799)
			(xy 159.486196 -8.665217) (xy 159.470228 -8.579797) (xy 159.46221 -8.493268) (xy 159.461708 -8.449818)
			(xy 159.462202 -8.40618) (xy 159.470288 -8.319278) (xy 159.486393 -8.2335) (xy 159.510376 -8.149584)
			(xy 159.542033 -8.068251) (xy 159.581091 -7.990201) (xy 159.627213 -7.916107) (xy 159.680004 -7.846606)
			(xy 159.739007 -7.782295) (xy 159.803716 -7.723729) (xy 159.873574 -7.671412) (xy 159.910526 -7.648194)
			(xy 159.917638 -7.643876) (xy 159.928052 -7.631176) (xy 159.9311 -7.623556) (xy 159.933598 -7.616667)
			(xy 159.935029 -7.602092) (xy 159.933894 -7.594854) (xy 159.906208 -7.497064) (xy 159.902693 -7.486616)
			(xy 159.88841 -7.469854) (xy 159.868447 -7.460557) (xy 159.85744 -7.45998) (xy 148.411692 -7.45998)
			(xy 148.400669 -7.460515) (xy 148.380662 -7.469769) (xy 148.36642 -7.486594) (xy 148.362924 -7.497064)
			(xy 148.335238 -7.594854) (xy 148.334082 -7.602093) (xy 148.335501 -7.616677) (xy 148.338032 -7.623556)
			(xy 148.34108 -7.631176) (xy 148.351494 -7.643876) (xy 148.358606 -7.648194) (xy 148.395548 -7.671426)
			(xy 148.465403 -7.723744) (xy 148.530109 -7.78231) (xy 148.589109 -7.846619) (xy 148.641896 -7.91612)
			(xy 148.688016 -7.990213) (xy 148.727072 -8.068261) (xy 148.758727 -8.149592) (xy 148.782709 -8.233506)
			(xy 148.798813 -8.319282) (xy 148.804021 -8.375257) (xy 151.837019 -8.375257) (xy 151.837019 -8.320743)
			(xy 151.844778 -8.266784) (xy 151.860137 -8.214478) (xy 151.882784 -8.164891) (xy 151.912258 -8.119031)
			(xy 151.947959 -8.077834) (xy 151.98916 -8.042137) (xy 152.035022 -8.012667) (xy 152.084612 -7.990024)
			(xy 152.136919 -7.97467) (xy 152.190879 -7.966916) (xy 152.218136 -7.966456) (xy 152.246736 -7.966999)
			(xy 152.303298 -7.975525) (xy 152.357954 -7.992395) (xy 152.409481 -8.017232) (xy 152.456725 -8.049479)
			(xy 152.498629 -8.088415) (xy 152.51684 -8.110474) (xy 152.525963 -8.121136) (xy 152.548759 -8.13748)
			(xy 152.575142 -8.147005) (xy 152.603121 -8.148993) (xy 152.630585 -8.143294) (xy 152.655462 -8.130337)
			(xy 152.675877 -8.111101) (xy 152.683464 -8.099298) (xy 152.700714 -8.071289) (xy 152.741342 -8.019553)
			(xy 152.788301 -7.973488) (xy 152.840808 -7.933861) (xy 152.897986 -7.901336) (xy 152.95888 -7.876454)
			(xy 153.022475 -7.859632) (xy 153.087707 -7.85115) (xy 153.120598 -7.850632) (xy 153.152563 -7.851033)
			(xy 153.215989 -7.859045) (xy 153.27791 -7.874944) (xy 153.337351 -7.898478) (xy 153.393373 -7.929276)
			(xy 153.445094 -7.966853) (xy 153.491696 -8.010616) (xy 153.532447 -8.059875) (xy 153.566702 -8.113852)
			(xy 153.593923 -8.171698) (xy 153.613678 -8.232499) (xy 153.625657 -8.295296) (xy 153.629672 -8.3591)
			(xy 153.625657 -8.422904) (xy 153.613678 -8.485701) (xy 153.593923 -8.546502) (xy 153.566702 -8.604348)
			(xy 153.532447 -8.658325) (xy 153.491696 -8.707584) (xy 153.445094 -8.751347) (xy 153.393373 -8.788924)
			(xy 153.337351 -8.819722) (xy 153.27791 -8.843256) (xy 153.215989 -8.859155) (xy 153.152563 -8.867167)
			(xy 153.120598 -8.867648) (xy 153.08693 -8.867102) (xy 153.020185 -8.858199) (xy 152.9552 -8.840562)
			(xy 152.893112 -8.8145) (xy 152.835008 -8.780469) (xy 152.781906 -8.739066) (xy 152.734734 -8.691014)
			(xy 152.694319 -8.637154) (xy 152.677368 -8.60806) (xy 152.670081 -8.596023) (xy 152.650111 -8.576215)
			(xy 152.625498 -8.5626) (xy 152.598105 -8.55621) (xy 152.570008 -8.557528) (xy 152.543334 -8.566454)
			(xy 152.520103 -8.582313) (xy 152.510744 -8.59282) (xy 152.492511 -8.613811) (xy 152.45101 -8.650812)
			(xy 152.40458 -8.681399) (xy 152.354204 -8.704926) (xy 152.300946 -8.720895) (xy 152.245936 -8.728967)
			(xy 152.218136 -8.729472) (xy 152.190879 -8.729084) (xy 152.136919 -8.72133) (xy 152.084612 -8.705976)
			(xy 152.035022 -8.683333) (xy 151.98916 -8.653863) (xy 151.947959 -8.618166) (xy 151.912258 -8.576969)
			(xy 151.882784 -8.531109) (xy 151.860137 -8.481522) (xy 151.844778 -8.429216) (xy 151.837019 -8.375257)
			(xy 148.804021 -8.375257) (xy 148.806898 -8.406181) (xy 148.807424 -8.449818) (xy 148.806922 -8.493268)
			(xy 148.798904 -8.579797) (xy 148.782936 -8.665217) (xy 148.759155 -8.748799) (xy 148.727763 -8.829831)
			(xy 148.689029 -8.90762) (xy 148.643282 -8.981504) (xy 148.590913 -9.050851) (xy 148.532369 -9.115071)
			(xy 148.476442 -9.166055) (xy 155.094426 -9.166055) (xy 155.094426 -9.102133) (xy 155.102437 -9.038715)
			(xy 155.118334 -8.976801) (xy 155.141866 -8.917368) (xy 155.17266 -8.861353) (xy 155.210233 -8.809638)
			(xy 155.25399 -8.763041) (xy 155.303243 -8.722296) (xy 155.357214 -8.688045) (xy 155.415053 -8.660828)
			(xy 155.475846 -8.641075) (xy 155.538636 -8.629097) (xy 155.602432 -8.625084) (xy 155.666228 -8.629097)
			(xy 155.729018 -8.641075) (xy 155.789811 -8.660828) (xy 155.84765 -8.688045) (xy 155.901621 -8.722296)
			(xy 155.950874 -8.763041) (xy 155.994631 -8.809638) (xy 156.032204 -8.861353) (xy 156.062998 -8.917368)
			(xy 156.08653 -8.976801) (xy 156.102427 -9.038715) (xy 156.110438 -9.102133) (xy 156.11094 -9.134094)
			(xy 156.110438 -9.166055) (xy 156.102427 -9.229473) (xy 156.08653 -9.291387) (xy 156.062998 -9.35082)
			(xy 156.032204 -9.406835) (xy 155.994631 -9.45855) (xy 155.950874 -9.505147) (xy 155.901621 -9.545892)
			(xy 155.84765 -9.580143) (xy 155.789811 -9.60736) (xy 155.729018 -9.627113) (xy 155.666228 -9.639091)
			(xy 155.602432 -9.643105) (xy 155.538636 -9.639091) (xy 155.475846 -9.627113) (xy 155.415053 -9.60736)
			(xy 155.357214 -9.580143) (xy 155.303243 -9.545892) (xy 155.25399 -9.505147) (xy 155.210233 -9.45855)
			(xy 155.17266 -9.406835) (xy 155.141866 -9.35082) (xy 155.118334 -9.291387) (xy 155.102437 -9.229473)
			(xy 155.094426 -9.166055) (xy 148.476442 -9.166055) (xy 148.468149 -9.173615) (xy 148.398802 -9.225984)
			(xy 148.324918 -9.271731) (xy 148.247129 -9.310465) (xy 148.166097 -9.341857) (xy 148.082515 -9.365638)
			(xy 147.997095 -9.381606) (xy 147.910566 -9.389624) (xy 147.823666 -9.389624) (xy 147.737137 -9.381606)
			(xy 147.651717 -9.365638) (xy 147.568135 -9.341857) (xy 147.487103 -9.310465) (xy 147.409314 -9.271731)
			(xy 147.33543 -9.225984) (xy 147.266083 -9.173615) (xy 147.201863 -9.115071) (xy 147.143319 -9.050851)
			(xy 147.09095 -8.981504) (xy 147.045203 -8.90762) (xy 147.006469 -8.829831) (xy 146.975077 -8.748799)
			(xy 146.951296 -8.665217) (xy 146.935328 -8.579797) (xy 146.92731 -8.493268) (xy 146.926808 -8.449818)
			(xy 146.927302 -8.40618) (xy 146.935388 -8.319278) (xy 146.951493 -8.2335) (xy 146.975476 -8.149584)
			(xy 147.007133 -8.068251) (xy 147.046191 -7.990201) (xy 147.092313 -7.916107) (xy 147.145104 -7.846606)
			(xy 147.204107 -7.782295) (xy 147.268816 -7.723729) (xy 147.338674 -7.671412) (xy 147.375626 -7.648194)
			(xy 147.382738 -7.643876) (xy 147.393152 -7.631176) (xy 147.3962 -7.623556) (xy 147.398698 -7.616667)
			(xy 147.400129 -7.602092) (xy 147.398994 -7.594854) (xy 147.371308 -7.497064) (xy 147.367793 -7.486616)
			(xy 147.35351 -7.469854) (xy 147.333547 -7.460557) (xy 147.32254 -7.45998) (xy 141.136116 -7.45998)
			(xy 141.127066 -7.46034) (xy 141.110088 -7.466613) (xy 141.09634 -7.478387) (xy 141.091666 -7.486142)
			(xy 141.054582 -7.552944) (xy 141.054582 -7.553452) (xy 141.048486 -7.564374) (xy 141.045463 -7.570407)
			(xy 141.042364 -7.583535) (xy 141.04239 -7.590282) (xy 141.042644 -7.603744) (xy 141.05001 -7.615428)
			(xy 141.05001 -7.615682) (xy 141.068483 -7.646204) (xy 141.097629 -7.711323) (xy 141.117384 -7.779877)
			(xy 141.12736 -7.85052) (xy 141.127988 -7.886192) (xy 141.127543 -7.916924) (xy 141.120135 -7.97794)
			(xy 141.105426 -8.037618) (xy 141.083631 -8.095088) (xy 141.055067 -8.149511) (xy 141.020151 -8.200095)
			(xy 140.979393 -8.246101) (xy 140.933386 -8.286859) (xy 140.882801 -8.321773) (xy 140.828377 -8.350336)
			(xy 140.770906 -8.37213) (xy 140.711228 -8.386837) (xy 140.650212 -8.394244) (xy 140.61948 -8.3947)
			(xy 140.587553 -8.394198) (xy 140.524203 -8.386195) (xy 140.462354 -8.370317) (xy 140.402983 -8.346814)
			(xy 140.347025 -8.316057) (xy 140.295361 -8.278532) (xy 140.248806 -8.234828) (xy 140.228066 -8.21055)
			(xy 140.225209 -8.207268) (xy 140.218572 -8.201642) (xy 140.214858 -8.199374) (xy 140.204444 -8.194548)
			(xy 140.193014 -8.192262) (xy 140.191998 -8.192262) (xy 140.18895 -8.192008) (xy 140.109956 -8.192008)
			(xy 140.106908 -8.192262) (xy 140.105892 -8.192262) (xy 140.094462 -8.194548) (xy 140.084048 -8.199374)
			(xy 140.080343 -8.201654) (xy 140.073702 -8.207274) (xy 140.07084 -8.21055) (xy 140.050117 -8.234845)
			(xy 140.003565 -8.278558) (xy 139.951901 -8.31609) (xy 139.89594 -8.34685) (xy 139.836564 -8.370353)
			(xy 139.774711 -8.386227) (xy 139.711355 -8.394223) (xy 139.679426 -8.3947) (xy 139.648693 -8.394256)
			(xy 139.587675 -8.38685) (xy 139.527995 -8.372142) (xy 139.470522 -8.350348) (xy 139.416096 -8.321785)
			(xy 139.36551 -8.28687) (xy 139.319501 -8.246112) (xy 139.278741 -8.200104) (xy 139.243824 -8.149519)
			(xy 139.215259 -8.095094) (xy 139.193463 -8.037623) (xy 139.178753 -7.977943) (xy 139.171345 -7.916925)
			(xy 139.170918 -7.886192) (xy 139.171522 -7.850519) (xy 139.181504 -7.779876) (xy 139.20127 -7.711324)
			(xy 139.230433 -7.646211) (xy 139.248896 -7.615682) (xy 139.248896 -7.615428) (xy 139.24915 -7.615428)
			(xy 139.250928 -7.61238) (xy 139.253117 -7.607953) (xy 139.255923 -7.598487) (xy 139.256516 -7.593584)
			(xy 139.256516 -7.590536) (xy 139.256567 -7.583725) (xy 139.253464 -7.570468) (xy 139.25042 -7.564374)
			(xy 139.244324 -7.553452) (xy 139.244324 -7.552944) (xy 139.20724 -7.486142) (xy 139.20254 -7.478396)
			(xy 139.188817 -7.466587) (xy 139.171842 -7.460291) (xy 139.16279 -7.45998) (xy 137.398252 -7.45998)
			(xy 137.388985 -7.460369) (xy 137.371668 -7.46697) (xy 137.357875 -7.479347) (xy 137.353294 -7.487412)
			(xy 137.316464 -7.567422) (xy 137.31367 -7.573772) (xy 137.311079 -7.579647) (xy 137.308629 -7.592247)
			(xy 137.308844 -7.598664) (xy 137.310114 -7.606538) (xy 137.310368 -7.608824) (xy 137.316464 -7.622286)
			(xy 137.32129 -7.627874) (xy 137.340702 -7.65102) (xy 137.374486 -7.701102) (xy 137.402104 -7.754831)
			(xy 137.423165 -7.811452) (xy 137.437375 -7.870168) (xy 137.444532 -7.930154) (xy 137.444988 -7.96036)
			(xy 137.444545 -7.991093) (xy 137.43714 -8.052112) (xy 137.422434 -8.111793) (xy 137.40064 -8.169266)
			(xy 137.372078 -8.223693) (xy 137.337163 -8.274281) (xy 137.296404 -8.32029) (xy 137.250396 -8.36105)
			(xy 137.199811 -8.395967) (xy 137.145385 -8.424532) (xy 137.087912 -8.446328) (xy 137.028232 -8.461036)
			(xy 136.967213 -8.468443) (xy 136.93648 -8.468868) (xy 136.90517 -8.468386) (xy 136.843024 -8.460693)
			(xy 136.782294 -8.445427) (xy 136.723898 -8.422819) (xy 136.66872 -8.39321) (xy 136.617596 -8.35705)
			(xy 136.571299 -8.314885) (xy 136.530531 -8.267354) (xy 136.512808 -8.241538) (xy 136.505486 -8.231515)
			(xy 136.483789 -8.21951) (xy 136.471406 -8.218678) (xy 136.385808 -8.218678) (xy 136.384792 -8.218678)
			(xy 136.372414 -8.219539) (xy 136.350718 -8.231524) (xy 136.34339 -8.241538) (xy 136.325674 -8.267357)
			(xy 136.284901 -8.314881) (xy 136.238601 -8.357039) (xy 136.187474 -8.393193) (xy 136.132296 -8.422796)
			(xy 136.0739 -8.4454) (xy 136.013171 -8.460663) (xy 135.951027 -8.468353) (xy 135.919718 -8.468868)
			(xy 135.888986 -8.468423) (xy 135.82797 -8.461016) (xy 135.768292 -8.446308) (xy 135.710822 -8.424513)
			(xy 135.656399 -8.39595) (xy 135.605815 -8.361034) (xy 135.55981 -8.320275) (xy 135.519053 -8.274268)
			(xy 135.484139 -8.223683) (xy 135.455578 -8.169258) (xy 135.433785 -8.111787) (xy 135.41908 -8.052108)
			(xy 135.411675 -7.991092) (xy 135.41121 -7.96036) (xy 135.411289 -7.947638) (xy 135.412561 -7.922226)
			(xy 135.41375 -7.90956) (xy 135.413496 -7.90956) (xy 135.417085 -7.87863) (xy 135.430847 -7.817902)
			(xy 135.451926 -7.75931) (xy 135.480004 -7.703732) (xy 135.514662 -7.652001) (xy 135.534654 -7.628128)
			(xy 135.534908 -7.627874) (xy 135.536432 -7.626096) (xy 135.540431 -7.620694) (xy 135.545698 -7.608335)
			(xy 135.546846 -7.601712) (xy 135.5471 -7.600696) (xy 135.547862 -7.5946) (xy 135.546846 -7.587742)
			(xy 135.546267 -7.584198) (xy 135.544224 -7.577315) (xy 135.542782 -7.574026) (xy 135.516112 -7.51586)
			(xy 135.503158 -7.487666) (xy 135.498545 -7.479552) (xy 135.484679 -7.467082) (xy 135.46727 -7.460396)
			(xy 135.457946 -7.45998) (xy 133.584442 -7.45998) (xy 133.578433 -7.460148) (xy 133.566751 -7.462973)
			(xy 133.561328 -7.465568) (xy 133.557851 -7.467404) (xy 133.551466 -7.471991) (xy 133.548628 -7.474712)
			(xy 133.234684 -7.788656) (xy 133.228105 -7.795905) (xy 133.220493 -7.813922) (xy 133.220145 -7.833477)
			(xy 133.223254 -7.842758) (xy 133.257798 -7.932928) (xy 133.260799 -7.938779) (xy 133.269283 -7.94882)
			(xy 133.274562 -7.95274) (xy 133.274816 -7.952994) (xy 133.28015 -7.956804) (xy 133.293866 -7.961376)
			(xy 133.30174 -7.961884) (xy 133.33395 -7.963942) (xy 133.397505 -7.975192) (xy 133.459125 -7.994395)
			(xy 133.51782 -8.021243) (xy 133.572644 -8.055303) (xy 133.622716 -8.096029) (xy 133.667232 -8.142764)
			(xy 133.705474 -8.194758) (xy 133.736828 -8.251173) (xy 133.76079 -8.311104) (xy 133.776974 -8.373585)
			(xy 133.78512 -8.437612) (xy 133.78561 -8.469884) (xy 133.785165 -8.500617) (xy 133.785016 -8.501845)
			(xy 134.039096 -8.501845) (xy 134.039096 -8.437923) (xy 134.047107 -8.374505) (xy 134.063004 -8.312591)
			(xy 134.086536 -8.253158) (xy 134.11733 -8.197143) (xy 134.154903 -8.145428) (xy 134.19866 -8.098831)
			(xy 134.247913 -8.058086) (xy 134.301884 -8.023835) (xy 134.359723 -7.996618) (xy 134.420516 -7.976865)
			(xy 134.483306 -7.964887) (xy 134.547102 -7.960874) (xy 134.610898 -7.964887) (xy 134.673688 -7.976865)
			(xy 134.734481 -7.996618) (xy 134.79232 -8.023835) (xy 134.846291 -8.058086) (xy 134.895544 -8.098831)
			(xy 134.939301 -8.145428) (xy 134.976874 -8.197143) (xy 135.007668 -8.253158) (xy 135.0312 -8.312591)
			(xy 135.047097 -8.374505) (xy 135.055108 -8.437923) (xy 135.05561 -8.469884) (xy 135.055108 -8.501845)
			(xy 135.047097 -8.565263) (xy 135.0312 -8.627177) (xy 135.007668 -8.68661) (xy 134.976874 -8.742625)
			(xy 134.939301 -8.79434) (xy 134.895544 -8.840937) (xy 134.846291 -8.881682) (xy 134.79232 -8.915933)
			(xy 134.734481 -8.94315) (xy 134.673688 -8.962903) (xy 134.610898 -8.974881) (xy 134.547102 -8.978895)
			(xy 134.483306 -8.974881) (xy 134.420516 -8.962903) (xy 134.359723 -8.94315) (xy 134.301884 -8.915933)
			(xy 134.247913 -8.881682) (xy 134.19866 -8.840937) (xy 134.154903 -8.79434) (xy 134.11733 -8.742625)
			(xy 134.086536 -8.68661) (xy 134.063004 -8.627177) (xy 134.047107 -8.565263) (xy 134.039096 -8.501845)
			(xy 133.785016 -8.501845) (xy 133.777758 -8.561634) (xy 133.76305 -8.621314) (xy 133.741256 -8.678786)
			(xy 133.712692 -8.733212) (xy 133.677777 -8.783798) (xy 133.637019 -8.829806) (xy 133.591012 -8.870566)
			(xy 133.540427 -8.905483) (xy 133.486003 -8.934048) (xy 133.428531 -8.955845) (xy 133.368852 -8.970555)
			(xy 133.307835 -8.977964) (xy 133.277102 -8.978392) (xy 133.26438 -8.978314) (xy 133.238968 -8.977045)
			(xy 133.226302 -8.975852) (xy 133.193631 -8.972047) (xy 133.12958 -8.957085) (xy 133.067992 -8.933993)
			(xy 133.009893 -8.903155) (xy 132.956254 -8.865086) (xy 132.90797 -8.820421) (xy 132.865844 -8.769905)
			(xy 132.830582 -8.71438) (xy 132.80277 -8.654774) (xy 132.782873 -8.592081) (xy 132.771222 -8.527345)
			(xy 132.769102 -8.494522) (xy 132.768848 -8.490204) (xy 132.767986 -8.484612) (xy 132.764133 -8.473978)
			(xy 132.761228 -8.469122) (xy 132.759196 -8.466328) (xy 132.756402 -8.462264) (xy 132.755386 -8.460994)
			(xy 132.750306 -8.45693) (xy 132.740146 -8.450834) (xy 132.649976 -8.416036) (xy 132.64069 -8.412925)
			(xy 132.621125 -8.413234) (xy 132.603107 -8.420863) (xy 132.595874 -8.427466) (xy 130.290062 -10.733278)
			(xy 131.168902 -10.733278) (xy 131.169416 -10.705195) (xy 131.177646 -10.649636) (xy 131.193941 -10.595886)
			(xy 131.217946 -10.545108) (xy 131.249143 -10.498403) (xy 131.286855 -10.456782) (xy 131.330267 -10.421145)
			(xy 131.378439 -10.392264) (xy 131.430327 -10.370765) (xy 131.457446 -10.363454) (xy 131.465956 -10.360881)
			(xy 131.480634 -10.350871) (xy 131.486148 -10.343896) (xy 131.504182 -10.319258) (xy 131.509197 -10.311719)
			(xy 131.513996 -10.294269) (xy 131.51358 -10.285222) (xy 131.511802 -10.243566) (xy 131.511802 -10.243312)
			(xy 131.512249 -10.21258) (xy 131.519656 -10.151563) (xy 131.534365 -10.091885) (xy 131.55616 -10.034414)
			(xy 131.584723 -9.97999) (xy 131.619638 -9.929405) (xy 131.660397 -9.883398) (xy 131.706404 -9.84264)
			(xy 131.756988 -9.807724) (xy 131.811412 -9.77916) (xy 131.868883 -9.757365) (xy 131.928561 -9.742657)
			(xy 131.989578 -9.735249) (xy 132.02031 -9.734804) (xy 132.055276 -9.735373) (xy 132.124546 -9.744977)
			(xy 132.191845 -9.763987) (xy 132.255902 -9.792046) (xy 132.315507 -9.828622) (xy 132.34289 -9.850374)
			(xy 132.349886 -9.855649) (xy 132.366391 -9.861491) (xy 132.375148 -9.861804) (xy 132.529072 -9.861804)
			(xy 132.537817 -9.861426) (xy 132.554309 -9.855599) (xy 132.56133 -9.850374) (xy 132.588708 -9.828619)
			(xy 132.648325 -9.792069) (xy 132.712384 -9.764026) (xy 132.779681 -9.745018) (xy 132.848946 -9.735404)
			(xy 132.88391 -9.734804) (xy 132.914643 -9.735228) (xy 132.97566 -9.742638) (xy 133.035339 -9.757349)
			(xy 133.09281 -9.779146) (xy 133.147235 -9.807712) (xy 133.197819 -9.84263) (xy 133.243826 -9.88339)
			(xy 133.284584 -9.929398) (xy 133.319499 -9.979984) (xy 133.341264 -10.021455) (xy 137.470512 -10.021455)
			(xy 137.478269 -9.967495) (xy 137.493627 -9.915188) (xy 137.516272 -9.8656) (xy 137.545745 -9.819739)
			(xy 137.581445 -9.77854) (xy 137.622644 -9.742841) (xy 137.668505 -9.713369) (xy 137.718094 -9.690725)
			(xy 137.770401 -9.675368) (xy 137.824361 -9.667612) (xy 137.878875 -9.667614) (xy 137.932834 -9.675375)
			(xy 137.98514 -9.690737) (xy 138.034726 -9.713387) (xy 138.080585 -9.742863) (xy 138.121781 -9.778566)
			(xy 138.157477 -9.819768) (xy 138.186945 -9.865632) (xy 138.209586 -9.915222) (xy 138.224939 -9.96753)
			(xy 138.23269 -10.021491) (xy 138.23315 -10.048748) (xy 138.232709 -10.073805) (xy 138.226117 -10.123484)
			(xy 138.213079 -10.171872) (xy 138.19382 -10.218138) (xy 138.181588 -10.24001) (xy 138.174748 -10.252575)
			(xy 138.167779 -10.280314) (xy 138.16877 -10.308898) (xy 138.177644 -10.336088) (xy 138.193705 -10.359754)
			(xy 138.215695 -10.378042) (xy 138.241892 -10.38952) (xy 138.270244 -10.393288) (xy 138.284458 -10.391648)
			(xy 138.303018 -10.389052) (xy 138.340394 -10.386252) (xy 138.359134 -10.38606) (xy 138.390673 -10.386604)
			(xy 138.453266 -10.39441) (xy 138.514412 -10.409899) (xy 138.573174 -10.432832) (xy 138.628647 -10.462858)
			(xy 138.67998 -10.499514) (xy 138.726385 -10.542238) (xy 138.767149 -10.590375) (xy 138.801646 -10.643184)
			(xy 138.829346 -10.699854) (xy 138.849823 -10.759516) (xy 138.862764 -10.821252) (xy 138.867968 -10.884114)
			(xy 138.866106 -10.929069) (xy 139.438882 -10.929069) (xy 139.438882 -10.865147) (xy 139.446893 -10.801729)
			(xy 139.46279 -10.739815) (xy 139.486322 -10.680382) (xy 139.517116 -10.624367) (xy 139.554689 -10.572652)
			(xy 139.598446 -10.526055) (xy 139.647699 -10.48531) (xy 139.70167 -10.451059) (xy 139.759509 -10.423842)
			(xy 139.820302 -10.404089) (xy 139.883092 -10.392111) (xy 139.946888 -10.388098) (xy 140.010684 -10.392111)
			(xy 140.073474 -10.404089) (xy 140.134267 -10.423842) (xy 140.192106 -10.451059) (xy 140.246077 -10.48531)
			(xy 140.29533 -10.526055) (xy 140.339087 -10.572652) (xy 140.37666 -10.624367) (xy 140.407454 -10.680382)
			(xy 140.430986 -10.739815) (xy 140.446883 -10.801729) (xy 140.454894 -10.865147) (xy 140.455396 -10.897108)
			(xy 140.454894 -10.929069) (xy 140.446883 -10.992487) (xy 140.430986 -11.054401) (xy 140.407454 -11.113834)
			(xy 140.37666 -11.169849) (xy 140.339087 -11.221564) (xy 140.29533 -11.268161) (xy 140.246077 -11.308906)
			(xy 140.192106 -11.343157) (xy 140.134267 -11.370374) (xy 140.073474 -11.390127) (xy 140.010684 -11.402105)
			(xy 139.946888 -11.406119) (xy 139.883092 -11.402105) (xy 139.820302 -11.390127) (xy 139.759509 -11.370374)
			(xy 139.70167 -11.343157) (xy 139.647699 -11.308906) (xy 139.598446 -11.268161) (xy 139.554689 -11.221564)
			(xy 139.517116 -11.169849) (xy 139.486322 -11.113834) (xy 139.46279 -11.054401) (xy 139.446893 -10.992487)
			(xy 139.438882 -10.929069) (xy 138.866106 -10.929069) (xy 138.865358 -10.947138) (xy 138.854971 -11.009355)
			(xy 138.836969 -11.069809) (xy 138.811627 -11.127573) (xy 138.779335 -11.181758) (xy 138.740589 -11.231532)
			(xy 138.695983 -11.276132) (xy 138.646203 -11.314872) (xy 138.592014 -11.347157) (xy 138.534247 -11.372492)
			(xy 138.473791 -11.390486) (xy 138.411572 -11.400864) (xy 138.348548 -11.403467) (xy 138.285686 -11.398254)
			(xy 138.223952 -11.385306) (xy 138.164293 -11.364821) (xy 138.107626 -11.337113) (xy 138.054822 -11.30261)
			(xy 138.006691 -11.261839) (xy 137.963972 -11.215429) (xy 137.927323 -11.164091) (xy 137.897304 -11.108614)
			(xy 137.874379 -11.049849) (xy 137.858898 -10.988701) (xy 137.8511 -10.926107) (xy 137.850626 -10.894568)
			(xy 137.851148 -10.862155) (xy 137.859384 -10.797855) (xy 137.875731 -10.735124) (xy 137.899923 -10.674982)
			(xy 137.931567 -10.618405) (xy 137.950448 -10.592054) (xy 137.958532 -10.580255) (xy 137.968572 -10.553494)
			(xy 137.970793 -10.524998) (xy 137.96502 -10.497005) (xy 137.951706 -10.471712) (xy 137.931897 -10.451108)
			(xy 137.907148 -10.436808) (xy 137.879403 -10.429938) (xy 137.865104 -10.430002) (xy 137.851642 -10.430256)
			(xy 137.824385 -10.42979) (xy 137.770424 -10.422037) (xy 137.718117 -10.406684) (xy 137.668526 -10.384042)
			(xy 137.622664 -10.354573) (xy 137.581462 -10.318877) (xy 137.545759 -10.27768) (xy 137.516284 -10.231821)
			(xy 137.493635 -10.182234) (xy 137.478274 -10.129929) (xy 137.470514 -10.075969) (xy 137.470512 -10.021455)
			(xy 133.341264 -10.021455) (xy 133.348063 -10.03441) (xy 133.369857 -10.091882) (xy 133.384566 -10.151562)
			(xy 133.391973 -10.212579) (xy 133.392418 -10.243312) (xy 133.39064 -10.285984) (xy 133.390233 -10.294967)
			(xy 133.395058 -10.312278) (xy 133.400038 -10.319766) (xy 133.417564 -10.344404) (xy 133.423025 -10.351434)
			(xy 133.437724 -10.361457) (xy 133.446266 -10.363962) (xy 133.473164 -10.371458) (xy 133.524572 -10.39325)
			(xy 133.572257 -10.4223) (xy 133.6152 -10.457988) (xy 133.652485 -10.499552) (xy 133.683316 -10.546106)
			(xy 133.707035 -10.596654) (xy 133.723136 -10.650119) (xy 133.731274 -10.70536) (xy 133.731762 -10.733278)
			(xy 133.731324 -10.760532) (xy 133.723569 -10.814487) (xy 133.708213 -10.866788) (xy 133.68557 -10.916371)
			(xy 133.683939 -10.918909) (xy 136.581128 -10.918909) (xy 136.581128 -10.854987) (xy 136.589139 -10.791569)
			(xy 136.605036 -10.729655) (xy 136.628568 -10.670222) (xy 136.659362 -10.614207) (xy 136.696935 -10.562492)
			(xy 136.740692 -10.515895) (xy 136.789945 -10.47515) (xy 136.843916 -10.440899) (xy 136.901755 -10.413682)
			(xy 136.962548 -10.393929) (xy 137.025338 -10.381951) (xy 137.089134 -10.377938) (xy 137.15293 -10.381951)
			(xy 137.21572 -10.393929) (xy 137.276513 -10.413682) (xy 137.334352 -10.440899) (xy 137.388323 -10.47515)
			(xy 137.437576 -10.515895) (xy 137.481333 -10.562492) (xy 137.518906 -10.614207) (xy 137.5497 -10.670222)
			(xy 137.573232 -10.729655) (xy 137.589129 -10.791569) (xy 137.59714 -10.854987) (xy 137.597642 -10.886948)
			(xy 137.59714 -10.918909) (xy 137.589129 -10.982327) (xy 137.573232 -11.044241) (xy 137.5497 -11.103674)
			(xy 137.518906 -11.159689) (xy 137.481333 -11.211404) (xy 137.437576 -11.258001) (xy 137.388323 -11.298746)
			(xy 137.334352 -11.332997) (xy 137.276513 -11.360214) (xy 137.21572 -11.379967) (xy 137.15293 -11.391945)
			(xy 137.089134 -11.395959) (xy 137.025338 -11.391945) (xy 136.962548 -11.379967) (xy 136.901755 -11.360214)
			(xy 136.843916 -11.332997) (xy 136.789945 -11.298746) (xy 136.740692 -11.258001) (xy 136.696935 -11.211404)
			(xy 136.659362 -11.159689) (xy 136.628568 -11.103674) (xy 136.605036 -11.044241) (xy 136.589139 -10.982327)
			(xy 136.581128 -10.918909) (xy 133.683939 -10.918909) (xy 133.6561 -10.962226) (xy 133.620403 -11.00342)
			(xy 133.579207 -11.039114) (xy 133.53335 -11.068582) (xy 133.483765 -11.091222) (xy 133.431463 -11.106574)
			(xy 133.377508 -11.114326) (xy 133.350254 -11.114786) (xy 133.321285 -11.114278) (xy 133.264012 -11.105519)
			(xy 133.208725 -11.088194) (xy 133.156696 -11.062702) (xy 133.109124 -11.029631) (xy 133.067104 -10.989742)
			(xy 133.031604 -10.943953) (xy 133.003441 -10.89332) (xy 132.983265 -10.839008) (xy 132.976874 -10.810748)
			(xy 132.974652 -10.802155) (xy 132.965305 -10.787083) (xy 132.958586 -10.781284) (xy 132.93471 -10.762488)
			(xy 132.927447 -10.757215) (xy 132.91041 -10.751608) (xy 132.901436 -10.751566) (xy 132.88391 -10.75182)
			(xy 132.848945 -10.751234) (xy 132.779675 -10.741634) (xy 132.712377 -10.722627) (xy 132.64832 -10.694572)
			(xy 132.588714 -10.658) (xy 132.56133 -10.63625) (xy 132.554326 -10.630986) (xy 132.537827 -10.625137)
			(xy 132.529072 -10.62482) (xy 132.375148 -10.62482) (xy 132.366398 -10.625157) (xy 132.349907 -10.631012)
			(xy 132.34289 -10.63625) (xy 132.315496 -10.657985) (xy 132.255885 -10.69454) (xy 132.191829 -10.722588)
			(xy 132.124536 -10.7416) (xy 132.055273 -10.751218) (xy 132.02031 -10.75182) (xy 131.999482 -10.751312)
			(xy 131.990444 -10.75135) (xy 131.973269 -10.756929) (xy 131.965954 -10.762234) (xy 131.942078 -10.78103)
			(xy 131.935276 -10.786836) (xy 131.925912 -10.80206) (xy 131.92379 -10.810748) (xy 131.917383 -10.839002)
			(xy 131.897199 -10.893305) (xy 131.869032 -10.943929) (xy 131.833531 -10.98971) (xy 131.791513 -11.029594)
			(xy 131.743946 -11.062661) (xy 131.691923 -11.088153) (xy 131.636642 -11.10548) (xy 131.579376 -11.114246)
			(xy 131.55041 -11.114786) (xy 131.523156 -11.114335) (xy 131.469204 -11.106579) (xy 131.416904 -11.091223)
			(xy 131.367323 -11.06858) (xy 131.321469 -11.039111) (xy 131.280275 -11.003416) (xy 131.244581 -10.962222)
			(xy 131.215114 -10.916367) (xy 131.192473 -10.866784) (xy 131.177118 -10.814484) (xy 131.169364 -10.760532)
			(xy 131.168902 -10.733278) (xy 130.290062 -10.733278) (xy 128.528318 -12.495022) (xy 129.364232 -12.495022)
			(xy 129.364758 -12.466674) (xy 129.373159 -12.410604) (xy 129.389764 -12.356394) (xy 129.414208 -12.305237)
			(xy 129.445953 -12.258261) (xy 129.484299 -12.2165) (xy 129.528402 -12.180872) (xy 129.577292 -12.152163)
			(xy 129.629892 -12.131003) (xy 129.657348 -12.123928) (xy 129.667762 -12.121388) (xy 129.684526 -12.108942)
			(xy 129.73177 -12.025122) (xy 129.734056 -12.004294) (xy 129.730754 -11.994388) (xy 129.730754 -11.99388)
			(xy 129.719505 -11.956331) (xy 129.707385 -11.878892) (xy 129.706624 -11.839702) (xy 129.70704 -11.808969)
			(xy 129.714449 -11.74795) (xy 129.729159 -11.68827) (xy 129.750956 -11.630798) (xy 129.779522 -11.576372)
			(xy 129.81444 -11.525787) (xy 129.855201 -11.47978) (xy 129.901211 -11.439021) (xy 129.951798 -11.404106)
			(xy 130.006225 -11.375544) (xy 130.063699 -11.35375) (xy 130.12338 -11.339043) (xy 130.184399 -11.331638)
			(xy 130.215132 -11.331194) (xy 130.250088 -11.331759) (xy 130.319342 -11.341325) (xy 130.386633 -11.360286)
			(xy 130.450693 -11.388285) (xy 130.510314 -11.424793) (xy 130.537712 -11.44651) (xy 130.544652 -11.451754)
			(xy 130.561024 -11.457596) (xy 130.569716 -11.45794) (xy 130.724148 -11.45794) (xy 130.732831 -11.457552)
			(xy 130.749189 -11.451712) (xy 130.756152 -11.44651) (xy 130.783569 -11.424821) (xy 130.84319 -11.388319)
			(xy 130.907246 -11.360322) (xy 130.974531 -11.341355) (xy 131.043779 -11.331777) (xy 131.078732 -11.331194)
			(xy 131.109464 -11.331626) (xy 131.170479 -11.339038) (xy 131.230155 -11.353751) (xy 131.287624 -11.375549)
			(xy 131.342046 -11.404115) (xy 131.392628 -11.439032) (xy 131.438633 -11.479791) (xy 131.479389 -11.525799)
			(xy 131.514303 -11.576383) (xy 131.542865 -11.630807) (xy 131.56466 -11.688277) (xy 131.579368 -11.747955)
			(xy 131.586776 -11.80897) (xy 131.58724 -11.839702) (xy 131.58724 -11.839956) (xy 131.586481 -11.879272)
			(xy 131.574367 -11.956965) (xy 131.56311 -11.994642) (xy 131.559808 -12.004802) (xy 131.56184 -12.02563)
			(xy 131.60883 -12.10945) (xy 131.62534 -12.121896) (xy 131.6355 -12.124436) (xy 131.636008 -12.124436)
			(xy 131.663313 -12.131634) (xy 131.715602 -12.152946) (xy 131.764177 -12.181734) (xy 131.807977 -12.21737)
			(xy 131.846045 -12.259074) (xy 131.877547 -12.305935) (xy 131.901796 -12.356929) (xy 131.918261 -12.41094)
			(xy 131.926583 -12.466789) (xy 131.927074 -12.494006) (xy 132.907784 -12.494006) (xy 132.911855 -12.438384)
			(xy 132.923981 -12.383947) (xy 132.943904 -12.331856) (xy 132.9712 -12.283221) (xy 133.005286 -12.239078)
			(xy 133.045435 -12.200369) (xy 133.090793 -12.167918) (xy 133.140393 -12.142417) (xy 133.193177 -12.12441)
			(xy 133.24802 -12.11428) (xy 133.303754 -12.112243) (xy 133.359191 -12.118343) (xy 133.413148 -12.132449)
			(xy 133.464477 -12.154261) (xy 133.512083 -12.183315) (xy 133.554951 -12.21899) (xy 133.592168 -12.260527)
			(xy 133.622941 -12.30704) (xy 133.646613 -12.357537) (xy 133.662681 -12.410944) (xy 133.670801 -12.46612)
			(xy 133.67131 -12.494006) (xy 133.671291 -12.495022) (xy 134.764272 -12.495022) (xy 134.764825 -12.467775)
			(xy 134.772589 -12.413836) (xy 134.787948 -12.36155) (xy 134.81059 -12.311981) (xy 134.840054 -12.266138)
			(xy 134.87574 -12.224954) (xy 134.916923 -12.189265) (xy 134.962765 -12.159799) (xy 135.012332 -12.137155)
			(xy 135.038338 -12.129008) (xy 135.038592 -12.129008) (xy 135.047017 -12.126074) (xy 135.061304 -12.11541)
			(xy 135.066532 -12.10818) (xy 135.107934 -12.045696) (xy 135.111998 -12.027916) (xy 135.110728 -12.018772)
			(xy 135.108841 -12.002901) (xy 135.106806 -11.971) (xy 135.106664 -11.955018) (xy 135.107173 -11.924288)
			(xy 135.114579 -11.863277) (xy 135.129285 -11.803604) (xy 135.151076 -11.746137) (xy 135.179635 -11.691717)
			(xy 135.214546 -11.641136) (xy 135.255299 -11.595131) (xy 135.301299 -11.554374) (xy 135.351878 -11.519459)
			(xy 135.406295 -11.490895) (xy 135.46376 -11.469098) (xy 135.523432 -11.454387) (xy 135.584443 -11.446976)
			(xy 135.615172 -11.44651) (xy 135.650127 -11.447105) (xy 135.71938 -11.456663) (xy 135.786671 -11.475617)
			(xy 135.850731 -11.503609) (xy 135.910354 -11.540112) (xy 135.937752 -11.561826) (xy 135.944707 -11.567047)
			(xy 135.961067 -11.572902) (xy 135.969756 -11.573256) (xy 136.124188 -11.573256) (xy 136.132872 -11.572883)
			(xy 136.149231 -11.567033) (xy 136.156192 -11.561826) (xy 136.183597 -11.540121) (xy 136.243221 -11.503621)
			(xy 136.30728 -11.475626) (xy 136.374567 -11.456664) (xy 136.443818 -11.447091) (xy 136.478772 -11.44651)
			(xy 136.509504 -11.446964) (xy 136.570521 -11.45437) (xy 136.6302 -11.469077) (xy 136.687671 -11.49087)
			(xy 136.742095 -11.519433) (xy 136.79268 -11.554347) (xy 136.838688 -11.595105) (xy 136.879446 -11.641112)
			(xy 136.914362 -11.691696) (xy 136.942926 -11.74612) (xy 136.96472 -11.803591) (xy 136.979428 -11.863269)
			(xy 136.986835 -11.924286) (xy 136.98728 -11.955018) (xy 136.98728 -11.955272) (xy 136.987105 -11.970298)
			(xy 136.985201 -12.000289) (xy 136.98347 -12.015216) (xy 136.983216 -12.018264) (xy 136.983216 -12.026138)
			(xy 136.983331 -12.031989) (xy 136.985898 -12.043405) (xy 136.988296 -12.048744) (xy 136.991344 -12.053824)
			(xy 137.031984 -12.116308) (xy 137.045954 -12.126976) (xy 137.054844 -12.129516) (xy 137.080721 -12.137745)
			(xy 137.130021 -12.160503) (xy 137.175595 -12.190024) (xy 137.216521 -12.225709) (xy 137.232968 -12.244789)
			(xy 138.838934 -12.244789) (xy 138.838934 -12.180867) (xy 138.846945 -12.117449) (xy 138.862842 -12.055535)
			(xy 138.886374 -11.996102) (xy 138.917168 -11.940087) (xy 138.954741 -11.888372) (xy 138.998498 -11.841775)
			(xy 139.047751 -11.80103) (xy 139.101722 -11.766779) (xy 139.159561 -11.739562) (xy 139.220354 -11.719809)
			(xy 139.283144 -11.707831) (xy 139.34694 -11.703818) (xy 139.410736 -11.707831) (xy 139.473526 -11.719809)
			(xy 139.534319 -11.739562) (xy 139.592158 -11.766779) (xy 139.646129 -11.80103) (xy 139.695382 -11.841775)
			(xy 139.739139 -11.888372) (xy 139.776712 -11.940087) (xy 139.807506 -11.996102) (xy 139.831038 -12.055535)
			(xy 139.846935 -12.117449) (xy 139.854946 -12.180867) (xy 139.855448 -12.212828) (xy 139.854946 -12.244789)
			(xy 139.846935 -12.308207) (xy 139.831038 -12.370121) (xy 139.816884 -12.405868) (xy 140.118846 -12.405868)
			(xy 140.119313 -12.373705) (xy 140.127406 -12.309889) (xy 140.143486 -12.247605) (xy 140.167294 -12.187847)
			(xy 140.198451 -12.13157) (xy 140.236458 -12.079672) (xy 140.280709 -12.032984) (xy 140.330496 -11.992251)
			(xy 140.385023 -11.958125) (xy 140.44342 -11.931149) (xy 140.473938 -11.920982) (xy 140.474192 -11.920982)
			(xy 140.484992 -11.916969) (xy 140.501655 -11.901091) (xy 140.506196 -11.890502) (xy 140.538454 -11.805158)
			(xy 140.536422 -11.78179) (xy 140.530326 -11.771884) (xy 140.513042 -11.74205) (xy 140.485777 -11.678722)
			(xy 140.467318 -11.612291) (xy 140.458003 -11.543976) (xy 140.457428 -11.509502) (xy 140.457428 -11.509248)
			(xy 140.457856 -11.478351) (xy 140.465361 -11.417015) (xy 140.480242 -11.357039) (xy 140.50228 -11.299309)
			(xy 140.53115 -11.244674) (xy 140.566426 -11.193939) (xy 140.60759 -11.147852) (xy 140.654035 -11.107091)
			(xy 140.705075 -11.072258) (xy 140.75996 -11.043866) (xy 140.81788 -11.022332) (xy 140.847826 -11.01471)
			(xy 140.853928 -11.013039) (xy 140.865108 -11.007128) (xy 140.869924 -11.003026) (xy 140.874384 -10.998721)
			(xy 140.881322 -10.988454) (xy 140.88364 -10.982706) (xy 140.91285 -10.90295) (xy 140.91285 -10.902696)
			(xy 140.91654 -10.890554) (xy 140.912801 -10.865487) (xy 140.905738 -10.854944) (xy 140.88663 -10.828485)
			(xy 140.854584 -10.771629) (xy 140.830076 -10.71114) (xy 140.813507 -10.648013) (xy 140.805151 -10.583285)
			(xy 140.804646 -10.550652) (xy 140.805148 -10.518691) (xy 140.813159 -10.455273) (xy 140.829056 -10.393359)
			(xy 140.852588 -10.333926) (xy 140.883382 -10.277911) (xy 140.920955 -10.226196) (xy 140.964712 -10.179599)
			(xy 141.013965 -10.138854) (xy 141.067936 -10.104603) (xy 141.125775 -10.077386) (xy 141.186568 -10.057633)
			(xy 141.249358 -10.045655) (xy 141.313154 -10.041642) (xy 141.37695 -10.045655) (xy 141.43974 -10.057633)
			(xy 141.500533 -10.077386) (xy 141.558372 -10.104603) (xy 141.612343 -10.138854) (xy 141.661596 -10.179599)
			(xy 141.705353 -10.226196) (xy 141.742926 -10.277911) (xy 141.77372 -10.333926) (xy 141.797252 -10.393359)
			(xy 141.812323 -10.452057) (xy 142.169128 -10.452057) (xy 142.169128 -10.388135) (xy 142.177139 -10.324717)
			(xy 142.193036 -10.262803) (xy 142.216568 -10.20337) (xy 142.247362 -10.147355) (xy 142.284935 -10.09564)
			(xy 142.328692 -10.049043) (xy 142.377945 -10.008298) (xy 142.431916 -9.974047) (xy 142.489755 -9.94683)
			(xy 142.550548 -9.927077) (xy 142.613338 -9.915099) (xy 142.677134 -9.911086) (xy 142.74093 -9.915099)
			(xy 142.80372 -9.927077) (xy 142.864513 -9.94683) (xy 142.922352 -9.974047) (xy 142.976323 -10.008298)
			(xy 143.025576 -10.049043) (xy 143.069333 -10.09564) (xy 143.106906 -10.147355) (xy 143.1377 -10.20337)
			(xy 143.161232 -10.262803) (xy 143.177129 -10.324717) (xy 143.18514 -10.388135) (xy 143.185642 -10.420096)
			(xy 143.18514 -10.452057) (xy 143.181643 -10.479743) (xy 143.451828 -10.479743) (xy 143.451828 -10.415821)
			(xy 143.459839 -10.352403) (xy 143.475736 -10.290489) (xy 143.499268 -10.231056) (xy 143.530062 -10.175041)
			(xy 143.567635 -10.123326) (xy 143.611392 -10.076729) (xy 143.660645 -10.035984) (xy 143.714616 -10.001733)
			(xy 143.772455 -9.974516) (xy 143.833248 -9.954763) (xy 143.896038 -9.942785) (xy 143.959834 -9.938772)
			(xy 144.02363 -9.942785) (xy 144.08642 -9.954763) (xy 144.147213 -9.974516) (xy 144.205052 -10.001733)
			(xy 144.259023 -10.035984) (xy 144.308276 -10.076729) (xy 144.352033 -10.123326) (xy 144.389606 -10.175041)
			(xy 144.4204 -10.231056) (xy 144.443932 -10.290489) (xy 144.459829 -10.352403) (xy 144.46784 -10.415821)
			(xy 144.468342 -10.447782) (xy 144.46784 -10.479743) (xy 144.459829 -10.543161) (xy 144.443932 -10.605075)
			(xy 144.4204 -10.664508) (xy 144.389606 -10.720523) (xy 144.352033 -10.772238) (xy 144.308276 -10.818835)
			(xy 144.259023 -10.85958) (xy 144.205052 -10.893831) (xy 144.147213 -10.921048) (xy 144.11471 -10.931609)
			(xy 145.082508 -10.931609) (xy 145.082508 -10.867687) (xy 145.090519 -10.804269) (xy 145.106416 -10.742355)
			(xy 145.129948 -10.682922) (xy 145.160742 -10.626907) (xy 145.198315 -10.575192) (xy 145.242072 -10.528595)
			(xy 145.291325 -10.48785) (xy 145.345296 -10.453599) (xy 145.403135 -10.426382) (xy 145.463928 -10.406629)
			(xy 145.526718 -10.394651) (xy 145.590514 -10.390638) (xy 145.65431 -10.394651) (xy 145.7171 -10.406629)
			(xy 145.777893 -10.426382) (xy 145.835732 -10.453599) (xy 145.889703 -10.48785) (xy 145.938956 -10.528595)
			(xy 145.982713 -10.575192) (xy 146.020286 -10.626907) (xy 146.05108 -10.682922) (xy 146.074612 -10.742355)
			(xy 146.090509 -10.804269) (xy 146.092766 -10.822135) (xy 151.71013 -10.822135) (xy 151.71013 -10.758213)
			(xy 151.718141 -10.694795) (xy 151.734038 -10.632881) (xy 151.75757 -10.573448) (xy 151.788364 -10.517433)
			(xy 151.825937 -10.465718) (xy 151.869694 -10.419121) (xy 151.918947 -10.378376) (xy 151.972918 -10.344125)
			(xy 152.030757 -10.316908) (xy 152.09155 -10.297155) (xy 152.15434 -10.285177) (xy 152.218136 -10.281164)
			(xy 152.281932 -10.285177) (xy 152.344722 -10.297155) (xy 152.405515 -10.316908) (xy 152.463354 -10.344125)
			(xy 152.517325 -10.378376) (xy 152.566578 -10.419121) (xy 152.610335 -10.465718) (xy 152.647908 -10.517433)
			(xy 152.678702 -10.573448) (xy 152.702234 -10.632881) (xy 152.718131 -10.694795) (xy 152.726142 -10.758213)
			(xy 152.726644 -10.790174) (xy 152.726142 -10.822135) (xy 152.718131 -10.885553) (xy 152.702234 -10.947467)
			(xy 152.678702 -11.0069) (xy 152.647908 -11.062915) (xy 152.610335 -11.11463) (xy 152.566578 -11.161227)
			(xy 152.517325 -11.201972) (xy 152.463354 -11.236223) (xy 152.405515 -11.26344) (xy 152.344722 -11.283193)
			(xy 152.281932 -11.295171) (xy 152.218136 -11.299185) (xy 152.15434 -11.295171) (xy 152.09155 -11.283193)
			(xy 152.030757 -11.26344) (xy 151.972918 -11.236223) (xy 151.918947 -11.201972) (xy 151.869694 -11.161227)
			(xy 151.825937 -11.11463) (xy 151.788364 -11.062915) (xy 151.75757 -11.0069) (xy 151.734038 -10.947467)
			(xy 151.718141 -10.885553) (xy 151.71013 -10.822135) (xy 146.092766 -10.822135) (xy 146.09852 -10.867687)
			(xy 146.099022 -10.899648) (xy 146.09852 -10.931609) (xy 146.090509 -10.995027) (xy 146.074612 -11.056941)
			(xy 146.05108 -11.116374) (xy 146.020286 -11.172389) (xy 145.982713 -11.224104) (xy 145.938956 -11.270701)
			(xy 145.889703 -11.311446) (xy 145.835732 -11.345697) (xy 145.777893 -11.372914) (xy 145.7171 -11.392667)
			(xy 145.65431 -11.404645) (xy 145.590514 -11.408659) (xy 145.526718 -11.404645) (xy 145.463928 -11.392667)
			(xy 145.403135 -11.372914) (xy 145.345296 -11.345697) (xy 145.291325 -11.311446) (xy 145.242072 -11.270701)
			(xy 145.198315 -11.224104) (xy 145.160742 -11.172389) (xy 145.129948 -11.116374) (xy 145.106416 -11.056941)
			(xy 145.090519 -10.995027) (xy 145.082508 -10.931609) (xy 144.11471 -10.931609) (xy 144.08642 -10.940801)
			(xy 144.02363 -10.952779) (xy 143.959834 -10.956793) (xy 143.896038 -10.952779) (xy 143.833248 -10.940801)
			(xy 143.772455 -10.921048) (xy 143.714616 -10.893831) (xy 143.660645 -10.85958) (xy 143.611392 -10.818835)
			(xy 143.567635 -10.772238) (xy 143.530062 -10.720523) (xy 143.499268 -10.664508) (xy 143.475736 -10.605075)
			(xy 143.459839 -10.543161) (xy 143.451828 -10.479743) (xy 143.181643 -10.479743) (xy 143.177129 -10.515475)
			(xy 143.161232 -10.577389) (xy 143.1377 -10.636822) (xy 143.106906 -10.692837) (xy 143.069333 -10.744552)
			(xy 143.025576 -10.791149) (xy 142.976323 -10.831894) (xy 142.922352 -10.866145) (xy 142.864513 -10.893362)
			(xy 142.80372 -10.913115) (xy 142.74093 -10.925093) (xy 142.677134 -10.929107) (xy 142.613338 -10.925093)
			(xy 142.550548 -10.913115) (xy 142.489755 -10.893362) (xy 142.431916 -10.866145) (xy 142.377945 -10.831894)
			(xy 142.328692 -10.791149) (xy 142.284935 -10.744552) (xy 142.247362 -10.692837) (xy 142.216568 -10.636822)
			(xy 142.193036 -10.577389) (xy 142.177139 -10.515475) (xy 142.169128 -10.452057) (xy 141.812323 -10.452057)
			(xy 141.813149 -10.455273) (xy 141.82116 -10.518691) (xy 141.821662 -10.550652) (xy 141.821242 -10.581549)
			(xy 141.813737 -10.642886) (xy 141.798855 -10.702862) (xy 141.776817 -10.760593) (xy 141.747946 -10.815229)
			(xy 141.712669 -10.865964) (xy 141.671504 -10.912051) (xy 141.625059 -10.952811) (xy 141.574017 -10.987644)
			(xy 141.519131 -11.016036) (xy 141.46121 -11.037569) (xy 141.431264 -11.04519) (xy 141.425161 -11.046858)
			(xy 141.413981 -11.052771) (xy 141.409166 -11.056874) (xy 141.404705 -11.061178) (xy 141.397768 -11.071445)
			(xy 141.39545 -11.077194) (xy 141.36624 -11.15695) (xy 141.36624 -11.157204) (xy 141.362552 -11.169346)
			(xy 141.36629 -11.194412) (xy 141.373352 -11.204956) (xy 141.392459 -11.231415) (xy 141.424505 -11.288271)
			(xy 141.449014 -11.34876) (xy 141.465583 -11.411887) (xy 141.473939 -11.476615) (xy 141.474444 -11.509248)
			(xy 141.473929 -11.541409) (xy 141.465835 -11.60522) (xy 141.449757 -11.6675) (xy 141.425952 -11.727255)
			(xy 141.3948 -11.78353) (xy 141.356798 -11.835426) (xy 141.312555 -11.882115) (xy 141.262775 -11.92285)
			(xy 141.208256 -11.956981) (xy 141.149866 -11.983963) (xy 141.119352 -11.994134) (xy 141.119098 -11.994134)
			(xy 141.108293 -11.998136) (xy 141.091632 -12.014022) (xy 141.087094 -12.024614) (xy 141.054836 -12.109958)
			(xy 141.056868 -12.133326) (xy 141.062964 -12.143232) (xy 141.080253 -12.173063) (xy 141.107517 -12.236392)
			(xy 141.125975 -12.302824) (xy 141.12604 -12.3033) (xy 142.323041 -12.3033) (xy 142.327055 -12.2395)
			(xy 142.339033 -12.176706) (xy 142.358787 -12.115909) (xy 142.386004 -12.058066) (xy 142.420256 -12.004091)
			(xy 142.461003 -11.954834) (xy 142.507602 -11.911073) (xy 142.559318 -11.873496) (xy 142.615336 -11.842698)
			(xy 142.674772 -11.819163) (xy 142.736689 -11.803262) (xy 142.800111 -11.795247) (xy 142.832074 -11.794744)
			(xy 142.832582 -11.794744) (xy 142.8658 -11.795305) (xy 142.931672 -11.803959) (xy 142.995857 -11.821109)
			(xy 143.057266 -11.846464) (xy 143.086328 -11.862562) (xy 143.093694 -11.86688) (xy 143.110204 -11.869928)
			(xy 143.164052 -11.862308) (xy 143.16837 -11.856974) (xy 143.161004 -11.805666) (xy 143.15694 -11.79195)
			(xy 143.154071 -11.786072) (xy 143.145838 -11.775912) (xy 143.140684 -11.771884) (xy 143.116881 -11.753731)
			(xy 143.074619 -11.711342) (xy 143.039494 -11.662874) (xy 143.012366 -11.609517) (xy 142.993901 -11.552579)
			(xy 142.984552 -11.493457) (xy 142.983966 -11.463528) (xy 142.984452 -11.436277) (xy 142.992208 -11.382329)
			(xy 143.007563 -11.330034) (xy 143.030205 -11.280457) (xy 143.059671 -11.234607) (xy 143.095362 -11.193416)
			(xy 143.136553 -11.157725) (xy 143.182403 -11.128259) (xy 143.23198 -11.105617) (xy 143.284275 -11.090262)
			(xy 143.338223 -11.082506) (xy 143.392725 -11.082506) (xy 143.446673 -11.090262) (xy 143.498968 -11.105617)
			(xy 143.548545 -11.128259) (xy 143.594395 -11.157725) (xy 143.635586 -11.193416) (xy 143.671277 -11.234607)
			(xy 143.700743 -11.280457) (xy 143.723385 -11.330034) (xy 143.73874 -11.382329) (xy 143.746496 -11.436277)
			(xy 143.746891 -11.458448) (xy 146.587716 -11.458448) (xy 146.591787 -11.402826) (xy 146.603913 -11.348389)
			(xy 146.623836 -11.296298) (xy 146.651132 -11.247663) (xy 146.685218 -11.20352) (xy 146.725367 -11.164811)
			(xy 146.770725 -11.13236) (xy 146.820325 -11.106859) (xy 146.873109 -11.088852) (xy 146.927952 -11.078722)
			(xy 146.983686 -11.076685) (xy 147.039123 -11.082785) (xy 147.09308 -11.096891) (xy 147.144409 -11.118703)
			(xy 147.192015 -11.147757) (xy 147.234883 -11.183432) (xy 147.2721 -11.224969) (xy 147.302873 -11.271482)
			(xy 147.326545 -11.321979) (xy 147.342613 -11.375386) (xy 147.350733 -11.430562) (xy 147.351242 -11.458448)
			(xy 147.350733 -11.486334) (xy 147.342613 -11.54151) (xy 147.326545 -11.594917) (xy 147.302873 -11.645414)
			(xy 147.2721 -11.691927) (xy 147.234883 -11.733464) (xy 147.192015 -11.769139) (xy 147.18622 -11.772676)
			(xy 149.843445 -11.772676) (xy 149.846057 -11.709654) (xy 149.856444 -11.64744) (xy 149.874447 -11.586988)
			(xy 149.899789 -11.529227) (xy 149.932081 -11.475044) (xy 149.970827 -11.425271) (xy 150.015431 -11.380674)
			(xy 150.06521 -11.341936) (xy 150.119398 -11.309652) (xy 150.177163 -11.284319) (xy 150.237618 -11.266326)
			(xy 150.299834 -11.255949) (xy 150.362856 -11.253347) (xy 150.425716 -11.25856) (xy 150.487448 -11.271509)
			(xy 150.547105 -11.291994) (xy 150.60377 -11.3197) (xy 150.656572 -11.354203) (xy 150.698676 -11.389868)
			(xy 150.92121 -11.389868) (xy 150.925281 -11.334246) (xy 150.937407 -11.279809) (xy 150.95733 -11.227718)
			(xy 150.984626 -11.179083) (xy 151.018712 -11.13494) (xy 151.058861 -11.096231) (xy 151.104219 -11.06378)
			(xy 151.153819 -11.038279) (xy 151.206603 -11.020272) (xy 151.261446 -11.010142) (xy 151.31718 -11.008105)
			(xy 151.372617 -11.014205) (xy 151.426574 -11.028311) (xy 151.477903 -11.050123) (xy 151.525509 -11.079177)
			(xy 151.568377 -11.114852) (xy 151.605594 -11.156389) (xy 151.636367 -11.202902) (xy 151.660039 -11.253399)
			(xy 151.676107 -11.306806) (xy 151.684227 -11.361982) (xy 151.684736 -11.389868) (xy 151.684227 -11.417754)
			(xy 151.676107 -11.47293) (xy 151.660039 -11.526337) (xy 151.636367 -11.576834) (xy 151.605594 -11.623347)
			(xy 151.568377 -11.664884) (xy 151.525509 -11.700559) (xy 151.477903 -11.729613) (xy 151.426574 -11.751425)
			(xy 151.372617 -11.765531) (xy 151.31718 -11.771631) (xy 151.261446 -11.769594) (xy 151.206603 -11.759464)
			(xy 151.153819 -11.741457) (xy 151.104219 -11.715956) (xy 151.058861 -11.683505) (xy 151.018712 -11.644796)
			(xy 150.984626 -11.600653) (xy 150.95733 -11.552018) (xy 150.937407 -11.499927) (xy 150.925281 -11.44549)
			(xy 150.92121 -11.389868) (xy 150.698676 -11.389868) (xy 150.704701 -11.394972) (xy 150.747418 -11.441381)
			(xy 150.784066 -11.492718) (xy 150.814084 -11.548193) (xy 150.837008 -11.606956) (xy 150.852488 -11.668102)
			(xy 150.860286 -11.730694) (xy 150.86076 -11.762232) (xy 150.86076 -11.762994) (xy 150.860117 -11.799061)
			(xy 150.849885 -11.870466) (xy 150.829641 -11.939701) (xy 150.815294 -11.972798) (xy 150.810214 -11.983974)
			(xy 150.81123 -12.008358) (xy 150.857966 -12.0904) (xy 150.864575 -12.100579) (xy 150.884852 -12.113845)
			(xy 150.896828 -12.1158) (xy 150.924525 -12.119312) (xy 150.978561 -12.133345) (xy 151.029974 -12.155106)
			(xy 151.077665 -12.184129) (xy 151.120615 -12.219795) (xy 151.13507 -12.235899) (xy 151.372818 -12.235899)
			(xy 151.372818 -12.171977) (xy 151.380829 -12.108559) (xy 151.396726 -12.046645) (xy 151.420258 -11.987212)
			(xy 151.451052 -11.931197) (xy 151.488625 -11.879482) (xy 151.532382 -11.832885) (xy 151.581635 -11.79214)
			(xy 151.635606 -11.757889) (xy 151.693445 -11.730672) (xy 151.754238 -11.710919) (xy 151.817028 -11.698941)
			(xy 151.880824 -11.694928) (xy 151.94462 -11.698941) (xy 152.00741 -11.710919) (xy 152.068203 -11.730672)
			(xy 152.126042 -11.757889) (xy 152.180013 -11.79214) (xy 152.229266 -11.832885) (xy 152.273023 -11.879482)
			(xy 152.310596 -11.931197) (xy 152.34139 -11.987212) (xy 152.364922 -12.046645) (xy 152.380819 -12.108559)
			(xy 152.38883 -12.171977) (xy 152.389236 -12.197842) (xy 152.669748 -12.197842) (xy 152.670241 -12.165135)
			(xy 152.678624 -12.100262) (xy 152.695259 -12.036999) (xy 152.719869 -11.976391) (xy 152.752048 -11.919441)
			(xy 152.791265 -11.867087) (xy 152.836873 -11.820195) (xy 152.888118 -11.77954) (xy 152.915874 -11.762232)
			(xy 152.925834 -11.755454) (xy 152.938566 -11.735043) (xy 152.940258 -11.723116) (xy 152.947116 -11.641074)
			(xy 152.947517 -11.628952) (xy 152.938354 -11.606534) (xy 152.92959 -11.598148) (xy 152.909124 -11.579954)
			(xy 152.873119 -11.538694) (xy 152.843387 -11.492708) (xy 152.820537 -11.442943) (xy 152.805041 -11.390421)
			(xy 152.797217 -11.336222) (xy 152.796748 -11.308842) (xy 152.797317 -11.281594) (xy 152.805067 -11.227651)
			(xy 152.820414 -11.175361) (xy 152.843047 -11.125787) (xy 152.872505 -11.079938) (xy 152.908188 -11.038749)
			(xy 152.949369 -11.003057) (xy 152.995211 -10.973589) (xy 153.04478 -10.950944) (xy 153.097067 -10.935585)
			(xy 153.151008 -10.927823) (xy 153.178256 -10.927334) (xy 153.17851 -10.927334) (xy 153.203836 -10.927738)
			(xy 153.254043 -10.93444) (xy 153.302919 -10.947738) (xy 153.349601 -10.967397) (xy 153.393265 -10.99307)
			(xy 153.41346 -11.00836) (xy 153.423874 -11.016488) (xy 153.449528 -11.020806) (xy 153.543 -10.987024)
			(xy 153.551005 -10.983826) (xy 153.564393 -10.972986) (xy 153.573389 -10.958295) (xy 153.575512 -10.94994)
			(xy 153.575512 -10.949432) (xy 153.582555 -10.918807) (xy 153.603227 -10.859462) (xy 153.631056 -10.803118)
			(xy 153.665619 -10.750634) (xy 153.706387 -10.702811) (xy 153.752739 -10.660377) (xy 153.803968 -10.623981)
			(xy 153.859293 -10.594177) (xy 153.91787 -10.571419) (xy 153.978805 -10.556056) (xy 154.041169 -10.548321)
			(xy 154.07259 -10.547858) (xy 154.104551 -10.548406) (xy 154.167968 -10.556417) (xy 154.229881 -10.572312)
			(xy 154.289314 -10.595842) (xy 154.345329 -10.626636) (xy 154.397043 -10.664207) (xy 154.44364 -10.707964)
			(xy 154.484385 -10.757216) (xy 154.518636 -10.811186) (xy 154.542878 -10.862702) (xy 155.199548 -10.862702)
			(xy 155.202156 -10.799682) (xy 155.212539 -10.737469) (xy 155.230538 -10.677019) (xy 155.255875 -10.619258)
			(xy 155.288162 -10.565075) (xy 155.326902 -10.515302) (xy 155.371502 -10.470702) (xy 155.421275 -10.431962)
			(xy 155.475458 -10.399675) (xy 155.533219 -10.374338) (xy 155.593669 -10.356339) (xy 155.655882 -10.345956)
			(xy 155.718902 -10.343348) (xy 155.78176 -10.348554) (xy 155.843491 -10.361495) (xy 155.903148 -10.381972)
			(xy 155.959814 -10.409671) (xy 156.012618 -10.444166) (xy 156.060751 -10.484927) (xy 156.103472 -10.531328)
			(xy 156.140127 -10.582658) (xy 156.17015 -10.638127) (xy 156.193083 -10.696883) (xy 156.208572 -10.758025)
			(xy 156.216379 -10.820613) (xy 156.216858 -10.85215) (xy 156.216503 -10.878444) (xy 156.211035 -10.930747)
			(xy 156.205936 -10.956544) (xy 156.205936 -10.956798) (xy 156.204203 -10.968532) (xy 156.210274 -10.99143)
			(xy 156.21762 -11.00074) (xy 156.280104 -11.070844) (xy 156.302456 -11.079734) (xy 156.314394 -11.078718)
			(xy 156.359098 -11.076686) (xy 156.39312 -11.077251) (xy 156.460556 -11.08633) (xy 156.526182 -11.104312)
			(xy 156.557726 -11.117072) (xy 156.569664 -11.122152) (xy 156.594556 -11.119866) (xy 156.686504 -11.060176)
			(xy 156.698696 -11.038078) (xy 156.69895 -11.025378) (xy 156.699785 -10.99959) (xy 156.707597 -10.948587)
			(xy 156.722209 -10.899102) (xy 156.743356 -10.852036) (xy 156.770651 -10.80825) (xy 156.803597 -10.76854)
			(xy 156.841593 -10.733631) (xy 156.862526 -10.718546) (xy 156.872686 -10.711434) (xy 156.884116 -10.68959)
			(xy 156.884878 -10.58164) (xy 156.873448 -10.559542) (xy 156.863288 -10.55243) (xy 156.838872 -10.534491)
			(xy 156.794012 -10.493765) (xy 156.754309 -10.447998) (xy 156.720325 -10.397838) (xy 156.692542 -10.343995)
			(xy 156.671352 -10.287233) (xy 156.657056 -10.228355) (xy 156.649857 -10.168196) (xy 156.64942 -10.137902)
			(xy 156.649943 -10.105522) (xy 156.658177 -10.041288) (xy 156.674498 -9.978619) (xy 156.698643 -9.918529)
			(xy 156.730221 -9.86199) (xy 156.76872 -9.809918) (xy 156.813519 -9.763154) (xy 156.863892 -9.722455)
			(xy 156.919024 -9.688481) (xy 156.978023 -9.66178) (xy 157.039935 -9.642786) (xy 157.103756 -9.631804)
			(xy 157.136084 -9.629902) (xy 157.136338 -9.629902) (xy 157.148479 -9.628627) (xy 157.169579 -9.616431)
			(xy 157.176724 -9.606534) (xy 157.22854 -9.525762) (xy 157.230826 -9.501632) (xy 157.226 -9.489948)
			(xy 157.216996 -9.466974) (xy 157.204344 -9.419278) (xy 157.197953 -9.370348) (xy 157.197552 -9.345676)
			(xy 157.198038 -9.318425) (xy 157.205794 -9.264477) (xy 157.221149 -9.212182) (xy 157.243791 -9.162605)
			(xy 157.273257 -9.116755) (xy 157.308948 -9.075564) (xy 157.350139 -9.039873) (xy 157.395989 -9.010407)
			(xy 157.445566 -8.987765) (xy 157.497861 -8.97241) (xy 157.551809 -8.964654) (xy 157.606311 -8.964654)
			(xy 157.660259 -8.97241) (xy 157.712554 -8.987765) (xy 157.762131 -9.010407) (xy 157.807981 -9.039873)
			(xy 157.849172 -9.075564) (xy 157.884863 -9.116755) (xy 157.914329 -9.162605) (xy 157.936971 -9.212182)
			(xy 157.952326 -9.264477) (xy 157.960082 -9.318425) (xy 157.960568 -9.345676) (xy 157.960071 -9.374617)
			(xy 157.951303 -9.431832) (xy 157.933995 -9.487067) (xy 157.908545 -9.539054) (xy 157.875535 -9.586602)
			(xy 157.835723 -9.628619) (xy 157.790022 -9.664142) (xy 157.739481 -9.692356) (xy 157.685258 -9.712613)
			(xy 157.657038 -9.719056) (xy 157.656784 -9.719056) (xy 157.645019 -9.722353) (xy 157.626182 -9.737849)
			(xy 157.620716 -9.748774) (xy 157.58287 -9.836658) (xy 157.584648 -9.861042) (xy 157.591252 -9.87171)
			(xy 157.609093 -9.901864) (xy 157.637202 -9.966042) (xy 157.656241 -10.033469) (xy 157.665852 -10.10287)
			(xy 157.666436 -10.137902) (xy 157.666004 -10.169717) (xy 157.658065 -10.232849) (xy 157.642312 -10.294498)
			(xy 157.61899 -10.353699) (xy 157.588463 -10.409528) (xy 157.55121 -10.461112) (xy 157.507813 -10.507646)
			(xy 157.458948 -10.548401) (xy 157.43635 -10.562888) (xy 163.58583 -10.562888) (xy 163.58844 -10.499864)
			(xy 163.598826 -10.437647) (xy 163.616828 -10.377192) (xy 163.64217 -10.319428) (xy 163.674462 -10.265243)
			(xy 163.713209 -10.215468) (xy 163.757814 -10.170867) (xy 163.807594 -10.132127) (xy 163.861783 -10.099842)
			(xy 163.91955 -10.074507) (xy 163.980007 -10.056512) (xy 164.042225 -10.046134) (xy 164.10525 -10.043531)
			(xy 164.168112 -10.048744) (xy 164.229847 -10.061692) (xy 164.289506 -10.082177) (xy 164.346173 -10.109884)
			(xy 164.398978 -10.144388) (xy 164.447109 -10.185158) (xy 164.489828 -10.231568) (xy 164.526478 -10.282906)
			(xy 164.556497 -10.338384) (xy 164.579423 -10.397148) (xy 164.594904 -10.458297) (xy 164.602702 -10.520891)
			(xy 164.603176 -10.55243) (xy 164.602548 -10.588023) (xy 164.592598 -10.658512) (xy 164.583364 -10.692892)
			(xy 164.583364 -10.693146) (xy 164.580656 -10.705127) (xy 164.585581 -10.729153) (xy 164.592762 -10.73912)
			(xy 164.64534 -10.80389) (xy 164.653568 -10.812852) (xy 164.675847 -10.822536) (xy 164.688012 -10.822432)
			(xy 164.68852 -10.822432) (xy 164.715698 -10.821416) (xy 164.728245 -10.821526) (xy 164.753284 -10.823175)
			(xy 164.765736 -10.824718) (xy 164.76599 -10.824718) (xy 164.778616 -10.825696) (xy 164.802221 -10.816623)
			(xy 164.810948 -10.807446) (xy 164.874956 -10.73277) (xy 164.88029 -10.707878) (xy 164.876734 -10.695432)
			(xy 164.867149 -10.66046) (xy 164.856822 -10.588686) (xy 164.85616 -10.55243) (xy 164.856636 -10.520886)
			(xy 164.864436 -10.458283) (xy 164.87992 -10.397125) (xy 164.90285 -10.338352) (xy 164.932873 -10.282867)
			(xy 164.96953 -10.231522) (xy 165.012256 -10.185105) (xy 165.060395 -10.14433) (xy 165.113209 -10.109823)
			(xy 165.169885 -10.082113) (xy 165.229554 -10.061627) (xy 165.291298 -10.048679) (xy 165.35417 -10.043468)
			(xy 165.417204 -10.046074) (xy 165.479431 -10.056457) (xy 165.539896 -10.074458) (xy 165.59767 -10.099799)
			(xy 165.651865 -10.132093) (xy 165.70165 -10.170842) (xy 165.74626 -10.215451) (xy 165.785009 -10.265236)
			(xy 165.817302 -10.319432) (xy 165.842643 -10.377206) (xy 165.860643 -10.437671) (xy 165.871026 -10.499898)
			(xy 165.873632 -10.562932) (xy 165.86842 -10.625804) (xy 165.855472 -10.687548) (xy 165.834986 -10.747217)
			(xy 165.807276 -10.803893) (xy 165.772769 -10.856706) (xy 165.731993 -10.904846) (xy 165.685576 -10.947572)
			(xy 165.634231 -10.984228) (xy 165.578746 -11.014251) (xy 165.519973 -11.037181) (xy 165.458815 -11.052664)
			(xy 165.396212 -11.060464) (xy 165.364668 -11.060938) (xy 165.328682 -11.060365) (xy 165.257419 -11.050288)
			(xy 165.222682 -11.040872) (xy 165.21049 -11.037316) (xy 165.18509 -11.04265) (xy 165.10127 -11.11504)
			(xy 165.092126 -11.13917) (xy 165.093904 -11.15187) (xy 165.095487 -11.164573) (xy 165.097137 -11.190123)
			(xy 165.097206 -11.202924) (xy 165.09666 -11.230734) (xy 165.088594 -11.285766) (xy 165.07262 -11.339043)
			(xy 165.049079 -11.389435) (xy 165.018469 -11.435875) (xy 164.98144 -11.477376) (xy 164.938775 -11.51306)
			(xy 164.915342 -11.528044) (xy 164.904928 -11.534394) (xy 164.899334 -11.543792) (xy 165.75532 -11.543792)
			(xy 165.755822 -11.511831) (xy 165.763833 -11.448413) (xy 165.77973 -11.386499) (xy 165.803262 -11.327066)
			(xy 165.834056 -11.271051) (xy 165.871629 -11.219336) (xy 165.915386 -11.172739) (xy 165.964639 -11.131994)
			(xy 166.01861 -11.097743) (xy 166.076449 -11.070526) (xy 166.137242 -11.050773) (xy 166.200032 -11.038795)
			(xy 166.263828 -11.034782) (xy 166.327624 -11.038795) (xy 166.390414 -11.050773) (xy 166.451207 -11.070526)
			(xy 166.509046 -11.097743) (xy 166.563017 -11.131994) (xy 166.61227 -11.172739) (xy 166.656027 -11.219336)
			(xy 166.6936 -11.271051) (xy 166.724394 -11.327066) (xy 166.747926 -11.386499) (xy 166.763823 -11.448413)
			(xy 166.769903 -11.496548) (xy 169.478198 -11.496548) (xy 169.478721 -11.470022) (xy 169.486086 -11.417485)
			(xy 169.500652 -11.366472) (xy 169.522141 -11.317967) (xy 169.550137 -11.272904) (xy 169.584101 -11.23215)
			(xy 169.62338 -11.196491) (xy 169.667218 -11.166612) (xy 169.714769 -11.143089) (xy 169.765119 -11.126375)
			(xy 169.791126 -11.121136) (xy 169.802556 -11.119104) (xy 169.821098 -11.105642) (xy 169.869866 -11.015726)
			(xy 169.871136 -10.992866) (xy 169.866564 -10.982198) (xy 169.854105 -10.951025) (xy 169.836569 -10.886224)
			(xy 169.82773 -10.819676) (xy 169.827194 -10.78611) (xy 169.827194 -10.785856) (xy 169.827614 -10.755124)
			(xy 169.835028 -10.694109) (xy 169.849742 -10.634432) (xy 169.871541 -10.576963) (xy 169.900108 -10.522541)
			(xy 169.935026 -10.471959) (xy 169.975787 -10.425954) (xy 170.021795 -10.385198) (xy 170.07238 -10.350284)
			(xy 170.126805 -10.321722) (xy 170.184276 -10.299928) (xy 170.243954 -10.28522) (xy 170.30497 -10.277811)
			(xy 170.335702 -10.277348) (xy 170.370668 -10.277912) (xy 170.439939 -10.287515) (xy 170.507238 -10.306527)
			(xy 170.571295 -10.334586) (xy 170.630899 -10.371165) (xy 170.658282 -10.392918) (xy 170.665285 -10.398183)
			(xy 170.681785 -10.404032) (xy 170.69054 -10.404348) (xy 170.844464 -10.404348) (xy 170.853215 -10.404024)
			(xy 170.869706 -10.398161) (xy 170.876722 -10.392918) (xy 170.902096 -10.372716) (xy 170.957018 -10.338216)
			(xy 171.015879 -10.310973) (xy 171.046648 -10.300716) (xy 171.060364 -10.296398) (xy 171.079414 -10.2743)
			(xy 171.097194 -10.15492) (xy 171.08551 -10.12825) (xy 171.073318 -10.120122) (xy 171.048077 -10.102331)
			(xy 171.001702 -10.061549) (xy 170.960605 -10.015453) (xy 170.925391 -9.96472) (xy 170.896579 -9.910097)
			(xy 170.874592 -9.852387) (xy 170.859753 -9.792441) (xy 170.852281 -9.731138) (xy 170.85183 -9.70026)
			(xy 170.852218 -9.669527) (xy 170.859632 -9.608509) (xy 170.874346 -9.548829) (xy 170.896147 -9.491359)
			(xy 170.924717 -9.436935) (xy 170.959638 -9.386351) (xy 171.000401 -9.340346) (xy 171.046413 -9.299589)
			(xy 171.097001 -9.264676) (xy 171.15143 -9.236115) (xy 171.208904 -9.214323) (xy 171.268585 -9.199618)
			(xy 171.329605 -9.192213) (xy 171.360338 -9.191752) (xy 171.389205 -9.192156) (xy 171.446564 -9.198722)
			(xy 171.502813 -9.211731) (xy 171.55723 -9.231018) (xy 171.58335 -9.243314) (xy 171.59478 -9.248902)
			(xy 171.619418 -9.24814) (xy 171.71416 -9.1948) (xy 171.727876 -9.173464) (xy 171.728892 -9.161272)
			(xy 171.731956 -9.133197) (xy 171.745356 -9.078335) (xy 171.766695 -9.026047) (xy 171.795507 -8.977474)
			(xy 171.831162 -8.933678) (xy 171.872882 -8.895614) (xy 171.919756 -8.864115) (xy 171.97076 -8.839866)
			(xy 172.024781 -8.8234) (xy 172.080639 -8.815073) (xy 172.108876 -8.814562) (xy 172.136125 -8.8151)
			(xy 172.190069 -8.822853) (xy 172.242361 -8.838204) (xy 172.291936 -8.86084) (xy 172.337785 -8.890301)
			(xy 172.378975 -8.925987) (xy 172.414667 -8.967171) (xy 172.444134 -9.013016) (xy 172.466778 -9.062588)
			(xy 172.482136 -9.114878) (xy 172.489896 -9.168821) (xy 172.490384 -9.19607) (xy 172.490384 -9.198102)
			(xy 172.490722 -9.207419) (xy 172.49721 -9.22488) (xy 172.50951 -9.238868) (xy 172.517562 -9.243568)
			(xy 172.610018 -9.292336) (xy 172.637958 -9.290558) (xy 172.649896 -9.282176) (xy 172.675493 -9.265016)
			(xy 172.730033 -9.236325) (xy 172.787639 -9.21443) (xy 172.847468 -9.199651) (xy 172.908643 -9.192204)
			(xy 172.939456 -9.191752) (xy 172.971001 -9.192221) (xy 173.033607 -9.20002) (xy 173.094767 -9.215503)
			(xy 173.153543 -9.238432) (xy 173.209031 -9.268455) (xy 173.260378 -9.305112) (xy 173.306798 -9.347839)
			(xy 173.347575 -9.395979) (xy 173.382085 -9.448794) (xy 173.409796 -9.505472) (xy 173.430284 -9.565142)
			(xy 173.443233 -9.626889) (xy 173.444806 -9.645861) (xy 174.202084 -9.645861) (xy 174.202084 -9.581939)
			(xy 174.210095 -9.518521) (xy 174.225992 -9.456607) (xy 174.249524 -9.397174) (xy 174.280318 -9.341159)
			(xy 174.317891 -9.289444) (xy 174.361648 -9.242847) (xy 174.410901 -9.202102) (xy 174.464872 -9.167851)
			(xy 174.522711 -9.140634) (xy 174.583504 -9.120881) (xy 174.646294 -9.108903) (xy 174.71009 -9.10489)
			(xy 174.773886 -9.108903) (xy 174.836676 -9.120881) (xy 174.897469 -9.140634) (xy 174.955308 -9.167851)
			(xy 175.009279 -9.202102) (xy 175.058532 -9.242847) (xy 175.102289 -9.289444) (xy 175.139862 -9.341159)
			(xy 175.170656 -9.397174) (xy 175.194188 -9.456607) (xy 175.210085 -9.518521) (xy 175.218096 -9.581939)
			(xy 175.218598 -9.6139) (xy 175.218096 -9.645861) (xy 175.210085 -9.709279) (xy 175.194188 -9.771193)
			(xy 175.170656 -9.830626) (xy 175.139862 -9.886641) (xy 175.102289 -9.938356) (xy 175.058532 -9.984953)
			(xy 175.009279 -10.025698) (xy 174.955308 -10.059949) (xy 174.897469 -10.087166) (xy 174.836676 -10.106919)
			(xy 174.773886 -10.118897) (xy 174.71009 -10.122911) (xy 174.646294 -10.118897) (xy 174.583504 -10.106919)
			(xy 174.522711 -10.087166) (xy 174.464872 -10.059949) (xy 174.410901 -10.025698) (xy 174.361648 -9.984953)
			(xy 174.317891 -9.938356) (xy 174.280318 -9.886641) (xy 174.249524 -9.830626) (xy 174.225992 -9.771193)
			(xy 174.210095 -9.709279) (xy 174.202084 -9.645861) (xy 173.444806 -9.645861) (xy 173.448445 -9.689763)
			(xy 173.44584 -9.752799) (xy 173.435458 -9.815028) (xy 173.417457 -9.875496) (xy 173.392115 -9.933272)
			(xy 173.359821 -9.98747) (xy 173.321071 -10.037257) (xy 173.27646 -10.081868) (xy 173.226673 -10.120619)
			(xy 173.172476 -10.152913) (xy 173.1147 -10.178256) (xy 173.054232 -10.196257) (xy 172.992003 -10.20664)
			(xy 172.928967 -10.209246) (xy 172.866093 -10.204034) (xy 172.804346 -10.191085) (xy 172.744676 -10.170598)
			(xy 172.687998 -10.142887) (xy 172.635182 -10.108378) (xy 172.587042 -10.0676) (xy 172.544315 -10.021182)
			(xy 172.507658 -9.969834) (xy 172.477634 -9.914346) (xy 172.454704 -9.855571) (xy 172.43922 -9.794411)
			(xy 172.431421 -9.731805) (xy 172.430948 -9.70026) (xy 172.431077 -9.684214) (xy 172.433109 -9.652186)
			(xy 172.435012 -9.636252) (xy 172.435012 -9.635998) (xy 172.435789 -9.626761) (xy 172.431397 -9.608768)
			(xy 172.420844 -9.593547) (xy 172.413422 -9.587992) (xy 172.32757 -9.528556) (xy 172.29963 -9.527032)
			(xy 172.28693 -9.533636) (xy 172.259323 -9.547501) (xy 172.200738 -9.567094) (xy 172.139764 -9.577002)
			(xy 172.108876 -9.577578) (xy 172.08084 -9.57712) (xy 172.025368 -9.568952) (xy 171.998386 -9.561322)
			(xy 171.986448 -9.557766) (xy 171.96181 -9.562338) (xy 171.886626 -9.622282) (xy 171.877318 -9.630453)
			(xy 171.867323 -9.653081) (xy 171.867576 -9.665462) (xy 171.868846 -9.70026) (xy 171.86842 -9.732465)
			(xy 171.860303 -9.796362) (xy 171.844179 -9.858721) (xy 171.820309 -9.918545) (xy 171.789073 -9.974874)
			(xy 171.750973 -10.026808) (xy 171.706619 -10.073513) (xy 171.656721 -10.114241) (xy 171.602078 -10.148341)
			(xy 171.543565 -10.175267) (xy 171.512992 -10.1854) (xy 171.499276 -10.189718) (xy 171.480226 -10.211816)
			(xy 171.462446 -10.331196) (xy 171.47413 -10.357866) (xy 171.486322 -10.365994) (xy 171.511557 -10.383794)
			(xy 171.557935 -10.424573) (xy 171.599033 -10.470667) (xy 171.634249 -10.521398) (xy 171.663062 -10.57602)
			(xy 171.684277 -10.6317) (xy 173.382167 -10.6317) (xy 173.386181 -10.567902) (xy 173.398159 -10.50511)
			(xy 173.417913 -10.444314) (xy 173.44513 -10.386473) (xy 173.479383 -10.3325) (xy 173.520129 -10.283245)
			(xy 173.566728 -10.239486) (xy 173.618444 -10.201912) (xy 173.674461 -10.171115) (xy 173.733896 -10.147583)
			(xy 173.795812 -10.131685) (xy 173.859232 -10.123672) (xy 173.891194 -10.12317) (xy 173.924039 -10.123684)
			(xy 173.989185 -10.132119) (xy 174.052703 -10.148873) (xy 174.113533 -10.173669) (xy 174.170663 -10.206094)
			(xy 174.223141 -10.245606) (xy 174.270093 -10.291548) (xy 174.310736 -10.343155) (xy 174.344395 -10.399567)
			(xy 174.370507 -10.459844) (xy 174.388638 -10.522982) (xy 174.398486 -10.58793) (xy 174.399702 -10.620756)
			(xy 174.399702 -10.630154) (xy 174.406814 -10.64768) (xy 174.466504 -10.71118) (xy 174.483268 -10.719054)
			(xy 174.492666 -10.719816) (xy 174.520925 -10.722699) (xy 174.576209 -10.735737) (xy 174.628949 -10.756826)
			(xy 174.677981 -10.7855) (xy 174.72222 -10.821126) (xy 174.76069 -10.862916) (xy 174.792539 -10.909947)
			(xy 174.817065 -10.961179) (xy 174.833726 -11.015482) (xy 174.842153 -11.071654) (xy 174.842678 -11.100054)
			(xy 174.842678 -11.100562) (xy 174.842097 -11.129579) (xy 174.833259 -11.186936) (xy 174.815842 -11.242294)
			(xy 174.790246 -11.294379) (xy 174.774098 -11.318494) (xy 174.767748 -11.327638) (xy 174.763684 -11.349228)
			(xy 174.785528 -11.434826) (xy 174.788809 -11.445278) (xy 174.802634 -11.462248) (xy 174.812198 -11.467592)
			(xy 174.840039 -11.481985) (xy 174.892303 -11.516579) (xy 174.939915 -11.557337) (xy 174.982155 -11.603641)
			(xy 175.01838 -11.654787) (xy 175.048042 -11.709999) (xy 175.070689 -11.76844) (xy 175.085979 -11.829222)
			(xy 175.093678 -11.891422) (xy 175.094138 -11.92276) (xy 175.09364 -11.954467) (xy 175.359054 -11.954467)
			(xy 175.359054 -11.890545) (xy 175.367065 -11.827127) (xy 175.382962 -11.765213) (xy 175.406494 -11.70578)
			(xy 175.437288 -11.649765) (xy 175.474861 -11.59805) (xy 175.518618 -11.551453) (xy 175.567871 -11.510708)
			(xy 175.621842 -11.476457) (xy 175.679681 -11.44924) (xy 175.740474 -11.429487) (xy 175.803264 -11.417509)
			(xy 175.86706 -11.413496) (xy 175.930856 -11.417509) (xy 175.993646 -11.429487) (xy 176.054439 -11.44924)
			(xy 176.074007 -11.458448) (xy 177.885088 -11.458448) (xy 177.889159 -11.402826) (xy 177.901285 -11.348389)
			(xy 177.921208 -11.296298) (xy 177.948504 -11.247663) (xy 177.98259 -11.20352) (xy 178.022739 -11.164811)
			(xy 178.068097 -11.13236) (xy 178.117697 -11.106859) (xy 178.170481 -11.088852) (xy 178.225324 -11.078722)
			(xy 178.281058 -11.076685) (xy 178.336495 -11.082785) (xy 178.390452 -11.096891) (xy 178.441781 -11.118703)
			(xy 178.489387 -11.147757) (xy 178.532255 -11.183432) (xy 178.569472 -11.224969) (xy 178.600245 -11.271482)
			(xy 178.623917 -11.321979) (xy 178.639985 -11.375386) (xy 178.648105 -11.430562) (xy 178.648614 -11.458448)
			(xy 178.648105 -11.486334) (xy 178.639985 -11.54151) (xy 178.623917 -11.594917) (xy 178.600245 -11.645414)
			(xy 178.569472 -11.691927) (xy 178.532255 -11.733464) (xy 178.489387 -11.769139) (xy 178.441781 -11.798193)
			(xy 178.390452 -11.820005) (xy 178.336495 -11.834111) (xy 178.281058 -11.840211) (xy 178.225324 -11.838174)
			(xy 178.170481 -11.828044) (xy 178.117697 -11.810037) (xy 178.068097 -11.784536) (xy 178.022739 -11.752085)
			(xy 177.98259 -11.713376) (xy 177.948504 -11.669233) (xy 177.921208 -11.620598) (xy 177.901285 -11.568507)
			(xy 177.889159 -11.51407) (xy 177.885088 -11.458448) (xy 176.074007 -11.458448) (xy 176.112278 -11.476457)
			(xy 176.166249 -11.510708) (xy 176.215502 -11.551453) (xy 176.259259 -11.59805) (xy 176.296832 -11.649765)
			(xy 176.327626 -11.70578) (xy 176.351158 -11.765213) (xy 176.367055 -11.827127) (xy 176.375066 -11.890545)
			(xy 176.375568 -11.922506) (xy 176.375066 -11.954467) (xy 176.368874 -12.003489) (xy 176.702206 -12.003489)
			(xy 176.702206 -11.939567) (xy 176.710217 -11.876149) (xy 176.726114 -11.814235) (xy 176.749646 -11.754802)
			(xy 176.78044 -11.698787) (xy 176.818013 -11.647072) (xy 176.86177 -11.600475) (xy 176.911023 -11.55973)
			(xy 176.964994 -11.525479) (xy 177.022833 -11.498262) (xy 177.083626 -11.478509) (xy 177.146416 -11.466531)
			(xy 177.210212 -11.462518) (xy 177.274008 -11.466531) (xy 177.336798 -11.478509) (xy 177.397591 -11.498262)
			(xy 177.45543 -11.525479) (xy 177.509401 -11.55973) (xy 177.558654 -11.600475) (xy 177.602411 -11.647072)
			(xy 177.639984 -11.698787) (xy 177.670778 -11.754802) (xy 177.69431 -11.814235) (xy 177.710207 -11.876149)
			(xy 177.718218 -11.939567) (xy 177.71872 -11.971528) (xy 177.718218 -12.003489) (xy 177.710207 -12.066907)
			(xy 177.69431 -12.128821) (xy 177.670778 -12.188254) (xy 177.649752 -12.226501) (xy 178.731158 -12.226501)
			(xy 178.731158 -12.162579) (xy 178.739169 -12.099161) (xy 178.755066 -12.037247) (xy 178.778598 -11.977814)
			(xy 178.809392 -11.921799) (xy 178.846965 -11.870084) (xy 178.890722 -11.823487) (xy 178.939975 -11.782742)
			(xy 178.993946 -11.748491) (xy 179.051785 -11.721274) (xy 179.112578 -11.701521) (xy 179.175368 -11.689543)
			(xy 179.239164 -11.68553) (xy 179.30296 -11.689543) (xy 179.36575 -11.701521) (xy 179.426543 -11.721274)
			(xy 179.484382 -11.748491) (xy 179.538353 -11.782742) (xy 179.587606 -11.823487) (xy 179.631363 -11.870084)
			(xy 179.668936 -11.921799) (xy 179.69973 -11.977814) (xy 179.723262 -12.037247) (xy 179.739159 -12.099161)
			(xy 179.74717 -12.162579) (xy 179.747672 -12.19454) (xy 179.74717 -12.226501) (xy 179.739159 -12.289919)
			(xy 179.723262 -12.351833) (xy 179.69973 -12.411266) (xy 179.668936 -12.467281) (xy 179.631363 -12.518996)
			(xy 179.587606 -12.565593) (xy 179.538353 -12.606338) (xy 179.484382 -12.640589) (xy 179.426543 -12.667806)
			(xy 179.36575 -12.687559) (xy 179.30296 -12.699537) (xy 179.239164 -12.703551) (xy 179.175368 -12.699537)
			(xy 179.112578 -12.687559) (xy 179.051785 -12.667806) (xy 178.993946 -12.640589) (xy 178.939975 -12.606338)
			(xy 178.890722 -12.565593) (xy 178.846965 -12.518996) (xy 178.809392 -12.467281) (xy 178.778598 -12.411266)
			(xy 178.755066 -12.351833) (xy 178.739169 -12.289919) (xy 178.731158 -12.226501) (xy 177.649752 -12.226501)
			(xy 177.639984 -12.244269) (xy 177.602411 -12.295984) (xy 177.558654 -12.342581) (xy 177.509401 -12.383326)
			(xy 177.45543 -12.417577) (xy 177.397591 -12.444794) (xy 177.336798 -12.464547) (xy 177.274008 -12.476525)
			(xy 177.210212 -12.480539) (xy 177.146416 -12.476525) (xy 177.083626 -12.464547) (xy 177.022833 -12.444794)
			(xy 176.964994 -12.417577) (xy 176.911023 -12.383326) (xy 176.86177 -12.342581) (xy 176.818013 -12.295984)
			(xy 176.78044 -12.244269) (xy 176.749646 -12.188254) (xy 176.726114 -12.128821) (xy 176.710217 -12.066907)
			(xy 176.702206 -12.003489) (xy 176.368874 -12.003489) (xy 176.367055 -12.017885) (xy 176.351158 -12.079799)
			(xy 176.327626 -12.139232) (xy 176.296832 -12.195247) (xy 176.259259 -12.246962) (xy 176.215502 -12.293559)
			(xy 176.166249 -12.334304) (xy 176.112278 -12.368555) (xy 176.054439 -12.395772) (xy 175.993646 -12.415525)
			(xy 175.930856 -12.427503) (xy 175.86706 -12.431517) (xy 175.803264 -12.427503) (xy 175.740474 -12.415525)
			(xy 175.679681 -12.395772) (xy 175.621842 -12.368555) (xy 175.567871 -12.334304) (xy 175.518618 -12.293559)
			(xy 175.474861 -12.246962) (xy 175.437288 -12.195247) (xy 175.406494 -12.139232) (xy 175.382962 -12.079799)
			(xy 175.367065 -12.017885) (xy 175.359054 -11.954467) (xy 175.09364 -11.954467) (xy 175.093636 -11.954721)
			(xy 175.085625 -12.018139) (xy 175.069728 -12.080053) (xy 175.046196 -12.139486) (xy 175.015402 -12.195501)
			(xy 174.977829 -12.247216) (xy 174.934072 -12.293813) (xy 174.884819 -12.334558) (xy 174.830848 -12.368809)
			(xy 174.773009 -12.396026) (xy 174.712216 -12.415779) (xy 174.649426 -12.427757) (xy 174.58563 -12.431771)
			(xy 174.521834 -12.427757) (xy 174.459044 -12.415779) (xy 174.398251 -12.396026) (xy 174.340412 -12.368809)
			(xy 174.286441 -12.334558) (xy 174.237188 -12.293813) (xy 174.193431 -12.247216) (xy 174.155858 -12.195501)
			(xy 174.125064 -12.139486) (xy 174.101532 -12.080053) (xy 174.085635 -12.018139) (xy 174.077624 -11.954721)
			(xy 174.077122 -11.92276) (xy 174.07768 -11.888459) (xy 174.086892 -11.820477) (xy 174.105157 -11.754351)
			(xy 174.132144 -11.691279) (xy 174.167364 -11.632407) (xy 174.210176 -11.578803) (xy 174.234602 -11.554714)
			(xy 174.24273 -11.54684) (xy 174.250858 -11.526774) (xy 174.246286 -11.438636) (xy 174.245239 -11.427823)
			(xy 174.235382 -11.408485) (xy 174.227236 -11.401298) (xy 174.226728 -11.401044) (xy 174.203318 -11.382095)
			(xy 174.162225 -11.338067) (xy 174.128567 -11.288124) (xy 174.103182 -11.23351) (xy 174.094394 -11.204702)
			(xy 174.091854 -11.195558) (xy 174.080678 -11.180572) (xy 174.014892 -11.139424) (xy 174.006787 -11.134868)
			(xy 173.988549 -11.131344) (xy 173.979332 -11.132566) (xy 173.979078 -11.132566) (xy 173.957347 -11.136135)
			(xy 173.913469 -11.139952) (xy 173.891448 -11.140186) (xy 173.891194 -11.140186) (xy 173.859232 -11.139728)
			(xy 173.795812 -11.131715) (xy 173.733896 -11.115817) (xy 173.674461 -11.092285) (xy 173.618444 -11.061488)
			(xy 173.566728 -11.023914) (xy 173.520129 -10.980155) (xy 173.479383 -10.9309) (xy 173.44513 -10.876927)
			(xy 173.417913 -10.819086) (xy 173.398159 -10.75829) (xy 173.386181 -10.695498) (xy 173.382167 -10.6317)
			(xy 171.684277 -10.6317) (xy 171.68505 -10.633729) (xy 171.699888 -10.693676) (xy 171.707359 -10.754978)
			(xy 171.70781 -10.785856) (xy 171.70781 -10.78611) (xy 171.707257 -10.819674) (xy 171.698401 -10.886217)
			(xy 171.680884 -10.951021) (xy 171.66844 -10.982198) (xy 171.663868 -10.992866) (xy 171.665138 -11.015726)
			(xy 171.713906 -11.105642) (xy 171.732448 -11.119104) (xy 171.743878 -11.121136) (xy 171.769896 -11.126349)
			(xy 171.820267 -11.143039) (xy 171.86784 -11.166547) (xy 171.911696 -11.196419) (xy 171.950991 -11.23208)
			(xy 171.984967 -11.27284) (xy 172.012967 -11.317915) (xy 172.034452 -11.366435) (xy 172.049008 -11.417463)
			(xy 172.056353 -11.470016) (xy 172.056806 -11.496548) (xy 172.05632 -11.523799) (xy 172.048564 -11.577747)
			(xy 172.033209 -11.630042) (xy 172.010567 -11.679619) (xy 171.981101 -11.725469) (xy 171.94541 -11.76666)
			(xy 171.904219 -11.802351) (xy 171.858369 -11.831817) (xy 171.808792 -11.854459) (xy 171.756497 -11.869814)
			(xy 171.702549 -11.87757) (xy 171.648047 -11.87757) (xy 171.594099 -11.869814) (xy 171.541804 -11.854459)
			(xy 171.492227 -11.831817) (xy 171.446377 -11.802351) (xy 171.405186 -11.76666) (xy 171.369495 -11.725469)
			(xy 171.340029 -11.679619) (xy 171.317387 -11.630042) (xy 171.302032 -11.577747) (xy 171.294276 -11.523799)
			(xy 171.29379 -11.496548) (xy 171.294039 -11.47652) (xy 171.298243 -11.436686) (xy 171.302172 -11.417046)
			(xy 171.304458 -11.40587) (xy 171.299124 -11.383518) (xy 171.234608 -11.304016) (xy 171.21378 -11.294364)
			(xy 171.199302 -11.294364) (xy 171.164336 -11.293795) (xy 171.095065 -11.284192) (xy 171.027766 -11.265182)
			(xy 170.963709 -11.237124) (xy 170.904105 -11.200546) (xy 170.876722 -11.178794) (xy 170.869717 -11.173532)
			(xy 170.853219 -11.16768) (xy 170.844464 -11.167364) (xy 170.69054 -11.167364) (xy 170.681791 -11.167708)
			(xy 170.665301 -11.173559) (xy 170.658282 -11.178794) (xy 170.630896 -11.200539) (xy 170.571282 -11.237092)
			(xy 170.507224 -11.265137) (xy 170.43993 -11.284147) (xy 170.370666 -11.293764) (xy 170.335702 -11.294364)
			(xy 170.321224 -11.294364) (xy 170.300396 -11.304016) (xy 170.23588 -11.383518) (xy 170.230546 -11.40587)
			(xy 170.232832 -11.417046) (xy 170.236766 -11.436685) (xy 170.240961 -11.47652) (xy 170.241214 -11.496548)
			(xy 170.240728 -11.523799) (xy 170.232972 -11.577747) (xy 170.217617 -11.630042) (xy 170.194975 -11.679619)
			(xy 170.165509 -11.725469) (xy 170.129818 -11.76666) (xy 170.088627 -11.802351) (xy 170.042777 -11.831817)
			(xy 169.9932 -11.854459) (xy 169.940905 -11.869814) (xy 169.886957 -11.87757) (xy 169.832455 -11.87757)
			(xy 169.778507 -11.869814) (xy 169.726212 -11.854459) (xy 169.676635 -11.831817) (xy 169.630785 -11.802351)
			(xy 169.589594 -11.76666) (xy 169.553903 -11.725469) (xy 169.524437 -11.679619) (xy 169.501795 -11.630042)
			(xy 169.48644 -11.577747) (xy 169.478684 -11.523799) (xy 169.478198 -11.496548) (xy 166.769903 -11.496548)
			(xy 166.771834 -11.511831) (xy 166.772336 -11.543792) (xy 166.771816 -11.575316) (xy 166.764012 -11.63788)
			(xy 166.748534 -11.699) (xy 166.72562 -11.757738) (xy 166.695621 -11.813193) (xy 166.658998 -11.864514)
			(xy 166.616312 -11.910915) (xy 166.599992 -11.924749) (xy 172.793908 -11.924749) (xy 172.793908 -11.860827)
			(xy 172.801919 -11.797409) (xy 172.817816 -11.735495) (xy 172.841348 -11.676062) (xy 172.872142 -11.620047)
			(xy 172.909715 -11.568332) (xy 172.953472 -11.521735) (xy 173.002725 -11.48099) (xy 173.056696 -11.446739)
			(xy 173.114535 -11.419522) (xy 173.175328 -11.399769) (xy 173.238118 -11.387791) (xy 173.301914 -11.383778)
			(xy 173.36571 -11.387791) (xy 173.4285 -11.399769) (xy 173.489293 -11.419522) (xy 173.547132 -11.446739)
			(xy 173.601103 -11.48099) (xy 173.650356 -11.521735) (xy 173.694113 -11.568332) (xy 173.731686 -11.620047)
			(xy 173.76248 -11.676062) (xy 173.786012 -11.735495) (xy 173.801909 -11.797409) (xy 173.80992 -11.860827)
			(xy 173.810422 -11.892788) (xy 173.80992 -11.924749) (xy 173.801909 -11.988167) (xy 173.786012 -12.050081)
			(xy 173.76248 -12.109514) (xy 173.731686 -12.165529) (xy 173.694113 -12.217244) (xy 173.650356 -12.263841)
			(xy 173.601103 -12.304586) (xy 173.547132 -12.338837) (xy 173.489293 -12.366054) (xy 173.4285 -12.385807)
			(xy 173.36571 -12.397785) (xy 173.301914 -12.401799) (xy 173.238118 -12.397785) (xy 173.175328 -12.385807)
			(xy 173.114535 -12.366054) (xy 173.056696 -12.338837) (xy 173.002725 -12.304586) (xy 172.953472 -12.263841)
			(xy 172.909715 -12.217244) (xy 172.872142 -12.165529) (xy 172.841348 -12.109514) (xy 172.817816 -12.050081)
			(xy 172.801919 -11.988167) (xy 172.793908 -11.924749) (xy 166.599992 -11.924749) (xy 166.568217 -11.951684)
			(xy 166.515453 -11.986196) (xy 166.487348 -12.000484) (xy 166.473861 -12.00772) (xy 166.451572 -12.028669)
			(xy 166.436484 -12.055277) (xy 166.429949 -12.085159) (xy 166.432553 -12.115637) (xy 166.444062 -12.143977)
			(xy 166.463444 -12.167641) (xy 166.475918 -12.176506) (xy 166.498123 -12.191748) (xy 166.538461 -12.227435)
			(xy 166.57338 -12.268438) (xy 166.602189 -12.313943) (xy 166.624315 -12.363046) (xy 166.639318 -12.414772)
			(xy 166.6469 -12.468093) (xy 166.647368 -12.495022) (xy 167.683686 -12.495022) (xy 167.687757 -12.4394)
			(xy 167.699883 -12.384963) (xy 167.719806 -12.332872) (xy 167.747102 -12.284237) (xy 167.781188 -12.240094)
			(xy 167.821337 -12.201385) (xy 167.866695 -12.168934) (xy 167.916295 -12.143433) (xy 167.969079 -12.125426)
			(xy 168.023922 -12.115296) (xy 168.079656 -12.113259) (xy 168.135093 -12.119359) (xy 168.18905 -12.133465)
			(xy 168.240379 -12.155277) (xy 168.287985 -12.184331) (xy 168.330853 -12.220006) (xy 168.36807 -12.261543)
			(xy 168.398843 -12.308056) (xy 168.422515 -12.358553) (xy 168.438583 -12.41196) (xy 168.446703 -12.467136)
			(xy 168.447212 -12.495022) (xy 169.483784 -12.495022) (xy 169.487855 -12.4394) (xy 169.499981 -12.384963)
			(xy 169.519904 -12.332872) (xy 169.5472 -12.284237) (xy 169.581286 -12.240094) (xy 169.621435 -12.201385)
			(xy 169.666793 -12.168934) (xy 169.716393 -12.143433) (xy 169.769177 -12.125426) (xy 169.82402 -12.115296)
			(xy 169.879754 -12.113259) (xy 169.935191 -12.119359) (xy 169.989148 -12.133465) (xy 170.040477 -12.155277)
			(xy 170.088083 -12.184331) (xy 170.130951 -12.220006) (xy 170.168168 -12.261543) (xy 170.198941 -12.308056)
			(xy 170.222613 -12.358553) (xy 170.238681 -12.41196) (xy 170.246801 -12.467136) (xy 170.24731 -12.495022)
			(xy 171.283628 -12.495022) (xy 171.287699 -12.4394) (xy 171.299825 -12.384963) (xy 171.319748 -12.332872)
			(xy 171.347044 -12.284237) (xy 171.38113 -12.240094) (xy 171.421279 -12.201385) (xy 171.466637 -12.168934)
			(xy 171.516237 -12.143433) (xy 171.569021 -12.125426) (xy 171.623864 -12.115296) (xy 171.679598 -12.113259)
			(xy 171.735035 -12.119359) (xy 171.788992 -12.133465) (xy 171.840321 -12.155277) (xy 171.887927 -12.184331)
			(xy 171.930795 -12.220006) (xy 171.968012 -12.261543) (xy 171.998785 -12.308056) (xy 172.022457 -12.358553)
			(xy 172.038525 -12.41196) (xy 172.046645 -12.467136) (xy 172.047154 -12.495022) (xy 172.046645 -12.522908)
			(xy 172.038525 -12.578084) (xy 172.022457 -12.631491) (xy 171.998785 -12.681988) (xy 171.968012 -12.728501)
			(xy 171.930795 -12.770038) (xy 171.887927 -12.805713) (xy 171.840321 -12.834767) (xy 171.788992 -12.856579)
			(xy 171.735035 -12.870685) (xy 171.679598 -12.876785) (xy 171.623864 -12.874748) (xy 171.569021 -12.864618)
			(xy 171.516237 -12.846611) (xy 171.466637 -12.82111) (xy 171.421279 -12.788659) (xy 171.38113 -12.74995)
			(xy 171.347044 -12.705807) (xy 171.319748 -12.657172) (xy 171.299825 -12.605081) (xy 171.287699 -12.550644)
			(xy 171.283628 -12.495022) (xy 170.24731 -12.495022) (xy 170.246801 -12.522908) (xy 170.238681 -12.578084)
			(xy 170.222613 -12.631491) (xy 170.198941 -12.681988) (xy 170.168168 -12.728501) (xy 170.130951 -12.770038)
			(xy 170.088083 -12.805713) (xy 170.040477 -12.834767) (xy 169.989148 -12.856579) (xy 169.935191 -12.870685)
			(xy 169.879754 -12.876785) (xy 169.82402 -12.874748) (xy 169.769177 -12.864618) (xy 169.716393 -12.846611)
			(xy 169.666793 -12.82111) (xy 169.621435 -12.788659) (xy 169.581286 -12.74995) (xy 169.5472 -12.705807)
			(xy 169.519904 -12.657172) (xy 169.499981 -12.605081) (xy 169.487855 -12.550644) (xy 169.483784 -12.495022)
			(xy 168.447212 -12.495022) (xy 168.446703 -12.522908) (xy 168.438583 -12.578084) (xy 168.422515 -12.631491)
			(xy 168.398843 -12.681988) (xy 168.36807 -12.728501) (xy 168.330853 -12.770038) (xy 168.287985 -12.805713)
			(xy 168.240379 -12.834767) (xy 168.18905 -12.856579) (xy 168.135093 -12.870685) (xy 168.079656 -12.876785)
			(xy 168.023922 -12.874748) (xy 167.969079 -12.864618) (xy 167.916295 -12.846611) (xy 167.866695 -12.82111)
			(xy 167.821337 -12.788659) (xy 167.781188 -12.74995) (xy 167.747102 -12.705807) (xy 167.719806 -12.657172)
			(xy 167.699883 -12.605081) (xy 167.687757 -12.550644) (xy 167.683686 -12.495022) (xy 166.647368 -12.495022)
			(xy 166.646882 -12.522273) (xy 166.639126 -12.576221) (xy 166.623771 -12.628516) (xy 166.601129 -12.678093)
			(xy 166.571663 -12.723943) (xy 166.535972 -12.765134) (xy 166.494781 -12.800825) (xy 166.448931 -12.830291)
			(xy 166.399354 -12.852933) (xy 166.347059 -12.868288) (xy 166.293111 -12.876044) (xy 166.238609 -12.876044)
			(xy 166.184661 -12.868288) (xy 166.132366 -12.852933) (xy 166.082789 -12.830291) (xy 166.036939 -12.800825)
			(xy 165.995748 -12.765134) (xy 165.960057 -12.723943) (xy 165.930591 -12.678093) (xy 165.907949 -12.628516)
			(xy 165.892594 -12.576221) (xy 165.884838 -12.522273) (xy 165.884352 -12.495022) (xy 165.88484 -12.468223)
			(xy 165.892327 -12.41515) (xy 165.907171 -12.363648) (xy 165.929078 -12.314731) (xy 165.957619 -12.269364)
			(xy 165.99223 -12.228439) (xy 166.03223 -12.192763) (xy 166.054278 -12.177522) (xy 166.066742 -12.168617)
			(xy 166.086105 -12.144899) (xy 166.097567 -12.116507) (xy 166.100099 -12.085994) (xy 166.093473 -12.056101)
			(xy 166.078285 -12.029516) (xy 166.055899 -12.008627) (xy 166.04234 -12.0015) (xy 166.014072 -11.987249)
			(xy 165.960944 -11.952824) (xy 165.912502 -11.912068) (xy 165.869495 -11.865613) (xy 165.832589 -11.814178)
			(xy 165.802354 -11.758559) (xy 165.779259 -11.699616) (xy 165.763662 -11.638261) (xy 165.755802 -11.575445)
			(xy 165.75532 -11.543792) (xy 164.899334 -11.543792) (xy 164.892228 -11.55573) (xy 164.88537 -11.66368)
			(xy 164.89553 -11.686286) (xy 164.905436 -11.693906) (xy 164.930674 -11.714612) (xy 164.976128 -11.761472)
			(xy 165.015207 -11.813766) (xy 165.04727 -11.870633) (xy 165.071789 -11.931136) (xy 165.088359 -11.994282)
			(xy 165.096708 -12.059028) (xy 165.097206 -12.09167) (xy 165.097206 -12.091924) (xy 165.096704 -12.123885)
			(xy 165.088693 -12.187303) (xy 165.072796 -12.249217) (xy 165.049264 -12.30865) (xy 165.01847 -12.364665)
			(xy 164.980897 -12.41638) (xy 164.93714 -12.462977) (xy 164.887887 -12.503722) (xy 164.833916 -12.537973)
			(xy 164.776077 -12.56519) (xy 164.715284 -12.584943) (xy 164.652494 -12.596921) (xy 164.588698 -12.600935)
			(xy 164.524902 -12.596921) (xy 164.462112 -12.584943) (xy 164.401319 -12.56519) (xy 164.34348 -12.537973)
			(xy 164.289509 -12.503722) (xy 164.240256 -12.462977) (xy 164.196499 -12.41638) (xy 164.158926 -12.364665)
			(xy 164.128132 -12.30865) (xy 164.1046 -12.249217) (xy 164.088703 -12.187303) (xy 164.080692 -12.123885)
			(xy 164.08019 -12.091924) (xy 164.08073 -12.058505) (xy 164.089484 -11.992241) (xy 164.106844 -11.927696)
			(xy 164.13251 -11.865982) (xy 164.166041 -11.808162) (xy 164.206857 -11.755233) (xy 164.254257 -11.708108)
			(xy 164.307421 -11.6676) (xy 164.365435 -11.634405) (xy 164.396166 -11.621262) (xy 164.407596 -11.61669)
			(xy 164.423598 -11.59764) (xy 164.447728 -11.49223) (xy 164.441378 -11.4681) (xy 164.432996 -11.458956)
			(xy 164.414508 -11.437809) (xy 164.383317 -11.391094) (xy 164.359303 -11.340315) (xy 164.342983 -11.286567)
			(xy 164.334711 -11.231009) (xy 164.33419 -11.202924) (xy 164.33424 -11.191659) (xy 164.335513 -11.169165)
			(xy 164.33673 -11.157966) (xy 164.338254 -11.14552) (xy 164.329618 -11.122152) (xy 164.248592 -11.05027)
			(xy 164.224716 -11.044174) (xy 164.212524 -11.047222) (xy 164.183487 -11.053662) (xy 164.124408 -11.060543)
			(xy 164.094668 -11.060938) (xy 164.063129 -11.060398) (xy 164.000536 -11.052592) (xy 163.939389 -11.037104)
			(xy 163.880627 -11.014171) (xy 163.825154 -10.984145) (xy 163.77382 -10.947489) (xy 163.727415 -10.904764)
			(xy 163.68665 -10.856628) (xy 163.652153 -10.803819) (xy 163.624453 -10.747149) (xy 163.603975 -10.687487)
			(xy 163.591035 -10.625751) (xy 163.58583 -10.562888) (xy 157.43635 -10.562888) (xy 157.405381 -10.582741)
			(xy 157.376876 -10.59688) (xy 157.366131 -10.602757) (xy 157.351401 -10.622276) (xy 157.348682 -10.634218)
			(xy 157.33268 -10.728706) (xy 157.340046 -10.75182) (xy 157.348936 -10.76071) (xy 157.369965 -10.782338)
			(xy 157.405612 -10.830999) (xy 157.433154 -10.884665) (xy 157.451905 -10.941998) (xy 157.461396 -11.001567)
			(xy 157.461966 -11.031728) (xy 157.461571 -11.058983) (xy 157.453809 -11.112939) (xy 157.438447 -11.165241)
			(xy 157.418894 -11.208049) (xy 158.353004 -11.208049) (xy 158.353004 -11.153551) (xy 158.36076 -11.099607)
			(xy 158.376114 -11.047316) (xy 158.398754 -10.997742) (xy 158.428218 -10.951895) (xy 158.463906 -10.910708)
			(xy 158.505094 -10.875019) (xy 158.550941 -10.845554) (xy 158.600514 -10.822915) (xy 158.652805 -10.807561)
			(xy 158.706749 -10.799804) (xy 158.733998 -10.799318) (xy 158.762656 -10.799807) (xy 158.819327 -10.808381)
			(xy 158.874078 -10.825336) (xy 158.925677 -10.85029) (xy 158.972961 -10.882683) (xy 159.014869 -10.921784)
			(xy 159.050455 -10.966714) (xy 159.07892 -11.016462) (xy 159.099622 -11.069909) (xy 159.106362 -11.097768)
			(xy 159.110203 -11.112457) (xy 159.125268 -11.138802) (xy 159.14741 -11.159556) (xy 159.174673 -11.172886)
			(xy 159.20465 -11.177616) (xy 159.234693 -11.173327) (xy 159.262149 -11.160399) (xy 159.273748 -11.1506)
			(xy 159.297205 -11.129926) (xy 159.348267 -11.093838) (xy 159.403369 -11.064285) (xy 159.461679 -11.041713)
			(xy 159.522318 -11.026461) (xy 159.584369 -11.018761) (xy 159.615632 -11.018266) (xy 159.61614 -11.018266)
			(xy 159.648098 -11.018822) (xy 159.711509 -11.026838) (xy 159.773415 -11.042737) (xy 159.832841 -11.066269)
			(xy 159.888849 -11.097064) (xy 159.940556 -11.134635) (xy 159.987147 -11.17839) (xy 160.027887 -11.227639)
			(xy 160.062133 -11.281606) (xy 160.089345 -11.339439) (xy 160.103982 -11.384491) (xy 162.599872 -11.384491)
			(xy 162.599872 -11.320569) (xy 162.607883 -11.257151) (xy 162.62378 -11.195237) (xy 162.647312 -11.135804)
			(xy 162.678106 -11.079789) (xy 162.715679 -11.028074) (xy 162.759436 -10.981477) (xy 162.808689 -10.940732)
			(xy 162.86266 -10.906481) (xy 162.920499 -10.879264) (xy 162.981292 -10.859511) (xy 163.044082 -10.847533)
			(xy 163.107878 -10.84352) (xy 163.171674 -10.847533) (xy 163.234464 -10.859511) (xy 163.295257 -10.879264)
			(xy 163.353096 -10.906481) (xy 163.407067 -10.940732) (xy 163.45632 -10.981477) (xy 163.500077 -11.028074)
			(xy 163.53765 -11.079789) (xy 163.568444 -11.135804) (xy 163.591976 -11.195237) (xy 163.607873 -11.257151)
			(xy 163.615884 -11.320569) (xy 163.616386 -11.35253) (xy 163.615884 -11.384491) (xy 163.607873 -11.447909)
			(xy 163.591976 -11.509823) (xy 163.568444 -11.569256) (xy 163.53765 -11.625271) (xy 163.500077 -11.676986)
			(xy 163.45632 -11.723583) (xy 163.407067 -11.764328) (xy 163.353096 -11.798579) (xy 163.295257 -11.825796)
			(xy 163.234464 -11.845549) (xy 163.171674 -11.857527) (xy 163.107878 -11.861541) (xy 163.044082 -11.857527)
			(xy 162.981292 -11.845549) (xy 162.920499 -11.825796) (xy 162.86266 -11.798579) (xy 162.808689 -11.764328)
			(xy 162.759436 -11.723583) (xy 162.715679 -11.676986) (xy 162.678106 -11.625271) (xy 162.647312 -11.569256)
			(xy 162.62378 -11.509823) (xy 162.607883 -11.447909) (xy 162.599872 -11.384491) (xy 160.103982 -11.384491)
			(xy 160.109095 -11.400227) (xy 160.121071 -11.463011) (xy 160.125085 -11.5268) (xy 160.121071 -11.590589)
			(xy 160.109095 -11.653373) (xy 160.089345 -11.714161) (xy 160.062133 -11.771994) (xy 160.027887 -11.825961)
			(xy 159.987147 -11.87521) (xy 159.940556 -11.918965) (xy 159.888849 -11.956536) (xy 159.832841 -11.987331)
			(xy 159.773415 -12.010863) (xy 159.711509 -12.026762) (xy 159.648098 -12.034778) (xy 159.61614 -12.035282)
			(xy 159.584647 -12.034761) (xy 159.522141 -12.026997) (xy 159.461074 -12.011573) (xy 159.402379 -11.988723)
			(xy 159.346956 -11.958798) (xy 159.295654 -11.922256) (xy 159.249259 -11.879657) (xy 159.208481 -11.831653)
			(xy 159.173945 -11.778979) (xy 159.14618 -11.722443) (xy 159.125612 -11.662911) (xy 159.112554 -11.601293)
			(xy 159.10941 -11.569954) (xy 159.107543 -11.554879) (xy 159.096198 -11.526721) (xy 159.07707 -11.503148)
			(xy 159.051852 -11.486248) (xy 159.022777 -11.477517) (xy 158.992421 -11.477728) (xy 158.96347 -11.486862)
			(xy 158.95066 -11.495024) (xy 158.926675 -11.510877) (xy 158.874973 -11.536018) (xy 158.820084 -11.553118)
			(xy 158.763251 -11.56179) (xy 158.734506 -11.562334) (xy 158.733998 -11.562334) (xy 158.706749 -11.561796)
			(xy 158.652805 -11.554039) (xy 158.600514 -11.538685) (xy 158.550941 -11.516046) (xy 158.505094 -11.486581)
			(xy 158.463906 -11.450892) (xy 158.428218 -11.409705) (xy 158.398754 -11.363858) (xy 158.376114 -11.314284)
			(xy 158.36076 -11.261993) (xy 158.353004 -11.208049) (xy 157.418894 -11.208049) (xy 157.415799 -11.214824)
			(xy 157.386324 -11.260679) (xy 157.350623 -11.301872) (xy 157.309423 -11.337566) (xy 157.263562 -11.367032)
			(xy 157.213975 -11.389672) (xy 157.161671 -11.405024) (xy 157.107714 -11.412776) (xy 157.080458 -11.413236)
			(xy 157.057102 -11.412866) (xy 157.010744 -11.407139) (xy 156.988002 -11.401806) (xy 156.987748 -11.401806)
			(xy 156.975484 -11.399424) (xy 156.951258 -11.40541) (xy 156.94152 -11.413236) (xy 156.879036 -11.469624)
			(xy 156.870195 -11.478448) (xy 156.86166 -11.501889) (xy 156.86278 -11.514328) (xy 156.86278 -11.514582)
			(xy 156.865067 -11.532145) (xy 156.867483 -11.567483) (xy 156.867606 -11.585194) (xy 156.86711 -11.618485)
			(xy 156.858417 -11.684498) (xy 156.841177 -11.74881) (xy 156.815688 -11.81032) (xy 156.782384 -11.867975)
			(xy 156.741837 -11.920788) (xy 156.694741 -11.967854) (xy 156.641902 -12.008367) (xy 156.584226 -12.041633)
			(xy 156.553662 -12.05484) (xy 156.553408 -12.05484) (xy 156.542111 -12.060365) (xy 156.526389 -12.079954)
			(xy 156.523436 -12.092178) (xy 156.50718 -12.17549) (xy 156.50548 -12.188032) (xy 156.513094 -12.212143)
			(xy 156.521658 -12.221464) (xy 156.521912 -12.221718) (xy 156.539824 -12.23973) (xy 156.571186 -12.279691)
			(xy 156.596968 -12.32346) (xy 156.616713 -12.370264) (xy 156.630073 -12.419274) (xy 156.636811 -12.469623)
			(xy 156.637228 -12.495022) (xy 156.636742 -12.522273) (xy 156.636065 -12.526983) (xy 156.860996 -12.526983)
			(xy 156.860996 -12.463061) (xy 156.869007 -12.399643) (xy 156.884904 -12.337729) (xy 156.908436 -12.278296)
			(xy 156.93923 -12.222281) (xy 156.976803 -12.170566) (xy 157.02056 -12.123969) (xy 157.069813 -12.083224)
			(xy 157.123784 -12.048973) (xy 157.181623 -12.021756) (xy 157.242416 -12.002003) (xy 157.305206 -11.990025)
			(xy 157.369002 -11.986012) (xy 157.432798 -11.990025) (xy 157.495588 -12.002003) (xy 157.556381 -12.021756)
			(xy 157.61422 -12.048973) (xy 157.668191 -12.083224) (xy 157.717444 -12.123969) (xy 157.761201 -12.170566)
			(xy 157.798774 -12.222281) (xy 157.81422 -12.250377) (xy 158.14903 -12.250377) (xy 158.14903 -12.186455)
			(xy 158.157041 -12.123037) (xy 158.172938 -12.061123) (xy 158.19647 -12.00169) (xy 158.227264 -11.945675)
			(xy 158.264837 -11.89396) (xy 158.308594 -11.847363) (xy 158.357847 -11.806618) (xy 158.411818 -11.772367)
			(xy 158.469657 -11.74515) (xy 158.53045 -11.725397) (xy 158.59324 -11.713419) (xy 158.657036 -11.709406)
			(xy 158.720832 -11.713419) (xy 158.783622 -11.725397) (xy 158.844415 -11.74515) (xy 158.902254 -11.772367)
			(xy 158.956225 -11.806618) (xy 159.005478 -11.847363) (xy 159.049235 -11.89396) (xy 159.086808 -11.945675)
			(xy 159.117602 -12.00169) (xy 159.141134 -12.061123) (xy 159.157031 -12.123037) (xy 159.165042 -12.186455)
			(xy 159.165544 -12.218416) (xy 159.165042 -12.250377) (xy 159.157031 -12.313795) (xy 159.141134 -12.375709)
			(xy 159.117602 -12.435142) (xy 159.086808 -12.491157) (xy 159.060779 -12.526983) (xy 162.020498 -12.526983)
			(xy 162.020498 -12.463061) (xy 162.028509 -12.399643) (xy 162.044406 -12.337729) (xy 162.067938 -12.278296)
			(xy 162.098732 -12.222281) (xy 162.136305 -12.170566) (xy 162.180062 -12.123969) (xy 162.229315 -12.083224)
			(xy 162.283286 -12.048973) (xy 162.341125 -12.021756) (xy 162.401918 -12.002003) (xy 162.464708 -11.990025)
			(xy 162.528504 -11.986012) (xy 162.5923 -11.990025) (xy 162.65509 -12.002003) (xy 162.715883 -12.021756)
			(xy 162.773722 -12.048973) (xy 162.827693 -12.083224) (xy 162.876946 -12.123969) (xy 162.920703 -12.170566)
			(xy 162.958276 -12.222281) (xy 162.98907 -12.278296) (xy 163.012602 -12.337729) (xy 163.028499 -12.399643)
			(xy 163.03651 -12.463061) (xy 163.037012 -12.495022) (xy 163.03651 -12.526983) (xy 163.028499 -12.590401)
			(xy 163.012602 -12.652315) (xy 162.98907 -12.711748) (xy 162.958276 -12.767763) (xy 162.920703 -12.819478)
			(xy 162.876946 -12.866075) (xy 162.827693 -12.90682) (xy 162.773722 -12.941071) (xy 162.715883 -12.968288)
			(xy 162.65509 -12.988041) (xy 162.5923 -13.000019) (xy 162.528504 -13.004033) (xy 162.464708 -13.000019)
			(xy 162.401918 -12.988041) (xy 162.341125 -12.968288) (xy 162.283286 -12.941071) (xy 162.229315 -12.90682)
			(xy 162.180062 -12.866075) (xy 162.136305 -12.819478) (xy 162.098732 -12.767763) (xy 162.067938 -12.711748)
			(xy 162.044406 -12.652315) (xy 162.028509 -12.590401) (xy 162.020498 -12.526983) (xy 159.060779 -12.526983)
			(xy 159.049235 -12.542872) (xy 159.005478 -12.589469) (xy 158.956225 -12.630214) (xy 158.902254 -12.664465)
			(xy 158.844415 -12.691682) (xy 158.783622 -12.711435) (xy 158.720832 -12.723413) (xy 158.657036 -12.727427)
			(xy 158.59324 -12.723413) (xy 158.53045 -12.711435) (xy 158.469657 -12.691682) (xy 158.411818 -12.664465)
			(xy 158.357847 -12.630214) (xy 158.308594 -12.589469) (xy 158.264837 -12.542872) (xy 158.227264 -12.491157)
			(xy 158.19647 -12.435142) (xy 158.172938 -12.375709) (xy 158.157041 -12.313795) (xy 158.14903 -12.250377)
			(xy 157.81422 -12.250377) (xy 157.829568 -12.278296) (xy 157.8531 -12.337729) (xy 157.868997 -12.399643)
			(xy 157.877008 -12.463061) (xy 157.87751 -12.495022) (xy 157.877008 -12.526983) (xy 157.868997 -12.590401)
			(xy 157.8531 -12.652315) (xy 157.829568 -12.711748) (xy 157.798774 -12.767763) (xy 157.761201 -12.819478)
			(xy 157.717444 -12.866075) (xy 157.668191 -12.90682) (xy 157.61422 -12.941071) (xy 157.556381 -12.968288)
			(xy 157.495588 -12.988041) (xy 157.432798 -13.000019) (xy 157.369002 -13.004033) (xy 157.305206 -13.000019)
			(xy 157.242416 -12.988041) (xy 157.181623 -12.968288) (xy 157.123784 -12.941071) (xy 157.069813 -12.90682)
			(xy 157.02056 -12.866075) (xy 156.976803 -12.819478) (xy 156.93923 -12.767763) (xy 156.908436 -12.711748)
			(xy 156.884904 -12.652315) (xy 156.869007 -12.590401) (xy 156.860996 -12.526983) (xy 156.636065 -12.526983)
			(xy 156.628986 -12.576221) (xy 156.613631 -12.628516) (xy 156.590989 -12.678093) (xy 156.561523 -12.723943)
			(xy 156.525832 -12.765134) (xy 156.484641 -12.800825) (xy 156.438791 -12.830291) (xy 156.389214 -12.852933)
			(xy 156.336919 -12.868288) (xy 156.282971 -12.876044) (xy 156.228469 -12.876044) (xy 156.174521 -12.868288)
			(xy 156.122226 -12.852933) (xy 156.072649 -12.830291) (xy 156.026799 -12.800825) (xy 155.985608 -12.765134)
			(xy 155.949917 -12.723943) (xy 155.920451 -12.678093) (xy 155.897809 -12.628516) (xy 155.882454 -12.576221)
			(xy 155.874698 -12.522273) (xy 155.874212 -12.495022) (xy 155.874721 -12.467066) (xy 155.882892 -12.411755)
			(xy 155.899047 -12.358227) (xy 155.92284 -12.307631) (xy 155.953763 -12.261048) (xy 155.991152 -12.219477)
			(xy 156.034208 -12.183807) (xy 156.057854 -12.168886) (xy 156.068304 -12.161704) (xy 156.081108 -12.139858)
			(xy 156.082238 -12.12723) (xy 156.085286 -12.042394) (xy 156.085081 -12.029779) (xy 156.074025 -12.007134)
			(xy 156.064204 -11.999214) (xy 156.06395 -11.999214) (xy 156.039584 -11.981287) (xy 155.994835 -11.94058)
			(xy 155.955232 -11.894851) (xy 155.921335 -11.844747) (xy 155.893621 -11.790975) (xy 155.872483 -11.734294)
			(xy 155.858219 -11.675506) (xy 155.851031 -11.615441) (xy 155.85059 -11.585194) (xy 155.850938 -11.5589)
			(xy 155.856411 -11.506597) (xy 155.861512 -11.4808) (xy 155.861512 -11.480546) (xy 155.863293 -11.468815)
			(xy 155.857191 -11.44591) (xy 155.849828 -11.436604) (xy 155.787344 -11.3665) (xy 155.764992 -11.35761)
			(xy 155.753054 -11.358626) (xy 155.70835 -11.360658) (xy 155.676813 -11.360179) (xy 155.614225 -11.352372)
			(xy 155.553083 -11.336883) (xy 155.494327 -11.31395) (xy 155.438858 -11.283927) (xy 155.387528 -11.247272)
			(xy 155.341127 -11.204551) (xy 155.300366 -11.156418) (xy 155.265871 -11.103614) (xy 155.238172 -11.046948)
			(xy 155.217695 -10.987291) (xy 155.204754 -10.92556) (xy 155.199548 -10.862702) (xy 154.542878 -10.862702)
			(xy 154.545853 -10.869023) (xy 154.565606 -10.929816) (xy 154.577584 -10.992605) (xy 154.581598 -11.0564)
			(xy 154.577584 -11.120195) (xy 154.565606 -11.182984) (xy 154.545853 -11.243777) (xy 154.518636 -11.301614)
			(xy 154.484385 -11.355584) (xy 154.44364 -11.404836) (xy 154.397043 -11.448593) (xy 154.345329 -11.486164)
			(xy 154.289314 -11.516958) (xy 154.229881 -11.540488) (xy 154.167968 -11.556383) (xy 154.104551 -11.564394)
			(xy 154.07259 -11.564874) (xy 154.038278 -11.56431) (xy 153.970278 -11.555076) (xy 153.904139 -11.536776)
			(xy 153.841064 -11.509743) (xy 153.7822 -11.47447) (xy 153.728616 -11.431597) (xy 153.704544 -11.40714)
			(xy 153.695654 -11.397742) (xy 153.670508 -11.389868) (xy 153.560272 -11.412474) (xy 153.54046 -11.429492)
			(xy 153.535888 -11.441938) (xy 153.524073 -11.471797) (xy 153.491904 -11.527366) (xy 153.450862 -11.576747)
			(xy 153.426922 -11.598148) (xy 153.418191 -11.606551) (xy 153.409049 -11.62896) (xy 153.409396 -11.641074)
			(xy 153.416254 -11.723116) (xy 153.417954 -11.735041) (xy 153.430681 -11.755454) (xy 153.440638 -11.762232)
			(xy 153.468369 -11.779577) (xy 153.519608 -11.820232) (xy 153.565211 -11.867121) (xy 153.604426 -11.91947)
			(xy 153.636606 -11.976414) (xy 153.66122 -12.037015) (xy 153.677861 -12.100271) (xy 153.686254 -12.165138)
			(xy 153.686764 -12.197842) (xy 153.686262 -12.229803) (xy 153.678251 -12.293221) (xy 153.662354 -12.355135)
			(xy 153.638822 -12.414568) (xy 153.608028 -12.470583) (xy 153.570455 -12.522298) (xy 153.526698 -12.568895)
			(xy 153.477445 -12.60964) (xy 153.423474 -12.643891) (xy 153.365635 -12.671108) (xy 153.304842 -12.690861)
			(xy 153.242052 -12.702839) (xy 153.178256 -12.706853) (xy 153.11446 -12.702839) (xy 153.05167 -12.690861)
			(xy 152.990877 -12.671108) (xy 152.933038 -12.643891) (xy 152.879067 -12.60964) (xy 152.829814 -12.568895)
			(xy 152.786057 -12.522298) (xy 152.748484 -12.470583) (xy 152.71769 -12.414568) (xy 152.694158 -12.355135)
			(xy 152.678261 -12.293221) (xy 152.67025 -12.229803) (xy 152.669748 -12.197842) (xy 152.389236 -12.197842)
			(xy 152.389332 -12.203938) (xy 152.38883 -12.235899) (xy 152.380819 -12.299317) (xy 152.364922 -12.361231)
			(xy 152.34139 -12.420664) (xy 152.310596 -12.476679) (xy 152.273023 -12.528394) (xy 152.229266 -12.574991)
			(xy 152.180013 -12.615736) (xy 152.126042 -12.649987) (xy 152.068203 -12.677204) (xy 152.00741 -12.696957)
			(xy 151.94462 -12.708935) (xy 151.880824 -12.712949) (xy 151.817028 -12.708935) (xy 151.754238 -12.696957)
			(xy 151.693445 -12.677204) (xy 151.635606 -12.649987) (xy 151.581635 -12.615736) (xy 151.532382 -12.574991)
			(xy 151.488625 -12.528394) (xy 151.451052 -12.476679) (xy 151.420258 -12.420664) (xy 151.396726 -12.361231)
			(xy 151.380829 -12.299317) (xy 151.372818 -12.235899) (xy 151.13507 -12.235899) (xy 151.157907 -12.261342)
			(xy 151.188744 -12.307881) (xy 151.212466 -12.358419) (xy 151.228567 -12.411875) (xy 151.236703 -12.467108)
			(xy 151.237188 -12.495022) (xy 151.236702 -12.522273) (xy 151.228946 -12.576221) (xy 151.213591 -12.628516)
			(xy 151.190949 -12.678093) (xy 151.161483 -12.723943) (xy 151.125792 -12.765134) (xy 151.084601 -12.800825)
			(xy 151.038751 -12.830291) (xy 150.989174 -12.852933) (xy 150.936879 -12.868288) (xy 150.882931 -12.876044)
			(xy 150.828429 -12.876044) (xy 150.774481 -12.868288) (xy 150.722186 -12.852933) (xy 150.672609 -12.830291)
			(xy 150.626759 -12.800825) (xy 150.585568 -12.765134) (xy 150.549877 -12.723943) (xy 150.520411 -12.678093)
			(xy 150.497769 -12.628516) (xy 150.482414 -12.576221) (xy 150.474658 -12.522273) (xy 150.474172 -12.495022)
			(xy 150.474172 -12.494768) (xy 150.474573 -12.470101) (xy 150.480942 -12.421179) (xy 150.486872 -12.397232)
			(xy 150.486872 -12.396978) (xy 150.489348 -12.385215) (xy 150.48429 -12.361744) (xy 150.47722 -12.35202)
			(xy 150.417276 -12.278868) (xy 150.394924 -12.268962) (xy 150.382732 -12.269724) (xy 150.352252 -12.27074)
			(xy 150.320714 -12.270181) (xy 150.258124 -12.262374) (xy 150.196979 -12.246884) (xy 150.138221 -12.22395)
			(xy 150.08275 -12.193924) (xy 150.031419 -12.157268) (xy 149.985017 -12.114543) (xy 149.944255 -12.066408)
			(xy 149.909761 -12.0136) (xy 149.882063 -11.956931) (xy 149.861588 -11.897271) (xy 149.848649 -11.835537)
			(xy 149.843445 -11.772676) (xy 147.18622 -11.772676) (xy 147.144409 -11.798193) (xy 147.09308 -11.820005)
			(xy 147.039123 -11.834111) (xy 146.983686 -11.840211) (xy 146.927952 -11.838174) (xy 146.873109 -11.828044)
			(xy 146.820325 -11.810037) (xy 146.770725 -11.784536) (xy 146.725367 -11.752085) (xy 146.685218 -11.713376)
			(xy 146.651132 -11.669233) (xy 146.623836 -11.620598) (xy 146.603913 -11.568507) (xy 146.591787 -11.51407)
			(xy 146.587716 -11.458448) (xy 143.746891 -11.458448) (xy 143.746982 -11.463528) (xy 143.746982 -11.46429)
			(xy 143.746643 -11.487324) (xy 143.741047 -11.533053) (xy 143.729972 -11.577771) (xy 143.72209 -11.599418)
			(xy 143.718534 -11.608562) (xy 143.718788 -11.627358) (xy 143.74749 -11.698224) (xy 143.751387 -11.706912)
			(xy 143.764443 -11.720753) (xy 143.77289 -11.725148) (xy 143.773144 -11.725402) (xy 143.802024 -11.739473)
			(xy 143.856326 -11.773801) (xy 143.90589 -11.814674) (xy 143.94993 -11.861446) (xy 143.987751 -11.913376)
			(xy 144.018753 -11.969643) (xy 144.042447 -12.029357) (xy 144.058458 -12.091573) (xy 144.066531 -12.155307)
			(xy 144.067022 -12.187428) (xy 144.066593 -12.218252) (xy 144.066455 -12.219389) (xy 144.32508 -12.219389)
			(xy 144.32508 -12.155467) (xy 144.333091 -12.092049) (xy 144.348988 -12.030135) (xy 144.37252 -11.970702)
			(xy 144.403314 -11.914687) (xy 144.440887 -11.862972) (xy 144.484644 -11.816375) (xy 144.533897 -11.77563)
			(xy 144.587868 -11.741379) (xy 144.645707 -11.714162) (xy 144.7065 -11.694409) (xy 144.76929 -11.682431)
			(xy 144.833086 -11.678418) (xy 144.896882 -11.682431) (xy 144.959672 -11.694409) (xy 145.020465 -11.714162)
			(xy 145.078304 -11.741379) (xy 145.132275 -11.77563) (xy 145.181528 -11.816375) (xy 145.225285 -11.862972)
			(xy 145.262858 -11.914687) (xy 145.293652 -11.970702) (xy 145.317184 -12.030135) (xy 145.333081 -12.092049)
			(xy 145.33922 -12.140649) (xy 145.626068 -12.140649) (xy 145.626068 -12.076727) (xy 145.634079 -12.013309)
			(xy 145.649976 -11.951395) (xy 145.673508 -11.891962) (xy 145.704302 -11.835947) (xy 145.741875 -11.784232)
			(xy 145.785632 -11.737635) (xy 145.834885 -11.69689) (xy 145.888856 -11.662639) (xy 145.946695 -11.635422)
			(xy 146.007488 -11.615669) (xy 146.070278 -11.603691) (xy 146.134074 -11.599678) (xy 146.19787 -11.603691)
			(xy 146.26066 -11.615669) (xy 146.321453 -11.635422) (xy 146.379292 -11.662639) (xy 146.433263 -11.69689)
			(xy 146.482516 -11.737635) (xy 146.526273 -11.784232) (xy 146.563846 -11.835947) (xy 146.59464 -11.891962)
			(xy 146.618172 -11.951395) (xy 146.634069 -12.013309) (xy 146.64208 -12.076727) (xy 146.642582 -12.108688)
			(xy 146.64208 -12.140649) (xy 146.634069 -12.204067) (xy 146.618172 -12.265981) (xy 146.59464 -12.325414)
			(xy 146.563846 -12.381429) (xy 146.526273 -12.433144) (xy 146.482516 -12.479741) (xy 146.433263 -12.520486)
			(xy 146.379292 -12.554737) (xy 146.321453 -12.581954) (xy 146.26066 -12.601707) (xy 146.19787 -12.613685)
			(xy 146.134074 -12.617699) (xy 146.070278 -12.613685) (xy 146.007488 -12.601707) (xy 145.946695 -12.581954)
			(xy 145.888856 -12.554737) (xy 145.834885 -12.520486) (xy 145.785632 -12.479741) (xy 145.741875 -12.433144)
			(xy 145.704302 -12.381429) (xy 145.673508 -12.325414) (xy 145.649976 -12.265981) (xy 145.634079 -12.204067)
			(xy 145.626068 -12.140649) (xy 145.33922 -12.140649) (xy 145.341092 -12.155467) (xy 145.341594 -12.187428)
			(xy 145.341092 -12.219389) (xy 145.333081 -12.282807) (xy 145.317184 -12.344721) (xy 145.293652 -12.404154)
			(xy 145.262858 -12.460169) (xy 145.225285 -12.511884) (xy 145.181528 -12.558481) (xy 145.132275 -12.599226)
			(xy 145.078304 -12.633477) (xy 145.020465 -12.660694) (xy 144.959672 -12.680447) (xy 144.896882 -12.692425)
			(xy 144.833086 -12.696439) (xy 144.76929 -12.692425) (xy 144.7065 -12.680447) (xy 144.645707 -12.660694)
			(xy 144.587868 -12.633477) (xy 144.533897 -12.599226) (xy 144.484644 -12.558481) (xy 144.440887 -12.511884)
			(xy 144.403314 -12.460169) (xy 144.37252 -12.404154) (xy 144.348988 -12.344721) (xy 144.333091 -12.282807)
			(xy 144.32508 -12.219389) (xy 144.066455 -12.219389) (xy 144.059159 -12.27945) (xy 144.044403 -12.339306)
			(xy 144.022539 -12.396948) (xy 143.993887 -12.451533) (xy 143.958865 -12.502267) (xy 143.917983 -12.54841)
			(xy 143.871837 -12.589289) (xy 143.821101 -12.624307) (xy 143.766513 -12.652955) (xy 143.70887 -12.674814)
			(xy 143.649013 -12.689566) (xy 143.587814 -12.696995) (xy 143.55699 -12.69746) (xy 143.556736 -12.69746)
			(xy 143.523043 -12.696931) (xy 143.456245 -12.688049) (xy 143.391202 -12.670435) (xy 143.32905 -12.644397)
			(xy 143.299688 -12.627864) (xy 143.292902 -12.624469) (xy 143.278055 -12.621368) (xy 143.270478 -12.621768)
			(xy 143.266922 -12.622276) (xy 143.239998 -12.626848) (xy 143.231784 -12.628541) (xy 143.217006 -12.636446)
			(xy 143.211042 -12.642342) (xy 143.210534 -12.64285) (xy 143.21028 -12.643104) (xy 143.189568 -12.665463)
			(xy 143.143716 -12.705615) (xy 143.09339 -12.739995) (xy 143.039314 -12.76811) (xy 142.982264 -12.789557)
			(xy 142.923059 -12.804027) (xy 142.862548 -12.811313) (xy 142.832074 -12.81176) (xy 142.800111 -12.811353)
			(xy 142.736689 -12.803338) (xy 142.674772 -12.787437) (xy 142.615336 -12.763902) (xy 142.559318 -12.733104)
			(xy 142.507602 -12.695527) (xy 142.461003 -12.651766) (xy 142.420256 -12.602509) (xy 142.386004 -12.548534)
			(xy 142.358787 -12.490691) (xy 142.339033 -12.429894) (xy 142.327055 -12.3671) (xy 142.323041 -12.3033)
			(xy 141.12604 -12.3033) (xy 141.135289 -12.37114) (xy 141.135862 -12.405614) (xy 141.135862 -12.405868)
			(xy 141.13536 -12.437829) (xy 141.127349 -12.501247) (xy 141.111452 -12.563161) (xy 141.08792 -12.622594)
			(xy 141.057126 -12.678609) (xy 141.019553 -12.730324) (xy 140.975796 -12.776921) (xy 140.926543 -12.817666)
			(xy 140.872572 -12.851917) (xy 140.814733 -12.879134) (xy 140.75394 -12.898887) (xy 140.69115 -12.910865)
			(xy 140.627354 -12.914879) (xy 140.563558 -12.910865) (xy 140.500768 -12.898887) (xy 140.439975 -12.879134)
			(xy 140.382136 -12.851917) (xy 140.328165 -12.817666) (xy 140.278912 -12.776921) (xy 140.235155 -12.730324)
			(xy 140.197582 -12.678609) (xy 140.166788 -12.622594) (xy 140.143256 -12.563161) (xy 140.127359 -12.501247)
			(xy 140.119348 -12.437829) (xy 140.118846 -12.405868) (xy 139.816884 -12.405868) (xy 139.807506 -12.429554)
			(xy 139.776712 -12.485569) (xy 139.739139 -12.537284) (xy 139.695382 -12.583881) (xy 139.646129 -12.624626)
			(xy 139.592158 -12.658877) (xy 139.534319 -12.686094) (xy 139.473526 -12.705847) (xy 139.410736 -12.717825)
			(xy 139.34694 -12.721839) (xy 139.283144 -12.717825) (xy 139.220354 -12.705847) (xy 139.159561 -12.686094)
			(xy 139.101722 -12.658877) (xy 139.047751 -12.624626) (xy 138.998498 -12.583881) (xy 138.954741 -12.537284)
			(xy 138.917168 -12.485569) (xy 138.886374 -12.429554) (xy 138.862842 -12.370121) (xy 138.846945 -12.308207)
			(xy 138.838934 -12.244789) (xy 137.232968 -12.244789) (xy 137.251974 -12.266837) (xy 137.281236 -12.312577)
			(xy 137.303715 -12.362005) (xy 137.318957 -12.414121) (xy 137.326654 -12.467872) (xy 137.327132 -12.495022)
			(xy 137.326643 -12.522273) (xy 137.318884 -12.576219) (xy 137.303527 -12.628512) (xy 137.280885 -12.678088)
			(xy 137.251419 -12.723937) (xy 137.215728 -12.765126) (xy 137.174539 -12.800818) (xy 137.12869 -12.830284)
			(xy 137.079114 -12.852926) (xy 137.026821 -12.868283) (xy 136.972875 -12.876043) (xy 136.945624 -12.87653)
			(xy 136.918428 -12.876075) (xy 136.864588 -12.86834) (xy 136.812393 -12.853038) (xy 136.762899 -12.830479)
			(xy 136.717111 -12.801119) (xy 136.675956 -12.765555) (xy 136.640268 -12.724507) (xy 136.610772 -12.678807)
			(xy 136.588064 -12.629382) (xy 136.572605 -12.577232) (xy 136.56818 -12.550394) (xy 136.56818 -12.55014)
			(xy 136.56645 -12.541496) (xy 136.558014 -12.526034) (xy 136.55167 -12.519914) (xy 136.495536 -12.47013)
			(xy 136.478772 -12.463526) (xy 136.469628 -12.463526) (xy 136.4356 -12.462374) (xy 136.368297 -12.452075)
			(xy 136.302969 -12.432889) (xy 136.240785 -12.40516) (xy 136.182857 -12.369382) (xy 136.156192 -12.34821)
			(xy 136.149249 -12.34297) (xy 136.13288 -12.337125) (xy 136.124188 -12.33678) (xy 135.969756 -12.33678)
			(xy 135.961075 -12.337186) (xy 135.944717 -12.343015) (xy 135.937752 -12.34821) (xy 135.910907 -12.369477)
			(xy 135.852604 -12.405412) (xy 135.790007 -12.4332) (xy 135.724248 -12.45234) (xy 135.656516 -12.462485)
			(xy 135.622284 -12.463526) (xy 135.61314 -12.463526) (xy 135.596376 -12.47013) (xy 135.53313 -12.52601)
			(xy 135.524494 -12.541758) (xy 135.523224 -12.550394) (xy 135.523224 -12.550648) (xy 135.518808 -12.577476)
			(xy 135.503321 -12.629595) (xy 135.480593 -12.678987) (xy 135.451082 -12.724653) (xy 135.415387 -12.765666)
			(xy 135.374232 -12.801197) (xy 135.328449 -12.830525) (xy 135.278966 -12.853056) (xy 135.226786 -12.868334)
			(xy 135.172965 -12.87605) (xy 135.14578 -12.87653) (xy 135.118529 -12.876041) (xy 135.064583 -12.868282)
			(xy 135.012289 -12.852926) (xy 134.962714 -12.830284) (xy 134.916864 -12.800817) (xy 134.875675 -12.765126)
			(xy 134.839984 -12.723937) (xy 134.810517 -12.678088) (xy 134.787875 -12.628512) (xy 134.772518 -12.576219)
			(xy 134.764759 -12.522273) (xy 134.764272 -12.495022) (xy 133.671291 -12.495022) (xy 133.670801 -12.521892)
			(xy 133.662681 -12.577068) (xy 133.646613 -12.630475) (xy 133.622941 -12.680972) (xy 133.592168 -12.727485)
			(xy 133.554951 -12.769022) (xy 133.512083 -12.804697) (xy 133.464477 -12.833751) (xy 133.413148 -12.855563)
			(xy 133.359191 -12.869669) (xy 133.303754 -12.875769) (xy 133.24802 -12.873732) (xy 133.193177 -12.863602)
			(xy 133.140393 -12.845595) (xy 133.090793 -12.820094) (xy 133.045435 -12.787643) (xy 133.005286 -12.748934)
			(xy 132.9712 -12.704791) (xy 132.943904 -12.656156) (xy 132.923981 -12.604065) (xy 132.911855 -12.549628)
			(xy 132.907784 -12.494006) (xy 131.927074 -12.494006) (xy 131.927092 -12.495022) (xy 131.926606 -12.522273)
			(xy 131.91885 -12.576221) (xy 131.903495 -12.628516) (xy 131.880853 -12.678093) (xy 131.851387 -12.723943)
			(xy 131.815696 -12.765134) (xy 131.774505 -12.800825) (xy 131.728655 -12.830291) (xy 131.679078 -12.852933)
			(xy 131.626783 -12.868288) (xy 131.572835 -12.876044) (xy 131.518333 -12.876044) (xy 131.464385 -12.868288)
			(xy 131.41209 -12.852933) (xy 131.362513 -12.830291) (xy 131.316663 -12.800825) (xy 131.275472 -12.765134)
			(xy 131.239781 -12.723943) (xy 131.210315 -12.678093) (xy 131.187673 -12.628516) (xy 131.172318 -12.576221)
			(xy 131.164562 -12.522273) (xy 131.164076 -12.495022) (xy 131.165854 -12.459208) (xy 131.165854 -12.458954)
			(xy 131.166253 -12.448521) (xy 131.159714 -12.42872) (xy 131.153154 -12.4206) (xy 131.096766 -12.3571)
			(xy 131.077716 -12.34821) (xy 131.067048 -12.347956) (xy 131.033287 -12.346653) (xy 130.966535 -12.336217)
			(xy 130.901755 -12.317027) (xy 130.840089 -12.28942) (xy 130.782627 -12.253884) (xy 130.756152 -12.232894)
			(xy 130.749194 -12.227677) (xy 130.732836 -12.221819) (xy 130.724148 -12.221464) (xy 130.569716 -12.221464)
			(xy 130.561034 -12.221855) (xy 130.544676 -12.227694) (xy 130.537712 -12.232894) (xy 130.511095 -12.254044)
			(xy 130.453259 -12.289777) (xy 130.391176 -12.317486) (xy 130.325956 -12.336675) (xy 130.25876 -12.347002)
			(xy 130.224784 -12.34821) (xy 130.214116 -12.34821) (xy 130.195066 -12.3571) (xy 130.131058 -12.428474)
			(xy 130.124454 -12.44854) (xy 130.12547 -12.459208) (xy 130.127248 -12.495022) (xy 130.126762 -12.522273)
			(xy 130.119006 -12.576221) (xy 130.103651 -12.628516) (xy 130.081009 -12.678093) (xy 130.051543 -12.723943)
			(xy 130.015852 -12.765134) (xy 129.974661 -12.800825) (xy 129.928811 -12.830291) (xy 129.879234 -12.852933)
			(xy 129.826939 -12.868288) (xy 129.772991 -12.876044) (xy 129.718489 -12.876044) (xy 129.664541 -12.868288)
			(xy 129.612246 -12.852933) (xy 129.562669 -12.830291) (xy 129.516819 -12.800825) (xy 129.475628 -12.765134)
			(xy 129.439937 -12.723943) (xy 129.410471 -12.678093) (xy 129.387829 -12.628516) (xy 129.372474 -12.576221)
			(xy 129.364718 -12.522273) (xy 129.364232 -12.495022) (xy 128.528318 -12.495022) (xy 127.429006 -13.594334)
			(xy 127.421611 -13.601189) (xy 127.403012 -13.608936) (xy 127.392938 -13.60932) (xy 122.03684 -13.60932)
			(xy 122.027756 -13.609674) (xy 122.010729 -13.616004) (xy 121.997008 -13.627908) (xy 121.99239 -13.635736)
			(xy 121.960386 -13.700506) (xy 121.954036 -13.713206) (xy 121.949972 -13.721588) (xy 121.947652 -13.727592)
			(xy 121.94572 -13.740313) (xy 121.946162 -13.746734) (xy 121.947432 -13.760958) (xy 121.951242 -13.766038)
			(xy 121.956322 -13.772642) (xy 121.974694 -13.79774) (xy 122.003896 -13.852652) (xy 122.023814 -13.911571)
			(xy 122.03392 -13.972939) (xy 122.034554 -14.004036) (xy 122.034554 -14.00429) (xy 122.034068 -14.031541)
			(xy 122.026312 -14.085489) (xy 122.010957 -14.137784) (xy 121.988315 -14.187361) (xy 121.958849 -14.233211)
			(xy 121.923158 -14.274402) (xy 121.881967 -14.310093) (xy 121.836117 -14.339559) (xy 121.78654 -14.362201)
			(xy 121.734245 -14.377556) (xy 121.680297 -14.385312) (xy 121.625795 -14.385312) (xy 121.571847 -14.377556)
			(xy 121.519552 -14.362201) (xy 121.469975 -14.339559) (xy 121.424125 -14.310093) (xy 121.382934 -14.274402)
			(xy 121.347243 -14.233211) (xy 121.317777 -14.187361) (xy 121.295135 -14.137784) (xy 121.27978 -14.085489)
			(xy 121.272024 -14.031541) (xy 121.271538 -14.00429) (xy 121.271538 -14.004036) (xy 121.271938 -13.979163)
			(xy 121.278405 -13.929838) (xy 121.291234 -13.881774) (xy 121.310207 -13.835788) (xy 121.335002 -13.792661)
			(xy 121.34977 -13.772642) (xy 121.35485 -13.766038) (xy 121.35866 -13.760958) (xy 121.35993 -13.746734)
			(xy 121.36042 -13.740311) (xy 121.358485 -13.72758) (xy 121.35612 -13.721588) (xy 121.352056 -13.713206)
			(xy 121.345706 -13.700506) (xy 121.313702 -13.635736) (xy 121.309006 -13.627974) (xy 121.295289 -13.616119)
			(xy 121.278315 -13.609753) (xy 121.269252 -13.60932) (xy 116.705888 -13.60932) (xy 116.69587 -13.609742)
			(xy 116.677361 -13.617415) (xy 116.663197 -13.631587) (xy 116.655536 -13.650102) (xy 116.655088 -13.66012)
			(xy 116.655088 -14.72946) (xy 138.964922 -14.72946) (xy 138.968993 -14.673838) (xy 138.981119 -14.619401)
			(xy 139.001042 -14.56731) (xy 139.028338 -14.518675) (xy 139.062424 -14.474532) (xy 139.102573 -14.435823)
			(xy 139.147931 -14.403372) (xy 139.197531 -14.377871) (xy 139.250315 -14.359864) (xy 139.305158 -14.349734)
			(xy 139.360892 -14.347697) (xy 139.416329 -14.353797) (xy 139.470286 -14.367903) (xy 139.521615 -14.389715)
			(xy 139.569221 -14.418769) (xy 139.612089 -14.454444) (xy 139.649306 -14.495981) (xy 139.680079 -14.542494)
			(xy 139.703751 -14.592991) (xy 139.719819 -14.646398) (xy 139.727939 -14.701574) (xy 139.728448 -14.72946)
			(xy 139.727939 -14.757346) (xy 139.719819 -14.812522) (xy 139.703751 -14.865929) (xy 139.680079 -14.916426)
			(xy 139.649306 -14.962939) (xy 139.648893 -14.9634) (xy 142.948683 -14.9634) (xy 142.952697 -14.899605)
			(xy 142.964674 -14.836816) (xy 142.984426 -14.776024) (xy 143.011642 -14.718186) (xy 143.045891 -14.664215)
			(xy 143.086635 -14.614963) (xy 143.13323 -14.571205) (xy 143.184942 -14.533631) (xy 143.240956 -14.502835)
			(xy 143.300387 -14.479302) (xy 143.362299 -14.463404) (xy 143.425716 -14.455389) (xy 143.457676 -14.454886)
			(xy 143.489711 -14.45539) (xy 143.553275 -14.463436) (xy 143.615325 -14.479403) (xy 143.674877 -14.503038)
			(xy 143.730988 -14.533967) (xy 143.782769 -14.5717) (xy 143.806418 -14.593316) (xy 143.813276 -14.599666)
			(xy 143.830294 -14.606778) (xy 143.90751 -14.60881) (xy 143.916766 -14.608666) (xy 143.934219 -14.602532)
			(xy 143.941546 -14.596872) (xy 143.9418 -14.596618) (xy 143.964823 -14.577575) (xy 144.014561 -14.544466)
			(xy 144.067836 -14.517414) (xy 144.123915 -14.496793) (xy 144.182024 -14.482887) (xy 144.241363 -14.475888)
			(xy 144.271238 -14.47546) (xy 144.303195 -14.476028) (xy 144.366606 -14.484043) (xy 144.428512 -14.499942)
			(xy 144.487937 -14.523474) (xy 144.543945 -14.554268) (xy 144.595652 -14.591839) (xy 144.642242 -14.635594)
			(xy 144.682981 -14.684842) (xy 144.717227 -14.738808) (xy 144.74444 -14.796641) (xy 144.76419 -14.857428)
			(xy 144.773607 -14.9068) (xy 145.22672 -14.9068) (xy 145.230735 -14.842995) (xy 145.242714 -14.780197)
			(xy 145.26247 -14.719395) (xy 145.289691 -14.661549) (xy 145.323947 -14.60757) (xy 145.364698 -14.55831)
			(xy 145.411301 -14.514547) (xy 145.463023 -14.476969) (xy 145.519046 -14.44617) (xy 145.578487 -14.422636)
			(xy 145.64041 -14.406737) (xy 145.703837 -14.398725) (xy 145.735802 -14.398244) (xy 145.767304 -14.398743)
			(xy 145.829824 -14.406529) (xy 145.890903 -14.421982) (xy 145.949604 -14.444865) (xy 146.005027 -14.474827)
			(xy 146.03095 -14.492732) (xy 146.040524 -14.49875) (xy 146.062759 -14.50267) (xy 146.084515 -14.496631)
			(xy 146.093434 -14.489684) (xy 146.116563 -14.470338) (xy 146.166578 -14.436654) (xy 146.22023 -14.409129)
			(xy 146.276762 -14.388148) (xy 146.335381 -14.374007) (xy 146.395262 -14.366906) (xy 146.425412 -14.366494)
			(xy 146.457373 -14.366993) (xy 146.52079 -14.375005) (xy 146.582703 -14.390903) (xy 146.642135 -14.414435)
			(xy 146.698149 -14.445231) (xy 146.749862 -14.482803) (xy 146.796458 -14.526561) (xy 146.80794 -14.540441)
			(xy 158.973768 -14.540441) (xy 158.973768 -14.476519) (xy 158.981779 -14.413101) (xy 158.997676 -14.351187)
			(xy 159.021208 -14.291754) (xy 159.052002 -14.235739) (xy 159.089575 -14.184024) (xy 159.133332 -14.137427)
			(xy 159.182585 -14.096682) (xy 159.236556 -14.062431) (xy 159.294395 -14.035214) (xy 159.355188 -14.015461)
			(xy 159.417978 -14.003483) (xy 159.481774 -13.99947) (xy 159.54557 -14.003483) (xy 159.60836 -14.015461)
			(xy 159.669153 -14.035214) (xy 159.726992 -14.062431) (xy 159.780963 -14.096682) (xy 159.830216 -14.137427)
			(xy 159.873973 -14.184024) (xy 159.911546 -14.235739) (xy 159.94234 -14.291754) (xy 159.965872 -14.351187)
			(xy 159.981769 -14.413101) (xy 159.98978 -14.476519) (xy 159.990282 -14.50848) (xy 159.98978 -14.540441)
			(xy 159.981769 -14.603859) (xy 159.965872 -14.665773) (xy 159.94234 -14.725206) (xy 159.911546 -14.781221)
			(xy 159.873973 -14.832936) (xy 159.87339 -14.833557) (xy 162.217856 -14.833557) (xy 162.217856 -14.769635)
			(xy 162.225867 -14.706217) (xy 162.241764 -14.644303) (xy 162.265296 -14.58487) (xy 162.29609 -14.528855)
			(xy 162.333663 -14.47714) (xy 162.37742 -14.430543) (xy 162.426673 -14.389798) (xy 162.480644 -14.355547)
			(xy 162.538483 -14.32833) (xy 162.599276 -14.308577) (xy 162.662066 -14.296599) (xy 162.725862 -14.292586)
			(xy 162.789658 -14.296599) (xy 162.852448 -14.308577) (xy 162.913241 -14.32833) (xy 162.97108 -14.355547)
			(xy 163.025051 -14.389798) (xy 163.074304 -14.430543) (xy 163.118061 -14.47714) (xy 163.155634 -14.528855)
			(xy 163.186428 -14.58487) (xy 163.20996 -14.644303) (xy 163.225857 -14.706217) (xy 163.233868 -14.769635)
			(xy 163.23437 -14.801596) (xy 163.233868 -14.833557) (xy 163.225857 -14.896975) (xy 163.20996 -14.958889)
			(xy 163.186428 -15.018322) (xy 163.155634 -15.074337) (xy 163.118061 -15.126052) (xy 163.074304 -15.172649)
			(xy 163.025051 -15.213394) (xy 162.97108 -15.247645) (xy 162.913241 -15.274862) (xy 162.852448 -15.294615)
			(xy 162.789658 -15.306593) (xy 162.725862 -15.310607) (xy 162.662066 -15.306593) (xy 162.599276 -15.294615)
			(xy 162.538483 -15.274862) (xy 162.480644 -15.247645) (xy 162.426673 -15.213394) (xy 162.37742 -15.172649)
			(xy 162.333663 -15.126052) (xy 162.29609 -15.074337) (xy 162.265296 -15.018322) (xy 162.241764 -14.958889)
			(xy 162.225867 -14.896975) (xy 162.217856 -14.833557) (xy 159.87339 -14.833557) (xy 159.830216 -14.879533)
			(xy 159.780963 -14.920278) (xy 159.726992 -14.954529) (xy 159.669153 -14.981746) (xy 159.60836 -15.001499)
			(xy 159.54557 -15.013477) (xy 159.481774 -15.017491) (xy 159.417978 -15.013477) (xy 159.355188 -15.001499)
			(xy 159.294395 -14.981746) (xy 159.236556 -14.954529) (xy 159.182585 -14.920278) (xy 159.133332 -14.879533)
			(xy 159.089575 -14.832936) (xy 159.052002 -14.781221) (xy 159.021208 -14.725206) (xy 158.997676 -14.665773)
			(xy 158.981779 -14.603859) (xy 158.973768 -14.540441) (xy 146.80794 -14.540441) (xy 146.837203 -14.575814)
			(xy 146.871453 -14.629785) (xy 146.898669 -14.687623) (xy 146.918421 -14.748416) (xy 146.930399 -14.811205)
			(xy 146.934413 -14.875) (xy 146.930399 -14.938795) (xy 146.918421 -15.001584) (xy 146.898669 -15.062377)
			(xy 146.871453 -15.120215) (xy 146.837203 -15.174186) (xy 146.796458 -15.223439) (xy 146.749862 -15.267197)
			(xy 146.698149 -15.304769) (xy 146.664962 -15.323015) (xy 149.623774 -15.323015) (xy 149.623774 -15.259093)
			(xy 149.631785 -15.195675) (xy 149.647682 -15.133761) (xy 149.671214 -15.074328) (xy 149.702008 -15.018313)
			(xy 149.739581 -14.966598) (xy 149.783338 -14.920001) (xy 149.832591 -14.879256) (xy 149.886562 -14.845005)
			(xy 149.944401 -14.817788) (xy 150.005194 -14.798035) (xy 150.067984 -14.786057) (xy 150.13178 -14.782044)
			(xy 150.195576 -14.786057) (xy 150.258366 -14.798035) (xy 150.319159 -14.817788) (xy 150.376998 -14.845005)
			(xy 150.430969 -14.879256) (xy 150.480222 -14.920001) (xy 150.523979 -14.966598) (xy 150.561552 -15.018313)
			(xy 150.592346 -15.074328) (xy 150.615878 -15.133761) (xy 150.631775 -15.195675) (xy 150.639786 -15.259093)
			(xy 150.640288 -15.291054) (xy 150.639786 -15.323015) (xy 150.636577 -15.348415) (xy 152.164536 -15.348415)
			(xy 152.164536 -15.284493) (xy 152.172547 -15.221075) (xy 152.188444 -15.159161) (xy 152.211976 -15.099728)
			(xy 152.24277 -15.043713) (xy 152.280343 -14.991998) (xy 152.3241 -14.945401) (xy 152.373353 -14.904656)
			(xy 152.427324 -14.870405) (xy 152.485163 -14.843188) (xy 152.545956 -14.823435) (xy 152.608746 -14.811457)
			(xy 152.672542 -14.807444) (xy 152.736338 -14.811457) (xy 152.799128 -14.823435) (xy 152.859921 -14.843188)
			(xy 152.91776 -14.870405) (xy 152.971731 -14.904656) (xy 153.020984 -14.945401) (xy 153.064741 -14.991998)
			(xy 153.102314 -15.043713) (xy 153.133108 -15.099728) (xy 153.15664 -15.159161) (xy 153.172537 -15.221075)
			(xy 153.180548 -15.284493) (xy 153.18105 -15.316454) (xy 153.180548 -15.348415) (xy 153.482796 -15.348415)
			(xy 153.482796 -15.284493) (xy 153.490807 -15.221075) (xy 153.506704 -15.159161) (xy 153.530236 -15.099728)
			(xy 153.56103 -15.043713) (xy 153.598603 -14.991998) (xy 153.64236 -14.945401) (xy 153.691613 -14.904656)
			(xy 153.745584 -14.870405) (xy 153.803423 -14.843188) (xy 153.864216 -14.823435) (xy 153.927006 -14.811457)
			(xy 153.990802 -14.807444) (xy 154.054598 -14.811457) (xy 154.117388 -14.823435) (xy 154.178181 -14.843188)
			(xy 154.23602 -14.870405) (xy 154.289991 -14.904656) (xy 154.339244 -14.945401) (xy 154.383001 -14.991998)
			(xy 154.420574 -15.043713) (xy 154.451368 -15.099728) (xy 154.4749 -15.159161) (xy 154.490797 -15.221075)
			(xy 154.498808 -15.284493) (xy 154.49931 -15.316454) (xy 154.498904 -15.342319) (xy 154.83306 -15.342319)
			(xy 154.83306 -15.278397) (xy 154.841071 -15.214979) (xy 154.856968 -15.153065) (xy 154.8805 -15.093632)
			(xy 154.911294 -15.037617) (xy 154.948867 -14.985902) (xy 154.992624 -14.939305) (xy 155.041877 -14.89856)
			(xy 155.095848 -14.864309) (xy 155.153687 -14.837092) (xy 155.21448 -14.817339) (xy 155.27727 -14.805361)
			(xy 155.341066 -14.801348) (xy 155.404862 -14.805361) (xy 155.467652 -14.817339) (xy 155.528445 -14.837092)
			(xy 155.586284 -14.864309) (xy 155.640255 -14.89856) (xy 155.689508 -14.939305) (xy 155.733265 -14.985902)
			(xy 155.770838 -15.037617) (xy 155.801632 -15.093632) (xy 155.825164 -15.153065) (xy 155.841061 -15.214979)
			(xy 155.849072 -15.278397) (xy 155.849574 -15.310358) (xy 155.849072 -15.342319) (xy 156.163004 -15.342319)
			(xy 156.163004 -15.278397) (xy 156.171015 -15.214979) (xy 156.186912 -15.153065) (xy 156.210444 -15.093632)
			(xy 156.241238 -15.037617) (xy 156.278811 -14.985902) (xy 156.322568 -14.939305) (xy 156.371821 -14.89856)
			(xy 156.425792 -14.864309) (xy 156.483631 -14.837092) (xy 156.544424 -14.817339) (xy 156.607214 -14.805361)
			(xy 156.67101 -14.801348) (xy 156.734806 -14.805361) (xy 156.797596 -14.817339) (xy 156.858389 -14.837092)
			(xy 156.916228 -14.864309) (xy 156.970199 -14.89856) (xy 157.019452 -14.939305) (xy 157.063209 -14.985902)
			(xy 157.100782 -15.037617) (xy 157.131576 -15.093632) (xy 157.155108 -15.153065) (xy 157.171005 -15.214979)
			(xy 157.179016 -15.278397) (xy 157.179518 -15.310358) (xy 157.179016 -15.342319) (xy 157.171005 -15.405737)
			(xy 157.167984 -15.417503) (xy 157.532572 -15.417503) (xy 157.532572 -15.353581) (xy 157.540583 -15.290163)
			(xy 157.55648 -15.228249) (xy 157.580012 -15.168816) (xy 157.610806 -15.112801) (xy 157.648379 -15.061086)
			(xy 157.692136 -15.014489) (xy 157.741389 -14.973744) (xy 157.79536 -14.939493) (xy 157.853199 -14.912276)
			(xy 157.913992 -14.892523) (xy 157.976782 -14.880545) (xy 158.040578 -14.876532) (xy 158.104374 -14.880545)
			(xy 158.167164 -14.892523) (xy 158.227957 -14.912276) (xy 158.285796 -14.939493) (xy 158.339767 -14.973744)
			(xy 158.38902 -15.014489) (xy 158.432777 -15.061086) (xy 158.47035 -15.112801) (xy 158.501144 -15.168816)
			(xy 158.524676 -15.228249) (xy 158.540573 -15.290163) (xy 158.548584 -15.353581) (xy 158.549086 -15.385542)
			(xy 158.548584 -15.417503) (xy 158.546018 -15.437816) (xy 164.848677 -15.437816) (xy 164.853882 -15.374947)
			(xy 164.866824 -15.313205) (xy 164.887303 -15.253538) (xy 164.915005 -15.196861) (xy 164.949504 -15.144047)
			(xy 164.990271 -15.095906) (xy 165.03668 -15.053176) (xy 165.088018 -15.016516) (xy 165.143496 -14.986486)
			(xy 165.202263 -14.96355) (xy 165.263415 -14.948059) (xy 165.326014 -14.94025) (xy 165.357556 -14.939772)
			(xy 165.39295 -14.940378) (xy 165.463055 -14.950196) (xy 165.497256 -14.95933) (xy 165.509194 -14.962886)
			(xy 165.533578 -14.957806) (xy 165.608 -14.8971) (xy 165.617049 -14.888774) (xy 165.626737 -14.866215)
			(xy 165.626542 -14.85392) (xy 165.626542 -14.853412) (xy 165.625272 -14.824456) (xy 165.625272 -14.823948)
			(xy 165.625775 -14.796709) (xy 165.633561 -14.742788) (xy 165.648938 -14.690524) (xy 165.671594 -14.640979)
			(xy 165.701067 -14.59516) (xy 165.736758 -14.554) (xy 165.777942 -14.518336) (xy 165.82378 -14.488894)
			(xy 165.87334 -14.466271) (xy 165.925615 -14.450929) (xy 165.97954 -14.443179) (xy 166.03402 -14.443179)
			(xy 166.087945 -14.450929) (xy 166.14022 -14.466271) (xy 166.18978 -14.488894) (xy 166.235618 -14.518336)
			(xy 166.276802 -14.554) (xy 166.312493 -14.59516) (xy 166.341966 -14.640979) (xy 166.364622 -14.690524)
			(xy 166.372853 -14.7185) (xy 171.526527 -14.7185) (xy 171.530541 -14.654711) (xy 171.542517 -14.591928)
			(xy 171.562267 -14.531141) (xy 171.589479 -14.473309) (xy 171.623726 -14.419343) (xy 171.664465 -14.370095)
			(xy 171.711056 -14.326341) (xy 171.762763 -14.288771) (xy 171.81877 -14.257977) (xy 171.878196 -14.234446)
			(xy 171.940102 -14.218548) (xy 172.003513 -14.210534) (xy 172.03547 -14.21003) (xy 172.067965 -14.210585)
			(xy 172.132424 -14.218866) (xy 172.195302 -14.235297) (xy 172.255573 -14.25961) (xy 172.312252 -14.291408)
			(xy 172.364415 -14.330172) (xy 172.41121 -14.375269) (xy 172.451875 -14.425964) (xy 172.485746 -14.48143)
			(xy 172.512269 -14.540761) (xy 172.522134 -14.571726) (xy 172.525105 -14.58029) (xy 172.536034 -14.594736)
			(xy 172.54347 -14.59992) (xy 172.56887 -14.61643) (xy 172.576477 -14.620851) (xy 172.593626 -14.62474)
			(xy 172.602398 -14.62405) (xy 172.613846 -14.622741) (xy 172.636849 -14.621341) (xy 172.648372 -14.621256)
			(xy 172.648626 -14.621256) (xy 172.67726 -14.621739) (xy 172.733887 -14.630291) (xy 172.788598 -14.647214)
			(xy 172.840164 -14.672127) (xy 172.887425 -14.704471) (xy 172.908722 -14.723618) (xy 172.915563 -14.729459)
			(xy 172.932136 -14.736416) (xy 172.950093 -14.737198) (xy 172.95876 -14.734794) (xy 173.043342 -14.70787)
			(xy 173.051749 -14.704796) (xy 173.065888 -14.693836) (xy 173.075415 -14.678696) (xy 173.077632 -14.670024)
			(xy 173.077632 -14.66977) (xy 173.084436 -14.638863) (xy 173.104734 -14.578917) (xy 173.132316 -14.521955)
			(xy 173.166753 -14.468856) (xy 173.207515 -14.420442) (xy 173.253971 -14.377462) (xy 173.305401 -14.34058)
			(xy 173.361012 -14.310366) (xy 173.419943 -14.287288) (xy 173.481282 -14.271702) (xy 173.544082 -14.263851)
			(xy 173.575726 -14.26337) (xy 173.607685 -14.263917) (xy 173.671097 -14.271931) (xy 173.733006 -14.28783)
			(xy 173.792434 -14.311361) (xy 173.848444 -14.342156) (xy 173.900153 -14.379727) (xy 173.946745 -14.423483)
			(xy 173.987486 -14.472732) (xy 174.021734 -14.5267) (xy 174.048948 -14.584535) (xy 174.068699 -14.645324)
			(xy 174.080675 -14.708109) (xy 174.084689 -14.7719) (xy 174.080675 -14.835691) (xy 174.068699 -14.898476)
			(xy 174.048948 -14.959265) (xy 174.021734 -15.0171) (xy 173.987486 -15.071068) (xy 173.946745 -15.120317)
			(xy 173.900153 -15.164073) (xy 173.848444 -15.201644) (xy 173.792434 -15.232439) (xy 173.733006 -15.25597)
			(xy 173.671097 -15.271869) (xy 173.607685 -15.279883) (xy 173.575726 -15.280386) (xy 173.543728 -15.279919)
			(xy 173.480238 -15.271896) (xy 173.418256 -15.255973) (xy 173.35876 -15.232401) (xy 173.30269 -15.201554)
			(xy 173.250932 -15.163918) (xy 173.204304 -15.120087) (xy 173.18355 -15.095728) (xy 173.174914 -15.08506)
			(xy 173.149006 -15.075408) (xy 173.034706 -15.096236) (xy 173.013878 -15.11427) (xy 173.009306 -15.127224)
			(xy 173.0003 -15.151898) (xy 172.976513 -15.198726) (xy 172.946528 -15.241849) (xy 172.910911 -15.280451)
			(xy 172.870337 -15.313804) (xy 172.825571 -15.341277) (xy 172.792871 -15.3556) (xy 176.076859 -15.3556)
			(xy 176.080873 -15.291802) (xy 176.092851 -15.22901) (xy 176.112604 -15.168214) (xy 176.139821 -15.110373)
			(xy 176.174073 -15.0564) (xy 176.214819 -15.007145) (xy 176.261417 -14.963385) (xy 176.313132 -14.92581)
			(xy 176.369148 -14.895013) (xy 176.428583 -14.871479) (xy 176.490498 -14.855579) (xy 176.553918 -14.847565)
			(xy 176.58588 -14.847062) (xy 176.586134 -14.847062) (xy 176.620596 -14.84762) (xy 176.688887 -14.856945)
			(xy 176.755294 -14.875406) (xy 176.818599 -14.902666) (xy 176.877644 -14.938224) (xy 176.931346 -14.981429)
			(xy 176.95545 -15.006066) (xy 176.962054 -15.013178) (xy 176.979072 -15.021306) (xy 177.066702 -15.027402)
			(xy 177.084736 -15.021814) (xy 177.092356 -15.015718) (xy 177.119449 -14.994823) (xy 177.178197 -14.959751)
			(xy 177.24112 -14.932879) (xy 177.30708 -14.914695) (xy 177.374884 -14.905526) (xy 177.409094 -14.904974)
			(xy 177.409348 -14.904974) (xy 177.441306 -14.905515) (xy 177.504717 -14.913531) (xy 177.566624 -14.929431)
			(xy 177.62605 -14.952965) (xy 177.682058 -14.98376) (xy 177.733765 -15.021332) (xy 177.780355 -15.065087)
			(xy 177.821095 -15.114337) (xy 177.855341 -15.168304) (xy 177.882554 -15.226138) (xy 177.902303 -15.286926)
			(xy 177.914279 -15.34971) (xy 177.918293 -15.4135) (xy 177.914279 -15.47729) (xy 177.902303 -15.540074)
			(xy 177.882554 -15.600862) (xy 177.855341 -15.658696) (xy 177.821095 -15.712663) (xy 177.780355 -15.761913)
			(xy 177.733765 -15.805668) (xy 177.682058 -15.84324) (xy 177.62605 -15.874035) (xy 177.566624 -15.897569)
			(xy 177.504717 -15.913469) (xy 177.441306 -15.921485) (xy 177.409348 -15.92199) (xy 177.409094 -15.92199)
			(xy 177.374633 -15.921398) (xy 177.306344 -15.912077) (xy 177.239939 -15.893622) (xy 177.176634 -15.866369)
			(xy 177.117588 -15.830817) (xy 177.063884 -15.787619) (xy 177.039778 -15.762986) (xy 177.033174 -15.755874)
			(xy 177.016156 -15.747746) (xy 176.928526 -15.74165) (xy 176.910492 -15.747238) (xy 176.902872 -15.753334)
			(xy 176.875775 -15.774224) (xy 176.817027 -15.809295) (xy 176.754105 -15.836167) (xy 176.688147 -15.854353)
			(xy 176.620344 -15.863524) (xy 176.586134 -15.864078) (xy 176.58588 -15.864078) (xy 176.553918 -15.863635)
			(xy 176.490498 -15.855621) (xy 176.428583 -15.839721) (xy 176.369148 -15.816187) (xy 176.313132 -15.78539)
			(xy 176.261417 -15.747815) (xy 176.214819 -15.704055) (xy 176.174073 -15.6548) (xy 176.139821 -15.600827)
			(xy 176.112604 -15.542986) (xy 176.092851 -15.48219) (xy 176.080873 -15.419398) (xy 176.076859 -15.3556)
			(xy 172.792871 -15.3556) (xy 172.77746 -15.36235) (xy 172.726914 -15.376625) (xy 172.674888 -15.383833)
			(xy 172.648626 -15.384272) (xy 172.621658 -15.383804) (xy 172.56826 -15.376199) (xy 172.516465 -15.361149)
			(xy 172.467306 -15.338956) (xy 172.421762 -15.310061) (xy 172.380741 -15.275041) (xy 172.34506 -15.234593)
			(xy 172.329856 -15.212314) (xy 172.324734 -15.205188) (xy 172.310696 -15.194673) (xy 172.302424 -15.19174)
			(xy 172.273468 -15.18285) (xy 172.264701 -15.180535) (xy 172.24661 -15.181587) (xy 172.238162 -15.184882)
			(xy 172.206061 -15.198237) (xy 172.139114 -15.217008) (xy 172.070234 -15.22648) (xy 172.03547 -15.227046)
			(xy 172.003513 -15.226466) (xy 171.940102 -15.218452) (xy 171.878196 -15.202554) (xy 171.81877 -15.179023)
			(xy 171.762763 -15.148229) (xy 171.711056 -15.110659) (xy 171.664465 -15.066905) (xy 171.623726 -15.017657)
			(xy 171.589479 -14.963691) (xy 171.562267 -14.905859) (xy 171.542517 -14.845072) (xy 171.530541 -14.782289)
			(xy 171.526527 -14.7185) (xy 166.372853 -14.7185) (xy 166.379999 -14.742788) (xy 166.387785 -14.796709)
			(xy 166.388288 -14.823948) (xy 166.388288 -14.824456) (xy 166.388034 -14.83487) (xy 166.388123 -14.843706)
			(xy 166.393673 -14.860473) (xy 166.404606 -14.874342) (xy 166.41191 -14.87932) (xy 166.498524 -14.933168)
			(xy 166.525448 -14.93393) (xy 166.537386 -14.92758) (xy 166.56507 -14.913372) (xy 166.623151 -14.891035)
			(xy 166.683524 -14.875956) (xy 166.745286 -14.868359) (xy 166.7764 -14.86789) (xy 166.809271 -14.86839)
			(xy 166.874466 -14.876852) (xy 166.938026 -14.893646) (xy 166.998892 -14.918492) (xy 167.056047 -14.950977)
			(xy 167.108538 -14.990558) (xy 167.155489 -15.036575) (xy 167.196117 -15.08826) (xy 167.229745 -15.14475)
			(xy 167.243252 -15.174722) (xy 167.249094 -15.188438) (xy 167.27297 -15.204694) (xy 167.393874 -15.209266)
			(xy 167.419274 -15.194788) (xy 167.426132 -15.181834) (xy 167.44089 -15.154974) (xy 167.475856 -15.104642)
			(xy 167.516616 -15.058875) (xy 167.56258 -15.018337) (xy 167.613081 -14.983614) (xy 167.667388 -14.95521)
			(xy 167.724713 -14.933536) (xy 167.784228 -14.918907) (xy 167.845069 -14.911533) (xy 167.875712 -14.91107)
			(xy 167.907671 -14.911617) (xy 167.971085 -14.919629) (xy 168.032995 -14.935526) (xy 168.092425 -14.959057)
			(xy 168.148436 -14.989851) (xy 168.200147 -15.027422) (xy 168.246741 -15.071178) (xy 168.287483 -15.120428)
			(xy 168.321732 -15.174396) (xy 168.348947 -15.232232) (xy 168.368698 -15.293022) (xy 168.380675 -15.355808)
			(xy 168.384689 -15.4196) (xy 168.380675 -15.483392) (xy 168.368698 -15.546178) (xy 168.348947 -15.606968)
			(xy 168.321732 -15.664804) (xy 168.287483 -15.718772) (xy 168.246741 -15.768022) (xy 168.200147 -15.811778)
			(xy 168.148436 -15.849349) (xy 168.092425 -15.880143) (xy 168.032995 -15.903674) (xy 167.971085 -15.919571)
			(xy 167.907671 -15.927583) (xy 167.875712 -15.928086) (xy 167.842841 -15.92759) (xy 167.777645 -15.91913)
			(xy 167.714084 -15.902336) (xy 167.653218 -15.87749) (xy 167.596062 -15.845004) (xy 167.543571 -15.805423)
			(xy 167.49662 -15.759405) (xy 167.455992 -15.707719) (xy 167.422366 -15.651227) (xy 167.40886 -15.621254)
			(xy 167.403018 -15.607538) (xy 167.379142 -15.591282) (xy 167.258238 -15.58671) (xy 167.232838 -15.601188)
			(xy 167.22598 -15.614142) (xy 167.211203 -15.640991) (xy 167.17624 -15.691324) (xy 167.135483 -15.737092)
			(xy 167.089522 -15.777631) (xy 167.039023 -15.812355) (xy 166.984719 -15.840761) (xy 166.927395 -15.862436)
			(xy 166.867882 -15.877067) (xy 166.807042 -15.884442) (xy 166.7764 -15.884906) (xy 166.745668 -15.884462)
			(xy 166.684652 -15.877054) (xy 166.624973 -15.862344) (xy 166.567503 -15.840549) (xy 166.513079 -15.811985)
			(xy 166.462495 -15.777069) (xy 166.416488 -15.73631) (xy 166.37573 -15.690303) (xy 166.340814 -15.639719)
			(xy 166.312251 -15.585295) (xy 166.290455 -15.527825) (xy 166.275746 -15.468146) (xy 166.268338 -15.40713)
			(xy 166.267892 -15.376398) (xy 166.268125 -15.355664) (xy 166.271556 -15.314336) (xy 166.27475 -15.293848)
			(xy 166.27475 -15.293594) (xy 166.275796 -15.284824) (xy 166.272482 -15.267486) (xy 166.263518 -15.252279)
			(xy 166.25697 -15.24635) (xy 166.189152 -15.19047) (xy 166.182093 -15.18506) (xy 166.165334 -15.179128)
			(xy 166.147557 -15.179289) (xy 166.139114 -15.182088) (xy 166.10715 -15.193122) (xy 166.040588 -15.205006)
			(xy 166.00678 -15.20571) (xy 165.995642 -15.205642) (xy 165.973403 -15.204372) (xy 165.96233 -15.20317)
			(xy 165.962076 -15.20317) (xy 165.94985 -15.202513) (xy 165.927026 -15.211259) (xy 165.918388 -15.219934)
			(xy 165.863016 -15.282418) (xy 165.855376 -15.292103) (xy 165.849404 -15.315997) (xy 165.851586 -15.328138)
			(xy 165.858343 -15.357714) (xy 165.865607 -15.417946) (xy 165.866064 -15.44828) (xy 165.865654 -15.479822)
			(xy 165.857853 -15.542422) (xy 165.842369 -15.603576) (xy 165.81944 -15.662345) (xy 165.789418 -15.717827)
			(xy 165.752764 -15.76917) (xy 165.710041 -15.815584) (xy 165.661904 -15.856358) (xy 165.609094 -15.890864)
			(xy 165.552422 -15.918573) (xy 165.492757 -15.939059) (xy 165.431016 -15.952008) (xy 165.368148 -15.957221)
			(xy 165.305118 -15.954618) (xy 165.242894 -15.944238) (xy 165.182431 -15.926241) (xy 165.124659 -15.900904)
			(xy 165.070465 -15.868616) (xy 165.02068 -15.829872) (xy 164.97607 -15.785268) (xy 164.93732 -15.735488)
			(xy 164.905025 -15.681298) (xy 164.879681 -15.623529) (xy 164.861676 -15.563069) (xy 164.851289 -15.500846)
			(xy 164.848677 -15.437816) (xy 158.546018 -15.437816) (xy 158.540573 -15.480921) (xy 158.524676 -15.542835)
			(xy 158.501144 -15.602268) (xy 158.47035 -15.658283) (xy 158.432777 -15.709998) (xy 158.38902 -15.756595)
			(xy 158.339767 -15.79734) (xy 158.285796 -15.831591) (xy 158.227957 -15.858808) (xy 158.167164 -15.878561)
			(xy 158.104374 -15.890539) (xy 158.040578 -15.894553) (xy 157.976782 -15.890539) (xy 157.913992 -15.878561)
			(xy 157.853199 -15.858808) (xy 157.79536 -15.831591) (xy 157.741389 -15.79734) (xy 157.692136 -15.756595)
			(xy 157.648379 -15.709998) (xy 157.610806 -15.658283) (xy 157.580012 -15.602268) (xy 157.55648 -15.542835)
			(xy 157.540583 -15.480921) (xy 157.532572 -15.417503) (xy 157.167984 -15.417503) (xy 157.155108 -15.467651)
			(xy 157.131576 -15.527084) (xy 157.100782 -15.583099) (xy 157.063209 -15.634814) (xy 157.019452 -15.681411)
			(xy 156.970199 -15.722156) (xy 156.916228 -15.756407) (xy 156.858389 -15.783624) (xy 156.797596 -15.803377)
			(xy 156.734806 -15.815355) (xy 156.67101 -15.819369) (xy 156.607214 -15.815355) (xy 156.544424 -15.803377)
			(xy 156.483631 -15.783624) (xy 156.425792 -15.756407) (xy 156.371821 -15.722156) (xy 156.322568 -15.681411)
			(xy 156.278811 -15.634814) (xy 156.241238 -15.583099) (xy 156.210444 -15.527084) (xy 156.186912 -15.467651)
			(xy 156.171015 -15.405737) (xy 156.163004 -15.342319) (xy 155.849072 -15.342319) (xy 155.841061 -15.405737)
			(xy 155.825164 -15.467651) (xy 155.801632 -15.527084) (xy 155.770838 -15.583099) (xy 155.733265 -15.634814)
			(xy 155.689508 -15.681411) (xy 155.640255 -15.722156) (xy 155.586284 -15.756407) (xy 155.528445 -15.783624)
			(xy 155.467652 -15.803377) (xy 155.404862 -15.815355) (xy 155.341066 -15.819369) (xy 155.27727 -15.815355)
			(xy 155.21448 -15.803377) (xy 155.153687 -15.783624) (xy 155.095848 -15.756407) (xy 155.041877 -15.722156)
			(xy 154.992624 -15.681411) (xy 154.948867 -15.634814) (xy 154.911294 -15.583099) (xy 154.8805 -15.527084)
			(xy 154.856968 -15.467651) (xy 154.841071 -15.405737) (xy 154.83306 -15.342319) (xy 154.498904 -15.342319)
			(xy 154.498808 -15.348415) (xy 154.490797 -15.411833) (xy 154.4749 -15.473747) (xy 154.451368 -15.53318)
			(xy 154.420574 -15.589195) (xy 154.383001 -15.64091) (xy 154.339244 -15.687507) (xy 154.289991 -15.728252)
			(xy 154.23602 -15.762503) (xy 154.178181 -15.78972) (xy 154.117388 -15.809473) (xy 154.054598 -15.821451)
			(xy 153.990802 -15.825465) (xy 153.927006 -15.821451) (xy 153.864216 -15.809473) (xy 153.803423 -15.78972)
			(xy 153.745584 -15.762503) (xy 153.691613 -15.728252) (xy 153.64236 -15.687507) (xy 153.598603 -15.64091)
			(xy 153.56103 -15.589195) (xy 153.530236 -15.53318) (xy 153.506704 -15.473747) (xy 153.490807 -15.411833)
			(xy 153.482796 -15.348415) (xy 153.180548 -15.348415) (xy 153.172537 -15.411833) (xy 153.15664 -15.473747)
			(xy 153.133108 -15.53318) (xy 153.102314 -15.589195) (xy 153.064741 -15.64091) (xy 153.020984 -15.687507)
			(xy 152.971731 -15.728252) (xy 152.91776 -15.762503) (xy 152.859921 -15.78972) (xy 152.799128 -15.809473)
			(xy 152.736338 -15.821451) (xy 152.672542 -15.825465) (xy 152.608746 -15.821451) (xy 152.545956 -15.809473)
			(xy 152.485163 -15.78972) (xy 152.427324 -15.762503) (xy 152.373353 -15.728252) (xy 152.3241 -15.687507)
			(xy 152.280343 -15.64091) (xy 152.24277 -15.589195) (xy 152.211976 -15.53318) (xy 152.188444 -15.473747)
			(xy 152.172547 -15.411833) (xy 152.164536 -15.348415) (xy 150.636577 -15.348415) (xy 150.631775 -15.386433)
			(xy 150.615878 -15.448347) (xy 150.592346 -15.50778) (xy 150.561552 -15.563795) (xy 150.523979 -15.61551)
			(xy 150.480222 -15.662107) (xy 150.430969 -15.702852) (xy 150.376998 -15.737103) (xy 150.319159 -15.76432)
			(xy 150.258366 -15.784073) (xy 150.195576 -15.796051) (xy 150.13178 -15.800065) (xy 150.067984 -15.796051)
			(xy 150.005194 -15.784073) (xy 149.944401 -15.76432) (xy 149.886562 -15.737103) (xy 149.832591 -15.702852)
			(xy 149.783338 -15.662107) (xy 149.739581 -15.61551) (xy 149.702008 -15.563795) (xy 149.671214 -15.50778)
			(xy 149.647682 -15.448347) (xy 149.631785 -15.386433) (xy 149.623774 -15.323015) (xy 146.664962 -15.323015)
			(xy 146.642135 -15.335565) (xy 146.582703 -15.359097) (xy 146.52079 -15.374995) (xy 146.457373 -15.383007)
			(xy 146.425412 -15.38351) (xy 146.39391 -15.383012) (xy 146.331389 -15.375227) (xy 146.27031 -15.359774)
			(xy 146.211609 -15.336891) (xy 146.156186 -15.306928) (xy 146.130264 -15.289022) (xy 146.120731 -15.282931)
			(xy 146.09847 -15.279041) (xy 146.076701 -15.285109) (xy 146.06778 -15.29207) (xy 146.044678 -15.311449)
			(xy 145.994657 -15.34513) (xy 145.941 -15.372652) (xy 145.884462 -15.393626) (xy 145.825839 -15.40776)
			(xy 145.765954 -15.414853) (xy 145.735802 -15.41526) (xy 145.703837 -15.414875) (xy 145.64041 -15.406863)
			(xy 145.578487 -15.390964) (xy 145.519046 -15.36743) (xy 145.463023 -15.336631) (xy 145.411301 -15.299053)
			(xy 145.364698 -15.25529) (xy 145.323947 -15.20603) (xy 145.289691 -15.152051) (xy 145.26247 -15.094205)
			(xy 145.242714 -15.033403) (xy 145.230735 -14.970605) (xy 145.22672 -14.9068) (xy 144.773607 -14.9068)
			(xy 144.776165 -14.920211) (xy 144.780179 -14.984) (xy 144.776165 -15.047789) (xy 144.76419 -15.110572)
			(xy 144.74444 -15.171359) (xy 144.717227 -15.229192) (xy 144.682981 -15.283158) (xy 144.642242 -15.332406)
			(xy 144.595652 -15.376161) (xy 144.543945 -15.413732) (xy 144.487937 -15.444526) (xy 144.428512 -15.468058)
			(xy 144.366606 -15.483957) (xy 144.303195 -15.491972) (xy 144.271238 -15.492476) (xy 144.239202 -15.491974)
			(xy 144.175638 -15.483929) (xy 144.113588 -15.467962) (xy 144.054036 -15.444327) (xy 143.997925 -15.413397)
			(xy 143.946144 -15.375663) (xy 143.922496 -15.354046) (xy 143.915638 -15.347696) (xy 143.89862 -15.340584)
			(xy 143.821404 -15.338552) (xy 143.812147 -15.33869) (xy 143.794693 -15.344826) (xy 143.787368 -15.35049)
			(xy 143.787114 -15.350744) (xy 143.76408 -15.369774) (xy 143.714346 -15.402886) (xy 143.661073 -15.429941)
			(xy 143.604996 -15.450564) (xy 143.546888 -15.464472) (xy 143.487551 -15.471473) (xy 143.457676 -15.471902)
			(xy 143.425716 -15.471411) (xy 143.362299 -15.463396) (xy 143.300387 -15.447498) (xy 143.240956 -15.423965)
			(xy 143.184942 -15.393169) (xy 143.13323 -15.355595) (xy 143.086635 -15.311837) (xy 143.045891 -15.262585)
			(xy 143.011642 -15.208614) (xy 142.984426 -15.150776) (xy 142.964674 -15.089984) (xy 142.952697 -15.027195)
			(xy 142.948683 -14.9634) (xy 139.648893 -14.9634) (xy 139.612089 -15.004476) (xy 139.569221 -15.040151)
			(xy 139.521615 -15.069205) (xy 139.470286 -15.091017) (xy 139.416329 -15.105123) (xy 139.360892 -15.111223)
			(xy 139.305158 -15.109186) (xy 139.250315 -15.099056) (xy 139.197531 -15.081049) (xy 139.147931 -15.055548)
			(xy 139.102573 -15.023097) (xy 139.062424 -14.984388) (xy 139.028338 -14.940245) (xy 139.001042 -14.89161)
			(xy 138.981119 -14.839519) (xy 138.968993 -14.785082) (xy 138.964922 -14.72946) (xy 116.655088 -14.72946)
			(xy 116.655088 -15.247366) (xy 121.271028 -15.247366) (xy 121.275099 -15.191744) (xy 121.287225 -15.137307)
			(xy 121.307148 -15.085216) (xy 121.334444 -15.036581) (xy 121.36853 -14.992438) (xy 121.408679 -14.953729)
			(xy 121.454037 -14.921278) (xy 121.503637 -14.895777) (xy 121.556421 -14.87777) (xy 121.611264 -14.86764)
			(xy 121.666998 -14.865603) (xy 121.722435 -14.871703) (xy 121.776392 -14.885809) (xy 121.827721 -14.907621)
			(xy 121.875327 -14.936675) (xy 121.918195 -14.97235) (xy 121.955412 -15.013887) (xy 121.986185 -15.0604)
			(xy 122.009857 -15.110897) (xy 122.025925 -15.164304) (xy 122.034045 -15.21948) (xy 122.034554 -15.247366)
			(xy 122.034045 -15.275252) (xy 122.025925 -15.330428) (xy 122.009857 -15.383835) (xy 121.986185 -15.434332)
			(xy 121.955412 -15.480845) (xy 121.918195 -15.522382) (xy 121.875327 -15.558057) (xy 121.827721 -15.587111)
			(xy 121.776392 -15.608923) (xy 121.722435 -15.623029) (xy 121.666998 -15.629129) (xy 121.611264 -15.627092)
			(xy 121.556421 -15.616962) (xy 121.503637 -15.598955) (xy 121.454037 -15.573454) (xy 121.408679 -15.541003)
			(xy 121.36853 -15.502294) (xy 121.334444 -15.458151) (xy 121.307148 -15.409516) (xy 121.287225 -15.357425)
			(xy 121.275099 -15.302988) (xy 121.271028 -15.247366) (xy 116.655088 -15.247366) (xy 116.655088 -16.50365)
			(xy 121.271028 -16.50365) (xy 121.275099 -16.448028) (xy 121.287225 -16.393591) (xy 121.307148 -16.3415)
			(xy 121.334444 -16.292865) (xy 121.36853 -16.248722) (xy 121.408679 -16.210013) (xy 121.454037 -16.177562)
			(xy 121.503637 -16.152061) (xy 121.556421 -16.134054) (xy 121.611264 -16.123924) (xy 121.666998 -16.121887)
			(xy 121.722435 -16.127987) (xy 121.776392 -16.142093) (xy 121.785527 -16.145975) (xy 148.578056 -16.145975)
			(xy 148.578056 -16.082053) (xy 148.586067 -16.018635) (xy 148.601964 -15.956721) (xy 148.625496 -15.897288)
			(xy 148.65629 -15.841273) (xy 148.693863 -15.789558) (xy 148.73762 -15.742961) (xy 148.786873 -15.702216)
			(xy 148.840844 -15.667965) (xy 148.898683 -15.640748) (xy 148.959476 -15.620995) (xy 149.022266 -15.609017)
			(xy 149.086062 -15.605004) (xy 149.149858 -15.609017) (xy 149.212648 -15.620995) (xy 149.273441 -15.640748)
			(xy 149.33128 -15.667965) (xy 149.385251 -15.702216) (xy 149.434504 -15.742961) (xy 149.478261 -15.789558)
			(xy 149.515834 -15.841273) (xy 149.546628 -15.897288) (xy 149.57016 -15.956721) (xy 149.586057 -16.018635)
			(xy 149.594068 -16.082053) (xy 149.59457 -16.114014) (xy 149.594068 -16.145975) (xy 149.586057 -16.209393)
			(xy 149.57016 -16.271307) (xy 149.546628 -16.33074) (xy 149.515834 -16.386755) (xy 149.478261 -16.43847)
			(xy 149.434504 -16.485067) (xy 149.385251 -16.525812) (xy 149.33128 -16.560063) (xy 149.273441 -16.58728)
			(xy 149.212648 -16.607033) (xy 149.149858 -16.619011) (xy 149.086062 -16.623025) (xy 149.022266 -16.619011)
			(xy 148.959476 -16.607033) (xy 148.898683 -16.58728) (xy 148.840844 -16.560063) (xy 148.786873 -16.525812)
			(xy 148.73762 -16.485067) (xy 148.693863 -16.43847) (xy 148.65629 -16.386755) (xy 148.625496 -16.33074)
			(xy 148.601964 -16.271307) (xy 148.586067 -16.209393) (xy 148.578056 -16.145975) (xy 121.785527 -16.145975)
			(xy 121.827721 -16.163905) (xy 121.875327 -16.192959) (xy 121.918195 -16.228634) (xy 121.955412 -16.270171)
			(xy 121.986185 -16.316684) (xy 122.009857 -16.367181) (xy 122.025925 -16.420588) (xy 122.034045 -16.475764)
			(xy 122.034554 -16.50365) (xy 122.034045 -16.531536) (xy 122.025925 -16.586712) (xy 122.009857 -16.640119)
			(xy 121.986185 -16.690616) (xy 121.955412 -16.737129) (xy 121.918195 -16.778666) (xy 121.875327 -16.814341)
			(xy 121.827721 -16.843395) (xy 121.776392 -16.865207) (xy 121.722435 -16.879313) (xy 121.666998 -16.885413)
			(xy 121.611264 -16.883376) (xy 121.556421 -16.873246) (xy 121.503637 -16.855239) (xy 121.454037 -16.829738)
			(xy 121.408679 -16.797287) (xy 121.36853 -16.758578) (xy 121.334444 -16.714435) (xy 121.307148 -16.6658)
			(xy 121.287225 -16.613709) (xy 121.275099 -16.559272) (xy 121.271028 -16.50365) (xy 116.655088 -16.50365)
			(xy 116.655088 -17.784064) (xy 118.547894 -17.784064) (xy 118.551965 -17.728442) (xy 118.564091 -17.674005)
			(xy 118.584014 -17.621914) (xy 118.61131 -17.573279) (xy 118.645396 -17.529136) (xy 118.685545 -17.490427)
			(xy 118.730903 -17.457976) (xy 118.780503 -17.432475) (xy 118.833287 -17.414468) (xy 118.88813 -17.404338)
			(xy 118.943864 -17.402301) (xy 118.999301 -17.408401) (xy 119.053258 -17.422507) (xy 119.104587 -17.444319)
			(xy 119.152193 -17.473373) (xy 119.195061 -17.509048) (xy 119.232278 -17.550585) (xy 119.263051 -17.597098)
			(xy 119.286723 -17.647595) (xy 119.293087 -17.668748) (xy 129.364992 -17.668748) (xy 129.369063 -17.613126)
			(xy 129.381189 -17.558689) (xy 129.401112 -17.506598) (xy 129.428408 -17.457963) (xy 129.462494 -17.41382)
			(xy 129.502643 -17.375111) (xy 129.548001 -17.34266) (xy 129.597601 -17.317159) (xy 129.650385 -17.299152)
			(xy 129.705228 -17.289022) (xy 129.760962 -17.286985) (xy 129.816399 -17.293085) (xy 129.870356 -17.307191)
			(xy 129.921685 -17.329003) (xy 129.969291 -17.358057) (xy 130.012159 -17.393732) (xy 130.049376 -17.435269)
			(xy 130.080149 -17.481782) (xy 130.103821 -17.532279) (xy 130.119889 -17.585686) (xy 130.128009 -17.640862)
			(xy 130.128263 -17.654778) (xy 131.16687 -17.654778) (xy 131.167357 -17.627527) (xy 131.175116 -17.573581)
			(xy 131.190473 -17.521287) (xy 131.213115 -17.471711) (xy 131.242582 -17.425862) (xy 131.278273 -17.384673)
			(xy 131.319462 -17.348982) (xy 131.365311 -17.319515) (xy 131.414887 -17.296873) (xy 131.467181 -17.281516)
			(xy 131.521127 -17.273757) (xy 131.548378 -17.27327) (xy 131.577346 -17.273784) (xy 131.634617 -17.282546)
			(xy 131.689902 -17.299873) (xy 131.741929 -17.325366) (xy 131.7895 -17.358436) (xy 131.831519 -17.398324)
			(xy 131.86702 -17.44411) (xy 131.895185 -17.49474) (xy 131.915364 -17.549049) (xy 131.921758 -17.577308)
			(xy 131.923948 -17.585911) (xy 131.933318 -17.600978) (xy 131.940046 -17.606772) (xy 131.963922 -17.625568)
			(xy 131.971173 -17.630861) (xy 131.988219 -17.636455) (xy 131.997196 -17.63649) (xy 132.014722 -17.636236)
			(xy 132.049689 -17.636791) (xy 132.11896 -17.646397) (xy 132.186259 -17.665411) (xy 132.250316 -17.693472)
			(xy 132.30992 -17.730052) (xy 132.337302 -17.751806) (xy 132.3443 -17.757078) (xy 132.360804 -17.762924)
			(xy 132.36956 -17.763236) (xy 132.523484 -17.763236) (xy 132.532229 -17.762857) (xy 132.54872 -17.75703)
			(xy 132.555742 -17.751806) (xy 132.583119 -17.73005) (xy 132.642736 -17.693499) (xy 132.706796 -17.665456)
			(xy 132.774092 -17.646448) (xy 132.843358 -17.636835) (xy 132.878322 -17.636236) (xy 132.89915 -17.636744)
			(xy 132.908189 -17.63673) (xy 132.925366 -17.631136) (xy 132.932678 -17.625822) (xy 132.956554 -17.607026)
			(xy 132.963343 -17.601207) (xy 132.972713 -17.585992) (xy 132.974842 -17.577308) (xy 132.981188 -17.549039)
			(xy 133.001381 -17.494734) (xy 133.029556 -17.444109) (xy 133.065065 -17.398328) (xy 133.10709 -17.358446)
			(xy 133.154666 -17.325381) (xy 133.206695 -17.299893) (xy 133.261982 -17.282569) (xy 133.319253 -17.273808)
			(xy 133.348222 -17.27327) (xy 133.375473 -17.273757) (xy 133.429419 -17.281516) (xy 133.481713 -17.296873)
			(xy 133.531289 -17.319515) (xy 133.577138 -17.348982) (xy 133.618327 -17.384673) (xy 133.654018 -17.425862)
			(xy 133.683485 -17.471711) (xy 133.706127 -17.521287) (xy 133.721484 -17.573581) (xy 133.729243 -17.627527)
			(xy 133.72973 -17.654778) (xy 134.766302 -17.654778) (xy 134.770373 -17.599156) (xy 134.782499 -17.544719)
			(xy 134.802422 -17.492628) (xy 134.829718 -17.443993) (xy 134.863804 -17.39985) (xy 134.903953 -17.361141)
			(xy 134.949311 -17.32869) (xy 134.998911 -17.303189) (xy 135.051695 -17.285182) (xy 135.106538 -17.275052)
			(xy 135.162272 -17.273015) (xy 135.217709 -17.279115) (xy 135.271666 -17.293221) (xy 135.322995 -17.315033)
			(xy 135.370601 -17.344087) (xy 135.413469 -17.379762) (xy 135.450686 -17.421299) (xy 135.481459 -17.467812)
			(xy 135.505131 -17.518309) (xy 135.521199 -17.571716) (xy 135.529319 -17.626892) (xy 135.529828 -17.654778)
			(xy 136.566656 -17.654778) (xy 136.567142 -17.627527) (xy 136.574898 -17.573579) (xy 136.590253 -17.521284)
			(xy 136.612895 -17.471707) (xy 136.642361 -17.425857) (xy 136.678052 -17.384666) (xy 136.719243 -17.348975)
			(xy 136.765093 -17.319509) (xy 136.81467 -17.296867) (xy 136.866965 -17.281512) (xy 136.920913 -17.273756)
			(xy 136.975415 -17.273756) (xy 137.029363 -17.281512) (xy 137.081658 -17.296867) (xy 137.131235 -17.319509)
			(xy 137.177085 -17.348975) (xy 137.218276 -17.384666) (xy 137.253967 -17.425857) (xy 137.283433 -17.471707)
			(xy 137.306075 -17.521284) (xy 137.32143 -17.573579) (xy 137.329186 -17.627527) (xy 137.329672 -17.654778)
			(xy 137.329672 -17.65554) (xy 137.328656 -17.682972) (xy 137.328402 -17.68475) (xy 137.328402 -17.689068)
			(xy 137.328777 -17.698775) (xy 137.33598 -17.716802) (xy 137.342372 -17.72412) (xy 137.37971 -17.763236)
			(xy 137.390632 -17.763236) (xy 137.414508 -17.762474) (xy 137.415016 -17.762474) (xy 137.435336 -17.763236)
			(xy 137.438384 -17.763236) (xy 138.278616 -17.763236) (xy 138.297412 -17.76349) (xy 138.30427 -17.763744)
			(xy 138.324082 -17.755616) (xy 138.3538 -17.724628) (xy 138.360271 -17.717271) (xy 138.367581 -17.69911)
			(xy 138.368024 -17.689322) (xy 138.368024 -17.685004) (xy 138.36777 -17.683226) (xy 138.366754 -17.654778)
			(xy 138.36724 -17.627527) (xy 138.374996 -17.573579) (xy 138.390351 -17.521284) (xy 138.412993 -17.471707)
			(xy 138.442459 -17.425857) (xy 138.47815 -17.384666) (xy 138.519341 -17.348975) (xy 138.565191 -17.319509)
			(xy 138.614768 -17.296867) (xy 138.667063 -17.281512) (xy 138.721011 -17.273756) (xy 138.775513 -17.273756)
			(xy 138.829461 -17.281512) (xy 138.881756 -17.296867) (xy 138.931333 -17.319509) (xy 138.977183 -17.348975)
			(xy 139.018374 -17.384666) (xy 139.054065 -17.425857) (xy 139.083531 -17.471707) (xy 139.106173 -17.521284)
			(xy 139.121528 -17.573579) (xy 139.129284 -17.627527) (xy 139.12977 -17.654778) (xy 140.166852 -17.654778)
			(xy 140.167338 -17.627527) (xy 140.175094 -17.573579) (xy 140.190449 -17.521284) (xy 140.213091 -17.471707)
			(xy 140.242557 -17.425857) (xy 140.278248 -17.384666) (xy 140.319439 -17.348975) (xy 140.365289 -17.319509)
			(xy 140.414866 -17.296867) (xy 140.467161 -17.281512) (xy 140.521109 -17.273756) (xy 140.575611 -17.273756)
			(xy 140.629559 -17.281512) (xy 140.681854 -17.296867) (xy 140.731431 -17.319509) (xy 140.777281 -17.348975)
			(xy 140.818472 -17.384666) (xy 140.854163 -17.425857) (xy 140.883629 -17.471707) (xy 140.906271 -17.521284)
			(xy 140.921626 -17.573579) (xy 140.929382 -17.627527) (xy 140.929868 -17.654778) (xy 140.929868 -17.65554)
			(xy 140.928852 -17.682972) (xy 140.928598 -17.68475) (xy 140.928598 -17.689068) (xy 140.928974 -17.698775)
			(xy 140.936177 -17.716802) (xy 140.942568 -17.72412) (xy 140.96492 -17.747488) (xy 140.972413 -17.754622)
			(xy 140.991416 -17.762751) (xy 141.00175 -17.763236) (xy 141.878304 -17.763236) (xy 141.893036 -17.76349)
			(xy 141.893544 -17.76349) (xy 141.904118 -17.763229) (xy 141.923672 -17.755229) (xy 141.93139 -17.747996)
			(xy 141.953742 -17.724628) (xy 141.960218 -17.717275) (xy 141.967524 -17.699111) (xy 141.967966 -17.689322)
			(xy 141.967966 -17.685004) (xy 141.967712 -17.683226) (xy 141.966696 -17.654778) (xy 141.967182 -17.627527)
			(xy 141.974938 -17.573579) (xy 141.990293 -17.521284) (xy 142.012935 -17.471707) (xy 142.042401 -17.425857)
			(xy 142.078092 -17.384666) (xy 142.119283 -17.348975) (xy 142.165133 -17.319509) (xy 142.21471 -17.296867)
			(xy 142.267005 -17.281512) (xy 142.320953 -17.273756) (xy 142.375455 -17.273756) (xy 142.429403 -17.281512)
			(xy 142.481698 -17.296867) (xy 142.531275 -17.319509) (xy 142.577125 -17.348975) (xy 142.618316 -17.384666)
			(xy 142.654007 -17.425857) (xy 142.683473 -17.471707) (xy 142.706115 -17.521284) (xy 142.72147 -17.573579)
			(xy 142.729226 -17.627527) (xy 142.729712 -17.654778) (xy 142.729205 -17.681994) (xy 142.721471 -17.735874)
			(xy 142.706157 -17.788107) (xy 142.683574 -17.837633) (xy 142.654181 -17.883447) (xy 142.618575 -17.924617)
			(xy 142.586815 -17.9522) (xy 147.747001 -17.9522) (xy 147.751015 -17.888406) (xy 147.762992 -17.825619)
			(xy 147.782744 -17.764827) (xy 147.80996 -17.706991) (xy 147.844209 -17.653021) (xy 147.884953 -17.60377)
			(xy 147.931548 -17.560013) (xy 147.98326 -17.522442) (xy 148.039272 -17.491647) (xy 148.098703 -17.468116)
			(xy 148.160615 -17.452219) (xy 148.22403 -17.444206) (xy 148.25599 -17.443704) (xy 148.257006 -17.443704)
			(xy 148.288713 -17.444199) (xy 148.351635 -17.452099) (xy 148.382482 -17.459452) (xy 148.391454 -17.461363)
			(xy 148.40968 -17.459414) (xy 148.418042 -17.455642) (xy 148.444966 -17.441926) (xy 148.453151 -17.437429)
			(xy 148.465674 -17.423588) (xy 148.46935 -17.415002) (xy 148.480853 -17.386767) (xy 148.509662 -17.333031)
			(xy 148.544688 -17.283126) (xy 148.58543 -17.237766) (xy 148.631303 -17.197603) (xy 148.681649 -17.163211)
			(xy 148.735745 -17.135086) (xy 148.792815 -17.11363) (xy 148.852042 -17.099151) (xy 148.912575 -17.091857)
			(xy 148.94306 -17.091406) (xy 148.975025 -17.091857) (xy 149.038451 -17.099864) (xy 149.100373 -17.115759)
			(xy 149.159815 -17.13929) (xy 149.215839 -17.170085) (xy 149.267561 -17.207659) (xy 149.314165 -17.25142)
			(xy 149.354917 -17.300678) (xy 149.389174 -17.354654) (xy 149.416395 -17.412499) (xy 149.436151 -17.473299)
			(xy 149.448131 -17.536097) (xy 149.452146 -17.5999) (xy 149.448131 -17.663703) (xy 149.436151 -17.726501)
			(xy 149.416395 -17.787301) (xy 149.389174 -17.845146) (xy 149.354917 -17.899122) (xy 149.345878 -17.910048)
			(xy 152.876248 -17.910048) (xy 152.880319 -17.854426) (xy 152.892445 -17.799989) (xy 152.912368 -17.747898)
			(xy 152.939664 -17.699263) (xy 152.97375 -17.65512) (xy 153.013899 -17.616411) (xy 153.059257 -17.58396)
			(xy 153.108857 -17.558459) (xy 153.161641 -17.540452) (xy 153.216484 -17.530322) (xy 153.272218 -17.528285)
			(xy 153.327655 -17.534385) (xy 153.381612 -17.548491) (xy 153.432941 -17.570303) (xy 153.480547 -17.599357)
			(xy 153.523415 -17.635032) (xy 153.560632 -17.676569) (xy 153.591405 -17.723082) (xy 153.615077 -17.773579)
			(xy 153.631145 -17.826986) (xy 153.639265 -17.882162) (xy 153.639774 -17.910048) (xy 153.639677 -17.915382)
			(xy 155.876242 -17.915382) (xy 155.880313 -17.85976) (xy 155.892439 -17.805323) (xy 155.912362 -17.753232)
			(xy 155.939658 -17.704597) (xy 155.973744 -17.660454) (xy 156.013893 -17.621745) (xy 156.059251 -17.589294)
			(xy 156.108851 -17.563793) (xy 156.161635 -17.545786) (xy 156.216478 -17.535656) (xy 156.272212 -17.533619)
			(xy 156.327649 -17.539719) (xy 156.381606 -17.553825) (xy 156.432935 -17.575637) (xy 156.480541 -17.604691)
			(xy 156.523409 -17.640366) (xy 156.560626 -17.681903) (xy 156.591399 -17.728416) (xy 156.615071 -17.778913)
			(xy 156.631139 -17.83232) (xy 156.639259 -17.887496) (xy 156.639768 -17.915382) (xy 156.639259 -17.943268)
			(xy 156.631139 -17.998444) (xy 156.615071 -18.051851) (xy 156.591399 -18.102348) (xy 156.560626 -18.148861)
			(xy 156.551836 -18.158671) (xy 158.659062 -18.158671) (xy 158.659062 -18.094749) (xy 158.667073 -18.031331)
			(xy 158.68297 -17.969417) (xy 158.706502 -17.909984) (xy 158.737296 -17.853969) (xy 158.774869 -17.802254)
			(xy 158.818626 -17.755657) (xy 158.867879 -17.714912) (xy 158.92185 -17.680661) (xy 158.979689 -17.653444)
			(xy 159.040482 -17.633691) (xy 159.103272 -17.621713) (xy 159.167068 -17.6177) (xy 159.230864 -17.621713)
			(xy 159.293654 -17.633691) (xy 159.354447 -17.653444) (xy 159.357282 -17.654778) (xy 163.486336 -17.654778)
			(xy 163.490407 -17.599156) (xy 163.502533 -17.544719) (xy 163.522456 -17.492628) (xy 163.549752 -17.443993)
			(xy 163.583838 -17.39985) (xy 163.623987 -17.361141) (xy 163.669345 -17.32869) (xy 163.718945 -17.303189)
			(xy 163.771729 -17.285182) (xy 163.826572 -17.275052) (xy 163.882306 -17.273015) (xy 163.937743 -17.279115)
			(xy 163.9917 -17.293221) (xy 164.043029 -17.315033) (xy 164.090635 -17.344087) (xy 164.133503 -17.379762)
			(xy 164.17072 -17.421299) (xy 164.201493 -17.467812) (xy 164.225165 -17.518309) (xy 164.241233 -17.571716)
			(xy 164.249353 -17.626892) (xy 164.249862 -17.654778) (xy 164.249353 -17.682664) (xy 164.242959 -17.726109)
			(xy 166.243248 -17.726109) (xy 166.243248 -17.662187) (xy 166.251259 -17.598769) (xy 166.267156 -17.536855)
			(xy 166.290688 -17.477422) (xy 166.321482 -17.421407) (xy 166.359055 -17.369692) (xy 166.402812 -17.323095)
			(xy 166.452065 -17.28235) (xy 166.506036 -17.248099) (xy 166.563875 -17.220882) (xy 166.624668 -17.201129)
			(xy 166.687458 -17.189151) (xy 166.751254 -17.185138) (xy 166.81505 -17.189151) (xy 166.87784 -17.201129)
			(xy 166.938633 -17.220882) (xy 166.996472 -17.248099) (xy 167.050443 -17.28235) (xy 167.099696 -17.323095)
			(xy 167.143453 -17.369692) (xy 167.181026 -17.421407) (xy 167.21182 -17.477422) (xy 167.235352 -17.536855)
			(xy 167.251249 -17.598769) (xy 167.25926 -17.662187) (xy 167.259762 -17.694148) (xy 167.25926 -17.726109)
			(xy 167.535346 -17.726109) (xy 167.535346 -17.662187) (xy 167.543357 -17.598769) (xy 167.559254 -17.536855)
			(xy 167.582786 -17.477422) (xy 167.61358 -17.421407) (xy 167.651153 -17.369692) (xy 167.69491 -17.323095)
			(xy 167.744163 -17.28235) (xy 167.798134 -17.248099) (xy 167.855973 -17.220882) (xy 167.916766 -17.201129)
			(xy 167.979556 -17.189151) (xy 168.043352 -17.185138) (xy 168.107148 -17.189151) (xy 168.169938 -17.201129)
			(xy 168.230731 -17.220882) (xy 168.28857 -17.248099) (xy 168.342541 -17.28235) (xy 168.391794 -17.323095)
			(xy 168.435551 -17.369692) (xy 168.473124 -17.421407) (xy 168.503918 -17.477422) (xy 168.52745 -17.536855)
			(xy 168.543347 -17.598769) (xy 168.550422 -17.654778) (xy 168.886376 -17.654778) (xy 168.890447 -17.599156)
			(xy 168.902573 -17.544719) (xy 168.922496 -17.492628) (xy 168.949792 -17.443993) (xy 168.983878 -17.39985)
			(xy 169.024027 -17.361141) (xy 169.069385 -17.32869) (xy 169.118985 -17.303189) (xy 169.171769 -17.285182)
			(xy 169.226612 -17.275052) (xy 169.282346 -17.273015) (xy 169.337783 -17.279115) (xy 169.39174 -17.293221)
			(xy 169.443069 -17.315033) (xy 169.490675 -17.344087) (xy 169.533543 -17.379762) (xy 169.57076 -17.421299)
			(xy 169.601533 -17.467812) (xy 169.625205 -17.518309) (xy 169.641273 -17.571716) (xy 169.649393 -17.626892)
			(xy 169.649902 -17.654778) (xy 169.649393 -17.682664) (xy 169.641273 -17.73784) (xy 169.625205 -17.791247)
			(xy 169.601533 -17.841744) (xy 169.57076 -17.888257) (xy 169.533543 -17.929794) (xy 169.490675 -17.965469)
			(xy 169.443069 -17.994523) (xy 169.39174 -18.016335) (xy 169.337783 -18.030441) (xy 169.282346 -18.036541)
			(xy 169.226612 -18.034504) (xy 169.171769 -18.024374) (xy 169.118985 -18.006367) (xy 169.069385 -17.980866)
			(xy 169.024027 -17.948415) (xy 168.983878 -17.909706) (xy 168.949792 -17.865563) (xy 168.922496 -17.816928)
			(xy 168.902573 -17.764837) (xy 168.890447 -17.7104) (xy 168.886376 -17.654778) (xy 168.550422 -17.654778)
			(xy 168.551358 -17.662187) (xy 168.55186 -17.694148) (xy 168.551358 -17.726109) (xy 168.543347 -17.789527)
			(xy 168.52745 -17.851441) (xy 168.503918 -17.910874) (xy 168.473124 -17.966889) (xy 168.435551 -18.018604)
			(xy 168.391794 -18.065201) (xy 168.342541 -18.105946) (xy 168.28857 -18.140197) (xy 168.230731 -18.167414)
			(xy 168.169938 -18.187167) (xy 168.107148 -18.199145) (xy 168.043352 -18.203159) (xy 167.979556 -18.199145)
			(xy 167.916766 -18.187167) (xy 167.855973 -18.167414) (xy 167.798134 -18.140197) (xy 167.744163 -18.105946)
			(xy 167.69491 -18.065201) (xy 167.651153 -18.018604) (xy 167.61358 -17.966889) (xy 167.582786 -17.910874)
			(xy 167.559254 -17.851441) (xy 167.543357 -17.789527) (xy 167.535346 -17.726109) (xy 167.25926 -17.726109)
			(xy 167.251249 -17.789527) (xy 167.235352 -17.851441) (xy 167.21182 -17.910874) (xy 167.181026 -17.966889)
			(xy 167.143453 -18.018604) (xy 167.099696 -18.065201) (xy 167.050443 -18.105946) (xy 166.996472 -18.140197)
			(xy 166.938633 -18.167414) (xy 166.87784 -18.187167) (xy 166.81505 -18.199145) (xy 166.751254 -18.203159)
			(xy 166.687458 -18.199145) (xy 166.624668 -18.187167) (xy 166.563875 -18.167414) (xy 166.506036 -18.140197)
			(xy 166.452065 -18.105946) (xy 166.402812 -18.065201) (xy 166.359055 -18.018604) (xy 166.321482 -17.966889)
			(xy 166.290688 -17.910874) (xy 166.267156 -17.851441) (xy 166.251259 -17.789527) (xy 166.243248 -17.726109)
			(xy 164.242959 -17.726109) (xy 164.241233 -17.73784) (xy 164.225165 -17.791247) (xy 164.201493 -17.841744)
			(xy 164.17072 -17.888257) (xy 164.133503 -17.929794) (xy 164.090635 -17.965469) (xy 164.043029 -17.994523)
			(xy 163.9917 -18.016335) (xy 163.937743 -18.030441) (xy 163.882306 -18.036541) (xy 163.826572 -18.034504)
			(xy 163.771729 -18.024374) (xy 163.718945 -18.006367) (xy 163.669345 -17.980866) (xy 163.623987 -17.948415)
			(xy 163.583838 -17.909706) (xy 163.549752 -17.865563) (xy 163.522456 -17.816928) (xy 163.502533 -17.764837)
			(xy 163.490407 -17.7104) (xy 163.486336 -17.654778) (xy 159.357282 -17.654778) (xy 159.412286 -17.680661)
			(xy 159.466257 -17.714912) (xy 159.51551 -17.755657) (xy 159.559267 -17.802254) (xy 159.59684 -17.853969)
			(xy 159.627634 -17.909984) (xy 159.651166 -17.969417) (xy 159.667063 -18.031331) (xy 159.675074 -18.094749)
			(xy 159.675576 -18.12671) (xy 159.675074 -18.158671) (xy 159.667063 -18.222089) (xy 159.651166 -18.284003)
			(xy 159.627634 -18.343436) (xy 159.59684 -18.399451) (xy 159.559267 -18.451166) (xy 159.51551 -18.497763)
			(xy 159.466257 -18.538508) (xy 159.412286 -18.572759) (xy 159.354447 -18.599976) (xy 159.293654 -18.619729)
			(xy 159.230864 -18.631707) (xy 159.167068 -18.635721) (xy 159.103272 -18.631707) (xy 159.040482 -18.619729)
			(xy 158.979689 -18.599976) (xy 158.92185 -18.572759) (xy 158.867879 -18.538508) (xy 158.818626 -18.497763)
			(xy 158.774869 -18.451166) (xy 158.737296 -18.399451) (xy 158.706502 -18.343436) (xy 158.68297 -18.284003)
			(xy 158.667073 -18.222089) (xy 158.659062 -18.158671) (xy 156.551836 -18.158671) (xy 156.523409 -18.190398)
			(xy 156.480541 -18.226073) (xy 156.432935 -18.255127) (xy 156.381606 -18.276939) (xy 156.327649 -18.291045)
			(xy 156.272212 -18.297145) (xy 156.216478 -18.295108) (xy 156.161635 -18.284978) (xy 156.108851 -18.266971)
			(xy 156.059251 -18.24147) (xy 156.013893 -18.209019) (xy 155.973744 -18.17031) (xy 155.939658 -18.126167)
			(xy 155.912362 -18.077532) (xy 155.892439 -18.025441) (xy 155.880313 -17.971004) (xy 155.876242 -17.915382)
			(xy 153.639677 -17.915382) (xy 153.639265 -17.937934) (xy 153.631145 -17.99311) (xy 153.615077 -18.046517)
			(xy 153.591405 -18.097014) (xy 153.560632 -18.143527) (xy 153.523415 -18.185064) (xy 153.480547 -18.220739)
			(xy 153.432941 -18.249793) (xy 153.381612 -18.271605) (xy 153.327655 -18.285711) (xy 153.272218 -18.291811)
			(xy 153.216484 -18.289774) (xy 153.161641 -18.279644) (xy 153.108857 -18.261637) (xy 153.059257 -18.236136)
			(xy 153.013899 -18.203685) (xy 152.97375 -18.164976) (xy 152.939664 -18.120833) (xy 152.912368 -18.072198)
			(xy 152.892445 -18.020107) (xy 152.880319 -17.96567) (xy 152.876248 -17.910048) (xy 149.345878 -17.910048)
			(xy 149.314165 -17.94838) (xy 149.267561 -17.992141) (xy 149.215839 -18.029715) (xy 149.159815 -18.06051)
			(xy 149.100373 -18.084041) (xy 149.038451 -18.099936) (xy 148.975025 -18.107943) (xy 148.94306 -18.108422)
			(xy 148.942044 -18.108422) (xy 148.910337 -18.107917) (xy 148.847415 -18.100024) (xy 148.816568 -18.092674)
			(xy 148.8076 -18.090734) (xy 148.789369 -18.092701) (xy 148.781008 -18.096484) (xy 148.754084 -18.1102)
			(xy 148.745901 -18.114702) (xy 148.733376 -18.128538) (xy 148.7297 -18.137124) (xy 148.718199 -18.165361)
			(xy 148.689394 -18.219099) (xy 148.654369 -18.269008) (xy 148.613628 -18.31437) (xy 148.567756 -18.354535)
			(xy 148.517409 -18.388927) (xy 148.463311 -18.417052) (xy 148.406239 -18.438506) (xy 148.34701 -18.452982)
			(xy 148.286476 -18.460271) (xy 148.25599 -18.46072) (xy 148.22403 -18.460194) (xy 148.160615 -18.452181)
			(xy 148.098703 -18.436284) (xy 148.039272 -18.412753) (xy 147.98326 -18.381958) (xy 147.931548 -18.344387)
			(xy 147.884953 -18.30063) (xy 147.844209 -18.251379) (xy 147.80996 -18.197409) (xy 147.782744 -18.139573)
			(xy 147.762992 -18.078781) (xy 147.751015 -18.015994) (xy 147.747001 -17.9522) (xy 142.586815 -17.9522)
			(xy 142.577478 -17.960309) (xy 142.531725 -17.989796) (xy 142.482246 -18.012481) (xy 142.430044 -18.027902)
			(xy 142.376181 -18.035748) (xy 142.348966 -18.036286) (xy 142.339568 -18.04035) (xy 142.33495 -18.042508)
			(xy 142.326633 -18.0484) (xy 142.323058 -18.052034) (xy 142.267178 -18.110708) (xy 142.263368 -18.119852)
			(xy 142.259812 -18.138648) (xy 142.259812 -18.144744) (xy 142.259363 -18.171996) (xy 142.251601 -18.225945)
			(xy 142.23624 -18.27824) (xy 142.213594 -18.327817) (xy 142.184124 -18.373667) (xy 142.148429 -18.414857)
			(xy 142.107235 -18.450548) (xy 142.061382 -18.480013) (xy 142.011803 -18.502654) (xy 141.959506 -18.518009)
			(xy 141.905556 -18.525766) (xy 141.878304 -18.526252) (xy 141.014704 -18.526252) (xy 140.987455 -18.525719)
			(xy 140.933511 -18.517964) (xy 140.88122 -18.502611) (xy 140.831646 -18.479974) (xy 140.785797 -18.450512)
			(xy 140.744608 -18.414826) (xy 140.708917 -18.373641) (xy 140.679449 -18.327797) (xy 140.656805 -18.278225)
			(xy 140.641446 -18.225936) (xy 140.633685 -18.171993) (xy 140.633196 -18.144744) (xy 140.633196 -18.128742)
			(xy 140.629386 -18.119344) (xy 140.62583 -18.1102) (xy 140.563092 -18.044414) (xy 140.545058 -18.036286)
			(xy 140.535152 -18.036032) (xy 140.508533 -18.034659) (xy 140.456037 -18.025424) (xy 140.405338 -18.00897)
			(xy 140.357424 -17.985618) (xy 140.313227 -17.955823) (xy 140.273609 -17.920166) (xy 140.23934 -17.87934)
			(xy 140.211089 -17.834141) (xy 140.189406 -17.785449) (xy 140.174712 -17.734212) (xy 140.167294 -17.681429)
			(xy 140.166852 -17.654778) (xy 139.12977 -17.654778) (xy 139.129304 -17.681996) (xy 139.121569 -17.735879)
			(xy 139.106254 -17.788116) (xy 139.083668 -17.837645) (xy 139.054271 -17.88346) (xy 139.01866 -17.924632)
			(xy 138.977558 -17.960323) (xy 138.9318 -17.98981) (xy 138.882316 -18.012492) (xy 138.830109 -18.02791)
			(xy 138.776241 -18.03575) (xy 138.749024 -18.036286) (xy 138.739626 -18.04035) (xy 138.735039 -18.042481)
			(xy 138.726723 -18.048234) (xy 138.723116 -18.05178) (xy 138.67257 -18.104866) (xy 138.671046 -18.106644)
			(xy 138.666038 -18.113538) (xy 138.660452 -18.129626) (xy 138.660124 -18.13814) (xy 138.660124 -18.14576)
			(xy 138.65955 -18.174321) (xy 138.650877 -18.230783) (xy 138.633883 -18.285321) (xy 138.608948 -18.336717)
			(xy 138.57663 -18.38382) (xy 138.53765 -18.425579) (xy 138.492881 -18.461061) (xy 138.468354 -18.475706)
			(xy 138.446632 -18.487681) (xy 138.400772 -18.506579) (xy 138.352848 -18.519369) (xy 138.30367 -18.525837)
			(xy 138.27887 -18.526252) (xy 137.438384 -18.526252) (xy 137.435336 -18.526252) (xy 137.415016 -18.527014)
			(xy 137.414508 -18.527014) (xy 137.387215 -18.526501) (xy 137.33319 -18.518696) (xy 137.280824 -18.503286)
			(xy 137.231183 -18.480584) (xy 137.185275 -18.451052) (xy 137.144034 -18.41529) (xy 137.1083 -18.374026)
			(xy 137.078797 -18.3281) (xy 137.056128 -18.278443) (xy 137.040751 -18.226067) (xy 137.032981 -18.172037)
			(xy 137.032492 -18.144744) (xy 137.032492 -18.138394) (xy 137.03226 -18.128428) (xy 137.02505 -18.109862)
			(xy 137.018522 -18.102326) (xy 136.962896 -18.044414) (xy 136.944862 -18.036286) (xy 136.934956 -18.036032)
			(xy 136.908337 -18.034655) (xy 136.855841 -18.025421) (xy 136.805143 -18.008967) (xy 136.757228 -17.985616)
			(xy 136.713031 -17.955822) (xy 136.673413 -17.920164) (xy 136.639144 -17.879339) (xy 136.610893 -17.83414)
			(xy 136.58921 -17.785448) (xy 136.574516 -17.734212) (xy 136.567098 -17.681429) (xy 136.566656 -17.654778)
			(xy 135.529828 -17.654778) (xy 135.529319 -17.682664) (xy 135.521199 -17.73784) (xy 135.505131 -17.791247)
			(xy 135.481459 -17.841744) (xy 135.450686 -17.888257) (xy 135.413469 -17.929794) (xy 135.370601 -17.965469)
			(xy 135.322995 -17.994523) (xy 135.271666 -18.016335) (xy 135.217709 -18.030441) (xy 135.162272 -18.036541)
			(xy 135.106538 -18.034504) (xy 135.051695 -18.024374) (xy 134.998911 -18.006367) (xy 134.949311 -17.980866)
			(xy 134.903953 -17.948415) (xy 134.863804 -17.909706) (xy 134.829718 -17.865563) (xy 134.802422 -17.816928)
			(xy 134.782499 -17.764837) (xy 134.770373 -17.7104) (xy 134.766302 -17.654778) (xy 133.72973 -17.654778)
			(xy 133.729242 -17.682861) (xy 133.721005 -17.738421) (xy 133.704704 -17.79217) (xy 133.680694 -17.842946)
			(xy 133.649494 -17.88965) (xy 133.611779 -17.931271) (xy 133.568366 -17.966907) (xy 133.520194 -17.995789)
			(xy 133.468305 -18.01729) (xy 133.441186 -18.024602) (xy 133.432685 -18.0272) (xy 133.418003 -18.037193)
			(xy 133.412484 -18.04416) (xy 133.39445 -18.068798) (xy 133.389458 -18.07635) (xy 133.384643 -18.09379)
			(xy 133.385052 -18.102834) (xy 133.38683 -18.14449) (xy 133.38683 -18.144744) (xy 133.386386 -18.175475)
			(xy 133.378973 -18.236489) (xy 133.36426 -18.296164) (xy 133.342462 -18.353631) (xy 133.313896 -18.408052)
			(xy 133.27898 -18.458633) (xy 133.238222 -18.504637) (xy 133.192216 -18.545393) (xy 133.141633 -18.580308)
			(xy 133.087211 -18.608871) (xy 133.029743 -18.630666) (xy 132.970067 -18.645377) (xy 132.909053 -18.652787)
			(xy 132.878322 -18.653252) (xy 132.843356 -18.652674) (xy 132.774086 -18.643074) (xy 132.706787 -18.624066)
			(xy 132.64273 -18.596009) (xy 132.583125 -18.559434) (xy 132.555742 -18.537682) (xy 132.548732 -18.532427)
			(xy 132.532238 -18.526571) (xy 132.523484 -18.526252) (xy 132.36956 -18.526252) (xy 132.36081 -18.526587)
			(xy 132.344319 -18.532442) (xy 132.337302 -18.537682) (xy 132.309908 -18.559416) (xy 132.250296 -18.595971)
			(xy 132.186241 -18.624019) (xy 132.118948 -18.643031) (xy 132.049685 -18.65265) (xy 132.014722 -18.653252)
			(xy 131.983993 -18.652723) (xy 131.922983 -18.645318) (xy 131.863311 -18.630613) (xy 131.805846 -18.608823)
			(xy 131.751426 -18.580266) (xy 131.700845 -18.545357) (xy 131.654841 -18.504606) (xy 131.614084 -18.458607)
			(xy 131.579169 -18.408031) (xy 131.550604 -18.353615) (xy 131.528806 -18.296152) (xy 131.514094 -18.236482)
			(xy 131.506681 -18.175473) (xy 131.506214 -18.144744) (xy 131.507992 -18.102072) (xy 131.508366 -18.09309)
			(xy 131.503563 -18.075781) (xy 131.498594 -18.06829) (xy 131.481068 -18.043652) (xy 131.475605 -18.036624)
			(xy 131.460907 -18.026601) (xy 131.452366 -18.024094) (xy 131.425471 -18.016592) (xy 131.374067 -17.994795)
			(xy 131.326386 -17.965742) (xy 131.283446 -17.930054) (xy 131.246163 -17.888491) (xy 131.215332 -17.84194)
			(xy 131.191611 -17.791395) (xy 131.175506 -17.737933) (xy 131.167361 -17.682695) (xy 131.16687 -17.654778)
			(xy 130.128263 -17.654778) (xy 130.128518 -17.668748) (xy 130.128009 -17.696634) (xy 130.119889 -17.75181)
			(xy 130.103821 -17.805217) (xy 130.080149 -17.855714) (xy 130.049376 -17.902227) (xy 130.012159 -17.943764)
			(xy 129.969291 -17.979439) (xy 129.921685 -18.008493) (xy 129.870356 -18.030305) (xy 129.816399 -18.044411)
			(xy 129.760962 -18.050511) (xy 129.705228 -18.048474) (xy 129.650385 -18.038344) (xy 129.597601 -18.020337)
			(xy 129.548001 -17.994836) (xy 129.502643 -17.962385) (xy 129.462494 -17.923676) (xy 129.428408 -17.879533)
			(xy 129.401112 -17.830898) (xy 129.381189 -17.778807) (xy 129.369063 -17.72437) (xy 129.364992 -17.668748)
			(xy 119.293087 -17.668748) (xy 119.302791 -17.701002) (xy 119.310911 -17.756178) (xy 119.31142 -17.784064)
			(xy 119.310911 -17.81195) (xy 119.302791 -17.867126) (xy 119.286723 -17.920533) (xy 119.263051 -17.97103)
			(xy 119.232278 -18.017543) (xy 119.195061 -18.05908) (xy 119.152193 -18.094755) (xy 119.104587 -18.123809)
			(xy 119.053258 -18.145621) (xy 118.999301 -18.159727) (xy 118.943864 -18.165827) (xy 118.88813 -18.16379)
			(xy 118.833287 -18.15366) (xy 118.780503 -18.135653) (xy 118.730903 -18.110152) (xy 118.685545 -18.077701)
			(xy 118.645396 -18.038992) (xy 118.61131 -17.994849) (xy 118.584014 -17.946214) (xy 118.564091 -17.894123)
			(xy 118.551965 -17.839686) (xy 118.547894 -17.784064) (xy 116.655088 -17.784064) (xy 116.655088 -18.329148)
			(xy 116.654591 -18.339148) (xy 116.646923 -18.357622) (xy 116.632771 -18.371757) (xy 116.614289 -18.379403)
			(xy 116.604288 -18.379948) (xy 109.825028 -18.379948) (xy 109.815535 -18.381015) (xy 109.798319 -18.389257)
			(xy 109.7915 -18.39595) (xy 109.787182 -18.400522) (xy 109.7407 -18.451068) (xy 109.737509 -18.454688)
			(xy 109.732399 -18.462871) (xy 109.73054 -18.467324) (xy 109.72673 -18.478246) (xy 109.727492 -18.48866)
			(xy 109.728508 -18.516346) (xy 109.728508 -18.5166) (xy 109.728 -18.538444) (xy 109.727746 -18.542254)
			(xy 109.727238 -18.546572) (xy 109.724469 -18.574913) (xy 109.711597 -18.630381) (xy 109.690627 -18.683321)
			(xy 109.662022 -18.732557) (xy 109.62642 -18.776997) (xy 109.58461 -18.815653) (xy 109.53752 -18.847668)
			(xy 109.486195 -18.87233) (xy 109.431776 -18.889092) (xy 109.375471 -18.897583) (xy 109.347 -18.898108)
			(xy 109.31813 -18.897576) (xy 109.26105 -18.888873) (xy 109.205934 -18.871666) (xy 109.154041 -18.846347)
			(xy 109.106557 -18.813496) (xy 109.064568 -18.773862) (xy 109.029032 -18.728353) (xy 109.000763 -18.678007)
			(xy 108.980404 -18.623975) (xy 108.973874 -18.595848) (xy 108.973874 -18.595594) (xy 108.97235 -18.58899)
			(xy 108.96727 -18.578576) (xy 108.963206 -18.57375) (xy 108.959163 -18.569105) (xy 108.949276 -18.56177)
			(xy 108.943648 -18.559272) (xy 108.942632 -18.558764) (xy 108.904786 -18.543524) (xy 108.864908 -18.527522)
			(xy 108.859138 -18.525334) (xy 108.846933 -18.523532) (xy 108.840778 -18.523966) (xy 108.828332 -18.525236)
			(xy 108.817664 -18.532348) (xy 108.792446 -18.548747) (xy 108.738898 -18.576154) (xy 108.68249 -18.597055)
			(xy 108.624011 -18.611156) (xy 108.564277 -18.618263) (xy 108.5342 -18.618708) (xy 108.502239 -18.618206)
			(xy 108.438821 -18.610195) (xy 108.376907 -18.594298) (xy 108.317474 -18.570766) (xy 108.261459 -18.539972)
			(xy 108.209744 -18.502399) (xy 108.163147 -18.458642) (xy 108.122402 -18.409389) (xy 108.088151 -18.355418)
			(xy 108.060934 -18.297579) (xy 108.041181 -18.236786) (xy 108.029203 -18.173996) (xy 108.02519 -18.1102)
			(xy 108.029203 -18.046404) (xy 108.041181 -17.983614) (xy 108.060934 -17.922821) (xy 108.088151 -17.864982)
			(xy 108.122402 -17.811011) (xy 108.163147 -17.761758) (xy 108.209744 -17.718001) (xy 108.261459 -17.680428)
			(xy 108.317474 -17.649634) (xy 108.376907 -17.626102) (xy 108.438821 -17.610205) (xy 108.502239 -17.602194)
			(xy 108.5342 -17.601692) (xy 108.566394 -17.602181) (xy 108.630268 -17.610299) (xy 108.692606 -17.626416)
			(xy 108.75241 -17.650275) (xy 108.808723 -17.681494) (xy 108.860643 -17.719573) (xy 108.90734 -17.763903)
			(xy 108.948066 -17.813775) (xy 108.98217 -17.868389) (xy 109.009104 -17.926873) (xy 109.028439 -17.988289)
			(xy 109.039864 -18.051655) (xy 109.041946 -18.083784) (xy 109.042708 -18.096484) (xy 109.050328 -18.10893)
			(xy 109.053248 -18.113242) (xy 109.060544 -18.120671) (xy 109.064806 -18.123662) (xy 109.073442 -18.128742)
			(xy 109.102652 -18.146268) (xy 109.13872 -18.168112) (xy 109.143308 -18.170778) (xy 109.153297 -18.174353)
			(xy 109.158532 -18.175224) (xy 109.16539 -18.175478) (xy 109.170636 -18.175266) (xy 109.180877 -18.172958)
			(xy 109.18571 -18.170906) (xy 109.186218 -18.170652) (xy 109.21152 -18.159428) (xy 109.264556 -18.143586)
			(xy 109.319325 -18.135582) (xy 109.347 -18.135092) (xy 109.373534 -18.135568) (xy 109.426086 -18.142955)
			(xy 109.47711 -18.157545) (xy 109.525623 -18.179057) (xy 109.570692 -18.207077) (xy 109.591348 -18.223738)
			(xy 109.591602 -18.223738) (xy 109.591602 -18.223992) (xy 109.593126 -18.225262) (xy 109.598454 -18.229031)
			(xy 109.610553 -18.23391) (xy 109.617002 -18.234914) (xy 109.61751 -18.234914) (xy 109.624658 -18.235603)
			(xy 109.638842 -18.233407) (xy 109.64545 -18.230596) (xy 109.730794 -18.190718) (xy 109.738301 -18.186417)
			(xy 109.750089 -18.17377) (xy 109.756977 -18.157912) (xy 109.757972 -18.149316) (xy 109.757972 -14.69263)
			(xy 109.756957 -14.684017) (xy 109.749944 -14.668167) (xy 109.738063 -14.655547) (xy 109.73054 -14.651228)
			(xy 109.720888 -14.646402) (xy 109.680756 -14.62659) (xy 109.645196 -14.60881) (xy 109.640329 -14.606945)
			(xy 109.630088 -14.605019) (xy 109.624876 -14.605) (xy 109.613192 -14.606016) (xy 109.600492 -14.61135)
			(xy 109.594904 -14.615668) (xy 109.569808 -14.634045) (xy 109.514898 -14.663259) (xy 109.455979 -14.683186)
			(xy 109.394609 -14.693301) (xy 109.36351 -14.6939) (xy 109.363256 -14.6939) (xy 109.348778 -14.693646)
			(xy 109.348524 -14.693646) (xy 109.321976 -14.692163) (xy 109.269644 -14.682761) (xy 109.219124 -14.666182)
			(xy 109.171396 -14.64275) (xy 109.127384 -14.612917) (xy 109.08794 -14.577262) (xy 109.05383 -14.536475)
			(xy 109.025713 -14.491348) (xy 109.004135 -14.442753) (xy 108.989513 -14.391632) (xy 108.982131 -14.338977)
			(xy 108.981748 -14.312392) (xy 108.982234 -14.28514) (xy 108.989991 -14.231191) (xy 109.005347 -14.178894)
			(xy 109.027988 -14.129315) (xy 109.057454 -14.083463) (xy 109.093145 -14.04227) (xy 109.134334 -14.006575)
			(xy 109.180184 -13.977105) (xy 109.229761 -13.954459) (xy 109.282056 -13.939099) (xy 109.336004 -13.931337)
			(xy 109.363256 -13.930884) (xy 109.36351 -13.930884) (xy 109.388384 -13.931281) (xy 109.437711 -13.937742)
			(xy 109.485778 -13.950567) (xy 109.531768 -13.969537) (xy 109.574898 -13.99433) (xy 109.594904 -14.009116)
			(xy 109.600492 -14.013434) (xy 109.613192 -14.018768) (xy 109.624876 -14.019784) (xy 109.630088 -14.019761)
			(xy 109.640329 -14.017839) (xy 109.645196 -14.015974) (xy 109.680756 -13.998194) (xy 109.720888 -13.978382)
			(xy 109.73054 -13.973556) (xy 109.738118 -13.969304) (xy 109.750046 -13.956687) (xy 109.75703 -13.940791)
			(xy 109.757972 -13.932154) (xy 109.757972 -13.66012) (xy 109.757555 -13.650098) (xy 109.749888 -13.631579)
			(xy 109.735714 -13.617408) (xy 109.717194 -13.609743) (xy 109.707172 -13.60932) (xy 106.501184 -13.60932)
			(xy 106.500422 -13.60932) (xy 106.488459 -13.610149) (xy 106.467253 -13.621276) (xy 106.459782 -13.630656)
			(xy 106.454448 -13.638276) (xy 106.411776 -13.698474) (xy 106.408468 -13.703429) (xy 106.403976 -13.714461)
			(xy 106.402886 -13.720318) (xy 106.402378 -13.724128) (xy 106.401616 -13.729208) (xy 106.401108 -13.732002)
			(xy 106.405172 -13.74394) (xy 106.413896 -13.770409) (xy 106.426176 -13.824774) (xy 106.432424 -13.880158)
			(xy 106.432858 -13.908024) (xy 106.432858 -13.912342) (xy 106.432188 -13.944189) (xy 106.423885 -14.007345)
			(xy 106.407759 -14.06897) (xy 106.384062 -14.128098) (xy 106.353167 -14.183803) (xy 106.315555 -14.235214)
			(xy 106.271817 -14.281524) (xy 106.222638 -14.322009) (xy 106.168787 -14.356034) (xy 106.111108 -14.383068)
			(xy 106.050504 -14.402686) (xy 105.987925 -14.41458) (xy 105.92435 -14.418566) (xy 105.860775 -14.41458)
			(xy 105.798196 -14.402686) (xy 105.737592 -14.383068) (xy 105.679913 -14.356034) (xy 105.626062 -14.322009)
			(xy 105.576883 -14.281524) (xy 105.533145 -14.235214) (xy 105.495533 -14.183803) (xy 105.464638 -14.128098)
			(xy 105.440941 -14.06897) (xy 105.424815 -14.007345) (xy 105.416512 -13.944189) (xy 105.415842 -13.912342)
			(xy 105.415842 -13.909294) (xy 105.41625 -13.881217) (xy 105.422465 -13.825409) (xy 105.434775 -13.770621)
			(xy 105.443528 -13.74394) (xy 105.443528 -13.743686) (xy 105.445172 -13.738454) (xy 105.446455 -13.727566)
			(xy 105.446068 -13.722096) (xy 105.44556 -13.719048) (xy 105.44429 -13.710412) (xy 105.444036 -13.70838)
			(xy 105.38841 -13.630148) (xy 105.380805 -13.620887) (xy 105.359479 -13.610025) (xy 105.347516 -13.60932)
			(xy 82.418682 -13.60932) (xy 82.412672 -13.609484) (xy 82.400986 -13.612302) (xy 82.395568 -13.614908)
			(xy 82.392095 -13.616749) (xy 82.385717 -13.621344) (xy 82.382868 -13.624052) (xy 81.672727 -14.334193)
			(xy 86.126822 -14.334193) (xy 86.126822 -14.270271) (xy 86.134833 -14.206853) (xy 86.15073 -14.144939)
			(xy 86.174262 -14.085506) (xy 86.205056 -14.029491) (xy 86.242629 -13.977776) (xy 86.286386 -13.931179)
			(xy 86.335639 -13.890434) (xy 86.38961 -13.856183) (xy 86.447449 -13.828966) (xy 86.508242 -13.809213)
			(xy 86.571032 -13.797235) (xy 86.634828 -13.793222) (xy 86.698624 -13.797235) (xy 86.761414 -13.809213)
			(xy 86.822207 -13.828966) (xy 86.880046 -13.856183) (xy 86.934017 -13.890434) (xy 86.98327 -13.931179)
			(xy 87.027027 -13.977776) (xy 87.0646 -14.029491) (xy 87.095394 -14.085506) (xy 87.118926 -14.144939)
			(xy 87.134823 -14.206853) (xy 87.142834 -14.270271) (xy 87.143336 -14.302232) (xy 87.142834 -14.334193)
			(xy 87.134823 -14.397611) (xy 87.118926 -14.459525) (xy 87.095394 -14.518958) (xy 87.0646 -14.574973)
			(xy 87.027027 -14.626688) (xy 86.98327 -14.673285) (xy 86.934017 -14.71403) (xy 86.880046 -14.748281)
			(xy 86.822207 -14.775498) (xy 86.761414 -14.795251) (xy 86.698624 -14.807229) (xy 86.634828 -14.811243)
			(xy 86.571032 -14.807229) (xy 86.508242 -14.795251) (xy 86.447449 -14.775498) (xy 86.38961 -14.748281)
			(xy 86.335639 -14.71403) (xy 86.286386 -14.673285) (xy 86.242629 -14.626688) (xy 86.205056 -14.574973)
			(xy 86.174262 -14.518958) (xy 86.15073 -14.459525) (xy 86.134833 -14.397611) (xy 86.126822 -14.334193)
			(xy 81.672727 -14.334193) (xy 81.033112 -14.973808) (xy 81.030407 -14.97666) (xy 81.025817 -14.98304)
			(xy 81.023968 -14.986508) (xy 81.021383 -14.991934) (xy 81.018553 -15.003614) (xy 81.01838 -15.009622)
			(xy 81.01838 -15.664688) (xy 81.018897 -15.674588) (xy 81.026472 -15.692888) (xy 81.033112 -15.700248)
			(xy 81.06156 -15.728696) (xy 81.068332 -15.736123) (xy 81.075918 -15.754719) (xy 81.076292 -15.764764)
			(xy 81.076292 -18.605711) (xy 81.543138 -18.605711) (xy 81.543138 -18.541789) (xy 81.551149 -18.478371)
			(xy 81.567046 -18.416457) (xy 81.590578 -18.357024) (xy 81.621372 -18.301009) (xy 81.658945 -18.249294)
			(xy 81.702702 -18.202697) (xy 81.751955 -18.161952) (xy 81.805926 -18.127701) (xy 81.863765 -18.100484)
			(xy 81.924558 -18.080731) (xy 81.987348 -18.068753) (xy 82.051144 -18.06474) (xy 82.11494 -18.068753)
			(xy 82.17773 -18.080731) (xy 82.238523 -18.100484) (xy 82.296362 -18.127701) (xy 82.350333 -18.161952)
			(xy 82.399586 -18.202697) (xy 82.443343 -18.249294) (xy 82.480916 -18.301009) (xy 82.51171 -18.357024)
			(xy 82.535242 -18.416457) (xy 82.551139 -18.478371) (xy 82.55915 -18.541789) (xy 82.559652 -18.57375)
			(xy 82.55915 -18.605711) (xy 82.551139 -18.669129) (xy 82.535242 -18.731043) (xy 82.51171 -18.790476)
			(xy 82.480916 -18.846491) (xy 82.443343 -18.898206) (xy 82.399586 -18.944803) (xy 82.350333 -18.985548)
			(xy 82.296362 -19.019799) (xy 82.238523 -19.047016) (xy 82.17773 -19.066769) (xy 82.11494 -19.078747)
			(xy 82.051144 -19.082761) (xy 81.987348 -19.078747) (xy 81.924558 -19.066769) (xy 81.863765 -19.047016)
			(xy 81.805926 -19.019799) (xy 81.751955 -18.985548) (xy 81.702702 -18.944803) (xy 81.658945 -18.898206)
			(xy 81.621372 -18.846491) (xy 81.590578 -18.790476) (xy 81.567046 -18.731043) (xy 81.551149 -18.669129)
			(xy 81.543138 -18.605711) (xy 81.076292 -18.605711) (xy 81.076292 -19.131026) (xy 81.076546 -19.13636)
			(xy 81.078115 -19.146609) (xy 81.088197 -19.164707) (xy 81.096104 -19.171412) (xy 81.159604 -19.220688)
			(xy 81.164242 -19.224019) (xy 81.174622 -19.228773) (xy 81.180178 -19.230086) (xy 81.191608 -19.232626)
			(xy 81.203038 -19.229832) (xy 81.233823 -19.222492) (xy 81.296616 -19.214595) (xy 81.32826 -19.214084)
			(xy 81.360224 -19.214563) (xy 81.42365 -19.22257) (xy 81.485571 -19.238465) (xy 81.545012 -19.261995)
			(xy 81.601035 -19.29279) (xy 81.652757 -19.330364) (xy 81.699361 -19.374124) (xy 81.740112 -19.423381)
			(xy 81.774369 -19.477357) (xy 81.801589 -19.535201) (xy 81.821345 -19.596001) (xy 81.833325 -19.658797)
			(xy 81.83734 -19.7226) (xy 81.833325 -19.786403) (xy 81.821345 -19.849199) (xy 81.801589 -19.909999)
			(xy 81.774369 -19.967843) (xy 81.740112 -20.021819) (xy 81.699361 -20.071076) (xy 81.652757 -20.114836)
			(xy 81.601035 -20.15241) (xy 81.545012 -20.183205) (xy 81.485571 -20.206735) (xy 81.42365 -20.22263)
			(xy 81.360224 -20.230637) (xy 81.32826 -20.2311) (xy 81.296615 -20.230605) (xy 81.23382 -20.222708)
			(xy 81.203038 -20.215352) (xy 81.191608 -20.212558) (xy 81.180178 -20.215098) (xy 81.174611 -20.216383)
			(xy 81.164222 -20.221131) (xy 81.159604 -20.224496) (xy 81.096104 -20.273772) (xy 81.088177 -20.280463)
			(xy 81.078086 -20.298564) (xy 81.076546 -20.308824) (xy 81.076292 -20.314158) (xy 81.076292 -21.325586)
			(xy 81.076292 -21.326602) (xy 81.077056 -21.337631) (xy 81.086654 -21.357521) (xy 81.094834 -21.364956)
			(xy 81.09585 -21.365718) (xy 81.160366 -21.41601) (xy 81.163985 -21.418559) (xy 81.171906 -21.422508)
			(xy 81.176114 -21.423884) (xy 81.190846 -21.427186) (xy 81.202276 -21.424392) (xy 81.224714 -21.419192)
			(xy 81.270432 -21.413588) (xy 81.293462 -21.413216) (xy 81.315961 -21.413513) (xy 81.360655 -21.418729)
			(xy 81.382616 -21.42363) (xy 81.393284 -21.42617) (xy 81.394808 -21.425916) (xy 81.397094 -21.425408)
			(xy 81.402936 -21.424392) (xy 81.408152 -21.423359) (xy 81.418011 -21.419379) (xy 81.422494 -21.416518)
			(xy 81.453482 -21.39569) (xy 81.453736 -21.39569) (xy 81.469484 -21.385022) (xy 81.487518 -21.37283)
			(xy 81.490457 -21.370511) (xy 81.495688 -21.365157) (xy 81.497932 -21.362162) (xy 81.505044 -21.350986)
			(xy 81.505806 -21.34489) (xy 81.506568 -21.340318) (xy 81.512053 -21.307978) (xy 81.530267 -21.244961)
			(xy 81.556435 -21.18481) (xy 81.590121 -21.128524) (xy 81.630766 -21.077039) (xy 81.677696 -21.031208)
			(xy 81.73013 -20.991793) (xy 81.787198 -20.95945) (xy 81.847952 -20.934715) (xy 81.911382 -20.917999)
			(xy 81.976436 -20.909579) (xy 82.009234 -20.909026) (xy 82.041192 -20.90953) (xy 82.104602 -20.917544)
			(xy 82.166508 -20.933443) (xy 82.225934 -20.956975) (xy 82.281942 -20.987769) (xy 82.333649 -21.025339)
			(xy 82.380239 -21.069094) (xy 82.420979 -21.118342) (xy 82.455225 -21.172308) (xy 82.482437 -21.230141)
			(xy 82.502187 -21.290928) (xy 82.514163 -21.353711) (xy 82.518177 -21.4175) (xy 82.514163 -21.481289)
			(xy 82.502187 -21.544072) (xy 82.482437 -21.604859) (xy 82.455225 -21.662692) (xy 82.420979 -21.716658)
			(xy 82.380239 -21.765906) (xy 82.333649 -21.809661) (xy 82.281942 -21.847231) (xy 82.225934 -21.878025)
			(xy 82.166508 -21.901557) (xy 82.104602 -21.917456) (xy 82.041192 -21.92547) (xy 82.009234 -21.926042)
			(xy 81.980721 -21.925645) (xy 81.924053 -21.919266) (xy 81.868454 -21.906586) (xy 81.814624 -21.887763)
			(xy 81.788762 -21.87575) (xy 81.778602 -21.870924) (xy 81.768442 -21.87067) (xy 81.768188 -21.87067)
			(xy 81.763598 -21.870663) (xy 81.754528 -21.872071) (xy 81.750154 -21.873464) (xy 81.722976 -21.884386)
			(xy 81.722468 -21.884386) (xy 81.70418 -21.892006) (xy 81.703672 -21.892006) (xy 81.67497 -21.903436)
			(xy 81.66354 -21.910802) (xy 81.653634 -21.920962) (xy 81.649824 -21.931122) (xy 81.640153 -21.955188)
			(xy 81.615224 -22.000672) (xy 81.584354 -22.042351) (xy 81.548113 -22.079456) (xy 81.527904 -22.095714)
			(xy 81.526126 -22.096984) (xy 81.519427 -22.103223) (xy 81.510581 -22.119235) (xy 81.508854 -22.128226)
			(xy 81.508346 -22.135846) (xy 81.508346 -22.215602) (xy 81.508854 -22.223222) (xy 81.510726 -22.232735)
			(xy 81.520524 -22.249446) (xy 81.527904 -22.255734) (xy 81.550389 -22.273924) (xy 81.574986 -22.29993)
			(xy 89.628224 -22.29993) (xy 89.632238 -22.094246) (xy 89.644274 -21.888876) (xy 89.664313 -21.684132)
			(xy 89.692326 -21.480325) (xy 89.728269 -21.277766) (xy 89.772088 -21.076764) (xy 89.823715 -20.877625)
			(xy 89.883073 -20.680652) (xy 89.950071 -20.486144) (xy 90.024607 -20.294399) (xy 90.106567 -20.105708)
			(xy 90.195827 -19.920358) (xy 90.29225 -19.738632) (xy 90.395691 -19.560806) (xy 90.50599 -19.387152)
			(xy 90.622981 -19.217933) (xy 90.746485 -19.053407) (xy 90.876314 -18.893826) (xy 91.012271 -18.739431)
			(xy 91.154148 -18.590459) (xy 91.301729 -18.447135) (xy 91.45479 -18.309679) (xy 91.613097 -18.178299)
			(xy 91.77641 -18.053196) (xy 91.944479 -17.934559) (xy 92.117049 -17.822571) (xy 92.293857 -17.7174)
			(xy 92.474634 -17.619209) (xy 92.659104 -17.528145) (xy 92.846986 -17.444348) (xy 93.037996 -17.367945)
			(xy 93.23184 -17.299052) (xy 93.428225 -17.237775) (xy 93.626851 -17.184207) (xy 93.827416 -17.13843)
			(xy 94.029614 -17.100512) (xy 94.233138 -17.070513) (xy 94.437677 -17.048476) (xy 94.64292 -17.034437)
			(xy 94.848555 -17.028417) (xy 95.054268 -17.030424) (xy 95.259746 -17.040456) (xy 95.464676 -17.058497)
			(xy 95.668746 -17.08452) (xy 95.871646 -17.118485) (xy 96.073066 -17.16034) (xy 96.272699 -17.210022)
			(xy 96.470242 -17.267456) (xy 96.665394 -17.332553) (xy 96.857858 -17.405214) (xy 97.04734 -17.48533)
			(xy 97.233551 -17.572777) (xy 97.328269 -17.621856) (xy 104.761935 -17.621856) (xy 104.761935 -17.567344)
			(xy 104.769694 -17.513386) (xy 104.785053 -17.461081) (xy 104.8077 -17.411496) (xy 104.837174 -17.365638)
			(xy 104.872874 -17.324442) (xy 104.914075 -17.288746) (xy 104.959936 -17.259278) (xy 105.009525 -17.236637)
			(xy 105.061831 -17.221284) (xy 105.11579 -17.213532) (xy 105.143046 -17.213072) (xy 105.1433 -17.213072)
			(xy 105.165609 -17.213389) (xy 105.20992 -17.218609) (xy 105.231692 -17.223486) (xy 105.241159 -17.225294)
			(xy 105.260219 -17.222549) (xy 105.276928 -17.212976) (xy 105.283254 -17.205706) (xy 105.340658 -17.133824)
			(xy 105.346238 -17.126115) (xy 105.351849 -17.107948) (xy 105.350484 -17.088983) (xy 105.346754 -17.08023)
			(xy 105.346754 -17.079976) (xy 105.334383 -17.053846) (xy 105.315001 -16.999376) (xy 105.301935 -16.943057)
			(xy 105.295353 -16.885618) (xy 105.294938 -16.85671) (xy 105.295357 -16.825169) (xy 105.303159 -16.762571)
			(xy 105.318643 -16.701418) (xy 105.341572 -16.642651) (xy 105.371595 -16.587171) (xy 105.408249 -16.53583)
			(xy 105.450972 -16.489418) (xy 105.499108 -16.448646) (xy 105.551917 -16.414141) (xy 105.608589 -16.386434)
			(xy 105.668252 -16.365949) (xy 105.729992 -16.353001) (xy 105.792858 -16.347789) (xy 105.855887 -16.350393)
			(xy 105.918109 -16.360773) (xy 105.97857 -16.37877) (xy 106.03634 -16.404107) (xy 106.090533 -16.436395)
			(xy 106.140316 -16.475138) (xy 106.184925 -16.519742) (xy 106.205384 -16.546025) (xy 108.24184 -16.546025)
			(xy 108.24184 -16.482103) (xy 108.249851 -16.418685) (xy 108.265748 -16.356771) (xy 108.28928 -16.297338)
			(xy 108.320074 -16.241323) (xy 108.357647 -16.189608) (xy 108.401404 -16.143011) (xy 108.450657 -16.102266)
			(xy 108.504628 -16.068015) (xy 108.562467 -16.040798) (xy 108.62326 -16.021045) (xy 108.68605 -16.009067)
			(xy 108.749846 -16.005054) (xy 108.813642 -16.009067) (xy 108.876432 -16.021045) (xy 108.937225 -16.040798)
			(xy 108.995064 -16.068015) (xy 109.049035 -16.102266) (xy 109.098288 -16.143011) (xy 109.142045 -16.189608)
			(xy 109.179618 -16.241323) (xy 109.210412 -16.297338) (xy 109.233944 -16.356771) (xy 109.249841 -16.418685)
			(xy 109.257852 -16.482103) (xy 109.258354 -16.514064) (xy 109.257852 -16.546025) (xy 109.249841 -16.609443)
			(xy 109.233944 -16.671357) (xy 109.210412 -16.73079) (xy 109.179618 -16.786805) (xy 109.142045 -16.83852)
			(xy 109.098288 -16.885117) (xy 109.049035 -16.925862) (xy 108.995064 -16.960113) (xy 108.937225 -16.98733)
			(xy 108.876432 -17.007083) (xy 108.813642 -17.019061) (xy 108.749846 -17.023075) (xy 108.68605 -17.019061)
			(xy 108.62326 -17.007083) (xy 108.562467 -16.98733) (xy 108.504628 -16.960113) (xy 108.450657 -16.925862)
			(xy 108.401404 -16.885117) (xy 108.357647 -16.83852) (xy 108.320074 -16.786805) (xy 108.28928 -16.73079)
			(xy 108.265748 -16.671357) (xy 108.249851 -16.609443) (xy 108.24184 -16.546025) (xy 106.205384 -16.546025)
			(xy 106.223673 -16.56952) (xy 106.255968 -16.62371) (xy 106.281311 -16.681477) (xy 106.299314 -16.741936)
			(xy 106.309701 -16.804157) (xy 106.312312 -16.867186) (xy 106.307107 -16.930053) (xy 106.294166 -16.991794)
			(xy 106.273688 -17.051459) (xy 106.245986 -17.108134) (xy 106.211488 -17.160947) (xy 106.170721 -17.209088)
			(xy 106.124313 -17.251816) (xy 106.072977 -17.288476) (xy 106.0175 -17.318504) (xy 105.958735 -17.34144)
			(xy 105.897584 -17.356931) (xy 105.834987 -17.364739) (xy 105.803446 -17.365218) (xy 105.803192 -17.365218)
			(xy 105.774082 -17.364798) (xy 105.716246 -17.358127) (xy 105.659547 -17.344907) (xy 105.631996 -17.3355)
			(xy 105.631742 -17.3355) (xy 105.622558 -17.332626) (xy 105.603342 -17.333222) (xy 105.585717 -17.340901)
			(xy 105.578656 -17.347438) (xy 105.513886 -17.412208) (xy 105.507364 -17.419267) (xy 105.499757 -17.436907)
			(xy 105.499116 -17.456107) (xy 105.501948 -17.465294) (xy 105.501948 -17.465548) (xy 105.512463 -17.496767)
			(xy 105.523837 -17.561646) (xy 105.524554 -17.59458) (xy 105.524046 -17.614138) (xy 105.524186 -17.626417)
			(xy 105.534381 -17.648708) (xy 105.543604 -17.65681) (xy 105.619042 -17.715738) (xy 105.643172 -17.720056)
			(xy 105.65511 -17.7165) (xy 105.691322 -17.706178) (xy 105.765798 -17.695083) (xy 105.803446 -17.694402)
			(xy 105.834983 -17.694916) (xy 105.897573 -17.702724) (xy 105.958717 -17.718213) (xy 106.017475 -17.741146)
			(xy 106.072945 -17.771171) (xy 106.124276 -17.807826) (xy 106.170678 -17.850549) (xy 106.21144 -17.898683)
			(xy 106.245936 -17.95149) (xy 106.273634 -18.008157) (xy 106.294111 -18.067816) (xy 106.307051 -18.129549)
			(xy 106.312256 -18.192409) (xy 106.309646 -18.25543) (xy 106.299262 -18.317644) (xy 106.281261 -18.378096)
			(xy 106.255922 -18.435857) (xy 106.223632 -18.49004) (xy 106.184889 -18.539814) (xy 106.140287 -18.584413)
			(xy 106.090511 -18.623153) (xy 106.036325 -18.655438) (xy 105.978562 -18.680774) (xy 105.918109 -18.69877)
			(xy 105.855894 -18.70915) (xy 105.792873 -18.711756) (xy 105.730013 -18.706546) (xy 105.668281 -18.693601)
			(xy 105.608624 -18.67312) (xy 105.551958 -18.645418) (xy 105.499154 -18.610919) (xy 105.451023 -18.570154)
			(xy 105.408303 -18.523748) (xy 105.371652 -18.472415) (xy 105.341631 -18.416942) (xy 105.318702 -18.358182)
			(xy 105.303217 -18.297038) (xy 105.295414 -18.234447) (xy 105.294938 -18.20291) (xy 105.295308 -18.175706)
			(xy 105.301164 -18.121613) (xy 105.306622 -18.09496) (xy 105.308549 -18.08286) (xy 105.302176 -18.059241)
			(xy 105.29443 -18.049748) (xy 105.229406 -17.97939) (xy 105.206292 -17.971008) (xy 105.193846 -17.972786)
			(xy 105.181206 -17.974362) (xy 105.155784 -17.976012) (xy 105.143046 -17.976088) (xy 105.11579 -17.975668)
			(xy 105.061831 -17.967916) (xy 105.009525 -17.952563) (xy 104.959936 -17.929922) (xy 104.914075 -17.900454)
			(xy 104.872874 -17.864758) (xy 104.837174 -17.823562) (xy 104.8077 -17.777704) (xy 104.785053 -17.728119)
			(xy 104.769694 -17.675814) (xy 104.761935 -17.621856) (xy 97.328269 -17.621856) (xy 97.41621 -17.667423)
			(xy 97.595036 -17.769123) (xy 97.769758 -17.877723) (xy 97.940111 -17.993058) (xy 98.105833 -18.114951)
			(xy 98.266674 -18.243217) (xy 98.422387 -18.37766) (xy 98.572737 -18.518077) (xy 98.717494 -18.664253)
			(xy 98.856437 -18.815965) (xy 98.981195 -18.963343) (xy 155.750254 -18.963343) (xy 155.750254 -18.899421)
			(xy 155.758265 -18.836003) (xy 155.774162 -18.774089) (xy 155.797694 -18.714656) (xy 155.828488 -18.658641)
			(xy 155.866061 -18.606926) (xy 155.909818 -18.560329) (xy 155.959071 -18.519584) (xy 156.013042 -18.485333)
			(xy 156.070881 -18.458116) (xy 156.131674 -18.438363) (xy 156.194464 -18.426385) (xy 156.25826 -18.422372)
			(xy 156.322056 -18.426385) (xy 156.384846 -18.438363) (xy 156.445639 -18.458116) (xy 156.503478 -18.485333)
			(xy 156.557449 -18.519584) (xy 156.606702 -18.560329) (xy 156.650459 -18.606926) (xy 156.688032 -18.658641)
			(xy 156.718826 -18.714656) (xy 156.742358 -18.774089) (xy 156.758255 -18.836003) (xy 156.759613 -18.846757)
			(xy 164.806878 -18.846757) (xy 164.806878 -18.782835) (xy 164.814889 -18.719417) (xy 164.830786 -18.657503)
			(xy 164.854318 -18.59807) (xy 164.885112 -18.542055) (xy 164.922685 -18.49034) (xy 164.966442 -18.443743)
			(xy 165.015695 -18.402998) (xy 165.069666 -18.368747) (xy 165.127505 -18.34153) (xy 165.188298 -18.321777)
			(xy 165.251088 -18.309799) (xy 165.314884 -18.305786) (xy 165.37868 -18.309799) (xy 165.44147 -18.321777)
			(xy 165.502263 -18.34153) (xy 165.560102 -18.368747) (xy 165.614073 -18.402998) (xy 165.663326 -18.443743)
			(xy 165.707083 -18.49034) (xy 165.744656 -18.542055) (xy 165.77545 -18.59807) (xy 165.798982 -18.657503)
			(xy 165.814879 -18.719417) (xy 165.82289 -18.782835) (xy 165.823392 -18.814796) (xy 165.82289 -18.846757)
			(xy 165.814879 -18.910175) (xy 165.798982 -18.972089) (xy 165.77545 -19.031522) (xy 165.744656 -19.087537)
			(xy 165.707083 -19.139252) (xy 165.688093 -19.159474) (xy 166.22395 -19.159474) (xy 166.224452 -19.127513)
			(xy 166.232463 -19.064095) (xy 166.24836 -19.002181) (xy 166.271892 -18.942748) (xy 166.302686 -18.886733)
			(xy 166.340259 -18.835018) (xy 166.384016 -18.788421) (xy 166.433269 -18.747676) (xy 166.48724 -18.713425)
			(xy 166.545079 -18.686208) (xy 166.605872 -18.666455) (xy 166.668662 -18.654477) (xy 166.732458 -18.650464)
			(xy 166.796254 -18.654477) (xy 166.859044 -18.666455) (xy 166.919837 -18.686208) (xy 166.977676 -18.713425)
			(xy 167.031647 -18.747676) (xy 167.0809 -18.788421) (xy 167.124657 -18.835018) (xy 167.16223 -18.886733)
			(xy 167.193024 -18.942748) (xy 167.216556 -19.002181) (xy 167.232453 -19.064095) (xy 167.240464 -19.127513)
			(xy 167.240966 -19.159474) (xy 167.240565 -19.189408) (xy 167.233524 -19.24886) (xy 167.219547 -19.307073)
			(xy 167.198829 -19.363241) (xy 167.171656 -19.416587) (xy 167.138404 -19.466371) (xy 167.1193 -19.48942)
			(xy 167.112208 -19.498551) (xy 167.106403 -19.520911) (xy 167.108124 -19.532346) (xy 167.126158 -19.622262)
			(xy 167.140128 -19.64055) (xy 167.150542 -19.645884) (xy 167.181323 -19.662137) (xy 167.238513 -19.70182)
			(xy 167.289743 -19.748947) (xy 167.31234 -19.775424) (xy 167.31822 -19.781893) (xy 167.333244 -19.790803)
			(xy 167.350387 -19.794152) (xy 167.359076 -19.793204) (xy 167.458644 -19.778472) (xy 167.479218 -19.76247)
			(xy 167.484552 -19.750024) (xy 167.484552 -19.749516) (xy 167.497174 -19.720648) (xy 167.530532 -19.667203)
			(xy 167.572241 -19.619985) (xy 167.596312 -19.599656) (xy 167.603678 -19.593814) (xy 167.612822 -19.577812)
			(xy 167.626792 -19.492214) (xy 167.622982 -19.47418) (xy 167.617902 -19.466306) (xy 167.60271 -19.441759)
			(xy 167.577372 -19.389886) (xy 167.558079 -19.335475) (xy 167.545081 -19.279227) (xy 167.538546 -19.221867)
			(xy 167.538146 -19.193002) (xy 167.538146 -19.192748) (xy 167.538648 -19.160787) (xy 167.546659 -19.097369)
			(xy 167.562556 -19.035455) (xy 167.586088 -18.976022) (xy 167.616882 -18.920007) (xy 167.654455 -18.868292)
			(xy 167.698212 -18.821695) (xy 167.747465 -18.78095) (xy 167.801436 -18.746699) (xy 167.859275 -18.719482)
			(xy 167.920068 -18.699729) (xy 167.982858 -18.687751) (xy 168.046654 -18.683738) (xy 168.11045 -18.687751)
			(xy 168.17324 -18.699729) (xy 168.234033 -18.719482) (xy 168.291872 -18.746699) (xy 168.345843 -18.78095)
			(xy 168.395096 -18.821695) (xy 168.438853 -18.868292) (xy 168.476426 -18.920007) (xy 168.481143 -18.928588)
			(xy 170.696636 -18.928588) (xy 170.697138 -18.896627) (xy 170.705149 -18.833209) (xy 170.721046 -18.771295)
			(xy 170.744578 -18.711862) (xy 170.775372 -18.655847) (xy 170.812945 -18.604132) (xy 170.856702 -18.557535)
			(xy 170.905955 -18.51679) (xy 170.959926 -18.482539) (xy 171.017765 -18.455322) (xy 171.078558 -18.435569)
			(xy 171.141348 -18.423591) (xy 171.205144 -18.419578) (xy 171.26894 -18.423591) (xy 171.33173 -18.435569)
			(xy 171.392523 -18.455322) (xy 171.450362 -18.482539) (xy 171.504333 -18.51679) (xy 171.553586 -18.557535)
			(xy 171.597343 -18.604132) (xy 171.634916 -18.655847) (xy 171.66571 -18.711862) (xy 171.689242 -18.771295)
			(xy 171.705139 -18.833209) (xy 171.71315 -18.896627) (xy 171.713652 -18.928588) (xy 171.713131 -18.960698)
			(xy 171.705058 -19.024409) (xy 171.689025 -19.086596) (xy 171.665289 -19.146269) (xy 171.634227 -19.202477)
			(xy 171.596334 -19.254326) (xy 171.552213 -19.300991) (xy 171.502566 -19.341727) (xy 171.448185 -19.375887)
			(xy 171.419266 -19.389852) (xy 171.406615 -19.396322) (xy 171.385197 -19.414974) (xy 171.369737 -19.438799)
			(xy 171.361428 -19.465958) (xy 171.36091 -19.494355) (xy 171.368225 -19.521798) (xy 171.382808 -19.54617)
			(xy 171.39285 -19.556222) (xy 171.411649 -19.574338) (xy 171.444629 -19.614811) (xy 171.471785 -19.659401)
			(xy 171.492609 -19.707276) (xy 171.506713 -19.757544) (xy 171.513833 -19.809264) (xy 171.514262 -19.835368)
			(xy 171.513776 -19.862619) (xy 171.50602 -19.916567) (xy 171.490665 -19.968862) (xy 171.468023 -20.018439)
			(xy 171.438557 -20.064289) (xy 171.402866 -20.10548) (xy 171.381007 -20.12442) (xy 172.358812 -20.12442)
			(xy 172.359314 -20.092459) (xy 172.367325 -20.029041) (xy 172.383222 -19.967127) (xy 172.406754 -19.907694)
			(xy 172.437548 -19.851679) (xy 172.475121 -19.799964) (xy 172.518878 -19.753367) (xy 172.568131 -19.712622)
			(xy 172.622102 -19.678371) (xy 172.679941 -19.651154) (xy 172.740734 -19.631401) (xy 172.803524 -19.619423)
			(xy 172.86732 -19.61541) (xy 172.931116 -19.619423) (xy 172.993906 -19.631401) (xy 173.054699 -19.651154)
			(xy 173.112538 -19.678371) (xy 173.166509 -19.712622) (xy 173.215762 -19.753367) (xy 173.259519 -19.799964)
			(xy 173.297092 -19.851679) (xy 173.327886 -19.907694) (xy 173.351418 -19.967127) (xy 173.367315 -20.029041)
			(xy 173.375326 -20.092459) (xy 173.375828 -20.12442) (xy 173.37525 -20.158678) (xy 173.366028 -20.22657)
			(xy 173.347769 -20.292608) (xy 173.320803 -20.355594) (xy 173.303692 -20.385278) (xy 173.298622 -20.394887)
			(xy 173.296241 -20.416459) (xy 173.29912 -20.426934) (xy 173.322742 -20.500086) (xy 173.326553 -20.510265)
			(xy 173.341158 -20.52633) (xy 173.350936 -20.531074) (xy 173.35119 -20.531074) (xy 173.376597 -20.542464)
			(xy 173.424083 -20.571535) (xy 173.466837 -20.607202) (xy 173.503949 -20.648707) (xy 173.534631 -20.695168)
			(xy 173.558231 -20.745597) (xy 173.574245 -20.798922) (xy 173.582335 -20.854009) (xy 173.582838 -20.881848)
			(xy 173.582352 -20.909099) (xy 173.574596 -20.963047) (xy 173.559241 -21.015342) (xy 173.536599 -21.064919)
			(xy 173.507133 -21.110769) (xy 173.471442 -21.15196) (xy 173.430251 -21.187651) (xy 173.384401 -21.217117)
			(xy 173.334824 -21.239759) (xy 173.282529 -21.255114) (xy 173.228581 -21.26287) (xy 173.174079 -21.26287)
			(xy 173.120131 -21.255114) (xy 173.067836 -21.239759) (xy 173.018259 -21.217117) (xy 172.972409 -21.187651)
			(xy 172.931218 -21.15196) (xy 172.895527 -21.110769) (xy 172.866061 -21.064919) (xy 172.843419 -21.015342)
			(xy 172.828064 -20.963047) (xy 172.820308 -20.909099) (xy 172.819822 -20.881848) (xy 172.819822 -20.881594)
			(xy 172.820489 -20.849542) (xy 172.831215 -20.786342) (xy 172.841158 -20.755864) (xy 172.844273 -20.745402)
			(xy 172.842297 -20.723684) (xy 172.837348 -20.713954) (xy 172.794168 -20.637754) (xy 172.776642 -20.625054)
			(xy 172.76572 -20.622768) (xy 172.734801 -20.615896) (xy 172.674798 -20.595619) (xy 172.617776 -20.568049)
			(xy 172.564618 -20.533614) (xy 172.516146 -20.492846) (xy 172.473111 -20.446376) (xy 172.436177 -20.394922)
			(xy 172.405917 -20.339281) (xy 172.382799 -20.280314) (xy 172.36718 -20.218933) (xy 172.359302 -20.156088)
			(xy 172.358812 -20.12442) (xy 171.381007 -20.12442) (xy 171.361675 -20.141171) (xy 171.315825 -20.170637)
			(xy 171.266248 -20.193279) (xy 171.213953 -20.208634) (xy 171.160005 -20.21639) (xy 171.105503 -20.21639)
			(xy 171.051555 -20.208634) (xy 170.99926 -20.193279) (xy 170.949683 -20.170637) (xy 170.903833 -20.141171)
			(xy 170.862642 -20.10548) (xy 170.826951 -20.064289) (xy 170.797485 -20.018439) (xy 170.774843 -19.968862)
			(xy 170.759488 -19.916567) (xy 170.751732 -19.862619) (xy 170.751246 -19.835368) (xy 170.751693 -19.808662)
			(xy 170.759159 -19.755773) (xy 170.773925 -19.704442) (xy 170.795705 -19.655671) (xy 170.824072 -19.610413)
			(xy 170.858471 -19.569553) (xy 170.898232 -19.533888) (xy 170.920156 -19.51863) (xy 170.931731 -19.510308)
			(xy 170.950145 -19.488563) (xy 170.961821 -19.462571) (xy 170.965848 -19.434363) (xy 170.961911 -19.406142)
			(xy 170.950318 -19.380113) (xy 170.931974 -19.358309) (xy 170.92041 -19.349974) (xy 170.89496 -19.332184)
			(xy 170.848129 -19.291407) (xy 170.806611 -19.245232) (xy 170.771024 -19.194345) (xy 170.741898 -19.139504)
			(xy 170.719666 -19.081525) (xy 170.704659 -19.02127) (xy 170.6971 -18.959636) (xy 170.696636 -18.928588)
			(xy 168.481143 -18.928588) (xy 168.50722 -18.976022) (xy 168.530752 -19.035455) (xy 168.546649 -19.097369)
			(xy 168.55466 -19.160787) (xy 168.555162 -19.192748) (xy 168.554608 -19.225186) (xy 168.546356 -19.289535)
			(xy 168.52999 -19.352312) (xy 168.505778 -19.412501) (xy 168.474112 -19.469123) (xy 168.435504 -19.521261)
			(xy 168.390583 -19.568069) (xy 168.340076 -19.608787) (xy 168.284803 -19.642754) (xy 168.255442 -19.656552)
			(xy 168.246806 -19.660362) (xy 168.233598 -19.67357) (xy 168.202356 -19.743928) (xy 168.19897 -19.752487)
			(xy 168.197936 -19.770852) (xy 168.200324 -19.779742) (xy 168.200324 -19.779996) (xy 168.208762 -19.808205)
			(xy 168.217816 -19.866381) (xy 168.218358 -19.89582) (xy 168.217964 -19.923076) (xy 168.210203 -19.977032)
			(xy 168.194841 -20.029334) (xy 168.172193 -20.078918) (xy 168.142718 -20.124773) (xy 168.107017 -20.165967)
			(xy 168.065817 -20.20166) (xy 168.019956 -20.231127) (xy 167.970368 -20.253766) (xy 167.918063 -20.269117)
			(xy 167.864106 -20.276869) (xy 167.83685 -20.277328) (xy 167.808563 -20.276801) (xy 167.75261 -20.268441)
			(xy 167.698504 -20.251913) (xy 167.647431 -20.227577) (xy 167.60051 -20.195968) (xy 167.579294 -20.177252)
			(xy 167.569388 -20.168362) (xy 167.54348 -20.162266) (xy 167.43426 -20.194778) (xy 167.415718 -20.213828)
			(xy 167.412416 -20.226782) (xy 167.40437 -20.256163) (xy 167.38216 -20.312888) (xy 167.353331 -20.366553)
			(xy 167.338234 -20.388029) (xy 169.149008 -20.388029) (xy 169.149008 -20.324107) (xy 169.157019 -20.260689)
			(xy 169.172916 -20.198775) (xy 169.196448 -20.139342) (xy 169.227242 -20.083327) (xy 169.264815 -20.031612)
			(xy 169.308572 -19.985015) (xy 169.357825 -19.94427) (xy 169.411796 -19.910019) (xy 169.469635 -19.882802)
			(xy 169.530428 -19.863049) (xy 169.593218 -19.851071) (xy 169.657014 -19.847058) (xy 169.72081 -19.851071)
			(xy 169.7836 -19.863049) (xy 169.844393 -19.882802) (xy 169.902232 -19.910019) (xy 169.956203 -19.94427)
			(xy 170.005456 -19.985015) (xy 170.049213 -20.031612) (xy 170.086786 -20.083327) (xy 170.11758 -20.139342)
			(xy 170.141112 -20.198775) (xy 170.157009 -20.260689) (xy 170.16502 -20.324107) (xy 170.165522 -20.356068)
			(xy 170.16502 -20.388029) (xy 170.157009 -20.451447) (xy 170.141112 -20.513361) (xy 170.11758 -20.572794)
			(xy 170.086786 -20.628809) (xy 170.049213 -20.680524) (xy 170.005456 -20.727121) (xy 169.956203 -20.767866)
			(xy 169.902232 -20.802117) (xy 169.844393 -20.829334) (xy 169.7836 -20.849087) (xy 169.72081 -20.861065)
			(xy 169.657014 -20.865079) (xy 169.593218 -20.861065) (xy 169.530428 -20.849087) (xy 169.469635 -20.829334)
			(xy 169.411796 -20.802117) (xy 169.357825 -20.767866) (xy 169.308572 -20.727121) (xy 169.264815 -20.680524)
			(xy 169.227242 -20.628809) (xy 169.196448 -20.572794) (xy 169.172916 -20.513361) (xy 169.157019 -20.451447)
			(xy 169.149008 -20.388029) (xy 167.338234 -20.388029) (xy 167.318296 -20.41639) (xy 167.277558 -20.461683)
			(xy 167.2317 -20.501785) (xy 167.181379 -20.53612) (xy 167.127317 -20.564197) (xy 167.070287 -20.585613)
			(xy 167.011106 -20.600062) (xy 166.950623 -20.607336) (xy 166.920164 -20.607782) (xy 166.889431 -20.607378)
			(xy 166.828414 -20.599965) (xy 166.768736 -20.585251) (xy 166.711266 -20.563452) (xy 166.656843 -20.534884)
			(xy 166.60626 -20.499964) (xy 166.560254 -20.459202) (xy 166.519498 -20.413192) (xy 166.484584 -20.362604)
			(xy 166.456023 -20.308178) (xy 166.43423 -20.250705) (xy 166.419524 -20.191025) (xy 166.412118 -20.130007)
			(xy 166.411656 -20.099274) (xy 166.412104 -20.069342) (xy 166.419138 -20.009892) (xy 166.433107 -19.95168)
			(xy 166.453817 -19.895512) (xy 166.480981 -19.842166) (xy 166.514223 -19.792379) (xy 166.533322 -19.769328)
			(xy 166.540389 -19.760181) (xy 166.546208 -19.737834) (xy 166.544498 -19.726402) (xy 166.526464 -19.636486)
			(xy 166.512494 -19.618198) (xy 166.50208 -19.612864) (xy 166.474585 -19.598313) (xy 166.422982 -19.563571)
			(xy 166.376003 -19.522794) (xy 166.334346 -19.476592) (xy 166.298636 -19.425655) (xy 166.269403 -19.370743)
			(xy 166.247086 -19.312676) (xy 166.232018 -19.252321) (xy 166.224422 -19.190578) (xy 166.22395 -19.159474)
			(xy 165.688093 -19.159474) (xy 165.663326 -19.185849) (xy 165.614073 -19.226594) (xy 165.560102 -19.260845)
			(xy 165.502263 -19.288062) (xy 165.44147 -19.307815) (xy 165.37868 -19.319793) (xy 165.314884 -19.323807)
			(xy 165.251088 -19.319793) (xy 165.188298 -19.307815) (xy 165.127505 -19.288062) (xy 165.069666 -19.260845)
			(xy 165.015695 -19.226594) (xy 164.966442 -19.185849) (xy 164.922685 -19.139252) (xy 164.885112 -19.087537)
			(xy 164.854318 -19.031522) (xy 164.830786 -18.972089) (xy 164.814889 -18.910175) (xy 164.806878 -18.846757)
			(xy 156.759613 -18.846757) (xy 156.766266 -18.899421) (xy 156.766768 -18.931382) (xy 156.766266 -18.963343)
			(xy 156.758255 -19.026761) (xy 156.742358 -19.088675) (xy 156.718826 -19.148108) (xy 156.688032 -19.204123)
			(xy 156.650459 -19.255838) (xy 156.606702 -19.302435) (xy 156.557449 -19.34318) (xy 156.503478 -19.377431)
			(xy 156.445639 -19.404648) (xy 156.384846 -19.424401) (xy 156.322056 -19.436379) (xy 156.25826 -19.440393)
			(xy 156.194464 -19.436379) (xy 156.131674 -19.424401) (xy 156.070881 -19.404648) (xy 156.013042 -19.377431)
			(xy 155.959071 -19.34318) (xy 155.909818 -19.302435) (xy 155.866061 -19.255838) (xy 155.828488 -19.204123)
			(xy 155.797694 -19.148108) (xy 155.774162 -19.088675) (xy 155.758265 -19.026761) (xy 155.750254 -18.963343)
			(xy 98.981195 -18.963343) (xy 98.989355 -18.972983) (xy 99.116046 -19.135068) (xy 99.236316 -19.301971)
			(xy 99.349983 -19.473441) (xy 99.456873 -19.649214) (xy 99.556824 -19.829024) (xy 99.649683 -20.012597)
			(xy 99.73531 -20.199653) (xy 99.813572 -20.389908) (xy 99.884353 -20.583071) (xy 99.947543 -20.778849)
			(xy 100.003046 -20.976943) (xy 100.050778 -21.177052) (xy 100.090667 -21.37887) (xy 100.122651 -21.582092)
			(xy 100.146681 -21.786406) (xy 100.162722 -21.991502) (xy 100.170748 -22.197069) (xy 100.17125 -22.29993)
			(xy 100.170748 -22.402791) (xy 100.162722 -22.608358) (xy 100.146681 -22.813454) (xy 100.122651 -23.017768)
			(xy 100.090667 -23.22099) (xy 100.050778 -23.422808) (xy 100.003046 -23.622917) (xy 99.947543 -23.821011)
			(xy 99.884353 -24.016789) (xy 99.813572 -24.209952) (xy 99.73531 -24.400207) (xy 99.649683 -24.587263)
			(xy 99.556824 -24.770836) (xy 99.456873 -24.950646) (xy 99.349983 -25.126419) (xy 99.236316 -25.297889)
			(xy 99.148825 -25.419304) (xy 102.804214 -25.419304) (xy 102.804752 -25.390396) (xy 102.813448 -25.333239)
			(xy 102.830672 -25.278049) (xy 102.856029 -25.226091) (xy 102.888938 -25.178556) (xy 102.928646 -25.136534)
			(xy 102.974241 -25.100986) (xy 103.024679 -25.072727) (xy 103.078806 -25.052406) (xy 103.106982 -25.045924)
			(xy 103.116544 -25.043408) (xy 103.132881 -25.032304) (xy 103.138732 -25.024334) (xy 103.183944 -24.956516)
			(xy 103.187754 -24.937212) (xy 103.185722 -24.927306) (xy 103.173962 -24.863681) (xy 103.157564 -24.735323)
			(xy 103.149375 -24.606181) (xy 103.148892 -24.54148) (xy 103.149421 -24.474839) (xy 103.158152 -24.341845)
			(xy 103.175577 -24.209708) (xy 103.201621 -24.078996) (xy 103.23617 -23.950271) (xy 103.279078 -23.824085)
			(xy 103.330159 -23.700982) (xy 103.389194 -23.581488) (xy 103.45593 -23.466119) (xy 103.53008 -23.355368)
			(xy 103.570278 -23.302214) (xy 103.57507 -23.295452) (xy 103.580377 -23.279762) (xy 103.580692 -23.27148)
			(xy 103.580692 -20.540472) (xy 103.581079 -20.530398) (xy 103.588824 -20.511799) (xy 103.595678 -20.504404)
			(xy 104.502204 -19.597878) (xy 104.509606 -19.59104) (xy 104.528204 -19.58332) (xy 104.538272 -19.582892)
			(xy 108.440728 -19.582892) (xy 108.450802 -19.583279) (xy 108.469401 -19.591024) (xy 108.476796 -19.597878)
			(xy 108.500629 -19.621711) (xy 111.552222 -19.621711) (xy 111.552222 -19.557789) (xy 111.560233 -19.494371)
			(xy 111.57613 -19.432457) (xy 111.599662 -19.373024) (xy 111.630456 -19.317009) (xy 111.668029 -19.265294)
			(xy 111.711786 -19.218697) (xy 111.761039 -19.177952) (xy 111.81501 -19.143701) (xy 111.872849 -19.116484)
			(xy 111.933642 -19.096731) (xy 111.996432 -19.084753) (xy 112.060228 -19.08074) (xy 112.124024 -19.084753)
			(xy 112.186814 -19.096731) (xy 112.247607 -19.116484) (xy 112.305446 -19.143701) (xy 112.359417 -19.177952)
			(xy 112.40867 -19.218697) (xy 112.452427 -19.265294) (xy 112.49 -19.317009) (xy 112.520794 -19.373024)
			(xy 112.544326 -19.432457) (xy 112.560223 -19.494371) (xy 112.568234 -19.557789) (xy 112.568736 -19.58975)
			(xy 112.568234 -19.621711) (xy 112.560223 -19.685129) (xy 112.559213 -19.689064) (xy 138.285982 -19.689064)
			(xy 138.286468 -19.661813) (xy 138.294224 -19.607865) (xy 138.309579 -19.55557) (xy 138.332221 -19.505993)
			(xy 138.361687 -19.460143) (xy 138.397378 -19.418952) (xy 138.438569 -19.383261) (xy 138.484419 -19.353795)
			(xy 138.533996 -19.331153) (xy 138.586291 -19.315798) (xy 138.640239 -19.308042) (xy 138.694741 -19.308042)
			(xy 138.748689 -19.315798) (xy 138.800984 -19.331153) (xy 138.850561 -19.353795) (xy 138.896411 -19.383261)
			(xy 138.937602 -19.418952) (xy 138.973293 -19.460143) (xy 139.002759 -19.505993) (xy 139.025401 -19.55557)
			(xy 139.040756 -19.607865) (xy 139.048512 -19.661813) (xy 139.048998 -19.689064) (xy 139.048744 -19.70405)
			(xy 139.048883 -19.714666) (xy 139.056775 -19.734353) (xy 139.063984 -19.74215) (xy 139.087098 -19.76501)
			(xy 139.094966 -19.772027) (xy 139.114655 -19.779501) (xy 139.125198 -19.779488) (xy 139.146534 -19.77898)
			(xy 140.137134 -19.77898) (xy 140.147122 -19.779032) (xy 140.167071 -19.780046) (xy 140.177012 -19.781012)
			(xy 140.18768 -19.782028) (xy 140.207746 -19.775678) (xy 140.280136 -19.71167) (xy 140.289026 -19.692366)
			(xy 140.289026 -19.681698) (xy 140.29002 -19.654795) (xy 140.298632 -19.601654) (xy 140.314626 -19.55025)
			(xy 140.337686 -19.501603) (xy 140.367352 -19.456681) (xy 140.403038 -19.416373) (xy 140.444033 -19.381479)
			(xy 140.489526 -19.352694) (xy 140.538612 -19.330587) (xy 140.590318 -19.315597) (xy 140.643617 -19.308022)
			(xy 140.670534 -19.307556) (xy 140.697781 -19.308117) (xy 140.75172 -19.315876) (xy 140.804006 -19.331233)
			(xy 140.853574 -19.353874) (xy 140.899416 -19.383338) (xy 140.940598 -19.419026) (xy 140.976282 -19.460212)
			(xy 141.005743 -19.506056) (xy 141.028379 -19.555626) (xy 141.043731 -19.607913) (xy 141.051486 -19.661853)
			(xy 141.051486 -19.716347) (xy 141.043731 -19.770287) (xy 141.028379 -19.822574) (xy 141.005743 -19.872144)
			(xy 140.976282 -19.917988) (xy 140.940598 -19.959174) (xy 140.899416 -19.994862) (xy 140.853574 -20.024326)
			(xy 140.804006 -20.046967) (xy 140.75172 -20.062324) (xy 140.697781 -20.070083) (xy 140.670534 -20.070572)
			(xy 140.670026 -20.070572) (xy 140.660229 -20.070505) (xy 140.640661 -20.06949) (xy 140.63091 -20.06854)
			(xy 140.630656 -20.06854) (xy 140.620122 -20.068028) (xy 140.600056 -20.074435) (xy 140.591794 -20.080986)
			(xy 140.535914 -20.130516) (xy 140.528325 -20.137807) (xy 140.519413 -20.156849) (xy 140.518642 -20.167346)
			(xy 140.518642 -20.1676) (xy 140.517657 -20.194515) (xy 140.50908 -20.247686) (xy 140.493111 -20.299123)
			(xy 140.470069 -20.347803) (xy 140.44041 -20.392759) (xy 140.404725 -20.433099) (xy 140.363722 -20.46802)
			(xy 140.318217 -20.496829) (xy 140.269113 -20.518953) (xy 140.217386 -20.533953) (xy 140.164063 -20.541531)
			(xy 140.137134 -20.541996) (xy 139.146534 -20.541996) (xy 139.119691 -20.54154) (xy 139.066532 -20.534044)
			(xy 139.014949 -20.519167) (xy 138.965962 -20.497203) (xy 138.920539 -20.468586) (xy 138.879579 -20.433882)
			(xy 138.84389 -20.393777) (xy 138.814178 -20.349063) (xy 138.791031 -20.300624) (xy 138.774905 -20.249418)
			(xy 138.766119 -20.196456) (xy 138.765026 -20.169632) (xy 138.764772 -20.159726) (xy 138.756898 -20.141692)
			(xy 138.69924 -20.08505) (xy 138.692003 -20.078598) (xy 138.67412 -20.07115) (xy 138.664442 -20.070572)
			(xy 138.664188 -20.070572) (xy 138.63709 -20.069893) (xy 138.583498 -20.061755) (xy 138.531597 -20.046113)
			(xy 138.482433 -20.023283) (xy 138.436995 -19.993724) (xy 138.396199 -19.958031) (xy 138.360865 -19.916923)
			(xy 138.331706 -19.871227) (xy 138.309308 -19.821865) (xy 138.294122 -19.769829) (xy 138.286455 -19.716167)
			(xy 138.285982 -19.689064) (xy 112.559213 -19.689064) (xy 112.544326 -19.747043) (xy 112.520794 -19.806476)
			(xy 112.49 -19.862491) (xy 112.452427 -19.914206) (xy 112.40867 -19.960803) (xy 112.359417 -20.001548)
			(xy 112.305446 -20.035799) (xy 112.247607 -20.063016) (xy 112.186814 -20.082769) (xy 112.124024 -20.094747)
			(xy 112.060228 -20.098761) (xy 111.996432 -20.094747) (xy 111.933642 -20.082769) (xy 111.872849 -20.063016)
			(xy 111.81501 -20.035799) (xy 111.761039 -20.001548) (xy 111.711786 -19.960803) (xy 111.668029 -19.914206)
			(xy 111.630456 -19.862491) (xy 111.599662 -19.806476) (xy 111.57613 -19.747043) (xy 111.560233 -19.685129)
			(xy 111.552222 -19.621711) (xy 108.500629 -19.621711) (xy 108.900722 -20.021804) (xy 108.90756 -20.029206)
			(xy 108.91528 -20.047804) (xy 108.915708 -20.057872) (xy 108.915708 -21.009567) (xy 109.05718 -21.009567)
			(xy 109.05718 -20.945645) (xy 109.065191 -20.882227) (xy 109.081088 -20.820313) (xy 109.10462 -20.76088)
			(xy 109.135414 -20.704865) (xy 109.172987 -20.65315) (xy 109.216744 -20.606553) (xy 109.265997 -20.565808)
			(xy 109.319968 -20.531557) (xy 109.377807 -20.50434) (xy 109.4386 -20.484587) (xy 109.50139 -20.472609)
			(xy 109.565186 -20.468596) (xy 109.628982 -20.472609) (xy 109.691772 -20.484587) (xy 109.752565 -20.50434)
			(xy 109.810404 -20.531557) (xy 109.864375 -20.565808) (xy 109.913628 -20.606553) (xy 109.957385 -20.65315)
			(xy 109.994958 -20.704865) (xy 110.025752 -20.76088) (xy 110.049284 -20.820313) (xy 110.065181 -20.882227)
			(xy 110.066347 -20.891457) (xy 112.589812 -20.891457) (xy 112.589812 -20.827535) (xy 112.597823 -20.764117)
			(xy 112.61372 -20.702203) (xy 112.637252 -20.64277) (xy 112.668046 -20.586755) (xy 112.705619 -20.53504)
			(xy 112.749376 -20.488443) (xy 112.798629 -20.447698) (xy 112.8526 -20.413447) (xy 112.910439 -20.38623)
			(xy 112.971232 -20.366477) (xy 113.034022 -20.354499) (xy 113.097818 -20.350486) (xy 113.161614 -20.354499)
			(xy 113.224404 -20.366477) (xy 113.285197 -20.38623) (xy 113.343036 -20.413447) (xy 113.397007 -20.447698)
			(xy 113.44626 -20.488443) (xy 113.490017 -20.53504) (xy 113.52759 -20.586755) (xy 113.558384 -20.64277)
			(xy 113.581916 -20.702203) (xy 113.597813 -20.764117) (xy 113.605824 -20.827535) (xy 113.606326 -20.859496)
			(xy 113.605824 -20.891457) (xy 113.597813 -20.954875) (xy 113.581916 -21.016789) (xy 113.558384 -21.076222)
			(xy 113.52759 -21.132237) (xy 113.490017 -21.183952) (xy 113.44626 -21.230549) (xy 113.397007 -21.271294)
			(xy 113.343036 -21.305545) (xy 113.285197 -21.332762) (xy 113.224404 -21.352515) (xy 113.161614 -21.364493)
			(xy 113.097818 -21.368507) (xy 113.034022 -21.364493) (xy 112.971232 -21.352515) (xy 112.910439 -21.332762)
			(xy 112.8526 -21.305545) (xy 112.798629 -21.271294) (xy 112.749376 -21.230549) (xy 112.705619 -21.183952)
			(xy 112.668046 -21.132237) (xy 112.637252 -21.076222) (xy 112.61372 -21.016789) (xy 112.597823 -20.954875)
			(xy 112.589812 -20.891457) (xy 110.066347 -20.891457) (xy 110.073192 -20.945645) (xy 110.073694 -20.977606)
			(xy 110.073192 -21.009567) (xy 110.065181 -21.072985) (xy 110.049284 -21.134899) (xy 110.025752 -21.194332)
			(xy 109.994958 -21.250347) (xy 109.957385 -21.302062) (xy 109.913628 -21.348659) (xy 109.864375 -21.389404)
			(xy 109.810404 -21.423655) (xy 109.752565 -21.450872) (xy 109.691772 -21.470625) (xy 109.628982 -21.482603)
			(xy 109.565186 -21.486617) (xy 109.50139 -21.482603) (xy 109.4386 -21.470625) (xy 109.377807 -21.450872)
			(xy 109.319968 -21.423655) (xy 109.265997 -21.389404) (xy 109.216744 -21.348659) (xy 109.172987 -21.302062)
			(xy 109.135414 -21.250347) (xy 109.10462 -21.194332) (xy 109.081088 -21.134899) (xy 109.065191 -21.072985)
			(xy 109.05718 -21.009567) (xy 108.915708 -21.009567) (xy 108.915708 -22.051772) (xy 108.916362 -22.063418)
			(xy 108.926662 -22.084317) (xy 108.93552 -22.091904) (xy 108.947053 -22.100794) (xy 113.9444 -22.100794)
			(xy 113.94485 -22.073541) (xy 113.952608 -22.019589) (xy 113.967965 -21.96729) (xy 113.990609 -21.91771)
			(xy 114.020078 -21.871856) (xy 114.055773 -21.830663) (xy 114.096967 -21.79497) (xy 114.142822 -21.765502)
			(xy 114.192403 -21.74286) (xy 114.244703 -21.727505) (xy 114.298655 -21.719749) (xy 114.325908 -21.719286)
			(xy 114.352283 -21.719749) (xy 114.40453 -21.727009) (xy 114.455276 -21.741404) (xy 114.503554 -21.762659)
			(xy 114.548439 -21.790366) (xy 114.589076 -21.823998) (xy 114.624687 -21.862912) (xy 114.654593 -21.906364)
			(xy 114.678222 -21.953525) (xy 114.687096 -21.978366) (xy 114.690223 -21.986482) (xy 114.701004 -22.000117)
			(xy 114.708178 -22.005036) (xy 114.733578 -22.021038) (xy 114.741274 -22.025401) (xy 114.758547 -22.029172)
			(xy 114.76736 -22.028404) (xy 114.783921 -22.026363) (xy 114.817222 -22.024203) (xy 114.833908 -22.024086)
			(xy 114.868863 -22.024666) (xy 114.938117 -22.034229) (xy 115.005407 -22.053186) (xy 115.069468 -22.081182)
			(xy 115.12909 -22.117687) (xy 115.156488 -22.139402) (xy 115.163435 -22.144635) (xy 115.179801 -22.150484)
			(xy 115.188492 -22.150832) (xy 115.342924 -22.150832) (xy 115.351608 -22.15046) (xy 115.367966 -22.144607)
			(xy 115.374928 -22.139402) (xy 115.402317 -22.117676) (xy 115.461946 -22.081181) (xy 115.526009 -22.05319)
			(xy 115.5933 -22.034233) (xy 115.662553 -22.024664) (xy 115.697508 -22.024086) (xy 115.714193 -22.024209)
			(xy 115.747494 -22.026373) (xy 115.764056 -22.028404) (xy 115.772875 -22.029292) (xy 115.790182 -22.025507)
			(xy 115.797838 -22.021038) (xy 115.823238 -22.005036) (xy 115.830429 -22.000138) (xy 115.841203 -21.98649)
			(xy 115.84432 -21.978366) (xy 115.853188 -21.953523) (xy 115.876823 -21.906366) (xy 115.906733 -21.862916)
			(xy 115.942346 -21.824004) (xy 115.982983 -21.790372) (xy 116.027867 -21.762662) (xy 116.076143 -21.741403)
			(xy 116.126888 -21.727002) (xy 116.179133 -21.719732) (xy 116.205508 -21.719286) (xy 116.232759 -21.71977)
			(xy 116.286707 -21.727528) (xy 116.339001 -21.742884) (xy 116.388578 -21.765525) (xy 116.434428 -21.794992)
			(xy 116.475618 -21.830683) (xy 116.511309 -21.871874) (xy 116.540776 -21.917724) (xy 116.558823 -21.957241)
			(xy 127.710178 -21.957241) (xy 127.710178 -21.893319) (xy 127.718189 -21.829901) (xy 127.734086 -21.767987)
			(xy 127.757618 -21.708554) (xy 127.788412 -21.652539) (xy 127.825985 -21.600824) (xy 127.869742 -21.554227)
			(xy 127.918995 -21.513482) (xy 127.972966 -21.479231) (xy 128.030805 -21.452014) (xy 128.091598 -21.432261)
			(xy 128.154388 -21.420283) (xy 128.218184 -21.41627) (xy 128.28198 -21.420283) (xy 128.34477 -21.432261)
			(xy 128.405563 -21.452014) (xy 128.463402 -21.479231) (xy 128.517373 -21.513482) (xy 128.566626 -21.554227)
			(xy 128.610383 -21.600824) (xy 128.647956 -21.652539) (xy 128.67875 -21.708554) (xy 128.702282 -21.767987)
			(xy 128.718179 -21.829901) (xy 128.72619 -21.893319) (xy 128.726692 -21.92528) (xy 128.72619 -21.957241)
			(xy 128.718179 -22.020659) (xy 128.702282 -22.082573) (xy 128.67875 -22.142006) (xy 128.647956 -22.198021)
			(xy 128.610383 -22.249736) (xy 128.566626 -22.296333) (xy 128.517373 -22.337078) (xy 128.463402 -22.371329)
			(xy 128.405563 -22.398546) (xy 128.34477 -22.418299) (xy 128.28198 -22.430277) (xy 128.218184 -22.434291)
			(xy 128.154388 -22.430277) (xy 128.091598 -22.418299) (xy 128.030805 -22.398546) (xy 127.972966 -22.371329)
			(xy 127.918995 -22.337078) (xy 127.869742 -22.296333) (xy 127.825985 -22.249736) (xy 127.788412 -22.198021)
			(xy 127.757618 -22.142006) (xy 127.734086 -22.082573) (xy 127.718189 -22.020659) (xy 127.710178 -21.957241)
			(xy 116.558823 -21.957241) (xy 116.563417 -21.967301) (xy 116.578773 -22.019595) (xy 116.58653 -22.073543)
			(xy 116.587016 -22.100794) (xy 116.586568 -22.127616) (xy 116.579063 -22.180732) (xy 116.564185 -22.232271)
			(xy 116.542229 -22.281215) (xy 116.513629 -22.326598) (xy 116.478948 -22.367524) (xy 116.438873 -22.403183)
			(xy 116.394194 -22.432872) (xy 116.345795 -22.456005) (xy 116.294631 -22.472124) (xy 116.268246 -22.476968)
			(xy 116.259669 -22.478727) (xy 116.244346 -22.48717) (xy 116.238274 -22.493478) (xy 116.206016 -22.530308)
			(xy 116.206016 -22.532594) (xy 116.205538 -22.563325) (xy 116.198131 -22.624338) (xy 116.183423 -22.684013)
			(xy 116.161629 -22.74148) (xy 116.133067 -22.795902) (xy 116.098154 -22.846484) (xy 116.057399 -22.892489)
			(xy 116.011395 -22.933246) (xy 115.960814 -22.96816) (xy 115.906393 -22.996723) (xy 115.848926 -23.018519)
			(xy 115.789251 -23.033228) (xy 115.728239 -23.040637) (xy 115.697508 -23.041102) (xy 115.662553 -23.040516)
			(xy 115.5933 -23.030955) (xy 115.526009 -23.011999) (xy 115.461949 -22.984005) (xy 115.402326 -22.947501)
			(xy 115.374928 -22.925786) (xy 115.367977 -22.920558) (xy 115.351614 -22.914707) (xy 115.342924 -22.914356)
			(xy 115.188492 -22.914356) (xy 115.179806 -22.914717) (xy 115.163448 -22.920575) (xy 115.156488 -22.925786)
			(xy 115.129092 -22.947502) (xy 115.069465 -22.984) (xy 115.005404 -23.011992) (xy 114.938114 -23.030952)
			(xy 114.868863 -23.040523) (xy 114.833908 -23.041102) (xy 114.803176 -23.040655) (xy 114.74216 -23.033247)
			(xy 114.682481 -23.018538) (xy 114.625011 -22.996743) (xy 114.570587 -22.96818) (xy 114.520002 -22.933264)
			(xy 114.473995 -22.892506) (xy 114.433237 -22.846499) (xy 114.398321 -22.795915) (xy 114.369758 -22.741491)
			(xy 114.347962 -22.684021) (xy 114.333253 -22.624342) (xy 114.325845 -22.563326) (xy 114.3254 -22.532594)
			(xy 114.3254 -22.530308) (xy 114.293142 -22.493478) (xy 114.287081 -22.487157) (xy 114.271751 -22.478716)
			(xy 114.26317 -22.476968) (xy 114.236799 -22.472071) (xy 114.185648 -22.45594) (xy 114.137262 -22.432801)
			(xy 114.092594 -22.403112) (xy 114.052527 -22.367457) (xy 114.01785 -22.326541) (xy 113.989247 -22.28117)
			(xy 113.967282 -22.23224) (xy 113.95239 -22.180715) (xy 113.944862 -22.127611) (xy 113.9444 -22.100794)
			(xy 108.947053 -22.100794) (xy 109.008672 -22.148292) (xy 109.031278 -22.152864) (xy 109.042962 -22.149816)
			(xy 109.06661 -22.144037) (xy 109.114888 -22.137791) (xy 109.139228 -22.13737) (xy 109.13999 -22.13737)
			(xy 109.167242 -22.137877) (xy 109.221191 -22.145632) (xy 109.273487 -22.160986) (xy 109.323065 -22.183627)
			(xy 109.368917 -22.213093) (xy 109.410108 -22.248784) (xy 109.445801 -22.289975) (xy 109.475268 -22.335826)
			(xy 109.49791 -22.385404) (xy 109.513266 -22.4377) (xy 109.521023 -22.491648) (xy 109.521023 -22.546152)
			(xy 109.513266 -22.6001) (xy 109.49791 -22.652396) (xy 109.475268 -22.701974) (xy 109.445801 -22.747825)
			(xy 109.410108 -22.789016) (xy 109.368917 -22.824707) (xy 109.323065 -22.854173) (xy 109.273487 -22.876814)
			(xy 109.221191 -22.892168) (xy 109.167242 -22.899923) (xy 109.13999 -22.900386) (xy 109.139228 -22.900386)
			(xy 109.114886 -22.899991) (xy 109.066605 -22.893746) (xy 109.042962 -22.88794) (xy 109.031278 -22.884892)
			(xy 109.008672 -22.889464) (xy 108.93552 -22.945852) (xy 108.926624 -22.953418) (xy 108.916286 -22.974322)
			(xy 108.915708 -22.985984) (xy 108.915708 -23.492707) (xy 112.144619 -23.492707) (xy 112.144625 -23.438211)
			(xy 112.152386 -23.38427) (xy 112.167745 -23.331984) (xy 112.190389 -23.282415) (xy 112.219857 -23.236573)
			(xy 112.255548 -23.195392) (xy 112.296737 -23.159709) (xy 112.342585 -23.130251) (xy 112.392159 -23.107617)
			(xy 112.444449 -23.092269) (xy 112.498391 -23.084519) (xy 112.552887 -23.084525) (xy 112.606827 -23.092286)
			(xy 112.659114 -23.107644) (xy 112.708683 -23.130288) (xy 112.754525 -23.159755) (xy 112.795707 -23.195446)
			(xy 112.83139 -23.236635) (xy 112.860848 -23.282483) (xy 112.883482 -23.332056) (xy 112.89883 -23.384346)
			(xy 112.90658 -23.438288) (xy 112.907064 -23.465536) (xy 112.906809 -23.485888) (xy 112.902481 -23.526362)
			(xy 112.898428 -23.546308) (xy 112.896594 -23.558015) (xy 112.90255 -23.580922) (xy 112.909858 -23.59025)
			(xy 112.963452 -23.651972) (xy 112.971646 -23.660407) (xy 112.993349 -23.669404) (xy 113.005108 -23.669244)
			(xy 113.005362 -23.669244) (xy 113.032794 -23.668228) (xy 113.897918 -23.668228) (xy 113.92535 -23.669244)
			(xy 113.925604 -23.669244) (xy 113.937377 -23.669455) (xy 113.959103 -23.660462) (xy 113.96726 -23.651972)
			(xy 114.020854 -23.59025) (xy 114.028213 -23.580946) (xy 114.034176 -23.558019) (xy 114.032284 -23.546308)
			(xy 114.028245 -23.52636) (xy 114.02392 -23.485887) (xy 114.023648 -23.465536) (xy 114.024116 -23.438279)
			(xy 114.03187 -23.38432) (xy 114.047224 -23.332014) (xy 114.069866 -23.282425) (xy 114.099335 -23.236563)
			(xy 114.135031 -23.195363) (xy 114.176227 -23.159662) (xy 114.222085 -23.130187) (xy 114.271671 -23.10754)
			(xy 114.323976 -23.092179) (xy 114.377934 -23.08442) (xy 114.432447 -23.084418) (xy 114.486406 -23.092175)
			(xy 114.538711 -23.107533) (xy 114.588298 -23.130178) (xy 114.634158 -23.159651) (xy 114.675356 -23.19535)
			(xy 114.711054 -23.236548) (xy 114.740525 -23.282409) (xy 114.76317 -23.331996) (xy 114.778526 -23.384302)
			(xy 114.786282 -23.438261) (xy 114.78628 -23.492774) (xy 114.778519 -23.546732) (xy 114.763158 -23.599036)
			(xy 114.740951 -23.647654) (xy 115.710716 -23.647654) (xy 115.711135 -23.620401) (xy 115.718899 -23.566449)
			(xy 115.734261 -23.514152) (xy 115.756909 -23.464573) (xy 115.786382 -23.418721) (xy 115.822081 -23.377531)
			(xy 115.863278 -23.34184) (xy 115.909134 -23.312375) (xy 115.958717 -23.289736) (xy 116.011018 -23.274384)
			(xy 116.06497 -23.26663) (xy 116.092224 -23.266146) (xy 116.121072 -23.266654) (xy 116.178112 -23.275332)
			(xy 116.233194 -23.2925) (xy 116.285063 -23.317767) (xy 116.332535 -23.350557) (xy 116.374528 -23.390122)
			(xy 116.410083 -23.43556) (xy 116.438391 -23.485834) (xy 116.458805 -23.539797) (xy 116.46535 -23.567898)
			(xy 116.467128 -23.576788) (xy 116.47678 -23.592028) (xy 116.54409 -23.643336) (xy 116.561362 -23.648416)
			(xy 116.570506 -23.647908) (xy 116.600224 -23.647146) (xy 116.635179 -23.647726) (xy 116.704432 -23.65729)
			(xy 116.771723 -23.676248) (xy 116.835783 -23.704243) (xy 116.895405 -23.740748) (xy 116.922804 -23.762462)
			(xy 116.929742 -23.767709) (xy 116.946116 -23.773548) (xy 116.954808 -23.773892) (xy 117.10924 -23.773892)
			(xy 117.117921 -23.77349) (xy 117.13428 -23.767659) (xy 117.141244 -23.762462) (xy 117.168623 -23.740723)
			(xy 117.228255 -23.704231) (xy 117.292321 -23.676244) (xy 117.359614 -23.657289) (xy 117.428868 -23.647723)
			(xy 117.463824 -23.647146) (xy 117.493542 -23.647908) (xy 117.502686 -23.648416) (xy 117.519958 -23.643336)
			(xy 117.587268 -23.592028) (xy 117.59692 -23.576788) (xy 117.598698 -23.567898) (xy 117.605259 -23.539805)
			(xy 117.625689 -23.485855) (xy 117.654005 -23.435594) (xy 117.689563 -23.390167) (xy 117.731554 -23.350609)
			(xy 117.779019 -23.317822) (xy 117.830878 -23.292551) (xy 117.88595 -23.275374) (xy 117.94298 -23.26668)
			(xy 117.971824 -23.266146) (xy 117.999074 -23.266655) (xy 118.053018 -23.274414) (xy 118.10531 -23.28977)
			(xy 118.154884 -23.31241) (xy 118.200732 -23.341875) (xy 118.241921 -23.377564) (xy 118.277612 -23.41875)
			(xy 118.307079 -23.464597) (xy 118.329723 -23.51417) (xy 118.345081 -23.56646) (xy 118.352843 -23.620404)
			(xy 118.353332 -23.647654) (xy 118.352868 -23.676504) (xy 118.344186 -23.733546) (xy 118.327013 -23.78863)
			(xy 118.30174 -23.8405) (xy 118.268944 -23.887973) (xy 118.229374 -23.929965) (xy 118.18393 -23.96552)
			(xy 118.133651 -23.993826) (xy 118.079683 -24.014237) (xy 118.05158 -24.02078) (xy 118.04269 -24.022558)
			(xy 118.02745 -24.03221) (xy 117.976142 -24.09952) (xy 117.971062 -24.116792) (xy 117.97157 -24.125936)
			(xy 117.972332 -24.155654) (xy 117.971819 -24.186384) (xy 117.964416 -24.247397) (xy 117.949713 -24.307073)
			(xy 117.927923 -24.364541) (xy 117.899365 -24.418964) (xy 117.864456 -24.469547) (xy 117.823703 -24.515554)
			(xy 117.777702 -24.556313) (xy 117.727124 -24.591229) (xy 117.672705 -24.619795) (xy 117.61524 -24.641592)
			(xy 117.555566 -24.656304) (xy 117.494554 -24.663715) (xy 117.463824 -24.664162) (xy 117.42887 -24.663553)
			(xy 117.359618 -24.653996) (xy 117.292328 -24.635044) (xy 117.228267 -24.607056) (xy 117.168643 -24.570557)
			(xy 117.141244 -24.548846) (xy 117.134292 -24.54362) (xy 117.117929 -24.537768) (xy 117.10924 -24.537416)
			(xy 116.954808 -24.537416) (xy 116.946124 -24.537793) (xy 116.929766 -24.543641) (xy 116.922804 -24.548846)
			(xy 116.895409 -24.570564) (xy 116.835781 -24.607059) (xy 116.77172 -24.63505) (xy 116.70443 -24.65401)
			(xy 116.635179 -24.663582) (xy 116.600224 -24.664162) (xy 116.569491 -24.66374) (xy 116.508472 -24.656333)
			(xy 116.448791 -24.641625) (xy 116.391318 -24.619829) (xy 116.336892 -24.591264) (xy 116.286306 -24.556347)
			(xy 116.240298 -24.515586) (xy 116.199539 -24.469577) (xy 116.164624 -24.418989) (xy 116.136062 -24.364562)
			(xy 116.114269 -24.307088) (xy 116.099563 -24.247407) (xy 116.092159 -24.186387) (xy 116.091716 -24.155654)
			(xy 116.092478 -24.125936) (xy 116.092986 -24.116792) (xy 116.087906 -24.09952) (xy 116.036598 -24.03221)
			(xy 116.021358 -24.022558) (xy 116.012468 -24.02078) (xy 115.984381 -24.014191) (xy 115.930429 -23.993769)
			(xy 115.880166 -23.965459) (xy 115.834737 -23.929905) (xy 115.795177 -23.887919) (xy 115.762388 -23.840456)
			(xy 115.737117 -23.788598) (xy 115.71994 -23.733527) (xy 115.711249 -23.676498) (xy 115.710716 -23.647654)
			(xy 114.740951 -23.647654) (xy 114.740509 -23.648622) (xy 114.711033 -23.694479) (xy 114.675332 -23.735675)
			(xy 114.63413 -23.77137) (xy 114.588268 -23.800838) (xy 114.538679 -23.823479) (xy 114.486372 -23.838832)
			(xy 114.432413 -23.846584) (xy 114.405156 -23.847044) (xy 114.376962 -23.846028) (xy 114.365024 -23.845012)
			(xy 114.342672 -23.854156) (xy 114.281204 -23.925022) (xy 114.273971 -23.934383) (xy 114.268149 -23.957284)
			(xy 114.270028 -23.968964) (xy 114.274063 -23.988913) (xy 114.278391 -24.029385) (xy 114.278664 -24.049736)
			(xy 114.278278 -24.076992) (xy 114.270515 -24.130948) (xy 114.255153 -24.18325) (xy 114.232503 -24.232833)
			(xy 114.203027 -24.278688) (xy 114.167325 -24.319882) (xy 114.126124 -24.355575) (xy 114.080263 -24.385041)
			(xy 114.030675 -24.407681) (xy 113.97837 -24.423032) (xy 113.924412 -24.430784) (xy 113.897156 -24.431244)
			(xy 113.033556 -24.431244) (xy 113.006305 -24.430763) (xy 112.952359 -24.423002) (xy 112.900067 -24.407643)
			(xy 112.850492 -24.384999) (xy 112.804643 -24.355532) (xy 112.763454 -24.31984) (xy 112.727764 -24.27865)
			(xy 112.698297 -24.232801) (xy 112.675654 -24.183226) (xy 112.660297 -24.130933) (xy 112.652536 -24.076987)
			(xy 112.652048 -24.049736) (xy 112.652298 -24.029384) (xy 112.656629 -23.98891) (xy 112.660684 -23.968964)
			(xy 112.662592 -23.957278) (xy 112.656786 -23.934359) (xy 112.649508 -23.925022) (xy 112.58804 -23.854156)
			(xy 112.565688 -23.845012) (xy 112.55375 -23.846028) (xy 112.525556 -23.847044) (xy 112.498308 -23.846475)
			(xy 112.444368 -23.838713) (xy 112.392081 -23.823354) (xy 112.342512 -23.80071) (xy 112.296671 -23.771242)
			(xy 112.25549 -23.73555) (xy 112.219807 -23.694361) (xy 112.190349 -23.648513) (xy 112.167716 -23.598939)
			(xy 112.152369 -23.546649) (xy 112.144619 -23.492707) (xy 108.915708 -23.492707) (xy 108.915708 -24.011128)
			(xy 108.915321 -24.021202) (xy 108.907576 -24.039801) (xy 108.900722 -24.047196) (xy 108.687362 -24.260302)
			(xy 108.679642 -24.268815) (xy 108.672094 -24.290494) (xy 108.672884 -24.301958) (xy 108.672884 -24.302466)
			(xy 108.679525 -24.361997) (xy 108.686642 -24.481582) (xy 108.687108 -24.54148) (xy 108.686597 -24.605338)
			(xy 108.678579 -24.732803) (xy 108.672138 -24.783796) (xy 121.259092 -24.783796) (xy 121.259092 -24.783542)
			(xy 121.259492 -24.753333) (xy 121.266638 -24.69334) (xy 121.280847 -24.634617) (xy 121.301918 -24.577992)
			(xy 121.329553 -24.524266) (xy 121.363364 -24.474194) (xy 121.38279 -24.451056) (xy 121.388447 -24.443994)
			(xy 121.394826 -24.427075) (xy 121.395236 -24.418036) (xy 121.395236 -24.387556) (xy 121.394815 -24.378519)
			(xy 121.388438 -24.361602) (xy 121.38279 -24.354536) (xy 121.363363 -24.331402) (xy 121.329577 -24.281318)
			(xy 121.301958 -24.227587) (xy 121.280896 -24.170964) (xy 121.266685 -24.112245) (xy 121.259526 -24.052257)
			(xy 121.259092 -24.02205) (xy 121.259092 -24.021796) (xy 121.259604 -23.990509) (xy 121.267275 -23.928409)
			(xy 121.282514 -23.86772) (xy 121.305088 -23.809361) (xy 121.334657 -23.754215) (xy 121.370774 -23.703118)
			(xy 121.412891 -23.656841) (xy 121.460371 -23.616086) (xy 121.486168 -23.598378) (xy 121.496312 -23.590847)
			(xy 121.508176 -23.56858) (xy 121.508774 -23.55596) (xy 121.508774 -23.471632) (xy 121.508116 -23.459029)
			(xy 121.496267 -23.436781) (xy 121.486168 -23.429214) (xy 121.460368 -23.411509) (xy 121.412888 -23.370751)
			(xy 121.37077 -23.324474) (xy 121.334651 -23.273376) (xy 121.305078 -23.218231) (xy 121.282498 -23.159873)
			(xy 121.267252 -23.099184) (xy 121.259572 -23.037083) (xy 121.259092 -23.005796) (xy 121.259594 -22.973835)
			(xy 121.267605 -22.910417) (xy 121.283502 -22.848503) (xy 121.307034 -22.78907) (xy 121.337828 -22.733055)
			(xy 121.375401 -22.68134) (xy 121.419158 -22.634743) (xy 121.468411 -22.593998) (xy 121.522382 -22.559747)
			(xy 121.580221 -22.53253) (xy 121.641014 -22.512777) (xy 121.703804 -22.500799) (xy 121.7676 -22.496786)
			(xy 121.831396 -22.500799) (xy 121.894186 -22.512777) (xy 121.954979 -22.53253) (xy 122.012818 -22.559747)
			(xy 122.066789 -22.593998) (xy 122.116042 -22.634743) (xy 122.159799 -22.68134) (xy 122.197372 -22.733055)
			(xy 122.228166 -22.78907) (xy 122.251698 -22.848503) (xy 122.267595 -22.910417) (xy 122.275606 -22.973835)
			(xy 122.276108 -23.005796) (xy 122.275923 -23.016972) (xy 136.196832 -23.016972) (xy 136.197312 -22.985772)
			(xy 136.204962 -22.923844) (xy 136.220132 -22.863316) (xy 136.242593 -22.8051) (xy 136.272008 -22.750068)
			(xy 136.307935 -22.699049) (xy 136.349835 -22.652809) (xy 136.397077 -22.612043) (xy 136.448951 -22.577363)
			(xy 136.504679 -22.549291) (xy 136.563423 -22.528247) (xy 136.624301 -22.514549) (xy 136.655302 -22.511004)
			(xy 136.664192 -22.510242) (xy 136.679686 -22.502876) (xy 136.802114 -22.380448) (xy 136.80948 -22.364954)
			(xy 136.810242 -22.356064) (xy 136.813789 -22.325061) (xy 136.827473 -22.264177) (xy 136.848506 -22.205425)
			(xy 136.876572 -22.149689) (xy 136.911249 -22.097808) (xy 136.952015 -22.050561) (xy 136.998257 -22.008659)
			(xy 137.04928 -21.972731) (xy 137.104317 -21.943319) (xy 137.162541 -21.920864) (xy 137.223074 -21.905704)
			(xy 137.285008 -21.898068) (xy 137.31621 -21.897594) (xy 137.34827 -21.8981) (xy 137.411882 -21.906147)
			(xy 137.473979 -21.922124) (xy 137.516378 -21.938953) (xy 148.019002 -21.938953) (xy 148.019002 -21.875031)
			(xy 148.027013 -21.811613) (xy 148.04291 -21.749699) (xy 148.066442 -21.690266) (xy 148.097236 -21.634251)
			(xy 148.134809 -21.582536) (xy 148.178566 -21.535939) (xy 148.227819 -21.495194) (xy 148.28179 -21.460943)
			(xy 148.339629 -21.433726) (xy 148.400422 -21.413973) (xy 148.463212 -21.401995) (xy 148.527008 -21.397982)
			(xy 148.590804 -21.401995) (xy 148.653594 -21.413973) (xy 148.714387 -21.433726) (xy 148.772226 -21.460943)
			(xy 148.817067 -21.4894) (xy 163.118284 -21.4894) (xy 163.122298 -21.425603) (xy 163.134276 -21.362812)
			(xy 163.15403 -21.302017) (xy 163.181248 -21.244178) (xy 163.2155 -21.190206) (xy 163.256246 -21.140952)
			(xy 163.302845 -21.097194) (xy 163.35456 -21.059621) (xy 163.410577 -21.028827) (xy 163.470012 -21.005296)
			(xy 163.531927 -20.989399) (xy 163.595346 -20.981388) (xy 163.627308 -20.980908) (xy 163.657271 -20.981313)
			(xy 163.716782 -20.988364) (xy 163.775049 -21.002368) (xy 163.831264 -21.02313) (xy 163.884646 -21.050361)
			(xy 163.934454 -21.083684) (xy 163.957508 -21.102828) (xy 163.957762 -21.103082) (xy 163.967067 -21.110121)
			(xy 163.989693 -21.115692) (xy 164.001196 -21.11375) (xy 164.08019 -21.096732) (xy 164.091585 -21.093682)
			(xy 164.109991 -21.078972) (xy 164.115496 -21.068538) (xy 164.129479 -21.03971) (xy 164.163708 -20.985543)
			(xy 164.204468 -20.936103) (xy 164.251114 -20.892175) (xy 164.302908 -20.854451) (xy 164.35903 -20.823532)
			(xy 164.41859 -20.799905) (xy 164.480646 -20.783945) (xy 164.544214 -20.775904) (xy 164.576252 -20.775422)
			(xy 164.608218 -20.77584) (xy 164.671647 -20.783847) (xy 164.733572 -20.799742) (xy 164.793017 -20.823273)
			(xy 164.849043 -20.854069) (xy 164.900767 -20.891644) (xy 164.947374 -20.935407) (xy 164.988128 -20.984666)
			(xy 165.022387 -21.038644) (xy 165.049609 -21.096491) (xy 165.069366 -21.157294) (xy 165.081347 -21.220094)
			(xy 165.085362 -21.2839) (xy 165.081347 -21.347706) (xy 165.069366 -21.410506) (xy 165.049609 -21.471309)
			(xy 165.022387 -21.529156) (xy 164.988128 -21.583134) (xy 164.985005 -21.586909) (xy 168.706794 -21.586909)
			(xy 168.706794 -21.522987) (xy 168.714805 -21.459569) (xy 168.730702 -21.397655) (xy 168.754234 -21.338222)
			(xy 168.785028 -21.282207) (xy 168.822601 -21.230492) (xy 168.866358 -21.183895) (xy 168.915611 -21.14315)
			(xy 168.969582 -21.108899) (xy 169.027421 -21.081682) (xy 169.088214 -21.061929) (xy 169.151004 -21.049951)
			(xy 169.2148 -21.045938) (xy 169.278596 -21.049951) (xy 169.341386 -21.061929) (xy 169.402179 -21.081682)
			(xy 169.460018 -21.108899) (xy 169.513989 -21.14315) (xy 169.563242 -21.183895) (xy 169.606999 -21.230492)
			(xy 169.644572 -21.282207) (xy 169.675366 -21.338222) (xy 169.698898 -21.397655) (xy 169.714795 -21.459569)
			(xy 169.722806 -21.522987) (xy 169.723308 -21.554948) (xy 169.722806 -21.586909) (xy 169.714795 -21.650327)
			(xy 169.698898 -21.712241) (xy 169.675366 -21.771674) (xy 169.644572 -21.827689) (xy 169.606999 -21.879404)
			(xy 169.563242 -21.926001) (xy 169.513989 -21.966746) (xy 169.460018 -22.000997) (xy 169.402179 -22.028214)
			(xy 169.341386 -22.047967) (xy 169.278596 -22.059945) (xy 169.2148 -22.063959) (xy 169.151004 -22.059945)
			(xy 169.088214 -22.047967) (xy 169.027421 -22.028214) (xy 168.969582 -22.000997) (xy 168.915611 -21.966746)
			(xy 168.866358 -21.926001) (xy 168.822601 -21.879404) (xy 168.785028 -21.827689) (xy 168.754234 -21.771674)
			(xy 168.730702 -21.712241) (xy 168.714805 -21.650327) (xy 168.706794 -21.586909) (xy 164.985005 -21.586909)
			(xy 164.947374 -21.632393) (xy 164.900767 -21.676156) (xy 164.849043 -21.713731) (xy 164.793017 -21.744527)
			(xy 164.733572 -21.768058) (xy 164.671647 -21.783953) (xy 164.608218 -21.79196) (xy 164.576252 -21.792438)
			(xy 164.54629 -21.791987) (xy 164.486782 -21.784943) (xy 164.428516 -21.770948) (xy 164.372301 -21.750194)
			(xy 164.318918 -21.722972) (xy 164.269108 -21.689658) (xy 164.246052 -21.670518) (xy 164.245798 -21.670264)
			(xy 164.23651 -21.663198) (xy 164.21387 -21.657645) (xy 164.202364 -21.659596) (xy 164.12337 -21.676614)
			(xy 164.111978 -21.67967) (xy 164.093572 -21.694377) (xy 164.088064 -21.704808) (xy 164.074009 -21.7336)
			(xy 164.039791 -21.787767) (xy 163.999041 -21.837208) (xy 163.952404 -21.88114) (xy 163.900619 -21.918867)
			(xy 163.844507 -21.949792) (xy 163.784954 -21.973424) (xy 163.722906 -21.989391) (xy 163.659343 -21.997438)
			(xy 163.627308 -21.997924) (xy 163.595346 -21.997412) (xy 163.531927 -21.989401) (xy 163.470012 -21.973504)
			(xy 163.410577 -21.949973) (xy 163.35456 -21.919179) (xy 163.302845 -21.881606) (xy 163.256246 -21.837848)
			(xy 163.2155 -21.788594) (xy 163.181248 -21.734622) (xy 163.15403 -21.676783) (xy 163.134276 -21.615988)
			(xy 163.122298 -21.553197) (xy 163.118284 -21.4894) (xy 148.817067 -21.4894) (xy 148.826197 -21.495194)
			(xy 148.87545 -21.535939) (xy 148.919207 -21.582536) (xy 148.95678 -21.634251) (xy 148.987574 -21.690266)
			(xy 149.011106 -21.749699) (xy 149.027003 -21.811613) (xy 149.035014 -21.875031) (xy 149.035516 -21.906992)
			(xy 149.035014 -21.938953) (xy 149.027003 -22.002371) (xy 149.011106 -22.064285) (xy 148.994254 -22.106847)
			(xy 149.479248 -22.106847) (xy 149.479248 -22.042925) (xy 149.487259 -21.979507) (xy 149.503156 -21.917593)
			(xy 149.526688 -21.85816) (xy 149.557482 -21.802145) (xy 149.595055 -21.75043) (xy 149.638812 -21.703833)
			(xy 149.688065 -21.663088) (xy 149.742036 -21.628837) (xy 149.799875 -21.60162) (xy 149.860668 -21.581867)
			(xy 149.923458 -21.569889) (xy 149.987254 -21.565876) (xy 150.05105 -21.569889) (xy 150.11384 -21.581867)
			(xy 150.174633 -21.60162) (xy 150.232472 -21.628837) (xy 150.286443 -21.663088) (xy 150.335696 -21.703833)
			(xy 150.379453 -21.75043) (xy 150.417026 -21.802145) (xy 150.44782 -21.85816) (xy 150.471352 -21.917593)
			(xy 150.487249 -21.979507) (xy 150.49526 -22.042925) (xy 150.495762 -22.074886) (xy 150.49526 -22.106847)
			(xy 150.487249 -22.170265) (xy 150.471352 -22.232179) (xy 150.44782 -22.291612) (xy 150.417026 -22.347627)
			(xy 150.379453 -22.399342) (xy 150.335696 -22.445939) (xy 150.286443 -22.486684) (xy 150.269401 -22.497499)
			(xy 166.681906 -22.497499) (xy 166.681906 -22.433577) (xy 166.689917 -22.370159) (xy 166.705814 -22.308245)
			(xy 166.729346 -22.248812) (xy 166.76014 -22.192797) (xy 166.797713 -22.141082) (xy 166.84147 -22.094485)
			(xy 166.890723 -22.05374) (xy 166.944694 -22.019489) (xy 167.002533 -21.992272) (xy 167.063326 -21.972519)
			(xy 167.126116 -21.960541) (xy 167.189912 -21.956528) (xy 167.253708 -21.960541) (xy 167.316498 -21.972519)
			(xy 167.377291 -21.992272) (xy 167.43513 -22.019489) (xy 167.489101 -22.05374) (xy 167.538354 -22.094485)
			(xy 167.582111 -22.141082) (xy 167.619684 -22.192797) (xy 167.650478 -22.248812) (xy 167.67401 -22.308245)
			(xy 167.689907 -22.370159) (xy 167.693159 -22.3959) (xy 171.070331 -22.3959) (xy 171.074345 -22.33211)
			(xy 171.086321 -22.269327) (xy 171.106072 -22.208539) (xy 171.133285 -22.150706) (xy 171.167533 -22.09674)
			(xy 171.208273 -22.047492) (xy 171.254865 -22.003738) (xy 171.306573 -21.966168) (xy 171.362583 -21.935376)
			(xy 171.422009 -21.911846) (xy 171.483917 -21.895949) (xy 171.547328 -21.887937) (xy 171.579286 -21.887434)
			(xy 171.611834 -21.887986) (xy 171.676398 -21.896291) (xy 171.739374 -21.912768) (xy 171.799732 -21.937147)
			(xy 171.856486 -21.969029) (xy 171.908708 -22.007893) (xy 171.955542 -22.053103) (xy 171.976288 -22.078188)
			(xy 171.982892 -22.08657) (xy 172.001434 -22.096476) (xy 172.09643 -22.103842) (xy 172.116242 -22.097238)
			(xy 172.124116 -22.090126) (xy 172.1453 -22.071573) (xy 172.192073 -22.040218) (xy 172.242944 -22.016072)
			(xy 172.296809 -21.999661) (xy 172.352501 -21.99134) (xy 172.380656 -21.990812) (xy 172.407912 -21.991232)
			(xy 172.461871 -21.998984) (xy 172.514177 -22.014337) (xy 172.563765 -22.036978) (xy 172.609626 -22.066447)
			(xy 172.650826 -22.102142) (xy 172.686527 -22.143338) (xy 172.716 -22.189196) (xy 172.738647 -22.238782)
			(xy 172.754006 -22.291086) (xy 172.761765 -22.345044) (xy 172.761765 -22.399556) (xy 172.754006 -22.453514)
			(xy 172.738647 -22.505818) (xy 172.716 -22.555404) (xy 172.686527 -22.601262) (xy 172.650826 -22.642458)
			(xy 172.609626 -22.678153) (xy 172.563765 -22.707622) (xy 172.514177 -22.730263) (xy 172.461871 -22.745616)
			(xy 172.407912 -22.753368) (xy 172.380656 -22.753828) (xy 172.35475 -22.753376) (xy 172.303417 -22.74636)
			(xy 172.253504 -22.732464) (xy 172.20593 -22.711942) (xy 172.161571 -22.685172) (xy 172.141134 -22.669246)
			(xy 172.133006 -22.662642) (xy 172.112686 -22.657054) (xy 172.018198 -22.670262) (xy 172.000418 -22.68093)
			(xy 171.994322 -22.689566) (xy 171.976444 -22.71411) (xy 171.935735 -22.759167) (xy 171.889946 -22.799051)
			(xy 171.839732 -22.833196) (xy 171.785807 -22.861114) (xy 171.728939 -22.882408) (xy 171.669939 -22.896775)
			(xy 171.609648 -22.904008) (xy 171.579286 -22.90445) (xy 171.547328 -22.903863) (xy 171.483917 -22.895851)
			(xy 171.422009 -22.879954) (xy 171.362583 -22.856424) (xy 171.306573 -22.825632) (xy 171.254865 -22.788062)
			(xy 171.208273 -22.744308) (xy 171.167533 -22.69506) (xy 171.133285 -22.641094) (xy 171.106072 -22.583261)
			(xy 171.086321 -22.522473) (xy 171.074345 -22.45969) (xy 171.070331 -22.3959) (xy 167.693159 -22.3959)
			(xy 167.697918 -22.433577) (xy 167.69842 -22.465538) (xy 167.697918 -22.497499) (xy 167.689907 -22.560917)
			(xy 167.67401 -22.622831) (xy 167.650478 -22.682264) (xy 167.619684 -22.738279) (xy 167.582111 -22.789994)
			(xy 167.538354 -22.836591) (xy 167.489101 -22.877336) (xy 167.43513 -22.911587) (xy 167.377291 -22.938804)
			(xy 167.316498 -22.958557) (xy 167.253708 -22.970535) (xy 167.189912 -22.974549) (xy 167.126116 -22.970535)
			(xy 167.063326 -22.958557) (xy 167.002533 -22.938804) (xy 166.944694 -22.911587) (xy 166.890723 -22.877336)
			(xy 166.84147 -22.836591) (xy 166.797713 -22.789994) (xy 166.76014 -22.738279) (xy 166.729346 -22.682264)
			(xy 166.705814 -22.622831) (xy 166.689917 -22.560917) (xy 166.681906 -22.497499) (xy 150.269401 -22.497499)
			(xy 150.232472 -22.520935) (xy 150.174633 -22.548152) (xy 150.11384 -22.567905) (xy 150.05105 -22.579883)
			(xy 149.987254 -22.583897) (xy 149.923458 -22.579883) (xy 149.860668 -22.567905) (xy 149.799875 -22.548152)
			(xy 149.742036 -22.520935) (xy 149.688065 -22.486684) (xy 149.638812 -22.445939) (xy 149.595055 -22.399342)
			(xy 149.557482 -22.347627) (xy 149.526688 -22.291612) (xy 149.503156 -22.232179) (xy 149.487259 -22.170265)
			(xy 149.479248 -22.106847) (xy 148.994254 -22.106847) (xy 148.987574 -22.123718) (xy 148.95678 -22.179733)
			(xy 148.919207 -22.231448) (xy 148.87545 -22.278045) (xy 148.826197 -22.31879) (xy 148.772226 -22.353041)
			(xy 148.714387 -22.380258) (xy 148.653594 -22.400011) (xy 148.590804 -22.411989) (xy 148.527008 -22.416003)
			(xy 148.463212 -22.411989) (xy 148.400422 -22.400011) (xy 148.339629 -22.380258) (xy 148.28179 -22.353041)
			(xy 148.227819 -22.31879) (xy 148.178566 -22.278045) (xy 148.134809 -22.231448) (xy 148.097236 -22.179733)
			(xy 148.066442 -22.123718) (xy 148.04291 -22.064285) (xy 148.027013 -22.002371) (xy 148.019002 -21.938953)
			(xy 137.516378 -21.938953) (xy 137.533576 -21.945779) (xy 137.589728 -21.976735) (xy 137.641544 -22.014502)
			(xy 137.688203 -22.058482) (xy 137.728965 -22.107977) (xy 137.746486 -22.13483) (xy 137.751683 -22.142378)
			(xy 137.766266 -22.153449) (xy 137.774934 -22.15642) (xy 137.804144 -22.16531) (xy 137.812848 -22.16761)
			(xy 137.830811 -22.166559) (xy 137.839196 -22.163278) (xy 137.863432 -22.153093) (xy 137.914005 -22.138733)
			(xy 137.966072 -22.131474) (xy 137.992358 -22.13102) (xy 138.019615 -22.131424) (xy 138.073574 -22.139177)
			(xy 138.125881 -22.15453) (xy 138.17547 -22.177172) (xy 138.221332 -22.206641) (xy 138.262533 -22.242337)
			(xy 138.298234 -22.283534) (xy 138.327708 -22.329393) (xy 138.350355 -22.378979) (xy 138.365714 -22.431285)
			(xy 138.373473 -22.485243) (xy 138.373473 -22.539757) (xy 138.365714 -22.593715) (xy 138.358241 -22.619165)
			(xy 146.41931 -22.619165) (xy 146.41931 -22.555243) (xy 146.427321 -22.491825) (xy 146.443218 -22.429911)
			(xy 146.46675 -22.370478) (xy 146.497544 -22.314463) (xy 146.535117 -22.262748) (xy 146.578874 -22.216151)
			(xy 146.628127 -22.175406) (xy 146.682098 -22.141155) (xy 146.739937 -22.113938) (xy 146.80073 -22.094185)
			(xy 146.86352 -22.082207) (xy 146.927316 -22.078194) (xy 146.991112 -22.082207) (xy 147.053902 -22.094185)
			(xy 147.114695 -22.113938) (xy 147.172534 -22.141155) (xy 147.226505 -22.175406) (xy 147.275758 -22.216151)
			(xy 147.319515 -22.262748) (xy 147.357088 -22.314463) (xy 147.387882 -22.370478) (xy 147.411414 -22.429911)
			(xy 147.427311 -22.491825) (xy 147.435322 -22.555243) (xy 147.435824 -22.587204) (xy 147.435322 -22.619165)
			(xy 147.427311 -22.682583) (xy 147.411414 -22.744497) (xy 147.387882 -22.80393) (xy 147.357088 -22.859945)
			(xy 147.319515 -22.91166) (xy 147.275758 -22.958257) (xy 147.226505 -22.999002) (xy 147.172534 -23.033253)
			(xy 147.114695 -23.06047) (xy 147.053902 -23.080223) (xy 146.991112 -23.092201) (xy 146.927316 -23.096215)
			(xy 146.86352 -23.092201) (xy 146.80073 -23.080223) (xy 146.739937 -23.06047) (xy 146.682098 -23.033253)
			(xy 146.628127 -22.999002) (xy 146.578874 -22.958257) (xy 146.535117 -22.91166) (xy 146.497544 -22.859945)
			(xy 146.46675 -22.80393) (xy 146.443218 -22.744497) (xy 146.427321 -22.682583) (xy 146.41931 -22.619165)
			(xy 138.358241 -22.619165) (xy 138.350355 -22.646021) (xy 138.327708 -22.695607) (xy 138.298234 -22.741466)
			(xy 138.262533 -22.782663) (xy 138.221332 -22.818359) (xy 138.17547 -22.847828) (xy 138.125881 -22.87047)
			(xy 138.073574 -22.885823) (xy 138.019615 -22.893576) (xy 137.992358 -22.894036) (xy 137.96466 -22.893542)
			(xy 137.909845 -22.885545) (xy 137.85676 -22.869712) (xy 137.806521 -22.846373) (xy 137.760181 -22.81602)
			(xy 137.73912 -22.798024) (xy 137.732234 -22.792266) (xy 137.715567 -22.785635) (xy 137.706608 -22.78507)
			(xy 137.675874 -22.784562) (xy 137.666703 -22.784694) (xy 137.649383 -22.790682) (xy 137.642092 -22.796246)
			(xy 137.618488 -22.815369) (xy 137.567558 -22.848486) (xy 137.513049 -22.875306) (xy 137.455734 -22.895446)
			(xy 137.39643 -22.90862) (xy 137.366248 -22.91207) (xy 137.357358 -22.912832) (xy 137.341864 -22.920198)
			(xy 137.219436 -23.042626) (xy 137.21207 -23.05812) (xy 137.211308 -23.06701) (xy 137.207829 -23.09751)
			(xy 137.194528 -23.157438) (xy 137.174101 -23.215327) (xy 137.146848 -23.270332) (xy 137.113164 -23.321652)
			(xy 137.093706 -23.345394) (xy 137.088049 -23.352588) (xy 137.081803 -23.369775) (xy 137.081514 -23.378922)
			(xy 137.082276 -23.409656) (xy 137.082824 -23.418643) (xy 137.089311 -23.435425) (xy 137.094976 -23.442422)
			(xy 137.112984 -23.463442) (xy 137.143327 -23.509734) (xy 137.166661 -23.559925) (xy 137.182494 -23.612962)
			(xy 137.190494 -23.667731) (xy 137.190988 -23.695406) (xy 137.190502 -23.722657) (xy 137.182746 -23.776605)
			(xy 137.167391 -23.8289) (xy 137.144749 -23.878477) (xy 137.115283 -23.924327) (xy 137.079592 -23.965518)
			(xy 137.038401 -24.001209) (xy 136.992551 -24.030675) (xy 136.942974 -24.053317) (xy 136.890679 -24.068672)
			(xy 136.836731 -24.076428) (xy 136.782229 -24.076428) (xy 136.728281 -24.068672) (xy 136.675986 -24.053317)
			(xy 136.626409 -24.030675) (xy 136.580559 -24.001209) (xy 136.539368 -23.965518) (xy 136.503677 -23.924327)
			(xy 136.474211 -23.878477) (xy 136.451569 -23.8289) (xy 136.436214 -23.776605) (xy 136.428458 -23.722657)
			(xy 136.427972 -23.695406) (xy 136.428433 -23.668662) (xy 136.435937 -23.615702) (xy 136.450743 -23.564304)
			(xy 136.461246 -23.539704) (xy 136.464569 -23.531268) (xy 136.465749 -23.513188) (xy 136.463532 -23.504398)
			(xy 136.454896 -23.475188) (xy 136.451918 -23.466527) (xy 136.440836 -23.451956) (xy 136.433306 -23.44674)
			(xy 136.406519 -23.429223) (xy 136.357176 -23.388455) (xy 136.313337 -23.341819) (xy 136.275693 -23.290053)
			(xy 136.24484 -23.233974) (xy 136.221264 -23.174469) (xy 136.205338 -23.112476) (xy 136.197313 -23.048975)
			(xy 136.196832 -23.016972) (xy 122.275923 -23.016972) (xy 122.27559 -23.037082) (xy 122.267919 -23.099183)
			(xy 122.252682 -23.159872) (xy 122.230109 -23.218231) (xy 122.20054 -23.273376) (xy 122.164425 -23.324474)
			(xy 122.122308 -23.37075) (xy 122.074829 -23.411506) (xy 122.049032 -23.429214) (xy 122.038892 -23.436749)
			(xy 122.027026 -23.459013) (xy 122.026426 -23.471632) (xy 122.026426 -23.55596) (xy 122.027089 -23.568563)
			(xy 122.038934 -23.59081) (xy 122.049032 -23.598378) (xy 122.074828 -23.616088) (xy 122.122308 -23.656845)
			(xy 122.164427 -23.703122) (xy 122.200545 -23.754219) (xy 122.230119 -23.809363) (xy 122.2527 -23.867721)
			(xy 122.267946 -23.928409) (xy 122.275628 -23.990509) (xy 122.276108 -24.021796) (xy 122.276108 -24.02205)
			(xy 122.275703 -24.052259) (xy 122.268558 -24.112252) (xy 122.266292 -24.121618) (xy 129.832608 -24.121618)
			(xy 129.833094 -24.094367) (xy 129.84085 -24.040419) (xy 129.856205 -23.988124) (xy 129.878847 -23.938547)
			(xy 129.908313 -23.892697) (xy 129.944004 -23.851506) (xy 129.985195 -23.815815) (xy 130.031045 -23.786349)
			(xy 130.080622 -23.763707) (xy 130.132917 -23.748352) (xy 130.186865 -23.740596) (xy 130.241367 -23.740596)
			(xy 130.295315 -23.748352) (xy 130.34761 -23.763707) (xy 130.397187 -23.786349) (xy 130.443037 -23.815815)
			(xy 130.484228 -23.851506) (xy 130.519919 -23.892697) (xy 130.549385 -23.938547) (xy 130.572027 -23.988124)
			(xy 130.587382 -24.040419) (xy 130.595138 -24.094367) (xy 130.595624 -24.121618) (xy 130.595502 -24.135512)
			(xy 130.593466 -24.163226) (xy 130.59156 -24.17699) (xy 130.59156 -24.177244) (xy 130.590483 -24.188095)
			(xy 130.596551 -24.20902) (xy 130.603244 -24.21763) (xy 130.653536 -24.27605) (xy 130.661147 -24.283995)
			(xy 130.681153 -24.29309) (xy 130.692144 -24.293576) (xy 131.408932 -24.293576) (xy 131.419924 -24.293096)
			(xy 131.439937 -24.284004) (xy 131.44754 -24.27605) (xy 131.497832 -24.21763) (xy 131.504521 -24.209018)
			(xy 131.510585 -24.188095) (xy 131.509516 -24.177244) (xy 131.509516 -24.17699) (xy 131.507618 -24.163226)
			(xy 131.505587 -24.135512) (xy 131.505452 -24.121618) (xy 131.505938 -24.094367) (xy 131.513694 -24.040419)
			(xy 131.529049 -23.988124) (xy 131.551691 -23.938547) (xy 131.581157 -23.892697) (xy 131.616848 -23.851506)
			(xy 131.658039 -23.815815) (xy 131.703889 -23.786349) (xy 131.753466 -23.763707) (xy 131.805761 -23.748352)
			(xy 131.859709 -23.740596) (xy 131.914211 -23.740596) (xy 131.968159 -23.748352) (xy 132.020454 -23.763707)
			(xy 132.070031 -23.786349) (xy 132.115881 -23.815815) (xy 132.157072 -23.851506) (xy 132.192763 -23.892697)
			(xy 132.222229 -23.938547) (xy 132.244871 -23.988124) (xy 132.260226 -24.040419) (xy 132.267982 -24.094367)
			(xy 132.268468 -24.121618) (xy 132.267996 -24.148793) (xy 132.260294 -24.202593) (xy 132.245034 -24.254755)
			(xy 132.222525 -24.304224) (xy 132.193223 -24.349997) (xy 132.157721 -24.391148) (xy 132.116738 -24.426843)
			(xy 132.071103 -24.456361) (xy 132.021741 -24.479103) (xy 131.969651 -24.494608) (xy 131.94284 -24.499062)
			(xy 131.932934 -24.500586) (xy 131.915662 -24.511) (xy 131.860544 -24.585676) (xy 131.855972 -24.605234)
			(xy 131.857496 -24.615394) (xy 131.859656 -24.630222) (xy 131.861949 -24.6601) (xy 131.862068 -24.675084)
			(xy 131.86163 -24.702338) (xy 131.853874 -24.756292) (xy 131.838518 -24.808593) (xy 131.815874 -24.858176)
			(xy 131.786404 -24.904031) (xy 131.750708 -24.945225) (xy 131.709512 -24.980919) (xy 131.663655 -25.010386)
			(xy 131.61407 -25.033026) (xy 131.561769 -25.048379) (xy 131.507814 -25.056131) (xy 131.48056 -25.056592)
			(xy 130.61696 -25.056592) (xy 130.589707 -25.056159) (xy 130.535757 -25.048397) (xy 130.48346 -25.033036)
			(xy 130.433881 -25.010389) (xy 130.38803 -24.980917) (xy 130.34684 -24.94522) (xy 130.311149 -24.904025)
			(xy 130.281684 -24.858169) (xy 130.259044 -24.808588) (xy 130.243691 -24.756289) (xy 130.235937 -24.702337)
			(xy 130.235452 -24.675084) (xy 130.235551 -24.659973) (xy 130.237837 -24.629838) (xy 130.240024 -24.614886)
			(xy 130.241206 -24.604906) (xy 130.23648 -24.585387) (xy 130.23088 -24.57704) (xy 130.18262 -24.510746)
			(xy 130.165602 -24.500078) (xy 130.155442 -24.498554) (xy 130.128821 -24.493858) (xy 130.077115 -24.478102)
			(xy 130.028151 -24.455204) (xy 129.982912 -24.425622) (xy 129.942301 -24.38995) (xy 129.907135 -24.3489)
			(xy 129.878116 -24.303297) (xy 129.855827 -24.254053) (xy 129.840714 -24.202156) (xy 129.83308 -24.148645)
			(xy 129.832608 -24.121618) (xy 122.266292 -24.121618) (xy 122.25435 -24.170975) (xy 122.23328 -24.227599)
			(xy 122.205646 -24.281326) (xy 122.171836 -24.331398) (xy 122.15241 -24.354536) (xy 122.146757 -24.3616)
			(xy 122.140375 -24.378518) (xy 122.139964 -24.387556) (xy 122.139964 -24.418036) (xy 122.140389 -24.427072)
			(xy 122.146763 -24.443989) (xy 122.15241 -24.451056) (xy 122.171834 -24.474193) (xy 122.20562 -24.524276)
			(xy 122.233239 -24.578007) (xy 122.254302 -24.634629) (xy 122.268514 -24.693348) (xy 122.275673 -24.753335)
			(xy 122.276108 -24.783542) (xy 122.276108 -24.783796) (xy 122.275606 -24.815757) (xy 122.267595 -24.879175)
			(xy 122.251698 -24.941089) (xy 122.228166 -25.000522) (xy 122.197372 -25.056537) (xy 122.159799 -25.108252)
			(xy 122.116042 -25.154849) (xy 122.066789 -25.195594) (xy 122.012818 -25.229845) (xy 121.954979 -25.257062)
			(xy 121.894186 -25.276815) (xy 121.831396 -25.288793) (xy 121.7676 -25.292807) (xy 121.703804 -25.288793)
			(xy 121.641014 -25.276815) (xy 121.580221 -25.257062) (xy 121.522382 -25.229845) (xy 121.468411 -25.195594)
			(xy 121.419158 -25.154849) (xy 121.375401 -25.108252) (xy 121.337828 -25.056537) (xy 121.307034 -25.000522)
			(xy 121.283502 -24.941089) (xy 121.267605 -24.879175) (xy 121.259594 -24.815757) (xy 121.259092 -24.783796)
			(xy 108.672138 -24.783796) (xy 108.662573 -24.859513) (xy 108.638643 -24.984968) (xy 108.606882 -25.108673)
			(xy 108.567416 -25.23014) (xy 108.520401 -25.348888) (xy 108.466023 -25.46445) (xy 108.404495 -25.57637)
			(xy 108.336062 -25.684205) (xy 108.260992 -25.787531) (xy 108.179583 -25.885939) (xy 108.092155 -25.979041)
			(xy 107.999054 -26.06647) (xy 107.900647 -26.14788) (xy 107.797322 -26.222951) (xy 107.689487 -26.291385)
			(xy 107.577568 -26.352914) (xy 107.462006 -26.407293) (xy 107.357367 -26.448723) (xy 114.540786 -26.448723)
			(xy 114.540786 -26.384801) (xy 114.548797 -26.321383) (xy 114.564694 -26.259469) (xy 114.588226 -26.200036)
			(xy 114.61902 -26.144021) (xy 114.656593 -26.092306) (xy 114.70035 -26.045709) (xy 114.749603 -26.004964)
			(xy 114.803574 -25.970713) (xy 114.861413 -25.943496) (xy 114.922206 -25.923743) (xy 114.984996 -25.911765)
			(xy 115.048792 -25.907752) (xy 115.112588 -25.911765) (xy 115.175378 -25.923743) (xy 115.236171 -25.943496)
			(xy 115.29401 -25.970713) (xy 115.347981 -26.004964) (xy 115.397234 -26.045709) (xy 115.440991 -26.092306)
			(xy 115.478564 -26.144021) (xy 115.509358 -26.200036) (xy 115.53289 -26.259469) (xy 115.548787 -26.321383)
			(xy 115.556798 -26.384801) (xy 115.5573 -26.416762) (xy 115.556798 -26.448723) (xy 115.548787 -26.512141)
			(xy 115.53289 -26.574055) (xy 115.509358 -26.633488) (xy 115.478564 -26.689503) (xy 115.440991 -26.741218)
			(xy 115.397234 -26.787815) (xy 115.347981 -26.82856) (xy 115.29401 -26.862811) (xy 115.236171 -26.890028)
			(xy 115.175378 -26.909781) (xy 115.112588 -26.921759) (xy 115.048792 -26.925773) (xy 114.984996 -26.921759)
			(xy 114.922206 -26.909781) (xy 114.861413 -26.890028) (xy 114.803574 -26.862811) (xy 114.749603 -26.82856)
			(xy 114.70035 -26.787815) (xy 114.656593 -26.741218) (xy 114.61902 -26.689503) (xy 114.588226 -26.633488)
			(xy 114.564694 -26.574055) (xy 114.548797 -26.512141) (xy 114.540786 -26.448723) (xy 107.357367 -26.448723)
			(xy 107.343258 -26.454309) (xy 107.221792 -26.493776) (xy 107.098088 -26.525538) (xy 106.972633 -26.54947)
			(xy 106.845923 -26.565477) (xy 106.718458 -26.573497) (xy 106.6546 -26.573988) (xy 106.59339 -26.573539)
			(xy 106.471193 -26.566167) (xy 106.349661 -26.55145) (xy 106.229236 -26.52944) (xy 106.110355 -26.500219)
			(xy 105.993449 -26.463892) (xy 105.936034 -26.44267) (xy 105.927247 -26.439763) (xy 105.908753 -26.439763)
			(xy 105.899966 -26.44267) (xy 105.842543 -26.463868) (xy 105.725635 -26.500181) (xy 105.606755 -26.529395)
			(xy 105.486332 -26.551405) (xy 105.364803 -26.566131) (xy 105.242609 -26.573519) (xy 105.1814 -26.573988)
			(xy 105.118185 -26.573545) (xy 104.991999 -26.565681) (xy 104.866545 -26.54999) (xy 104.74231 -26.526532)
			(xy 104.619772 -26.495399) (xy 104.499406 -26.456711) (xy 104.381677 -26.410616) (xy 104.267041 -26.357294)
			(xy 104.15594 -26.29695) (xy 104.048804 -26.229819) (xy 103.946048 -26.156158) (xy 103.848068 -26.076254)
			(xy 103.755243 -25.990415) (xy 103.667933 -25.898973) (xy 103.586474 -25.802281) (xy 103.548434 -25.75179)
			(xy 103.542183 -25.744038) (xy 103.525172 -25.733719) (xy 103.515414 -25.731724) (xy 103.445056 -25.720802)
			(xy 103.435333 -25.719665) (xy 103.416256 -25.723969) (xy 103.407972 -25.729184) (xy 103.407464 -25.729692)
			(xy 103.383066 -25.746458) (xy 103.330173 -25.773036) (xy 103.273805 -25.791114) (xy 103.21532 -25.800257)
			(xy 103.185722 -25.800812) (xy 103.15847 -25.800324) (xy 103.10452 -25.79257) (xy 103.052223 -25.777217)
			(xy 103.002643 -25.754578) (xy 102.95679 -25.725112) (xy 102.915597 -25.689421) (xy 102.879903 -25.648231)
			(xy 102.850435 -25.60238) (xy 102.827792 -25.552802) (xy 102.812435 -25.500505) (xy 102.804678 -25.446556)
			(xy 102.804214 -25.419304) (xy 99.148825 -25.419304) (xy 99.116046 -25.464792) (xy 98.989355 -25.626877)
			(xy 98.856437 -25.783895) (xy 98.717494 -25.935607) (xy 98.572737 -26.081783) (xy 98.422387 -26.2222)
			(xy 98.266674 -26.356643) (xy 98.105833 -26.484909) (xy 97.940111 -26.606802) (xy 97.769758 -26.722137)
			(xy 97.595036 -26.830737) (xy 97.41621 -26.932437) (xy 97.233551 -27.027083) (xy 97.04734 -27.11453)
			(xy 96.857858 -27.194646) (xy 96.665394 -27.267307) (xy 96.470242 -27.332404) (xy 96.272699 -27.389838)
			(xy 96.073066 -27.43952) (xy 95.871646 -27.481375) (xy 95.668746 -27.51534) (xy 95.464676 -27.541363)
			(xy 95.259746 -27.559404) (xy 95.054268 -27.569436) (xy 94.848555 -27.571443) (xy 94.64292 -27.565423)
			(xy 94.437677 -27.551384) (xy 94.233138 -27.529347) (xy 94.029614 -27.499348) (xy 93.827416 -27.46143)
			(xy 93.626851 -27.415653) (xy 93.428225 -27.362085) (xy 93.23184 -27.300808) (xy 93.037996 -27.231915)
			(xy 92.846986 -27.155512) (xy 92.659104 -27.071715) (xy 92.474634 -26.980651) (xy 92.293857 -26.88246)
			(xy 92.117049 -26.777289) (xy 91.944479 -26.665301) (xy 91.77641 -26.546664) (xy 91.613097 -26.421561)
			(xy 91.45479 -26.290181) (xy 91.301729 -26.152725) (xy 91.154148 -26.009401) (xy 91.012271 -25.860429)
			(xy 90.876314 -25.706034) (xy 90.746485 -25.546453) (xy 90.622981 -25.381927) (xy 90.50599 -25.212708)
			(xy 90.395691 -25.039054) (xy 90.29225 -24.861228) (xy 90.195827 -24.679502) (xy 90.106567 -24.494152)
			(xy 90.024607 -24.305461) (xy 89.950071 -24.113716) (xy 89.883073 -23.919208) (xy 89.823715 -23.722235)
			(xy 89.772088 -23.523096) (xy 89.728269 -23.322094) (xy 89.692326 -23.119535) (xy 89.664313 -22.915728)
			(xy 89.644274 -22.710984) (xy 89.632238 -22.505614) (xy 89.628224 -22.29993) (xy 81.574986 -22.29993)
			(xy 81.59013 -22.315941) (xy 81.623073 -22.363475) (xy 81.648464 -22.415437) (xy 81.66572 -22.470636)
			(xy 81.674446 -22.527807) (xy 81.67497 -22.556724) (xy 81.674505 -22.583975) (xy 81.666745 -22.637921)
			(xy 81.651387 -22.690214) (xy 81.628742 -22.739789) (xy 81.599273 -22.785636) (xy 81.563579 -22.826823)
			(xy 81.522386 -22.86251) (xy 81.476534 -22.891972) (xy 81.426956 -22.914608) (xy 81.37466 -22.929958)
			(xy 81.320713 -22.937709) (xy 81.293462 -22.938232) (xy 81.270433 -22.937854) (xy 81.224715 -22.93225)
			(xy 81.202276 -22.927056) (xy 81.190846 -22.924262) (xy 81.176114 -22.927564) (xy 81.171897 -22.928913)
			(xy 81.163982 -22.932881) (xy 81.160366 -22.935438) (xy 81.09585 -22.98573) (xy 81.094834 -22.986492)
			(xy 81.08662 -22.993909) (xy 81.076985 -23.013803) (xy 81.076292 -23.024846) (xy 81.076292 -25.090628)
			(xy 81.07584 -25.100654) (xy 81.068246 -25.119209) (xy 81.06156 -25.126696) (xy 81.033366 -25.15489)
			(xy 81.026547 -25.162231) (xy 81.0188 -25.180694) (xy 81.01838 -25.190704) (xy 81.01838 -28.022804)
			(xy 102.166418 -28.022804) (xy 102.170489 -27.967182) (xy 102.182615 -27.912745) (xy 102.202538 -27.860654)
			(xy 102.229834 -27.812019) (xy 102.26392 -27.767876) (xy 102.304069 -27.729167) (xy 102.349427 -27.696716)
			(xy 102.399027 -27.671215) (xy 102.451811 -27.653208) (xy 102.506654 -27.643078) (xy 102.562388 -27.641041)
			(xy 102.617825 -27.647141) (xy 102.671782 -27.661247) (xy 102.723111 -27.683059) (xy 102.770717 -27.712113)
			(xy 102.813585 -27.747788) (xy 102.850802 -27.789325) (xy 102.881575 -27.835838) (xy 102.905247 -27.886335)
			(xy 102.921315 -27.939742) (xy 102.929435 -27.994918) (xy 102.929944 -28.022804) (xy 102.929435 -28.05069)
			(xy 102.921315 -28.105866) (xy 102.905247 -28.159273) (xy 102.893155 -28.185067) (xy 107.20933 -28.185067)
			(xy 107.20933 -28.121145) (xy 107.217341 -28.057727) (xy 107.233238 -27.995813) (xy 107.25677 -27.93638)
			(xy 107.287564 -27.880365) (xy 107.325137 -27.82865) (xy 107.368894 -27.782053) (xy 107.418147 -27.741308)
			(xy 107.472118 -27.707057) (xy 107.529957 -27.67984) (xy 107.59075 -27.660087) (xy 107.65354 -27.648109)
			(xy 107.717336 -27.644096) (xy 107.781132 -27.648109) (xy 107.843922 -27.660087) (xy 107.904715 -27.67984)
			(xy 107.962554 -27.707057) (xy 108.016525 -27.741308) (xy 108.065778 -27.782053) (xy 108.109535 -27.82865)
			(xy 108.147108 -27.880365) (xy 108.177902 -27.93638) (xy 108.201434 -27.995813) (xy 108.217331 -28.057727)
			(xy 108.225342 -28.121145) (xy 108.225844 -28.153106) (xy 108.225481 -28.1762) (xy 121.25861 -28.1762)
			(xy 121.262623 -28.112407) (xy 121.2746 -28.049619) (xy 121.294353 -27.988828) (xy 121.321568 -27.930992)
			(xy 121.355818 -27.877023) (xy 121.396562 -27.827772) (xy 121.443157 -27.784016) (xy 121.494869 -27.746445)
			(xy 121.550882 -27.715652) (xy 121.610313 -27.692121) (xy 121.672225 -27.676225) (xy 121.73564 -27.668214)
			(xy 121.7676 -27.667712) (xy 121.796648 -27.66812) (xy 121.854363 -27.674747) (xy 121.910946 -27.687916)
			(xy 121.965657 -27.707453) (xy 122.017782 -27.733105) (xy 122.042428 -27.748484) (xy 122.050277 -27.753103)
			(xy 122.068072 -27.756937) (xy 122.086084 -27.754311) (xy 122.094244 -27.750262) (xy 122.172476 -27.70759)
			(xy 122.180284 -27.702866) (xy 122.192236 -27.6891) (xy 122.198561 -27.672003) (xy 122.198892 -27.662886)
			(xy 122.198892 -27.474672) (xy 122.199279 -27.464598) (xy 122.207024 -27.445999) (xy 122.213878 -27.438604)
			(xy 123.349004 -26.303478) (xy 123.356406 -26.29664) (xy 123.375004 -26.28892) (xy 123.385072 -26.288492)
			(xy 127.214376 -26.288492) (xy 127.226314 -26.287222) (xy 127.28423 -26.27382) (xy 127.401284 -26.253)
			(xy 127.519355 -26.239062) (xy 127.638039 -26.232055) (xy 127.697484 -26.231596) (xy 127.6985 -26.231596)
			(xy 127.761355 -26.23212) (xy 127.886826 -26.239889) (xy 128.011577 -26.255396) (xy 128.135131 -26.278584)
			(xy 128.257015 -26.309362) (xy 128.376765 -26.347614) (xy 128.493922 -26.393193) (xy 128.608039 -26.445925)
			(xy 128.718678 -26.505608) (xy 128.825418 -26.572015) (xy 128.92785 -26.644891) (xy 129.025583 -26.723957)
			(xy 129.118243 -26.808913) (xy 129.205475 -26.899432) (xy 129.286947 -26.995169) (xy 129.362347 -27.095757)
			(xy 129.431387 -27.200813) (xy 129.493802 -27.309935) (xy 129.549355 -27.422705) (xy 129.574036 -27.480514)
			(xy 129.577592 -27.489404) (xy 129.591308 -27.503628) (xy 129.67335 -27.539696) (xy 129.692654 -27.540458)
			(xy 129.701798 -27.537156) (xy 129.732732 -27.526863) (xy 129.796966 -27.515747) (xy 129.82956 -27.515058)
			(xy 129.856812 -27.515587) (xy 129.910763 -27.523338) (xy 129.963061 -27.538689) (xy 130.012641 -27.561328)
			(xy 130.058496 -27.590792) (xy 130.099689 -27.626482) (xy 130.135384 -27.667672) (xy 130.164853 -27.713523)
			(xy 130.183605 -27.75458) (xy 130.560572 -27.75458) (xy 130.561143 -27.719614) (xy 130.570747 -27.650344)
			(xy 130.589758 -27.583046) (xy 130.617816 -27.518989) (xy 130.654391 -27.459384) (xy 130.676142 -27.432)
			(xy 130.681417 -27.425004) (xy 130.68726 -27.408499) (xy 130.687572 -27.399742) (xy 130.687572 -27.118818)
			(xy 130.687205 -27.110071) (xy 130.681371 -27.09358) (xy 130.676142 -27.08656) (xy 130.654392 -27.059178)
			(xy 130.617839 -26.999563) (xy 130.589794 -26.935505) (xy 130.570785 -26.868209) (xy 130.561171 -26.798944)
			(xy 130.560572 -26.76398) (xy 130.561018 -26.733454) (xy 130.568331 -26.672841) (xy 130.582848 -26.613539)
			(xy 130.60436 -26.556402) (xy 130.632559 -26.502252) (xy 130.667039 -26.451867) (xy 130.707303 -26.405974)
			(xy 130.729736 -26.385266) (xy 130.737994 -26.377009) (xy 130.746724 -26.355383) (xy 130.74503 -26.332123)
			(xy 130.739642 -26.321766) (xy 130.727286 -26.299762) (xy 130.707817 -26.253204) (xy 130.69464 -26.20449)
			(xy 130.687985 -26.154466) (xy 130.687572 -26.129234) (xy 130.687572 -26.12898) (xy 130.688058 -26.101729)
			(xy 130.695814 -26.047781) (xy 130.711169 -25.995486) (xy 130.733811 -25.945909) (xy 130.763277 -25.900059)
			(xy 130.798968 -25.858868) (xy 130.840159 -25.823177) (xy 130.886009 -25.793711) (xy 130.935586 -25.771069)
			(xy 130.987881 -25.755714) (xy 131.041829 -25.747958) (xy 131.096331 -25.747958) (xy 131.150279 -25.755714)
			(xy 131.202574 -25.771069) (xy 131.252151 -25.793711) (xy 131.298001 -25.823177) (xy 131.339192 -25.858868)
			(xy 131.374883 -25.900059) (xy 131.404349 -25.945909) (xy 131.426991 -25.995486) (xy 131.442346 -26.047781)
			(xy 131.450102 -26.101729) (xy 131.450379 -26.117271) (xy 132.672027 -26.117271) (xy 132.679781 -26.063316)
			(xy 132.695134 -26.011014) (xy 132.717775 -25.961428) (xy 132.747242 -25.91557) (xy 132.782935 -25.874372)
			(xy 132.824128 -25.838673) (xy 132.869983 -25.8092) (xy 132.919565 -25.786553) (xy 132.971865 -25.771192)
			(xy 133.025819 -25.763431) (xy 133.053074 -25.762966) (xy 133.053328 -25.762966) (xy 133.079009 -25.763404)
			(xy 133.129906 -25.770301) (xy 133.179413 -25.783981) (xy 133.203188 -25.7937) (xy 133.211622 -25.796961)
			(xy 133.229673 -25.797845) (xy 133.246898 -25.792374) (xy 133.254242 -25.787096) (xy 133.335522 -25.724358)
			(xy 133.345682 -25.698704) (xy 133.34365 -25.684988) (xy 133.341636 -25.67085) (xy 133.339472 -25.642372)
			(xy 133.339332 -25.628092) (xy 133.339332 -24.763222) (xy 133.339493 -24.748107) (xy 133.341909 -24.717972)
			(xy 133.344158 -24.703024) (xy 133.344158 -24.70277) (xy 133.345168 -24.693829) (xy 133.341598 -24.676203)
			(xy 133.332194 -24.660874) (xy 133.325362 -24.655018) (xy 133.255004 -24.600154) (xy 133.247636 -24.59484)
			(xy 133.230317 -24.589385) (xy 133.212182 -24.590302) (xy 133.203696 -24.59355) (xy 133.179812 -24.603361)
			(xy 133.130054 -24.617154) (xy 133.078891 -24.624113) (xy 133.053074 -24.624538) (xy 133.025823 -24.624017)
			(xy 132.971876 -24.616257) (xy 132.919583 -24.600898) (xy 132.870008 -24.578254) (xy 132.824159 -24.548784)
			(xy 132.782972 -24.51309) (xy 132.747284 -24.471898) (xy 132.717821 -24.426046) (xy 132.695183 -24.376467)
			(xy 132.679832 -24.324172) (xy 132.672079 -24.270224) (xy 132.672083 -24.215722) (xy 132.679844 -24.161775)
			(xy 132.695202 -24.109482) (xy 132.717847 -24.059906) (xy 132.747316 -24.014058) (xy 132.783011 -23.972871)
			(xy 132.824203 -23.937183) (xy 132.870056 -23.90772) (xy 132.919634 -23.885083) (xy 132.97193 -23.869732)
			(xy 133.025878 -23.861979) (xy 133.08038 -23.861983) (xy 133.134326 -23.869744) (xy 133.18662 -23.885103)
			(xy 133.236195 -23.907748) (xy 133.282043 -23.937217) (xy 133.32323 -23.972912) (xy 133.358918 -24.014104)
			(xy 133.388381 -24.059957) (xy 133.411018 -24.109535) (xy 133.426369 -24.161831) (xy 133.434121 -24.215779)
			(xy 133.434582 -24.24303) (xy 133.434582 -24.243538) (xy 133.434416 -24.258653) (xy 133.432003 -24.288788)
			(xy 133.429756 -24.303736) (xy 133.42747 -24.317452) (xy 133.43763 -24.343106) (xy 133.51891 -24.406606)
			(xy 133.526272 -24.411834) (xy 133.543488 -24.417244) (xy 133.561513 -24.416391) (xy 133.569964 -24.41321)
			(xy 133.570472 -24.41321) (xy 133.594306 -24.403364) (xy 133.643972 -24.389488) (xy 133.695057 -24.382441)
			(xy 133.72084 -24.381968) (xy 133.74808 -24.38244) (xy 133.802004 -24.390194) (xy 133.854277 -24.405541)
			(xy 133.903836 -24.428166) (xy 133.949673 -24.457611) (xy 133.990856 -24.493276) (xy 133.99279 -24.495506)
			(xy 146.962874 -24.495506) (xy 146.966945 -24.439884) (xy 146.979071 -24.385447) (xy 146.998994 -24.333356)
			(xy 147.02629 -24.284721) (xy 147.060376 -24.240578) (xy 147.100525 -24.201869) (xy 147.145883 -24.169418)
			(xy 147.195483 -24.143917) (xy 147.248267 -24.12591) (xy 147.30311 -24.11578) (xy 147.358844 -24.113743)
			(xy 147.414281 -24.119843) (xy 147.468238 -24.133949) (xy 147.519567 -24.155761) (xy 147.567173 -24.184815)
			(xy 147.610041 -24.22049) (xy 147.647258 -24.262027) (xy 147.678031 -24.30854) (xy 147.701703 -24.359037)
			(xy 147.714855 -24.402753) (xy 148.43607 -24.402753) (xy 148.43607 -24.338831) (xy 148.444081 -24.275413)
			(xy 148.459978 -24.213499) (xy 148.48351 -24.154066) (xy 148.514304 -24.098051) (xy 148.551877 -24.046336)
			(xy 148.595634 -23.999739) (xy 148.644887 -23.958994) (xy 148.698858 -23.924743) (xy 148.756697 -23.897526)
			(xy 148.81749 -23.877773) (xy 148.88028 -23.865795) (xy 148.944076 -23.861782) (xy 149.007872 -23.865795)
			(xy 149.070662 -23.877773) (xy 149.131455 -23.897526) (xy 149.189294 -23.924743) (xy 149.243265 -23.958994)
			(xy 149.292518 -23.999739) (xy 149.336275 -24.046336) (xy 149.373848 -24.098051) (xy 149.398091 -24.142149)
			(xy 151.199844 -24.142149) (xy 151.199844 -24.078227) (xy 151.207855 -24.014809) (xy 151.223752 -23.952895)
			(xy 151.247284 -23.893462) (xy 151.278078 -23.837447) (xy 151.315651 -23.785732) (xy 151.359408 -23.739135)
			(xy 151.408661 -23.69839) (xy 151.462632 -23.664139) (xy 151.520471 -23.636922) (xy 151.581264 -23.617169)
			(xy 151.644054 -23.605191) (xy 151.70785 -23.601178) (xy 151.771646 -23.605191) (xy 151.834436 -23.617169)
			(xy 151.895229 -23.636922) (xy 151.953068 -23.664139) (xy 152.007039 -23.69839) (xy 152.056292 -23.739135)
			(xy 152.100049 -23.785732) (xy 152.137622 -23.837447) (xy 152.168416 -23.893462) (xy 152.191948 -23.952895)
			(xy 152.207845 -24.014809) (xy 152.215856 -24.078227) (xy 152.216358 -24.110188) (xy 152.215856 -24.142149)
			(xy 152.207845 -24.205567) (xy 152.191948 -24.267481) (xy 152.168416 -24.326914) (xy 152.137622 -24.382929)
			(xy 152.13706 -24.383703) (xy 153.462476 -24.383703) (xy 153.462476 -24.319781) (xy 153.470487 -24.256363)
			(xy 153.486384 -24.194449) (xy 153.509916 -24.135016) (xy 153.54071 -24.079001) (xy 153.578283 -24.027286)
			(xy 153.62204 -23.980689) (xy 153.671293 -23.939944) (xy 153.725264 -23.905693) (xy 153.783103 -23.878476)
			(xy 153.843896 -23.858723) (xy 153.906686 -23.846745) (xy 153.970482 -23.842732) (xy 154.034278 -23.846745)
			(xy 154.097068 -23.858723) (xy 154.157861 -23.878476) (xy 154.2157 -23.905693) (xy 154.269671 -23.939944)
			(xy 154.318924 -23.980689) (xy 154.362681 -24.027286) (xy 154.400254 -24.079001) (xy 154.431048 -24.135016)
			(xy 154.45458 -24.194449) (xy 154.470477 -24.256363) (xy 154.478488 -24.319781) (xy 154.47899 -24.351742)
			(xy 154.478488 -24.383703) (xy 155.519622 -24.383703) (xy 155.519622 -24.319781) (xy 155.527633 -24.256363)
			(xy 155.54353 -24.194449) (xy 155.567062 -24.135016) (xy 155.597856 -24.079001) (xy 155.635429 -24.027286)
			(xy 155.679186 -23.980689) (xy 155.728439 -23.939944) (xy 155.78241 -23.905693) (xy 155.840249 -23.878476)
			(xy 155.901042 -23.858723) (xy 155.963832 -23.846745) (xy 156.027628 -23.842732) (xy 156.091424 -23.846745)
			(xy 156.154214 -23.858723) (xy 156.215007 -23.878476) (xy 156.272846 -23.905693) (xy 156.326817 -23.939944)
			(xy 156.37607 -23.980689) (xy 156.419827 -24.027286) (xy 156.4574 -24.079001) (xy 156.488194 -24.135016)
			(xy 156.511726 -24.194449) (xy 156.527623 -24.256363) (xy 156.535634 -24.319781) (xy 156.536136 -24.351742)
			(xy 156.535634 -24.383703) (xy 156.533228 -24.402753) (xy 157.519618 -24.402753) (xy 157.519618 -24.338831)
			(xy 157.527629 -24.275413) (xy 157.543526 -24.213499) (xy 157.567058 -24.154066) (xy 157.597852 -24.098051)
			(xy 157.635425 -24.046336) (xy 157.679182 -23.999739) (xy 157.728435 -23.958994) (xy 157.782406 -23.924743)
			(xy 157.840245 -23.897526) (xy 157.901038 -23.877773) (xy 157.963828 -23.865795) (xy 158.027624 -23.861782)
			(xy 158.09142 -23.865795) (xy 158.15421 -23.877773) (xy 158.215003 -23.897526) (xy 158.272842 -23.924743)
			(xy 158.292826 -23.937425) (xy 162.714172 -23.937425) (xy 162.714172 -23.873503) (xy 162.722183 -23.810085)
			(xy 162.73808 -23.748171) (xy 162.761612 -23.688738) (xy 162.792406 -23.632723) (xy 162.829979 -23.581008)
			(xy 162.873736 -23.534411) (xy 162.922989 -23.493666) (xy 162.97696 -23.459415) (xy 163.034799 -23.432198)
			(xy 163.095592 -23.412445) (xy 163.158382 -23.400467) (xy 163.222178 -23.396454) (xy 163.285974 -23.400467)
			(xy 163.348764 -23.412445) (xy 163.409557 -23.432198) (xy 163.467396 -23.459415) (xy 163.521367 -23.493666)
			(xy 163.57062 -23.534411) (xy 163.614377 -23.581008) (xy 163.65195 -23.632723) (xy 163.682744 -23.688738)
			(xy 163.706276 -23.748171) (xy 163.722173 -23.810085) (xy 163.730184 -23.873503) (xy 163.730686 -23.905464)
			(xy 163.730184 -23.937425) (xy 163.722173 -24.000843) (xy 163.706276 -24.062757) (xy 163.682744 -24.12219)
			(xy 163.65195 -24.178205) (xy 163.614377 -24.22992) (xy 163.57062 -24.276517) (xy 163.521367 -24.317262)
			(xy 163.467396 -24.351513) (xy 163.409557 -24.37873) (xy 163.348764 -24.398483) (xy 163.285974 -24.410461)
			(xy 163.222178 -24.414475) (xy 163.158382 -24.410461) (xy 163.095592 -24.398483) (xy 163.034799 -24.37873)
			(xy 162.97696 -24.351513) (xy 162.922989 -24.317262) (xy 162.873736 -24.276517) (xy 162.829979 -24.22992)
			(xy 162.792406 -24.178205) (xy 162.761612 -24.12219) (xy 162.73808 -24.062757) (xy 162.722183 -24.000843)
			(xy 162.714172 -23.937425) (xy 158.292826 -23.937425) (xy 158.326813 -23.958994) (xy 158.376066 -23.999739)
			(xy 158.419823 -24.046336) (xy 158.457396 -24.098051) (xy 158.48819 -24.154066) (xy 158.511722 -24.213499)
			(xy 158.527619 -24.275413) (xy 158.53563 -24.338831) (xy 158.536132 -24.370792) (xy 158.53563 -24.402753)
			(xy 158.527619 -24.466171) (xy 158.511722 -24.528085) (xy 158.48819 -24.587518) (xy 158.457396 -24.643533)
			(xy 158.419823 -24.695248) (xy 158.376066 -24.741845) (xy 158.326813 -24.78259) (xy 158.272842 -24.816841)
			(xy 158.215003 -24.844058) (xy 158.15421 -24.863811) (xy 158.09142 -24.875789) (xy 158.027624 -24.879803)
			(xy 157.963828 -24.875789) (xy 157.901038 -24.863811) (xy 157.840245 -24.844058) (xy 157.782406 -24.816841)
			(xy 157.728435 -24.78259) (xy 157.679182 -24.741845) (xy 157.635425 -24.695248) (xy 157.597852 -24.643533)
			(xy 157.567058 -24.587518) (xy 157.543526 -24.528085) (xy 157.527629 -24.466171) (xy 157.519618 -24.402753)
			(xy 156.533228 -24.402753) (xy 156.527623 -24.447121) (xy 156.511726 -24.509035) (xy 156.488194 -24.568468)
			(xy 156.4574 -24.624483) (xy 156.419827 -24.676198) (xy 156.37607 -24.722795) (xy 156.326817 -24.76354)
			(xy 156.272846 -24.797791) (xy 156.215007 -24.825008) (xy 156.154214 -24.844761) (xy 156.091424 -24.856739)
			(xy 156.027628 -24.860753) (xy 155.963832 -24.856739) (xy 155.901042 -24.844761) (xy 155.840249 -24.825008)
			(xy 155.78241 -24.797791) (xy 155.728439 -24.76354) (xy 155.679186 -24.722795) (xy 155.635429 -24.676198)
			(xy 155.597856 -24.624483) (xy 155.567062 -24.568468) (xy 155.54353 -24.509035) (xy 155.527633 -24.447121)
			(xy 155.519622 -24.383703) (xy 154.478488 -24.383703) (xy 154.470477 -24.447121) (xy 154.45458 -24.509035)
			(xy 154.431048 -24.568468) (xy 154.400254 -24.624483) (xy 154.362681 -24.676198) (xy 154.318924 -24.722795)
			(xy 154.269671 -24.76354) (xy 154.2157 -24.797791) (xy 154.157861 -24.825008) (xy 154.097068 -24.844761)
			(xy 154.034278 -24.856739) (xy 153.970482 -24.860753) (xy 153.906686 -24.856739) (xy 153.843896 -24.844761)
			(xy 153.783103 -24.825008) (xy 153.725264 -24.797791) (xy 153.671293 -24.76354) (xy 153.62204 -24.722795)
			(xy 153.578283 -24.676198) (xy 153.54071 -24.624483) (xy 153.509916 -24.568468) (xy 153.486384 -24.509035)
			(xy 153.470487 -24.447121) (xy 153.462476 -24.383703) (xy 152.13706 -24.383703) (xy 152.100049 -24.434644)
			(xy 152.056292 -24.481241) (xy 152.007039 -24.521986) (xy 151.953068 -24.556237) (xy 151.895229 -24.583454)
			(xy 151.834436 -24.603207) (xy 151.771646 -24.615185) (xy 151.70785 -24.619199) (xy 151.644054 -24.615185)
			(xy 151.581264 -24.603207) (xy 151.520471 -24.583454) (xy 151.462632 -24.556237) (xy 151.408661 -24.521986)
			(xy 151.359408 -24.481241) (xy 151.315651 -24.434644) (xy 151.278078 -24.382929) (xy 151.247284 -24.326914)
			(xy 151.223752 -24.267481) (xy 151.207855 -24.205567) (xy 151.199844 -24.142149) (xy 149.398091 -24.142149)
			(xy 149.404642 -24.154066) (xy 149.428174 -24.213499) (xy 149.444071 -24.275413) (xy 149.452082 -24.338831)
			(xy 149.452584 -24.370792) (xy 149.452082 -24.402753) (xy 149.444071 -24.466171) (xy 149.428174 -24.528085)
			(xy 149.404642 -24.587518) (xy 149.373848 -24.643533) (xy 149.336275 -24.695248) (xy 149.292518 -24.741845)
			(xy 149.250149 -24.776895) (xy 149.811988 -24.776895) (xy 149.811988 -24.712973) (xy 149.819999 -24.649555)
			(xy 149.835896 -24.587641) (xy 149.859428 -24.528208) (xy 149.890222 -24.472193) (xy 149.927795 -24.420478)
			(xy 149.971552 -24.373881) (xy 150.020805 -24.333136) (xy 150.074776 -24.298885) (xy 150.132615 -24.271668)
			(xy 150.193408 -24.251915) (xy 150.256198 -24.239937) (xy 150.319994 -24.235924) (xy 150.38379 -24.239937)
			(xy 150.44658 -24.251915) (xy 150.507373 -24.271668) (xy 150.565212 -24.298885) (xy 150.619183 -24.333136)
			(xy 150.668436 -24.373881) (xy 150.712193 -24.420478) (xy 150.749766 -24.472193) (xy 150.78056 -24.528208)
			(xy 150.804092 -24.587641) (xy 150.819989 -24.649555) (xy 150.828 -24.712973) (xy 150.828502 -24.744934)
			(xy 150.828 -24.776895) (xy 150.819989 -24.840313) (xy 150.804092 -24.902227) (xy 150.78056 -24.96166)
			(xy 150.749766 -25.017675) (xy 150.712193 -25.06939) (xy 150.668436 -25.115987) (xy 150.619183 -25.156732)
			(xy 150.565212 -25.190983) (xy 150.507373 -25.2182) (xy 150.44658 -25.237953) (xy 150.38379 -25.249931)
			(xy 150.319994 -25.253945) (xy 150.256198 -25.249931) (xy 150.193408 -25.237953) (xy 150.132615 -25.2182)
			(xy 150.074776 -25.190983) (xy 150.020805 -25.156732) (xy 149.971552 -25.115987) (xy 149.927795 -25.06939)
			(xy 149.890222 -25.017675) (xy 149.859428 -24.96166) (xy 149.835896 -24.902227) (xy 149.819999 -24.840313)
			(xy 149.811988 -24.776895) (xy 149.250149 -24.776895) (xy 149.243265 -24.78259) (xy 149.189294 -24.816841)
			(xy 149.131455 -24.844058) (xy 149.070662 -24.863811) (xy 149.007872 -24.875789) (xy 148.944076 -24.879803)
			(xy 148.88028 -24.875789) (xy 148.81749 -24.863811) (xy 148.756697 -24.844058) (xy 148.698858 -24.816841)
			(xy 148.644887 -24.78259) (xy 148.595634 -24.741845) (xy 148.551877 -24.695248) (xy 148.514304 -24.643533)
			(xy 148.48351 -24.587518) (xy 148.459978 -24.528085) (xy 148.444081 -24.466171) (xy 148.43607 -24.402753)
			(xy 147.714855 -24.402753) (xy 147.717771 -24.412444) (xy 147.725891 -24.46762) (xy 147.7264 -24.495506)
			(xy 147.725891 -24.523392) (xy 147.717771 -24.578568) (xy 147.701703 -24.631975) (xy 147.678031 -24.682472)
			(xy 147.647258 -24.728985) (xy 147.610041 -24.770522) (xy 147.567173 -24.806197) (xy 147.519567 -24.835251)
			(xy 147.468238 -24.857063) (xy 147.414281 -24.871169) (xy 147.358844 -24.877269) (xy 147.30311 -24.875232)
			(xy 147.248267 -24.865102) (xy 147.195483 -24.847095) (xy 147.145883 -24.821594) (xy 147.100525 -24.789143)
			(xy 147.060376 -24.750434) (xy 147.02629 -24.706291) (xy 146.998994 -24.657656) (xy 146.979071 -24.605565)
			(xy 146.966945 -24.551128) (xy 146.962874 -24.495506) (xy 133.99279 -24.495506) (xy 134.026546 -24.534436)
			(xy 134.05602 -24.580254) (xy 134.078676 -24.629799) (xy 134.094055 -24.682063) (xy 134.101843 -24.735983)
			(xy 134.102348 -24.763222) (xy 134.102348 -25.62733) (xy 134.101904 -25.654589) (xy 134.094145 -25.708553)
			(xy 134.078788 -25.760864) (xy 134.056146 -25.810458) (xy 134.026679 -25.856327) (xy 133.990987 -25.897538)
			(xy 133.949795 -25.933253) (xy 133.903942 -25.962745) (xy 133.854361 -25.985414) (xy 133.802058 -26.0008)
			(xy 133.748099 -26.008589) (xy 133.72084 -26.009092) (xy 133.695109 -26.008636) (xy 133.644123 -26.001642)
			(xy 133.594536 -25.987869) (xy 133.570726 -25.978104) (xy 133.570472 -25.97785) (xy 133.562045 -25.974719)
			(xy 133.544091 -25.973986) (xy 133.526978 -25.979468) (xy 133.519672 -25.984708) (xy 133.438392 -26.047446)
			(xy 133.428232 -26.0731) (xy 133.430264 -26.086816) (xy 133.432278 -26.100954) (xy 133.434442 -26.129432)
			(xy 133.434582 -26.143712) (xy 133.434582 -26.144474) (xy 133.434173 -26.171729) (xy 133.426419 -26.225684)
			(xy 133.411066 -26.277986) (xy 133.388425 -26.327572) (xy 133.358958 -26.37343) (xy 133.323265 -26.414628)
			(xy 133.282072 -26.450327) (xy 133.236217 -26.4798) (xy 133.186635 -26.502447) (xy 133.134335 -26.517808)
			(xy 133.080381 -26.525569) (xy 133.025871 -26.525573) (xy 132.971916 -26.517819) (xy 132.919614 -26.502466)
			(xy 132.870028 -26.479825) (xy 132.82417 -26.450358) (xy 132.782972 -26.414665) (xy 132.747273 -26.373472)
			(xy 132.7178 -26.327617) (xy 132.695153 -26.278035) (xy 132.679792 -26.225735) (xy 132.672031 -26.171781)
			(xy 132.672027 -26.117271) (xy 131.450379 -26.117271) (xy 131.450588 -26.12898) (xy 131.450588 -26.129234)
			(xy 131.450208 -26.15447) (xy 131.443585 -26.204505) (xy 131.430407 -26.253225) (xy 131.410905 -26.299776)
			(xy 131.398518 -26.321766) (xy 131.393099 -26.332124) (xy 131.391356 -26.355408) (xy 131.400102 -26.377058)
			(xy 131.408424 -26.385266) (xy 131.430845 -26.405987) (xy 131.47111 -26.451877) (xy 131.505591 -26.502259)
			(xy 131.533791 -26.556407) (xy 131.555305 -26.613542) (xy 131.569822 -26.672843) (xy 131.577135 -26.733454)
			(xy 131.577588 -26.76398) (xy 131.577524 -26.76779) (xy 141.495018 -26.76779) (xy 141.49559 -26.732834)
			(xy 141.505153 -26.663581) (xy 141.524112 -26.596289) (xy 141.55211 -26.532229) (xy 141.588618 -26.472608)
			(xy 141.610334 -26.44521) (xy 141.615572 -26.438266) (xy 141.621417 -26.421897) (xy 141.621764 -26.413206)
			(xy 141.621764 -26.258774) (xy 141.621361 -26.250093) (xy 141.615531 -26.233734) (xy 141.610334 -26.22677)
			(xy 141.588612 -26.199378) (xy 141.552115 -26.13975) (xy 141.524123 -26.075688) (xy 141.505165 -26.008398)
			(xy 141.495596 -25.939145) (xy 141.495018 -25.90419) (xy 141.495428 -25.873457) (xy 141.502839 -25.812438)
			(xy 141.51755 -25.752758) (xy 141.539348 -25.695286) (xy 141.567915 -25.640861) (xy 141.602833 -25.590276)
			(xy 141.643595 -25.544269) (xy 141.689605 -25.503511) (xy 141.740192 -25.468596) (xy 141.794619 -25.440033)
			(xy 141.852093 -25.418239) (xy 141.911774 -25.403532) (xy 141.972793 -25.396126) (xy 142.003526 -25.395682)
			(xy 142.00378 -25.395682) (xy 142.032092 -25.396102) (xy 142.088358 -25.402466) (xy 142.116048 -25.408382)
			(xy 142.12504 -25.410023) (xy 142.143136 -25.407556) (xy 142.151354 -25.403556) (xy 142.178278 -25.389078)
			(xy 142.186096 -25.384523) (xy 142.198069 -25.370974) (xy 142.201646 -25.362662) (xy 142.212465 -25.336185)
			(xy 142.240971 -25.286598) (xy 142.276563 -25.241823) (xy 142.318442 -25.202866) (xy 142.365669 -25.1706)
			(xy 142.417186 -25.145749) (xy 142.471836 -25.128871) (xy 142.528393 -25.120342) (xy 142.556992 -25.119838)
			(xy 142.584247 -25.120263) (xy 142.638201 -25.12802) (xy 142.690503 -25.143377) (xy 142.740086 -25.166022)
			(xy 142.785941 -25.195494) (xy 142.827135 -25.231192) (xy 142.862829 -25.272389) (xy 142.892296 -25.318247)
			(xy 142.914936 -25.367833) (xy 142.930288 -25.420136) (xy 142.93804 -25.474091) (xy 142.9385 -25.501346)
			(xy 142.937928 -25.530186) (xy 142.929225 -25.587206) (xy 142.918458 -25.621699) (xy 151.712924 -25.621699)
			(xy 151.712924 -25.557777) (xy 151.720935 -25.494359) (xy 151.736832 -25.432445) (xy 151.760364 -25.373012)
			(xy 151.791158 -25.316997) (xy 151.828731 -25.265282) (xy 151.872488 -25.218685) (xy 151.921741 -25.17794)
			(xy 151.975712 -25.143689) (xy 152.033551 -25.116472) (xy 152.094344 -25.096719) (xy 152.157134 -25.084741)
			(xy 152.22093 -25.080728) (xy 152.284726 -25.084741) (xy 152.347516 -25.096719) (xy 152.408309 -25.116472)
			(xy 152.466148 -25.143689) (xy 152.520119 -25.17794) (xy 152.569372 -25.218685) (xy 152.613129 -25.265282)
			(xy 152.650702 -25.316997) (xy 152.681496 -25.373012) (xy 152.705028 -25.432445) (xy 152.720925 -25.494359)
			(xy 152.728936 -25.557777) (xy 152.729438 -25.589738) (xy 152.728936 -25.621699) (xy 152.728904 -25.621953)
			(xy 154.43428 -25.621953) (xy 154.43428 -25.558031) (xy 154.442291 -25.494613) (xy 154.458188 -25.432699)
			(xy 154.48172 -25.373266) (xy 154.512514 -25.317251) (xy 154.550087 -25.265536) (xy 154.593844 -25.218939)
			(xy 154.643097 -25.178194) (xy 154.697068 -25.143943) (xy 154.754907 -25.116726) (xy 154.8157 -25.096973)
			(xy 154.87849 -25.084995) (xy 154.942286 -25.080982) (xy 155.006082 -25.084995) (xy 155.068872 -25.096973)
			(xy 155.129665 -25.116726) (xy 155.187504 -25.143943) (xy 155.241475 -25.178194) (xy 155.290728 -25.218939)
			(xy 155.334485 -25.265536) (xy 155.372058 -25.317251) (xy 155.402852 -25.373266) (xy 155.426384 -25.432699)
			(xy 155.442281 -25.494613) (xy 155.450292 -25.558031) (xy 155.450794 -25.589992) (xy 155.450292 -25.621953)
			(xy 155.449073 -25.631605) (xy 156.510222 -25.631605) (xy 156.510222 -25.567683) (xy 156.518233 -25.504265)
			(xy 156.53413 -25.442351) (xy 156.557662 -25.382918) (xy 156.588456 -25.326903) (xy 156.626029 -25.275188)
			(xy 156.669786 -25.228591) (xy 156.719039 -25.187846) (xy 156.77301 -25.153595) (xy 156.830849 -25.126378)
			(xy 156.891642 -25.106625) (xy 156.954432 -25.094647) (xy 157.018228 -25.090634) (xy 157.082024 -25.094647)
			(xy 157.144814 -25.106625) (xy 157.205607 -25.126378) (xy 157.263446 -25.153595) (xy 157.317417 -25.187846)
			(xy 157.36667 -25.228591) (xy 157.410427 -25.275188) (xy 157.448 -25.326903) (xy 157.478794 -25.382918)
			(xy 157.502326 -25.442351) (xy 157.518223 -25.504265) (xy 157.526234 -25.567683) (xy 157.526736 -25.599644)
			(xy 157.526234 -25.631605) (xy 157.523828 -25.650655) (xy 158.548826 -25.650655) (xy 158.548826 -25.586733)
			(xy 158.556837 -25.523315) (xy 158.572734 -25.461401) (xy 158.596266 -25.401968) (xy 158.62706 -25.345953)
			(xy 158.664633 -25.294238) (xy 158.70839 -25.247641) (xy 158.757643 -25.206896) (xy 158.811614 -25.172645)
			(xy 158.869453 -25.145428) (xy 158.930246 -25.125675) (xy 158.993036 -25.113697) (xy 159.056832 -25.109684)
			(xy 159.120628 -25.113697) (xy 159.183418 -25.125675) (xy 159.244211 -25.145428) (xy 159.30205 -25.172645)
			(xy 159.356021 -25.206896) (xy 159.405274 -25.247641) (xy 159.449031 -25.294238) (xy 159.486604 -25.345953)
			(xy 159.495202 -25.361593) (xy 165.086358 -25.361593) (xy 165.091566 -25.29872) (xy 165.104511 -25.236974)
			(xy 165.124995 -25.177304) (xy 165.152702 -25.120626) (xy 165.187207 -25.06781) (xy 165.22798 -25.019668)
			(xy 165.274395 -24.976939) (xy 165.325739 -24.940279) (xy 165.381223 -24.910252) (xy 165.439995 -24.887319)
			(xy 165.501152 -24.871831) (xy 165.563756 -24.864028) (xy 165.5953 -24.863552) (xy 165.632384 -24.864822)
			(xy 165.647116 -24.866092) (xy 165.673278 -24.851614) (xy 165.72484 -24.756872) (xy 165.729062 -24.748099)
			(xy 165.731234 -24.728767) (xy 165.726064 -24.710013) (xy 165.720522 -24.702008) (xy 165.700936 -24.675383)
			(xy 165.668101 -24.618017) (xy 165.642977 -24.556881) (xy 165.625987 -24.493003) (xy 165.61742 -24.427463)
			(xy 165.61689 -24.394414) (xy 165.617503 -24.359356) (xy 165.627144 -24.289907) (xy 165.646233 -24.222439)
			(xy 165.674406 -24.158233) (xy 165.711131 -24.098505) (xy 165.732968 -24.071072) (xy 165.739929 -24.06163)
			(xy 165.745249 -24.038811) (xy 165.739939 -24.01599) (xy 165.732968 -24.006556) (xy 165.711094 -23.979149)
			(xy 165.674359 -23.91942) (xy 165.646182 -23.855208) (xy 165.6271 -23.787733) (xy 165.617473 -23.718275)
			(xy 165.61689 -23.683214) (xy 165.617468 -23.649638) (xy 165.626315 -23.58307) (xy 165.643845 -23.518246)
			(xy 165.669751 -23.456292) (xy 165.703584 -23.398285) (xy 165.744756 -23.345234) (xy 165.768274 -23.321264)
			(xy 165.774878 -23.31466) (xy 165.782752 -23.297388) (xy 165.786816 -23.21941) (xy 165.786903 -23.209998)
			(xy 165.781053 -23.192125) (xy 165.775386 -23.184612) (xy 165.759132 -23.164061) (xy 165.731794 -23.119361)
			(xy 165.710828 -23.071342) (xy 165.696627 -23.020906) (xy 165.689459 -22.969002) (xy 165.689026 -22.942804)
			(xy 165.689512 -22.915553) (xy 165.697268 -22.861605) (xy 165.712623 -22.80931) (xy 165.735265 -22.759733)
			(xy 165.764731 -22.713883) (xy 165.800422 -22.672692) (xy 165.841613 -22.637001) (xy 165.887463 -22.607535)
			(xy 165.93704 -22.584893) (xy 165.989335 -22.569538) (xy 166.043283 -22.561782) (xy 166.097785 -22.561782)
			(xy 166.151733 -22.569538) (xy 166.204028 -22.584893) (xy 166.253605 -22.607535) (xy 166.299455 -22.637001)
			(xy 166.340646 -22.672692) (xy 166.376337 -22.713883) (xy 166.405803 -22.759733) (xy 166.428445 -22.80931)
			(xy 166.4438 -22.861605) (xy 166.451556 -22.915553) (xy 166.452042 -22.942804) (xy 166.45162 -22.968489)
			(xy 166.444687 -23.019391) (xy 166.430987 -23.068902) (xy 166.410767 -23.116127) (xy 166.39794 -23.138384)
			(xy 166.397686 -23.138638) (xy 166.393395 -23.146899) (xy 166.390395 -23.165257) (xy 166.391844 -23.174452)
			(xy 166.407338 -23.25116) (xy 166.417752 -23.266908) (xy 166.425372 -23.272496) (xy 166.452624 -23.293097)
			(xy 166.501889 -23.340428) (xy 166.544375 -23.393927) (xy 166.57932 -23.45263) (xy 166.606093 -23.515483)
			(xy 166.624213 -23.581353) (xy 166.633355 -23.649055) (xy 166.633906 -23.683214) (xy 166.63331 -23.718272)
			(xy 166.623664 -23.787723) (xy 166.604572 -23.85519) (xy 166.576395 -23.919396) (xy 166.539667 -23.979124)
			(xy 166.517828 -24.006556) (xy 166.510841 -24.015982) (xy 166.50553 -24.038811) (xy 166.510851 -24.061638)
			(xy 166.517828 -24.071072) (xy 166.539668 -24.098504) (xy 166.576408 -24.158227) (xy 166.604592 -24.222432)
			(xy 166.623683 -24.289901) (xy 166.633318 -24.359355) (xy 166.633906 -24.394414) (xy 166.633457 -24.425145)
			(xy 166.626047 -24.48616) (xy 166.611337 -24.545836) (xy 166.58954 -24.603304) (xy 166.560976 -24.657726)
			(xy 166.52606 -24.708309) (xy 166.485302 -24.754313) (xy 166.439296 -24.79507) (xy 166.388713 -24.829984)
			(xy 166.33429 -24.858547) (xy 166.276821 -24.880341) (xy 166.217144 -24.89505) (xy 166.156129 -24.902458)
			(xy 166.125398 -24.902922) (xy 166.088314 -24.901652) (xy 166.073582 -24.900382) (xy 166.04742 -24.91486)
			(xy 165.995858 -25.009602) (xy 165.991658 -25.018384) (xy 165.989479 -25.03771) (xy 165.994639 -25.056461)
			(xy 166.000176 -25.064466) (xy 166.01975 -25.0911) (xy 166.052587 -25.148463) (xy 166.077714 -25.209597)
			(xy 166.094706 -25.273473) (xy 166.103277 -25.339012) (xy 166.103808 -25.37206) (xy 166.103375 -25.403604)
			(xy 166.095576 -25.466208) (xy 166.080093 -25.527367) (xy 166.057165 -25.586141) (xy 166.027142 -25.641627)
			(xy 165.990486 -25.692974) (xy 165.947761 -25.739392) (xy 165.899622 -25.780169) (xy 165.846809 -25.814678)
			(xy 165.790133 -25.84239) (xy 165.730464 -25.862878) (xy 165.66872 -25.875828) (xy 165.605847 -25.881041)
			(xy 165.542813 -25.878437) (xy 165.480585 -25.868057) (xy 165.420119 -25.850058) (xy 165.362343 -25.824719)
			(xy 165.308146 -25.792427) (xy 165.258359 -25.75368) (xy 165.213747 -25.709071) (xy 165.174996 -25.659287)
			(xy 165.1427 -25.605092) (xy 165.117356 -25.547319) (xy 165.099353 -25.486854) (xy 165.088967 -25.424627)
			(xy 165.086358 -25.361593) (xy 159.495202 -25.361593) (xy 159.517398 -25.401968) (xy 159.54093 -25.461401)
			(xy 159.556827 -25.523315) (xy 159.564838 -25.586733) (xy 159.56534 -25.618694) (xy 159.564838 -25.650655)
			(xy 159.556827 -25.714073) (xy 159.54093 -25.775987) (xy 159.517398 -25.83542) (xy 159.486604 -25.891435)
			(xy 159.449031 -25.94315) (xy 159.405274 -25.989747) (xy 159.356021 -26.030492) (xy 159.30205 -26.064743)
			(xy 159.244211 -26.09196) (xy 159.183418 -26.111713) (xy 159.120628 -26.123691) (xy 159.056832 -26.127705)
			(xy 158.993036 -26.123691) (xy 158.930246 -26.111713) (xy 158.869453 -26.09196) (xy 158.811614 -26.064743)
			(xy 158.757643 -26.030492) (xy 158.70839 -25.989747) (xy 158.664633 -25.94315) (xy 158.62706 -25.891435)
			(xy 158.596266 -25.83542) (xy 158.572734 -25.775987) (xy 158.556837 -25.714073) (xy 158.548826 -25.650655)
			(xy 157.523828 -25.650655) (xy 157.518223 -25.695023) (xy 157.502326 -25.756937) (xy 157.478794 -25.81637)
			(xy 157.448 -25.872385) (xy 157.410427 -25.9241) (xy 157.36667 -25.970697) (xy 157.317417 -26.011442)
			(xy 157.263446 -26.045693) (xy 157.205607 -26.07291) (xy 157.144814 -26.092663) (xy 157.082024 -26.104641)
			(xy 157.018228 -26.108655) (xy 156.954432 -26.104641) (xy 156.891642 -26.092663) (xy 156.830849 -26.07291)
			(xy 156.77301 -26.045693) (xy 156.719039 -26.011442) (xy 156.669786 -25.970697) (xy 156.626029 -25.9241)
			(xy 156.588456 -25.872385) (xy 156.557662 -25.81637) (xy 156.53413 -25.756937) (xy 156.518233 -25.695023)
			(xy 156.510222 -25.631605) (xy 155.449073 -25.631605) (xy 155.442281 -25.685371) (xy 155.426384 -25.747285)
			(xy 155.402852 -25.806718) (xy 155.372058 -25.862733) (xy 155.334485 -25.914448) (xy 155.290728 -25.961045)
			(xy 155.241475 -26.00179) (xy 155.187504 -26.036041) (xy 155.129665 -26.063258) (xy 155.068872 -26.083011)
			(xy 155.006082 -26.094989) (xy 154.942286 -26.099003) (xy 154.87849 -26.094989) (xy 154.8157 -26.083011)
			(xy 154.754907 -26.063258) (xy 154.697068 -26.036041) (xy 154.643097 -26.00179) (xy 154.593844 -25.961045)
			(xy 154.550087 -25.914448) (xy 154.512514 -25.862733) (xy 154.48172 -25.806718) (xy 154.458188 -25.747285)
			(xy 154.442291 -25.685371) (xy 154.43428 -25.621953) (xy 152.728904 -25.621953) (xy 152.720925 -25.685117)
			(xy 152.705028 -25.747031) (xy 152.681496 -25.806464) (xy 152.650702 -25.862479) (xy 152.613129 -25.914194)
			(xy 152.569372 -25.960791) (xy 152.520119 -26.001536) (xy 152.466148 -26.035787) (xy 152.408309 -26.063004)
			(xy 152.347516 -26.082757) (xy 152.284726 -26.094735) (xy 152.22093 -26.098749) (xy 152.157134 -26.094735)
			(xy 152.094344 -26.082757) (xy 152.033551 -26.063004) (xy 151.975712 -26.035787) (xy 151.921741 -26.001536)
			(xy 151.872488 -25.960791) (xy 151.828731 -25.914194) (xy 151.791158 -25.862479) (xy 151.760364 -25.806464)
			(xy 151.736832 -25.747031) (xy 151.720935 -25.685117) (xy 151.712924 -25.621699) (xy 142.918458 -25.621699)
			(xy 142.912038 -25.642267) (xy 142.886759 -25.694114) (xy 142.853965 -25.741565) (xy 142.814402 -25.783539)
			(xy 142.768972 -25.819081) (xy 142.718711 -25.847379) (xy 142.664762 -25.86779) (xy 142.608356 -25.879849)
			(xy 142.579598 -25.882092) (xy 142.570705 -25.883024) (xy 142.554334 -25.890184) (xy 142.547594 -25.896062)
			(xy 142.525496 -25.917398) (xy 142.519104 -25.923995) (xy 142.511163 -25.940543) (xy 142.510002 -25.949656)
			(xy 142.506859 -25.979895) (xy 142.494273 -26.039375) (xy 142.474674 -26.096926) (xy 142.448344 -26.151726)
			(xy 142.415659 -26.20299) (xy 142.396718 -26.22677) (xy 142.391483 -26.233716) (xy 142.385638 -26.250083)
			(xy 142.385288 -26.258774) (xy 142.385288 -26.413206) (xy 142.385664 -26.42189) (xy 142.391513 -26.438248)
			(xy 142.396718 -26.44521) (xy 142.415883 -26.469235) (xy 142.448842 -26.52111) (xy 142.475303 -26.576583)
			(xy 142.494879 -26.634842) (xy 142.507284 -26.695037) (xy 142.510256 -26.725626) (xy 142.511378 -26.734709)
			(xy 142.519199 -26.751242) (xy 142.525496 -26.757884) (xy 142.547594 -26.77922) (xy 142.554328 -26.785252)
			(xy 142.570856 -26.792545) (xy 142.579852 -26.793444) (xy 142.608609 -26.795628) (xy 142.665004 -26.807697)
			(xy 142.718939 -26.82812) (xy 142.769185 -26.85643) (xy 142.814595 -26.891982) (xy 142.854135 -26.933966)
			(xy 142.886904 -26.981424) (xy 142.912153 -27.033276) (xy 142.929308 -27.088337) (xy 142.937978 -27.145354)
			(xy 142.938219 -27.158653) (xy 150.893266 -27.158653) (xy 150.893266 -27.094731) (xy 150.901277 -27.031313)
			(xy 150.917174 -26.969399) (xy 150.940706 -26.909966) (xy 150.9715 -26.853951) (xy 151.009073 -26.802236)
			(xy 151.05283 -26.755639) (xy 151.102083 -26.714894) (xy 151.156054 -26.680643) (xy 151.213893 -26.653426)
			(xy 151.274686 -26.633673) (xy 151.337476 -26.621695) (xy 151.401272 -26.617682) (xy 151.465068 -26.621695)
			(xy 151.527858 -26.633673) (xy 151.588651 -26.653426) (xy 151.64649 -26.680643) (xy 151.700461 -26.714894)
			(xy 151.749714 -26.755639) (xy 151.793471 -26.802236) (xy 151.831044 -26.853951) (xy 151.861838 -26.909966)
			(xy 151.88537 -26.969399) (xy 151.901267 -27.031313) (xy 151.909278 -27.094731) (xy 151.90978 -27.126692)
			(xy 151.909278 -27.158653) (xy 151.901267 -27.222071) (xy 151.88537 -27.283985) (xy 151.861838 -27.343418)
			(xy 151.831044 -27.399433) (xy 151.793471 -27.451148) (xy 151.749714 -27.497745) (xy 151.700461 -27.53849)
			(xy 151.64649 -27.572741) (xy 151.588651 -27.599958) (xy 151.527858 -27.619711) (xy 151.465068 -27.631689)
			(xy 151.401272 -27.635703) (xy 151.337476 -27.631689) (xy 151.274686 -27.619711) (xy 151.213893 -27.599958)
			(xy 151.156054 -27.572741) (xy 151.102083 -27.53849) (xy 151.05283 -27.497745) (xy 151.009073 -27.451148)
			(xy 150.9715 -27.399433) (xy 150.940706 -27.343418) (xy 150.917174 -27.283985) (xy 150.901277 -27.222071)
			(xy 150.893266 -27.158653) (xy 142.938219 -27.158653) (xy 142.9385 -27.17419) (xy 142.938035 -27.201443)
			(xy 142.93028 -27.255394) (xy 142.914924 -27.307693) (xy 142.892282 -27.357273) (xy 142.862815 -27.403127)
			(xy 142.827121 -27.44432) (xy 142.785928 -27.480014) (xy 142.740075 -27.509481) (xy 142.690494 -27.532124)
			(xy 142.638196 -27.547479) (xy 142.584245 -27.555235) (xy 142.556992 -27.555698) (xy 142.5282 -27.555202)
			(xy 142.471272 -27.546539) (xy 142.41629 -27.529426) (xy 142.3645 -27.504251) (xy 142.317079 -27.471585)
			(xy 142.2751 -27.432168) (xy 142.239516 -27.386895) (xy 142.211134 -27.336792) (xy 142.200376 -27.31008)
			(xy 142.196868 -27.301738) (xy 142.185016 -27.288077) (xy 142.177262 -27.28341) (xy 142.150338 -27.268932)
			(xy 142.142132 -27.264886) (xy 142.124041 -27.262266) (xy 142.115032 -27.263852) (xy 142.087522 -27.269666)
			(xy 142.03164 -27.275907) (xy 142.003526 -27.276298) (xy 141.972794 -27.275838) (xy 141.911778 -27.268432)
			(xy 141.8521 -27.253725) (xy 141.794629 -27.231932) (xy 141.740205 -27.20337) (xy 141.68962 -27.168455)
			(xy 141.643613 -27.127698) (xy 141.602854 -27.081692) (xy 141.567939 -27.031109) (xy 141.539375 -26.976685)
			(xy 141.51758 -26.919216) (xy 141.502871 -26.859538) (xy 141.495463 -26.798522) (xy 141.495018 -26.76779)
			(xy 131.577524 -26.76779) (xy 131.577003 -26.798946) (xy 131.567404 -26.868215) (xy 131.548397 -26.935514)
			(xy 131.520342 -26.999571) (xy 131.483768 -27.059176) (xy 131.462018 -27.08656) (xy 131.456755 -27.093564)
			(xy 131.450906 -27.110063) (xy 131.450588 -27.118818) (xy 131.450588 -27.399742) (xy 131.450935 -27.40849)
			(xy 131.456783 -27.424981) (xy 131.462018 -27.432) (xy 131.483758 -27.459389) (xy 131.520311 -27.519003)
			(xy 131.548357 -27.58306) (xy 131.567368 -27.650353) (xy 131.576986 -27.719617) (xy 131.577588 -27.75458)
			(xy 131.577127 -27.785106) (xy 131.569819 -27.845719) (xy 131.557375 -27.896566) (xy 132.058662 -27.896566)
			(xy 132.062733 -27.840944) (xy 132.074859 -27.786507) (xy 132.094782 -27.734416) (xy 132.122078 -27.685781)
			(xy 132.156164 -27.641638) (xy 132.196313 -27.602929) (xy 132.241671 -27.570478) (xy 132.291271 -27.544977)
			(xy 132.344055 -27.52697) (xy 132.398898 -27.51684) (xy 132.454632 -27.514803) (xy 132.510069 -27.520903)
			(xy 132.564026 -27.535009) (xy 132.615355 -27.556821) (xy 132.662961 -27.585875) (xy 132.705829 -27.62155)
			(xy 132.743046 -27.663087) (xy 132.773819 -27.7096) (xy 132.797491 -27.760097) (xy 132.813559 -27.813504)
			(xy 132.821679 -27.86868) (xy 132.822188 -27.896566) (xy 132.821679 -27.924452) (xy 132.813559 -27.979628)
			(xy 132.797491 -28.033035) (xy 132.773819 -28.083532) (xy 132.743046 -28.130045) (xy 132.705829 -28.171582)
			(xy 132.662961 -28.207257) (xy 132.615355 -28.236311) (xy 132.564026 -28.258123) (xy 132.510069 -28.272229)
			(xy 132.454632 -28.278329) (xy 132.398898 -28.276292) (xy 132.344055 -28.266162) (xy 132.291271 -28.248155)
			(xy 132.241671 -28.222654) (xy 132.196313 -28.190203) (xy 132.156164 -28.151494) (xy 132.122078 -28.107351)
			(xy 132.094782 -28.058716) (xy 132.074859 -28.006625) (xy 132.062733 -27.952188) (xy 132.058662 -27.896566)
			(xy 131.557375 -27.896566) (xy 131.555306 -27.905021) (xy 131.533796 -27.962158) (xy 131.505599 -28.016309)
			(xy 131.47112 -28.066693) (xy 131.430857 -28.112587) (xy 131.408424 -28.133294) (xy 131.400115 -28.141506)
			(xy 131.391403 -28.163158) (xy 131.393118 -28.186433) (xy 131.398518 -28.196794) (xy 131.410864 -28.218803)
			(xy 131.430334 -28.265359) (xy 131.443513 -28.314072) (xy 131.450172 -28.364094) (xy 131.450588 -28.389326)
			(xy 131.450588 -28.38958) (xy 131.450102 -28.416831) (xy 131.442346 -28.470779) (xy 131.426991 -28.523074)
			(xy 131.404349 -28.572651) (xy 131.374883 -28.618501) (xy 131.339192 -28.659692) (xy 131.298001 -28.695383)
			(xy 131.252151 -28.724849) (xy 131.202574 -28.747491) (xy 131.150279 -28.762846) (xy 131.096331 -28.770602)
			(xy 131.041829 -28.770602) (xy 130.987881 -28.762846) (xy 130.935586 -28.747491) (xy 130.886009 -28.724849)
			(xy 130.840159 -28.695383) (xy 130.798968 -28.659692) (xy 130.763277 -28.618501) (xy 130.733811 -28.572651)
			(xy 130.711169 -28.523074) (xy 130.695814 -28.470779) (xy 130.688058 -28.416831) (xy 130.687572 -28.38958)
			(xy 130.687572 -28.389326) (xy 130.68794 -28.36409) (xy 130.694568 -28.314055) (xy 130.707749 -28.265335)
			(xy 130.727254 -28.218784) (xy 130.739642 -28.196794) (xy 130.745111 -28.186456) (xy 130.746842 -28.163156)
			(xy 130.738072 -28.1415) (xy 130.729736 -28.133294) (xy 130.707288 -28.112602) (xy 130.667026 -28.066705)
			(xy 130.632549 -28.016318) (xy 130.604353 -27.962165) (xy 130.582843 -27.905025) (xy 130.56833 -27.845722)
			(xy 130.561023 -27.785107) (xy 130.560572 -27.75458) (xy 130.183605 -27.75458) (xy 130.187497 -27.763102)
			(xy 130.202853 -27.815398) (xy 130.210611 -27.869348) (xy 130.210611 -27.923852) (xy 130.202853 -27.977802)
			(xy 130.187497 -28.030098) (xy 130.164853 -28.079677) (xy 130.135384 -28.125528) (xy 130.099689 -28.166718)
			(xy 130.058496 -28.202408) (xy 130.012641 -28.231872) (xy 129.963061 -28.254511) (xy 129.910763 -28.269862)
			(xy 129.856812 -28.277613) (xy 129.82956 -28.278074) (xy 129.819855 -28.278471) (xy 129.801828 -28.28566)
			(xy 129.794508 -28.292044) (xy 129.736596 -28.346908) (xy 129.728468 -28.36418) (xy 129.72796 -28.373832)
			(xy 129.72796 -28.37434) (xy 129.724121 -28.436653) (xy 129.709712 -28.560679) (xy 129.687716 -28.683586)
			(xy 129.658216 -28.804911) (xy 129.621322 -28.924195) (xy 129.577175 -29.04099) (xy 129.52594 -29.154854)
			(xy 129.479561 -29.24302) (xy 135.424672 -29.24302) (xy 135.425266 -29.208055) (xy 135.434864 -29.138786)
			(xy 135.45387 -29.071488) (xy 135.481923 -29.00743) (xy 135.518493 -28.947824) (xy 135.540242 -28.92044)
			(xy 135.545501 -28.913433) (xy 135.551354 -28.896936) (xy 135.551672 -28.888182) (xy 135.551672 -28.607258)
			(xy 135.551332 -28.598509) (xy 135.54548 -28.582017) (xy 135.540242 -28.575) (xy 135.518511 -28.547604)
			(xy 135.481955 -28.487993) (xy 135.453906 -28.423938) (xy 135.434893 -28.356645) (xy 135.425274 -28.287383)
			(xy 135.424672 -28.25242) (xy 135.425146 -28.221895) (xy 135.432453 -28.161282) (xy 135.446966 -28.101981)
			(xy 135.468474 -28.044845) (xy 135.496669 -27.990694) (xy 135.531144 -27.940309) (xy 135.571405 -27.894414)
			(xy 135.593836 -27.873706) (xy 135.602144 -27.865491) (xy 135.610862 -27.843842) (xy 135.609145 -27.820566)
			(xy 135.603742 -27.810206) (xy 135.591401 -27.788194) (xy 135.571928 -27.741639) (xy 135.558748 -27.692927)
			(xy 135.552088 -27.642905) (xy 135.551672 -27.617674) (xy 135.551672 -27.61742) (xy 135.552158 -27.590169)
			(xy 135.559914 -27.536221) (xy 135.575269 -27.483926) (xy 135.597911 -27.434349) (xy 135.627377 -27.388499)
			(xy 135.663068 -27.347308) (xy 135.704259 -27.311617) (xy 135.750109 -27.282151) (xy 135.799686 -27.259509)
			(xy 135.851981 -27.244154) (xy 135.905929 -27.236398) (xy 135.960431 -27.236398) (xy 136.014379 -27.244154)
			(xy 136.066674 -27.259509) (xy 136.116251 -27.282151) (xy 136.162101 -27.311617) (xy 136.203292 -27.347308)
			(xy 136.238983 -27.388499) (xy 136.268449 -27.434349) (xy 136.291091 -27.483926) (xy 136.306446 -27.536221)
			(xy 136.314202 -27.590169) (xy 136.314688 -27.61742) (xy 136.314688 -27.617674) (xy 136.314325 -27.642911)
			(xy 136.307697 -27.692946) (xy 136.294514 -27.741666) (xy 136.275008 -27.788217) (xy 136.262618 -27.810206)
			(xy 136.25716 -27.820547) (xy 136.25543 -27.843843) (xy 136.264193 -27.865498) (xy 136.272524 -27.873706)
			(xy 136.294964 -27.894406) (xy 136.335228 -27.940301) (xy 136.369707 -27.990686) (xy 136.397905 -28.044838)
			(xy 136.419415 -28.101976) (xy 136.433929 -28.161279) (xy 136.441237 -28.221893) (xy 136.441688 -28.25242)
			(xy 136.441126 -28.287386) (xy 136.431521 -28.356657) (xy 136.412509 -28.423956) (xy 136.384449 -28.488013)
			(xy 136.347871 -28.547617) (xy 136.326118 -28.575) (xy 136.320838 -28.581993) (xy 136.314999 -28.598501)
			(xy 136.314688 -28.607258) (xy 136.314688 -28.888182) (xy 136.315063 -28.896928) (xy 136.320892 -28.913419)
			(xy 136.326118 -28.92044) (xy 136.347877 -28.947815) (xy 136.384427 -29.007433) (xy 136.404386 -29.053028)
			(xy 139.446762 -29.053028) (xy 139.447314 -29.024239) (xy 139.455971 -28.967314) (xy 139.473077 -28.912334)
			(xy 139.498244 -28.860547) (xy 139.530902 -28.813125) (xy 139.570311 -28.771145) (xy 139.615576 -28.735559)
			(xy 139.665672 -28.707172) (xy 139.69238 -28.696412) (xy 139.700709 -28.692879) (xy 139.714377 -28.681044)
			(xy 139.71905 -28.673298) (xy 139.733528 -28.646374) (xy 139.737608 -28.638182) (xy 139.740205 -28.62008)
			(xy 139.738608 -28.611068) (xy 139.732783 -28.583561) (xy 139.72655 -28.527677) (xy 139.726162 -28.499562)
			(xy 139.72662 -28.468831) (xy 139.734032 -28.407819) (xy 139.748744 -28.348144) (xy 139.770541 -28.290677)
			(xy 139.799105 -28.236257) (xy 139.834021 -28.185676) (xy 139.874778 -28.139672) (xy 139.920782 -28.098916)
			(xy 139.971364 -28.064001) (xy 140.025785 -28.035438) (xy 140.083252 -28.013642) (xy 140.142926 -27.998931)
			(xy 140.203939 -27.991519) (xy 140.23467 -27.991054) (xy 140.269626 -27.991606) (xy 140.33888 -28.001177)
			(xy 140.406171 -28.020141) (xy 140.470231 -28.048142) (xy 140.529852 -28.084653) (xy 140.55725 -28.10637)
			(xy 140.564202 -28.111595) (xy 140.580565 -28.117447) (xy 140.589254 -28.1178) (xy 140.743686 -28.1178)
			(xy 140.752369 -28.117417) (xy 140.768727 -28.111573) (xy 140.77569 -28.10637) (xy 140.803089 -28.084657)
			(xy 140.862715 -28.048161) (xy 140.926776 -28.020168) (xy 140.994065 -28.001207) (xy 141.063315 -27.991635)
			(xy 141.09827 -27.991054) (xy 141.128999 -27.991584) (xy 141.190009 -27.998988) (xy 141.249682 -28.013693)
			(xy 141.307147 -28.035482) (xy 141.361567 -28.06404) (xy 141.412148 -28.098948) (xy 141.458153 -28.139699)
			(xy 141.49891 -28.185698) (xy 141.533825 -28.236275) (xy 141.56239 -28.290691) (xy 141.584187 -28.348153)
			(xy 141.598899 -28.407824) (xy 141.606312 -28.468833) (xy 141.606778 -28.499562) (xy 141.606778 -28.499816)
			(xy 141.606364 -28.528128) (xy 141.599996 -28.584394) (xy 141.594078 -28.612084) (xy 141.592412 -28.621073)
			(xy 141.594895 -28.639173) (xy 141.598904 -28.64739) (xy 141.613382 -28.674314) (xy 141.617942 -28.682128)
			(xy 141.631488 -28.694103) (xy 141.639798 -28.697682) (xy 141.666243 -28.708575) (xy 141.715829 -28.73707)
			(xy 141.760604 -28.77265) (xy 141.799564 -28.814519) (xy 141.831834 -28.861735) (xy 141.85669 -28.913242)
			(xy 141.873576 -28.967883) (xy 141.882113 -29.024433) (xy 141.882622 -29.053028) (xy 141.882148 -29.080279)
			(xy 141.874388 -29.134227) (xy 141.85903 -29.186521) (xy 141.836387 -29.236097) (xy 141.806919 -29.281947)
			(xy 141.771226 -29.323136) (xy 141.730036 -29.358827) (xy 141.684185 -29.388294) (xy 141.634608 -29.410935)
			(xy 141.582313 -29.426291) (xy 141.528365 -29.434049) (xy 141.501114 -29.434536) (xy 141.47227 -29.434061)
			(xy 141.415243 -29.42535) (xy 141.360176 -29.408154) (xy 141.308326 -29.382865) (xy 141.260872 -29.35006)
			(xy 141.218897 -29.310486) (xy 141.183358 -29.265045) (xy 141.155063 -29.214772) (xy 141.134657 -29.160812)
			(xy 141.122606 -29.104396) (xy 141.120368 -29.075634) (xy 141.119406 -29.066746) (xy 141.112265 -29.050374)
			(xy 141.106398 -29.04363) (xy 141.085062 -29.021532) (xy 141.078453 -29.015154) (xy 141.061913 -29.007207)
			(xy 141.052804 -29.006038) (xy 141.022561 -29.002928) (xy 140.96308 -28.990335) (xy 140.905529 -28.97073)
			(xy 140.85073 -28.944392) (xy 140.799468 -28.911699) (xy 140.77569 -28.892754) (xy 140.768752 -28.887507)
			(xy 140.752379 -28.881667) (xy 140.743686 -28.881324) (xy 140.589254 -28.881324) (xy 140.580572 -28.88172)
			(xy 140.564214 -28.887555) (xy 140.55725 -28.892754) (xy 140.533199 -28.911885) (xy 140.481331 -28.944852)
			(xy 140.425866 -28.97132) (xy 140.367612 -28.990903) (xy 140.307421 -29.003316) (xy 140.276834 -29.006292)
			(xy 140.267755 -29.007433) (xy 140.25122 -29.01524) (xy 140.244576 -29.021532) (xy 140.22324 -29.04363)
			(xy 140.217188 -29.050349) (xy 140.209908 -29.066889) (xy 140.209016 -29.075888) (xy 140.206718 -29.104634)
			(xy 140.19466 -29.161022) (xy 140.17425 -29.214952) (xy 140.145953 -29.265195) (xy 140.110414 -29.310604)
			(xy 140.068443 -29.350146) (xy 140.020997 -29.382917) (xy 139.969158 -29.408171) (xy 139.914108 -29.425332)
			(xy 139.857102 -29.434009) (xy 139.82827 -29.434536) (xy 139.801019 -29.43405) (xy 139.747073 -29.42629)
			(xy 139.69478 -29.410933) (xy 139.645205 -29.38829) (xy 139.599356 -29.358823) (xy 139.558166 -29.323132)
			(xy 139.522475 -29.281943) (xy 139.493009 -29.236094) (xy 139.470366 -29.186518) (xy 139.455009 -29.134225)
			(xy 139.44725 -29.080279) (xy 139.446762 -29.053028) (xy 136.404386 -29.053028) (xy 136.412469 -29.071493)
			(xy 136.431476 -29.13879) (xy 136.441089 -29.208056) (xy 136.441688 -29.24302) (xy 136.441255 -29.273547)
			(xy 136.433942 -29.334161) (xy 136.419424 -29.393463) (xy 136.397909 -29.450601) (xy 136.369708 -29.504751)
			(xy 136.335226 -29.555135) (xy 136.294959 -29.601027) (xy 136.272524 -29.621734) (xy 136.264265 -29.629989)
			(xy 136.25554 -29.651616) (xy 136.257233 -29.674876) (xy 136.262618 -29.685234) (xy 136.27498 -29.707235)
			(xy 136.294446 -29.753794) (xy 136.307621 -29.802509) (xy 136.314275 -29.852534) (xy 136.314688 -29.877766)
			(xy 136.314688 -29.87802) (xy 136.314202 -29.905271) (xy 136.306446 -29.959219) (xy 136.291091 -30.011514)
			(xy 136.268449 -30.061091) (xy 136.238983 -30.106941) (xy 136.203292 -30.148132) (xy 136.162101 -30.183823)
			(xy 136.116251 -30.213289) (xy 136.066674 -30.235931) (xy 136.014379 -30.251286) (xy 135.960431 -30.259042)
			(xy 135.905929 -30.259042) (xy 135.851981 -30.251286) (xy 135.799686 -30.235931) (xy 135.750109 -30.213289)
			(xy 135.704259 -30.183823) (xy 135.663068 -30.148132) (xy 135.627377 -30.106941) (xy 135.597911 -30.061091)
			(xy 135.575269 -30.011514) (xy 135.559914 -29.959219) (xy 135.552158 -29.905271) (xy 135.551672 -29.87802)
			(xy 135.551672 -29.877766) (xy 135.552058 -29.85253) (xy 135.55868 -29.802496) (xy 135.571856 -29.753776)
			(xy 135.591356 -29.707224) (xy 135.603742 -29.685234) (xy 135.609172 -29.67488) (xy 135.610917 -29.651591)
			(xy 135.602164 -29.62994) (xy 135.593836 -29.621734) (xy 135.571407 -29.601022) (xy 135.531144 -29.555129)
			(xy 135.496665 -29.504745) (xy 135.468466 -29.450595) (xy 135.446954 -29.393459) (xy 135.432437 -29.334158)
			(xy 135.425125 -29.273546) (xy 135.424672 -29.24302) (xy 129.479561 -29.24302) (xy 129.467811 -29.265357)
			(xy 129.403008 -29.372083) (xy 129.331774 -29.474629) (xy 129.254379 -29.572609) (xy 129.213102 -29.619448)
			(xy 129.207615 -29.626055) (xy 129.200993 -29.64189) (xy 129.200148 -29.650436) (xy 129.195869 -29.71431)
			(xy 129.180272 -29.841386) (xy 129.156707 -29.967228) (xy 129.125268 -30.091337) (xy 129.08608 -30.213222)
			(xy 129.039297 -30.332398) (xy 128.985105 -30.448393) (xy 128.92372 -30.560747) (xy 128.862462 -30.6578)
			(xy 138.403582 -30.6578) (xy 138.407653 -30.602178) (xy 138.419779 -30.547741) (xy 138.439702 -30.49565)
			(xy 138.466998 -30.447015) (xy 138.501084 -30.402872) (xy 138.541233 -30.364163) (xy 138.586591 -30.331712)
			(xy 138.636191 -30.306211) (xy 138.688975 -30.288204) (xy 138.743818 -30.278074) (xy 138.799552 -30.276037)
			(xy 138.854989 -30.282137) (xy 138.908946 -30.296243) (xy 138.960275 -30.318055) (xy 139.007881 -30.347109)
			(xy 139.050749 -30.382784) (xy 139.087966 -30.424321) (xy 139.118739 -30.470834) (xy 139.142411 -30.521331)
			(xy 139.158479 -30.574738) (xy 139.166599 -30.629914) (xy 139.167108 -30.6578) (xy 139.166599 -30.685686)
			(xy 139.158479 -30.740862) (xy 139.142411 -30.794269) (xy 139.118739 -30.844766) (xy 139.087966 -30.891279)
			(xy 139.050749 -30.932816) (xy 139.007881 -30.968491) (xy 138.960275 -30.997545) (xy 138.908946 -31.019357)
			(xy 138.854989 -31.033463) (xy 138.799552 -31.039563) (xy 138.743818 -31.037526) (xy 138.688975 -31.027396)
			(xy 138.636191 -31.009389) (xy 138.586591 -30.983888) (xy 138.541233 -30.951437) (xy 138.501084 -30.912728)
			(xy 138.466998 -30.868585) (xy 138.439702 -30.81995) (xy 138.419779 -30.767859) (xy 138.407653 -30.713422)
			(xy 138.403582 -30.6578) (xy 128.862462 -30.6578) (xy 128.855384 -30.669014) (xy 128.780369 -30.772766)
			(xy 128.698972 -30.871589) (xy 128.611517 -30.965094) (xy 128.518349 -31.052908) (xy 128.419838 -31.134684)
			(xy 128.316376 -31.210097) (xy 128.208372 -31.278848) (xy 128.096255 -31.340665) (xy 127.980469 -31.395301)
			(xy 127.861473 -31.442542) (xy 127.73974 -31.482199) (xy 127.615753 -31.514114) (xy 127.490002 -31.538162)
			(xy 127.362987 -31.554248) (xy 127.235211 -31.562306) (xy 127.171196 -31.562802) (xy 127.170942 -31.562802)
			(xy 127.105764 -31.562313) (xy 126.975678 -31.553944) (xy 126.846395 -31.537258) (xy 126.718446 -31.512322)
			(xy 126.592359 -31.47924) (xy 126.46865 -31.438147) (xy 126.347828 -31.389212) (xy 126.23039 -31.332636)
			(xy 126.116818 -31.268653) (xy 126.007579 -31.197523) (xy 125.955044 -31.158942) (xy 125.947496 -31.153794)
			(xy 125.929989 -31.14863) (xy 125.911783 -31.149941) (xy 125.895195 -31.157559) (xy 125.888496 -31.163768)
			(xy 125.647196 -31.405322) (xy 125.639794 -31.41216) (xy 125.621196 -31.41988) (xy 125.611128 -31.420308)
			(xy 125.52172 -31.420308) (xy 125.510702 -31.420854) (xy 125.490685 -31.430068) (xy 125.483112 -31.438088)
			(xy 125.433074 -31.496254) (xy 125.426251 -31.504942) (xy 125.420202 -31.526164) (xy 125.42139 -31.537148)
			(xy 125.423408 -31.551285) (xy 125.425569 -31.579764) (xy 125.425708 -31.594044) (xy 125.425708 -31.594806)
			(xy 125.425222 -31.622057) (xy 125.417466 -31.676005) (xy 125.402111 -31.7283) (xy 125.379469 -31.777877)
			(xy 125.350003 -31.823727) (xy 125.314312 -31.864918) (xy 125.273121 -31.900609) (xy 125.227271 -31.930075)
			(xy 125.177694 -31.952717) (xy 125.125399 -31.968072) (xy 125.071451 -31.975828) (xy 125.016949 -31.975828)
			(xy 124.963001 -31.968072) (xy 124.910706 -31.952717) (xy 124.861129 -31.930075) (xy 124.815279 -31.900609)
			(xy 124.774088 -31.864918) (xy 124.738397 -31.823727) (xy 124.708931 -31.777877) (xy 124.686289 -31.7283)
			(xy 124.670934 -31.676005) (xy 124.663178 -31.622057) (xy 124.662692 -31.594806) (xy 124.662692 -31.594044)
			(xy 124.662837 -31.579764) (xy 124.665002 -31.551287) (xy 124.66701 -31.537148) (xy 124.668097 -31.526172)
			(xy 124.662062 -31.504985) (xy 124.655326 -31.496254) (xy 124.605288 -31.438088) (xy 124.597721 -31.43006)
			(xy 124.5777 -31.420845) (xy 124.56668 -31.420308) (xy 123.258072 -31.420308) (xy 123.247998 -31.419921)
			(xy 123.229399 -31.412176) (xy 123.222004 -31.405322) (xy 122.403616 -30.58668) (xy 122.394571 -30.578574)
			(xy 122.371492 -30.571134) (xy 122.35942 -30.572456) (xy 122.26544 -30.58795) (xy 122.245882 -30.602682)
			(xy 122.240548 -30.613858) (xy 122.225269 -30.643721) (xy 122.188004 -30.699497) (xy 122.143721 -30.749883)
			(xy 122.093192 -30.794002) (xy 122.065542 -30.812994) (xy 122.055413 -30.820541) (xy 122.043541 -30.842796)
			(xy 122.042936 -30.855412) (xy 122.042936 -30.93974) (xy 122.043607 -30.952342) (xy 122.055446 -30.97459)
			(xy 122.065542 -30.982158) (xy 122.091331 -30.999878) (xy 122.138811 -31.040634) (xy 122.180929 -31.086909)
			(xy 122.217049 -31.138005) (xy 122.246623 -31.193148) (xy 122.269205 -31.251504) (xy 122.284453 -31.31219)
			(xy 122.292137 -31.37429) (xy 122.292618 -31.405576) (xy 122.292116 -31.437537) (xy 122.284105 -31.500955)
			(xy 122.268208 -31.562869) (xy 122.244676 -31.622302) (xy 122.213882 -31.678317) (xy 122.176309 -31.730032)
			(xy 122.132552 -31.776629) (xy 122.083299 -31.817374) (xy 122.029328 -31.851625) (xy 121.971489 -31.878842)
			(xy 121.910696 -31.898595) (xy 121.847906 -31.910573) (xy 121.78411 -31.914587) (xy 121.720314 -31.910573)
			(xy 121.657524 -31.898595) (xy 121.596731 -31.878842) (xy 121.538892 -31.851625) (xy 121.484921 -31.817374)
			(xy 121.435668 -31.776629) (xy 121.391911 -31.730032) (xy 121.354338 -31.678317) (xy 121.323544 -31.622302)
			(xy 121.300012 -31.562869) (xy 121.284115 -31.500955) (xy 121.276104 -31.437537) (xy 121.275602 -31.405576)
			(xy 121.276094 -31.374289) (xy 121.283768 -31.312187) (xy 121.299009 -31.251497) (xy 121.321586 -31.193138)
			(xy 121.351158 -31.137993) (xy 121.387277 -31.086896) (xy 121.429397 -31.04062) (xy 121.47688 -30.999866)
			(xy 121.502678 -30.982158) (xy 121.512833 -30.974639) (xy 121.524691 -30.952363) (xy 121.525284 -30.93974)
			(xy 121.525284 -30.855412) (xy 121.524634 -30.842808) (xy 121.512779 -30.820561) (xy 121.502678 -30.812994)
			(xy 121.476867 -30.79531) (xy 121.429403 -30.754542) (xy 121.3873 -30.708257) (xy 121.351195 -30.657156)
			(xy 121.321634 -30.60201) (xy 121.299063 -30.543653) (xy 121.283825 -30.482968) (xy 121.276148 -30.420871)
			(xy 121.27615 -30.358302) (xy 121.28383 -30.296206) (xy 121.299072 -30.235521) (xy 121.321645 -30.177166)
			(xy 121.351209 -30.122022) (xy 121.387316 -30.070922) (xy 121.429422 -30.02464) (xy 121.476888 -29.983874)
			(xy 121.502678 -29.966158) (xy 121.512833 -29.958639) (xy 121.524691 -29.936363) (xy 121.525284 -29.92374)
			(xy 121.525284 -29.839412) (xy 121.524634 -29.826808) (xy 121.512779 -29.804561) (xy 121.502678 -29.796994)
			(xy 121.476871 -29.779299) (xy 121.429391 -29.73854) (xy 121.387273 -29.692261) (xy 121.351154 -29.641162)
			(xy 121.321582 -29.586015) (xy 121.299003 -29.527656) (xy 121.283759 -29.466966) (xy 121.27608 -29.404864)
			(xy 121.275602 -29.373576) (xy 121.276034 -29.342844) (xy 121.283445 -29.281829) (xy 121.298157 -29.222152)
			(xy 121.319954 -29.164683) (xy 121.34852 -29.11026) (xy 121.383438 -29.059678) (xy 121.424197 -29.013673)
			(xy 121.470205 -28.972917) (xy 121.52079 -28.938003) (xy 121.575214 -28.909441) (xy 121.632684 -28.887647)
			(xy 121.692362 -28.872939) (xy 121.753378 -28.865531) (xy 121.78411 -28.865068) (xy 121.818399 -28.865634)
			(xy 121.886353 -28.874856) (xy 121.952454 -28.893118) (xy 122.015505 -28.920089) (xy 122.045222 -28.937204)
			(xy 122.05716 -28.944316) (xy 122.084338 -28.94457) (xy 122.173238 -28.894278) (xy 122.180824 -28.889515)
			(xy 122.192373 -28.875838) (xy 122.198534 -28.859032) (xy 122.198892 -28.850082) (xy 122.198892 -28.689554)
			(xy 122.198525 -28.680445) (xy 122.192172 -28.66337) (xy 122.180275 -28.649572) (xy 122.172476 -28.64485)
			(xy 122.094244 -28.602178) (xy 122.08608 -28.59814) (xy 122.068073 -28.595503) (xy 122.050286 -28.599352)
			(xy 122.042428 -28.603956) (xy 122.01778 -28.619328) (xy 121.965647 -28.644955) (xy 121.910935 -28.664481)
			(xy 121.854356 -28.677652) (xy 121.796646 -28.684298) (xy 121.7676 -28.684728) (xy 121.73564 -28.684186)
			(xy 121.672225 -28.676175) (xy 121.610313 -28.660279) (xy 121.550882 -28.636748) (xy 121.494869 -28.605955)
			(xy 121.443157 -28.568384) (xy 121.396562 -28.524628) (xy 121.355818 -28.475377) (xy 121.321568 -28.421408)
			(xy 121.294353 -28.363572) (xy 121.2746 -28.302781) (xy 121.262623 -28.239993) (xy 121.25861 -28.1762)
			(xy 108.225481 -28.1762) (xy 108.225342 -28.185067) (xy 108.217331 -28.248485) (xy 108.201434 -28.310399)
			(xy 108.177902 -28.369832) (xy 108.147108 -28.425847) (xy 108.109535 -28.477562) (xy 108.065778 -28.524159)
			(xy 108.016525 -28.564904) (xy 107.962554 -28.599155) (xy 107.904715 -28.626372) (xy 107.843922 -28.646125)
			(xy 107.781132 -28.658103) (xy 107.717336 -28.662117) (xy 107.65354 -28.658103) (xy 107.59075 -28.646125)
			(xy 107.529957 -28.626372) (xy 107.472118 -28.599155) (xy 107.418147 -28.564904) (xy 107.368894 -28.524159)
			(xy 107.325137 -28.477562) (xy 107.287564 -28.425847) (xy 107.25677 -28.369832) (xy 107.233238 -28.310399)
			(xy 107.217341 -28.248485) (xy 107.20933 -28.185067) (xy 102.893155 -28.185067) (xy 102.881575 -28.20977)
			(xy 102.850802 -28.256283) (xy 102.813585 -28.29782) (xy 102.770717 -28.333495) (xy 102.723111 -28.362549)
			(xy 102.671782 -28.384361) (xy 102.617825 -28.398467) (xy 102.562388 -28.404567) (xy 102.506654 -28.40253)
			(xy 102.451811 -28.3924) (xy 102.399027 -28.374393) (xy 102.349427 -28.348892) (xy 102.304069 -28.316441)
			(xy 102.26392 -28.277732) (xy 102.229834 -28.233589) (xy 102.202538 -28.184954) (xy 102.182615 -28.132863)
			(xy 102.170489 -28.078426) (xy 102.166418 -28.022804) (xy 81.01838 -28.022804) (xy 81.01838 -29.51861)
			(xy 100.564696 -29.51861) (xy 100.565095 -29.492229) (xy 100.57236 -29.43997) (xy 100.586752 -29.389209)
			(xy 100.607998 -29.340913) (xy 100.635692 -29.296004) (xy 100.669306 -29.255336) (xy 100.708201 -29.219685)
			(xy 100.751635 -29.18973) (xy 100.775008 -29.177488) (xy 100.787962 -29.171138) (xy 100.803202 -29.1465)
			(xy 100.803202 -29.02712) (xy 100.787962 -29.002482) (xy 100.775008 -28.996132) (xy 100.751644 -28.983879)
			(xy 100.708219 -28.953919) (xy 100.669333 -28.918266) (xy 100.635726 -28.877598) (xy 100.608038 -28.832691)
			(xy 100.586797 -28.784399) (xy 100.572407 -28.733643) (xy 100.565142 -28.681388) (xy 100.564696 -28.65501)
			(xy 100.565165 -28.627757) (xy 100.57292 -28.573806) (xy 100.588275 -28.521508) (xy 100.610917 -28.471928)
			(xy 100.640384 -28.426075) (xy 100.676077 -28.384882) (xy 100.71727 -28.349188) (xy 100.763123 -28.31972)
			(xy 100.812703 -28.297077) (xy 100.865 -28.281722) (xy 100.918951 -28.273965) (xy 100.946204 -28.273502)
			(xy 100.976897 -28.27412) (xy 101.037492 -28.283942) (xy 101.095734 -28.303334) (xy 101.150123 -28.331794)
			(xy 101.175058 -28.349702) (xy 101.175312 -28.349702) (xy 101.183354 -28.355227) (xy 101.20216 -28.360339)
			(xy 101.211888 -28.359608) (xy 101.281738 -28.351226) (xy 101.291301 -28.349552) (xy 101.308276 -28.340164)
			(xy 101.314758 -28.332938) (xy 101.335521 -28.30839) (xy 101.382188 -28.264162) (xy 101.434058 -28.226171)
			(xy 101.490304 -28.195021) (xy 101.550027 -28.17121) (xy 101.612276 -28.155118) (xy 101.676057 -28.147001)
			(xy 101.708204 -28.146502) (xy 101.738937 -28.146934) (xy 101.799954 -28.154343) (xy 101.859632 -28.169053)
			(xy 101.917103 -28.19085) (xy 101.971528 -28.219415) (xy 102.022112 -28.254332) (xy 102.068119 -28.295091)
			(xy 102.108877 -28.341099) (xy 102.143792 -28.391684) (xy 102.172356 -28.44611) (xy 102.194151 -28.503581)
			(xy 102.208859 -28.56326) (xy 102.216267 -28.624277) (xy 102.216712 -28.65501) (xy 102.216139 -28.689976)
			(xy 102.206536 -28.759246) (xy 102.187526 -28.826545) (xy 102.159468 -28.890601) (xy 102.122893 -28.950207)
			(xy 102.101142 -28.97759) (xy 102.095869 -28.984587) (xy 102.090025 -29.001092) (xy 102.089712 -29.009848)
			(xy 102.089712 -29.163772) (xy 102.090087 -29.172518) (xy 102.095915 -29.189009) (xy 102.101142 -29.19603)
			(xy 102.1229 -29.223406) (xy 102.159449 -29.283023) (xy 102.187491 -29.347084) (xy 102.206498 -29.41438)
			(xy 102.213633 -29.465778) (xy 110.384842 -29.465778) (xy 110.388913 -29.410156) (xy 110.401039 -29.355719)
			(xy 110.420962 -29.303628) (xy 110.448258 -29.254993) (xy 110.482344 -29.21085) (xy 110.522493 -29.172141)
			(xy 110.567851 -29.13969) (xy 110.617451 -29.114189) (xy 110.670235 -29.096182) (xy 110.725078 -29.086052)
			(xy 110.780812 -29.084015) (xy 110.836249 -29.090115) (xy 110.890206 -29.104221) (xy 110.941535 -29.126033)
			(xy 110.989141 -29.155087) (xy 111.032009 -29.190762) (xy 111.069226 -29.232299) (xy 111.099999 -29.278812)
			(xy 111.123671 -29.329309) (xy 111.139739 -29.382716) (xy 111.147859 -29.437892) (xy 111.148368 -29.465778)
			(xy 112.416842 -29.465778) (xy 112.420913 -29.410156) (xy 112.433039 -29.355719) (xy 112.452962 -29.303628)
			(xy 112.480258 -29.254993) (xy 112.514344 -29.21085) (xy 112.554493 -29.172141) (xy 112.599851 -29.13969)
			(xy 112.649451 -29.114189) (xy 112.702235 -29.096182) (xy 112.757078 -29.086052) (xy 112.812812 -29.084015)
			(xy 112.868249 -29.090115) (xy 112.922206 -29.104221) (xy 112.973535 -29.126033) (xy 113.021141 -29.155087)
			(xy 113.064009 -29.190762) (xy 113.101226 -29.232299) (xy 113.131999 -29.278812) (xy 113.155671 -29.329309)
			(xy 113.171739 -29.382716) (xy 113.179859 -29.437892) (xy 113.180368 -29.465778) (xy 113.432842 -29.465778)
			(xy 113.436913 -29.410156) (xy 113.449039 -29.355719) (xy 113.468962 -29.303628) (xy 113.496258 -29.254993)
			(xy 113.530344 -29.21085) (xy 113.570493 -29.172141) (xy 113.615851 -29.13969) (xy 113.665451 -29.114189)
			(xy 113.718235 -29.096182) (xy 113.773078 -29.086052) (xy 113.828812 -29.084015) (xy 113.884249 -29.090115)
			(xy 113.938206 -29.104221) (xy 113.989535 -29.126033) (xy 114.037141 -29.155087) (xy 114.080009 -29.190762)
			(xy 114.117226 -29.232299) (xy 114.147999 -29.278812) (xy 114.171671 -29.329309) (xy 114.187739 -29.382716)
			(xy 114.195859 -29.437892) (xy 114.196368 -29.465778) (xy 114.448842 -29.465778) (xy 114.452913 -29.410156)
			(xy 114.465039 -29.355719) (xy 114.484962 -29.303628) (xy 114.512258 -29.254993) (xy 114.546344 -29.21085)
			(xy 114.586493 -29.172141) (xy 114.631851 -29.13969) (xy 114.681451 -29.114189) (xy 114.734235 -29.096182)
			(xy 114.789078 -29.086052) (xy 114.844812 -29.084015) (xy 114.900249 -29.090115) (xy 114.954206 -29.104221)
			(xy 115.005535 -29.126033) (xy 115.053141 -29.155087) (xy 115.096009 -29.190762) (xy 115.133226 -29.232299)
			(xy 115.163999 -29.278812) (xy 115.187671 -29.329309) (xy 115.203739 -29.382716) (xy 115.211859 -29.437892)
			(xy 115.212368 -29.465778) (xy 115.211859 -29.493664) (xy 115.203739 -29.54884) (xy 115.187671 -29.602247)
			(xy 115.163999 -29.652744) (xy 115.133226 -29.699257) (xy 115.096009 -29.740794) (xy 115.053141 -29.776469)
			(xy 115.005535 -29.805523) (xy 114.954206 -29.827335) (xy 114.900249 -29.841441) (xy 114.844812 -29.847541)
			(xy 114.789078 -29.845504) (xy 114.734235 -29.835374) (xy 114.681451 -29.817367) (xy 114.631851 -29.791866)
			(xy 114.586493 -29.759415) (xy 114.546344 -29.720706) (xy 114.512258 -29.676563) (xy 114.484962 -29.627928)
			(xy 114.465039 -29.575837) (xy 114.452913 -29.5214) (xy 114.448842 -29.465778) (xy 114.196368 -29.465778)
			(xy 114.195859 -29.493664) (xy 114.187739 -29.54884) (xy 114.171671 -29.602247) (xy 114.147999 -29.652744)
			(xy 114.117226 -29.699257) (xy 114.080009 -29.740794) (xy 114.037141 -29.776469) (xy 113.989535 -29.805523)
			(xy 113.938206 -29.827335) (xy 113.884249 -29.841441) (xy 113.828812 -29.847541) (xy 113.773078 -29.845504)
			(xy 113.718235 -29.835374) (xy 113.665451 -29.817367) (xy 113.615851 -29.791866) (xy 113.570493 -29.759415)
			(xy 113.530344 -29.720706) (xy 113.496258 -29.676563) (xy 113.468962 -29.627928) (xy 113.449039 -29.575837)
			(xy 113.436913 -29.5214) (xy 113.432842 -29.465778) (xy 113.180368 -29.465778) (xy 113.179859 -29.493664)
			(xy 113.171739 -29.54884) (xy 113.155671 -29.602247) (xy 113.131999 -29.652744) (xy 113.101226 -29.699257)
			(xy 113.064009 -29.740794) (xy 113.021141 -29.776469) (xy 112.973535 -29.805523) (xy 112.922206 -29.827335)
			(xy 112.868249 -29.841441) (xy 112.812812 -29.847541) (xy 112.757078 -29.845504) (xy 112.702235 -29.835374)
			(xy 112.649451 -29.817367) (xy 112.599851 -29.791866) (xy 112.554493 -29.759415) (xy 112.514344 -29.720706)
			(xy 112.480258 -29.676563) (xy 112.452962 -29.627928) (xy 112.433039 -29.575837) (xy 112.420913 -29.5214)
			(xy 112.416842 -29.465778) (xy 111.148368 -29.465778) (xy 111.147859 -29.493664) (xy 111.139739 -29.54884)
			(xy 111.123671 -29.602247) (xy 111.099999 -29.652744) (xy 111.069226 -29.699257) (xy 111.032009 -29.740794)
			(xy 110.989141 -29.776469) (xy 110.941535 -29.805523) (xy 110.890206 -29.827335) (xy 110.836249 -29.841441)
			(xy 110.780812 -29.847541) (xy 110.725078 -29.845504) (xy 110.670235 -29.835374) (xy 110.617451 -29.817367)
			(xy 110.567851 -29.791866) (xy 110.522493 -29.759415) (xy 110.482344 -29.720706) (xy 110.448258 -29.676563)
			(xy 110.420962 -29.627928) (xy 110.401039 -29.575837) (xy 110.388913 -29.5214) (xy 110.384842 -29.465778)
			(xy 102.213633 -29.465778) (xy 102.216113 -29.483646) (xy 102.216712 -29.51861) (xy 102.216253 -29.549341)
			(xy 102.208844 -29.610355) (xy 102.194134 -29.670031) (xy 102.172339 -29.727499) (xy 102.143775 -29.78192)
			(xy 102.10886 -29.832502) (xy 102.068103 -29.878507) (xy 102.022098 -29.919264) (xy 101.971515 -29.954178)
			(xy 101.917093 -29.982741) (xy 101.859625 -30.004536) (xy 101.799949 -30.019245) (xy 101.738935 -30.026654)
			(xy 101.708204 -30.027118) (xy 101.676053 -30.026644) (xy 101.612264 -30.018544) (xy 101.550007 -30.002462)
			(xy 101.490276 -29.978654) (xy 101.434026 -29.9475) (xy 101.382155 -29.909499) (xy 101.335494 -29.865257)
			(xy 101.314758 -29.840682) (xy 101.308295 -29.833428) (xy 101.291316 -29.824022) (xy 101.281738 -29.822394)
			(xy 101.211888 -29.814012) (xy 101.202162 -29.813305) (xy 101.183355 -29.818403) (xy 101.175312 -29.823918)
			(xy 101.175058 -29.823918) (xy 101.150128 -29.841832) (xy 101.095737 -29.870292) (xy 101.037493 -29.889683)
			(xy 100.976897 -29.899505) (xy 100.946204 -29.900118) (xy 100.918953 -29.899619) (xy 100.865007 -29.891863)
			(xy 100.812713 -29.876509) (xy 100.763136 -29.853869) (xy 100.717286 -29.824404) (xy 100.676096 -29.788714)
			(xy 100.640405 -29.747525) (xy 100.610938 -29.701676) (xy 100.588296 -29.6521) (xy 100.57294 -29.599807)
			(xy 100.565182 -29.545861) (xy 100.564696 -29.51861) (xy 81.01838 -29.51861) (xy 81.01838 -30.63156)
			(xy 85.961755 -30.63156) (xy 85.964357 -30.568526) (xy 85.974736 -30.506298) (xy 85.992733 -30.445831)
			(xy 86.018071 -30.388055) (xy 86.050361 -30.333857) (xy 86.089106 -30.284069) (xy 86.133713 -30.239455)
			(xy 86.183495 -30.200702) (xy 86.237689 -30.168405) (xy 86.295461 -30.143059) (xy 86.355925 -30.125053)
			(xy 86.418152 -30.114665) (xy 86.481186 -30.112054) (xy 86.544059 -30.117259) (xy 86.605805 -30.130201)
			(xy 86.665476 -30.150682) (xy 86.722155 -30.178386) (xy 86.774972 -30.212889) (xy 86.823116 -30.253659)
			(xy 86.865848 -30.300072) (xy 86.90251 -30.351414) (xy 86.93254 -30.406896) (xy 86.955476 -30.465667)
			(xy 86.970967 -30.526823) (xy 86.978774 -30.589426) (xy 86.979252 -30.62097) (xy 86.978998 -30.63748)
			(xy 86.979138 -30.64841) (xy 86.987582 -30.668553) (xy 86.995254 -30.676342) (xy 87.013185 -30.693063)
			(xy 91.37497 -30.693063) (xy 91.37497 -30.629141) (xy 91.382981 -30.565723) (xy 91.398878 -30.503809)
			(xy 91.42241 -30.444376) (xy 91.453204 -30.388361) (xy 91.490777 -30.336646) (xy 91.534534 -30.290049)
			(xy 91.583787 -30.249304) (xy 91.637758 -30.215053) (xy 91.695597 -30.187836) (xy 91.75639 -30.168083)
			(xy 91.81918 -30.156105) (xy 91.882976 -30.152092) (xy 91.946772 -30.156105) (xy 92.009562 -30.168083)
			(xy 92.070355 -30.187836) (xy 92.128194 -30.215053) (xy 92.135838 -30.219904) (xy 102.166418 -30.219904)
			(xy 102.170489 -30.164282) (xy 102.182615 -30.109845) (xy 102.202538 -30.057754) (xy 102.229834 -30.009119)
			(xy 102.26392 -29.964976) (xy 102.304069 -29.926267) (xy 102.349427 -29.893816) (xy 102.399027 -29.868315)
			(xy 102.451811 -29.850308) (xy 102.506654 -29.840178) (xy 102.562388 -29.838141) (xy 102.617825 -29.844241)
			(xy 102.671782 -29.858347) (xy 102.723111 -29.880159) (xy 102.770717 -29.909213) (xy 102.813585 -29.944888)
			(xy 102.850802 -29.986425) (xy 102.881575 -30.032938) (xy 102.905247 -30.083435) (xy 102.921315 -30.136842)
			(xy 102.929435 -30.192018) (xy 102.929944 -30.219904) (xy 102.929435 -30.24779) (xy 102.921315 -30.302966)
			(xy 102.905247 -30.356373) (xy 102.881575 -30.40687) (xy 102.850802 -30.453383) (xy 102.82536 -30.481778)
			(xy 110.384842 -30.481778) (xy 110.388913 -30.426156) (xy 110.401039 -30.371719) (xy 110.420962 -30.319628)
			(xy 110.448258 -30.270993) (xy 110.482344 -30.22685) (xy 110.522493 -30.188141) (xy 110.567851 -30.15569)
			(xy 110.617451 -30.130189) (xy 110.670235 -30.112182) (xy 110.725078 -30.102052) (xy 110.780812 -30.100015)
			(xy 110.836249 -30.106115) (xy 110.890206 -30.120221) (xy 110.941535 -30.142033) (xy 110.989141 -30.171087)
			(xy 111.032009 -30.206762) (xy 111.069226 -30.248299) (xy 111.099999 -30.294812) (xy 111.123671 -30.345309)
			(xy 111.139739 -30.398716) (xy 111.147859 -30.453892) (xy 111.148368 -30.481778) (xy 111.147859 -30.509664)
			(xy 111.139739 -30.56484) (xy 111.123671 -30.618247) (xy 111.099999 -30.668744) (xy 111.069226 -30.715257)
			(xy 111.032009 -30.756794) (xy 110.989141 -30.792469) (xy 110.941535 -30.821523) (xy 110.890206 -30.843335)
			(xy 110.836249 -30.857441) (xy 110.780812 -30.863541) (xy 110.725078 -30.861504) (xy 110.670235 -30.851374)
			(xy 110.617451 -30.833367) (xy 110.567851 -30.807866) (xy 110.522493 -30.775415) (xy 110.482344 -30.736706)
			(xy 110.448258 -30.692563) (xy 110.420962 -30.643928) (xy 110.401039 -30.591837) (xy 110.388913 -30.5374)
			(xy 110.384842 -30.481778) (xy 102.82536 -30.481778) (xy 102.813585 -30.49492) (xy 102.770717 -30.530595)
			(xy 102.723111 -30.559649) (xy 102.671782 -30.581461) (xy 102.617825 -30.595567) (xy 102.562388 -30.601667)
			(xy 102.506654 -30.59963) (xy 102.451811 -30.5895) (xy 102.399027 -30.571493) (xy 102.349427 -30.545992)
			(xy 102.304069 -30.513541) (xy 102.26392 -30.474832) (xy 102.229834 -30.430689) (xy 102.202538 -30.382054)
			(xy 102.182615 -30.329963) (xy 102.170489 -30.275526) (xy 102.166418 -30.219904) (xy 92.135838 -30.219904)
			(xy 92.182165 -30.249304) (xy 92.231418 -30.290049) (xy 92.275175 -30.336646) (xy 92.312748 -30.388361)
			(xy 92.343542 -30.444376) (xy 92.367074 -30.503809) (xy 92.382971 -30.565723) (xy 92.390982 -30.629141)
			(xy 92.391484 -30.661102) (xy 92.390982 -30.693063) (xy 92.382971 -30.756481) (xy 92.377135 -30.779212)
			(xy 99.084382 -30.779212) (xy 99.088453 -30.72359) (xy 99.100579 -30.669153) (xy 99.120502 -30.617062)
			(xy 99.147798 -30.568427) (xy 99.181884 -30.524284) (xy 99.222033 -30.485575) (xy 99.267391 -30.453124)
			(xy 99.316991 -30.427623) (xy 99.369775 -30.409616) (xy 99.424618 -30.399486) (xy 99.480352 -30.397449)
			(xy 99.535789 -30.403549) (xy 99.589746 -30.417655) (xy 99.641075 -30.439467) (xy 99.688681 -30.468521)
			(xy 99.731549 -30.504196) (xy 99.768766 -30.545733) (xy 99.799539 -30.592246) (xy 99.823211 -30.642743)
			(xy 99.839279 -30.69615) (xy 99.847399 -30.751326) (xy 99.847908 -30.779212) (xy 99.847482 -30.802537)
			(xy 100.90505 -30.802537) (xy 100.90505 -30.738615) (xy 100.913061 -30.675197) (xy 100.928958 -30.613283)
			(xy 100.95249 -30.55385) (xy 100.983284 -30.497835) (xy 101.020857 -30.44612) (xy 101.064614 -30.399523)
			(xy 101.113867 -30.358778) (xy 101.167838 -30.324527) (xy 101.225677 -30.29731) (xy 101.28647 -30.277557)
			(xy 101.34926 -30.265579) (xy 101.413056 -30.261566) (xy 101.476852 -30.265579) (xy 101.539642 -30.277557)
			(xy 101.600435 -30.29731) (xy 101.658274 -30.324527) (xy 101.712245 -30.358778) (xy 101.761498 -30.399523)
			(xy 101.805255 -30.44612) (xy 101.842828 -30.497835) (xy 101.873622 -30.55385) (xy 101.897154 -30.613283)
			(xy 101.913051 -30.675197) (xy 101.921062 -30.738615) (xy 101.921564 -30.770576) (xy 101.921062 -30.802537)
			(xy 101.913051 -30.865955) (xy 101.897154 -30.927869) (xy 101.873622 -30.987302) (xy 101.842828 -31.043317)
			(xy 101.805255 -31.095032) (xy 101.761498 -31.141629) (xy 101.712245 -31.182374) (xy 101.658274 -31.216625)
			(xy 101.600435 -31.243842) (xy 101.539642 -31.263595) (xy 101.476852 -31.275573) (xy 101.413056 -31.279587)
			(xy 101.34926 -31.275573) (xy 101.28647 -31.263595) (xy 101.225677 -31.243842) (xy 101.167838 -31.216625)
			(xy 101.113867 -31.182374) (xy 101.064614 -31.141629) (xy 101.020857 -31.095032) (xy 100.983284 -31.043317)
			(xy 100.95249 -30.987302) (xy 100.928958 -30.927869) (xy 100.913061 -30.865955) (xy 100.90505 -30.802537)
			(xy 99.847482 -30.802537) (xy 99.847399 -30.807098) (xy 99.839279 -30.862274) (xy 99.823211 -30.915681)
			(xy 99.799539 -30.966178) (xy 99.768766 -31.012691) (xy 99.731549 -31.054228) (xy 99.688681 -31.089903)
			(xy 99.641075 -31.118957) (xy 99.589746 -31.140769) (xy 99.535789 -31.154875) (xy 99.480352 -31.160975)
			(xy 99.424618 -31.158938) (xy 99.369775 -31.148808) (xy 99.316991 -31.130801) (xy 99.267391 -31.1053)
			(xy 99.222033 -31.072849) (xy 99.181884 -31.03414) (xy 99.147798 -30.989997) (xy 99.120502 -30.941362)
			(xy 99.100579 -30.889271) (xy 99.088453 -30.834834) (xy 99.084382 -30.779212) (xy 92.377135 -30.779212)
			(xy 92.367074 -30.818395) (xy 92.343542 -30.877828) (xy 92.312748 -30.933843) (xy 92.275175 -30.985558)
			(xy 92.231418 -31.032155) (xy 92.182165 -31.0729) (xy 92.128194 -31.107151) (xy 92.070355 -31.134368)
			(xy 92.009562 -31.154121) (xy 91.946772 -31.166099) (xy 91.882976 -31.170113) (xy 91.81918 -31.166099)
			(xy 91.75639 -31.154121) (xy 91.695597 -31.134368) (xy 91.637758 -31.107151) (xy 91.583787 -31.0729)
			(xy 91.534534 -31.032155) (xy 91.490777 -30.985558) (xy 91.453204 -30.933843) (xy 91.42241 -30.877828)
			(xy 91.398878 -30.818395) (xy 91.382981 -30.756481) (xy 91.37497 -30.693063) (xy 87.013185 -30.693063)
			(xy 87.059262 -30.736032) (xy 87.080344 -30.743144) (xy 87.091266 -30.741874) (xy 87.101207 -30.740913)
			(xy 87.121156 -30.739895) (xy 87.131144 -30.739842) (xy 87.158397 -30.740231) (xy 87.212347 -30.747994)
			(xy 87.264643 -30.763354) (xy 87.314221 -30.786001) (xy 87.360072 -30.815472) (xy 87.401263 -30.851169)
			(xy 87.436954 -30.892363) (xy 87.46642 -30.938217) (xy 87.489061 -30.987798) (xy 87.504416 -31.040096)
			(xy 87.512172 -31.094047) (xy 87.512172 -31.148553) (xy 87.504416 -31.202504) (xy 87.489061 -31.254802)
			(xy 87.476524 -31.282257) (xy 104.254709 -31.282257) (xy 104.254709 -31.227743) (xy 104.262467 -31.173785)
			(xy 104.277825 -31.12148) (xy 104.300471 -31.071894) (xy 104.329944 -31.026035) (xy 104.365642 -30.984837)
			(xy 104.406841 -30.949139) (xy 104.452701 -30.919667) (xy 104.502288 -30.897023) (xy 104.554593 -30.881665)
			(xy 104.608551 -30.873908) (xy 104.635808 -30.873446) (xy 104.662014 -30.873882) (xy 104.71393 -30.881065)
			(xy 104.764377 -30.89528) (xy 104.812405 -30.916261) (xy 104.857113 -30.943614) (xy 104.89766 -30.976824)
			(xy 104.933284 -31.015267) (xy 104.963315 -31.058221) (xy 104.98719 -31.104879) (xy 104.996234 -31.129478)
			(xy 104.999536 -31.139384) (xy 105.01376 -31.154878) (xy 105.101136 -31.19374) (xy 105.12171 -31.193994)
			(xy 105.131362 -31.18993) (xy 105.154893 -31.180472) (xy 105.203824 -31.167142) (xy 105.254087 -31.160394)
			(xy 105.279444 -31.159958) (xy 105.310138 -31.160544) (xy 105.370735 -31.170374) (xy 105.428977 -31.189775)
			(xy 105.483365 -31.218245) (xy 105.508298 -31.236158) (xy 105.508552 -31.236158) (xy 105.516579 -31.241708)
			(xy 105.535397 -31.246803) (xy 105.545128 -31.246064) (xy 105.614978 -31.237682) (xy 105.624549 -31.23604)
			(xy 105.641521 -31.226631) (xy 105.647998 -31.219394) (xy 105.668753 -31.194838) (xy 105.71542 -31.150609)
			(xy 105.767291 -31.112617) (xy 105.823538 -31.081467) (xy 105.883263 -31.057657) (xy 105.945514 -31.041568)
			(xy 106.009296 -31.033454) (xy 106.041444 -31.032958) (xy 106.072175 -31.033414) (xy 106.133187 -31.040827)
			(xy 106.192862 -31.055539) (xy 106.250328 -31.077337) (xy 106.304748 -31.105902) (xy 106.355329 -31.140817)
			(xy 106.401333 -31.181574) (xy 106.442089 -31.227579) (xy 106.477004 -31.27816) (xy 106.477866 -31.279803)
			(xy 107.209838 -31.279803) (xy 107.209838 -31.215881) (xy 107.217849 -31.152463) (xy 107.233746 -31.090549)
			(xy 107.257278 -31.031116) (xy 107.288072 -30.975101) (xy 107.325645 -30.923386) (xy 107.369402 -30.876789)
			(xy 107.418655 -30.836044) (xy 107.472626 -30.801793) (xy 107.530465 -30.774576) (xy 107.591258 -30.754823)
			(xy 107.654048 -30.742845) (xy 107.717844 -30.738832) (xy 107.78164 -30.742845) (xy 107.84443 -30.754823)
			(xy 107.905223 -30.774576) (xy 107.963062 -30.801793) (xy 108.017033 -30.836044) (xy 108.066286 -30.876789)
			(xy 108.110043 -30.923386) (xy 108.147616 -30.975101) (xy 108.17841 -31.031116) (xy 108.201942 -31.090549)
			(xy 108.217839 -31.152463) (xy 108.22585 -31.215881) (xy 108.226352 -31.247842) (xy 108.22585 -31.279803)
			(xy 108.217839 -31.343221) (xy 108.201942 -31.405135) (xy 108.17841 -31.464568) (xy 108.160153 -31.497778)
			(xy 110.384842 -31.497778) (xy 110.388913 -31.442156) (xy 110.401039 -31.387719) (xy 110.420962 -31.335628)
			(xy 110.448258 -31.286993) (xy 110.482344 -31.24285) (xy 110.522493 -31.204141) (xy 110.567851 -31.17169)
			(xy 110.617451 -31.146189) (xy 110.670235 -31.128182) (xy 110.725078 -31.118052) (xy 110.780812 -31.116015)
			(xy 110.836249 -31.122115) (xy 110.890206 -31.136221) (xy 110.941535 -31.158033) (xy 110.989141 -31.187087)
			(xy 111.032009 -31.222762) (xy 111.069226 -31.264299) (xy 111.099999 -31.310812) (xy 111.123671 -31.361309)
			(xy 111.139739 -31.414716) (xy 111.147859 -31.469892) (xy 111.148368 -31.497778) (xy 114.448842 -31.497778)
			(xy 114.452913 -31.442156) (xy 114.465039 -31.387719) (xy 114.484962 -31.335628) (xy 114.512258 -31.286993)
			(xy 114.546344 -31.24285) (xy 114.586493 -31.204141) (xy 114.631851 -31.17169) (xy 114.681451 -31.146189)
			(xy 114.734235 -31.128182) (xy 114.789078 -31.118052) (xy 114.844812 -31.116015) (xy 114.900249 -31.122115)
			(xy 114.954206 -31.136221) (xy 115.005535 -31.158033) (xy 115.053141 -31.187087) (xy 115.096009 -31.222762)
			(xy 115.133226 -31.264299) (xy 115.163999 -31.310812) (xy 115.187671 -31.361309) (xy 115.203739 -31.414716)
			(xy 115.211859 -31.469892) (xy 115.212368 -31.497778) (xy 115.211859 -31.525664) (xy 115.203739 -31.58084)
			(xy 115.187671 -31.634247) (xy 115.163999 -31.684744) (xy 115.133226 -31.731257) (xy 115.096009 -31.772794)
			(xy 115.053141 -31.808469) (xy 115.005535 -31.837523) (xy 114.954206 -31.859335) (xy 114.900249 -31.873441)
			(xy 114.844812 -31.879541) (xy 114.789078 -31.877504) (xy 114.734235 -31.867374) (xy 114.681451 -31.849367)
			(xy 114.631851 -31.823866) (xy 114.586493 -31.791415) (xy 114.546344 -31.752706) (xy 114.512258 -31.708563)
			(xy 114.484962 -31.659928) (xy 114.465039 -31.607837) (xy 114.452913 -31.5534) (xy 114.448842 -31.497778)
			(xy 111.148368 -31.497778) (xy 111.147859 -31.525664) (xy 111.139739 -31.58084) (xy 111.123671 -31.634247)
			(xy 111.099999 -31.684744) (xy 111.069226 -31.731257) (xy 111.032009 -31.772794) (xy 110.989141 -31.808469)
			(xy 110.941535 -31.837523) (xy 110.890206 -31.859335) (xy 110.836249 -31.873441) (xy 110.780812 -31.879541)
			(xy 110.725078 -31.877504) (xy 110.670235 -31.867374) (xy 110.617451 -31.849367) (xy 110.567851 -31.823866)
			(xy 110.522493 -31.791415) (xy 110.482344 -31.752706) (xy 110.448258 -31.708563) (xy 110.420962 -31.659928)
			(xy 110.401039 -31.607837) (xy 110.388913 -31.5534) (xy 110.384842 -31.497778) (xy 108.160153 -31.497778)
			(xy 108.147616 -31.520583) (xy 108.110043 -31.572298) (xy 108.066286 -31.618895) (xy 108.017033 -31.65964)
			(xy 107.963062 -31.693891) (xy 107.905223 -31.721108) (xy 107.84443 -31.740861) (xy 107.78164 -31.752839)
			(xy 107.717844 -31.756853) (xy 107.654048 -31.752839) (xy 107.591258 -31.740861) (xy 107.530465 -31.721108)
			(xy 107.472626 -31.693891) (xy 107.418655 -31.65964) (xy 107.369402 -31.618895) (xy 107.325645 -31.572298)
			(xy 107.288072 -31.520583) (xy 107.257278 -31.464568) (xy 107.233746 -31.405135) (xy 107.217849 -31.343221)
			(xy 107.209838 -31.279803) (xy 106.477866 -31.279803) (xy 106.505567 -31.332581) (xy 106.527363 -31.390048)
			(xy 106.542075 -31.449723) (xy 106.549486 -31.510735) (xy 106.549952 -31.541466) (xy 106.549368 -31.576432)
			(xy 106.539769 -31.645701) (xy 106.520763 -31.713001) (xy 106.492707 -31.777058) (xy 106.456133 -31.836663)
			(xy 106.434382 -31.864046) (xy 106.429132 -31.871059) (xy 106.423273 -31.887551) (xy 106.422952 -31.896304)
			(xy 106.422952 -32.050228) (xy 106.423293 -32.058977) (xy 106.429144 -32.075469) (xy 106.434382 -32.082486)
			(xy 106.456111 -32.109884) (xy 106.492666 -32.169495) (xy 106.520715 -32.233549) (xy 106.539729 -32.300841)
			(xy 106.549349 -32.370103) (xy 106.549952 -32.405066) (xy 106.549412 -32.435795) (xy 106.542008 -32.496804)
			(xy 106.537826 -32.513778) (xy 110.384842 -32.513778) (xy 110.388913 -32.458156) (xy 110.401039 -32.403719)
			(xy 110.420962 -32.351628) (xy 110.448258 -32.302993) (xy 110.482344 -32.25885) (xy 110.522493 -32.220141)
			(xy 110.567851 -32.18769) (xy 110.617451 -32.162189) (xy 110.670235 -32.144182) (xy 110.725078 -32.134052)
			(xy 110.780812 -32.132015) (xy 110.836249 -32.138115) (xy 110.890206 -32.152221) (xy 110.941535 -32.174033)
			(xy 110.989141 -32.203087) (xy 111.032009 -32.238762) (xy 111.069226 -32.280299) (xy 111.099999 -32.326812)
			(xy 111.123671 -32.377309) (xy 111.139739 -32.430716) (xy 111.147859 -32.485892) (xy 111.148368 -32.513778)
			(xy 114.448842 -32.513778) (xy 114.452913 -32.458156) (xy 114.465039 -32.403719) (xy 114.484962 -32.351628)
			(xy 114.512258 -32.302993) (xy 114.546344 -32.25885) (xy 114.586493 -32.220141) (xy 114.631851 -32.18769)
			(xy 114.681451 -32.162189) (xy 114.734235 -32.144182) (xy 114.789078 -32.134052) (xy 114.844812 -32.132015)
			(xy 114.900249 -32.138115) (xy 114.954206 -32.152221) (xy 115.005535 -32.174033) (xy 115.053141 -32.203087)
			(xy 115.096009 -32.238762) (xy 115.133226 -32.280299) (xy 115.163999 -32.326812) (xy 115.187671 -32.377309)
			(xy 115.203739 -32.430716) (xy 115.211859 -32.485892) (xy 115.212368 -32.513778) (xy 115.212308 -32.51708)
			(xy 119.225822 -32.51708) (xy 119.226236 -32.489825) (xy 119.233997 -32.435871) (xy 119.249357 -32.38357)
			(xy 119.272004 -32.333988) (xy 119.301477 -32.288134) (xy 119.337176 -32.24694) (xy 119.378374 -32.211247)
			(xy 119.424232 -32.18178) (xy 119.473817 -32.159139) (xy 119.52612 -32.143786) (xy 119.580075 -32.136033)
			(xy 119.60733 -32.135572) (xy 119.636179 -32.136054) (xy 119.693221 -32.144733) (xy 119.748305 -32.161903)
			(xy 119.800175 -32.187173) (xy 119.847648 -32.219967) (xy 119.889641 -32.259535) (xy 119.925195 -32.304977)
			(xy 119.953501 -32.355255) (xy 119.973913 -32.409222) (xy 119.980456 -32.437324) (xy 119.982234 -32.446214)
			(xy 119.991886 -32.461454) (xy 120.059196 -32.512762) (xy 120.076468 -32.517842) (xy 120.085612 -32.517334)
			(xy 120.11533 -32.516572) (xy 120.150294 -32.517194) (xy 120.219562 -32.526786) (xy 120.28686 -32.545785)
			(xy 120.350918 -32.573831) (xy 120.410525 -32.610396) (xy 120.43791 -32.632142) (xy 120.444903 -32.637422)
			(xy 120.46141 -32.643262) (xy 120.470168 -32.643572) (xy 120.624092 -32.643572) (xy 120.632839 -32.64321)
			(xy 120.649331 -32.637373) (xy 120.65635 -32.632142) (xy 120.683728 -32.610387) (xy 120.743344 -32.573835)
			(xy 120.807404 -32.545791) (xy 120.8747 -32.526783) (xy 120.943966 -32.51717) (xy 120.97893 -32.516572)
			(xy 121.008648 -32.517334) (xy 121.017792 -32.517842) (xy 121.035064 -32.512762) (xy 121.102374 -32.461454)
			(xy 121.112026 -32.446214) (xy 121.113804 -32.437324) (xy 121.120377 -32.409234) (xy 121.140804 -32.355283)
			(xy 121.169118 -32.305021) (xy 121.204674 -32.259594) (xy 121.246663 -32.220035) (xy 121.294127 -32.187247)
			(xy 121.345986 -32.161977) (xy 121.401057 -32.144799) (xy 121.458086 -32.136106) (xy 121.48693 -32.135572)
			(xy 121.514181 -32.13605) (xy 121.568128 -32.14381) (xy 121.620422 -32.159168) (xy 121.669998 -32.181811)
			(xy 121.715847 -32.211279) (xy 121.757036 -32.246971) (xy 121.792727 -32.288161) (xy 121.822194 -32.334011)
			(xy 121.844836 -32.383588) (xy 121.860192 -32.435882) (xy 121.867951 -32.489829) (xy 121.868438 -32.51708)
			(xy 121.867902 -32.545927) (xy 121.859231 -32.602966) (xy 121.842068 -32.658049) (xy 121.816805 -32.709918)
			(xy 121.784019 -32.757391) (xy 121.744456 -32.799384) (xy 121.699021 -32.83494) (xy 121.648748 -32.863248)
			(xy 121.594786 -32.883661) (xy 121.566686 -32.890206) (xy 121.557796 -32.891984) (xy 121.542556 -32.901636)
			(xy 121.491248 -32.968946) (xy 121.486168 -32.986218) (xy 121.486676 -32.995362) (xy 121.487438 -33.02508)
			(xy 121.486925 -33.055809) (xy 121.47952 -33.11682) (xy 121.464814 -33.176494) (xy 121.443023 -33.23396)
			(xy 121.414464 -33.28838) (xy 121.379554 -33.338962) (xy 121.338801 -33.384966) (xy 121.292801 -33.425723)
			(xy 121.242223 -33.460638) (xy 121.187806 -33.489202) (xy 121.130342 -33.510999) (xy 121.07067 -33.525711)
			(xy 121.009659 -33.533122) (xy 120.97893 -33.533588) (xy 120.943965 -33.532998) (xy 120.874695 -33.5234)
			(xy 120.807397 -33.504394) (xy 120.743339 -33.47634) (xy 120.683734 -33.439768) (xy 120.65635 -33.418018)
			(xy 120.649343 -33.412759) (xy 120.632846 -33.406908) (xy 120.624092 -33.406588) (xy 120.470168 -33.406588)
			(xy 120.46142 -33.40694) (xy 120.444929 -33.412785) (xy 120.43791 -33.418018) (xy 120.410517 -33.439754)
			(xy 120.350905 -33.476307) (xy 120.286849 -33.504354) (xy 120.219556 -33.523366) (xy 120.150293 -33.532986)
			(xy 120.11533 -33.533588) (xy 120.084598 -33.533134) (xy 120.023581 -33.525729) (xy 119.963902 -33.511022)
			(xy 119.906431 -33.489228) (xy 119.852006 -33.460666) (xy 119.801421 -33.425751) (xy 119.755414 -33.384993)
			(xy 119.714655 -33.338987) (xy 119.679739 -33.288402) (xy 119.651176 -33.233978) (xy 119.629381 -33.176508)
			(xy 119.614673 -33.116829) (xy 119.607266 -33.055812) (xy 119.606822 -33.02508) (xy 119.607584 -32.995362)
			(xy 119.608092 -32.986218) (xy 119.603012 -32.968946) (xy 119.551704 -32.901636) (xy 119.536464 -32.891984)
			(xy 119.527574 -32.890206) (xy 119.499495 -32.883588) (xy 119.445544 -32.863169) (xy 119.395282 -32.834863)
			(xy 119.349853 -32.799313) (xy 119.310293 -32.75733) (xy 119.277504 -32.70987) (xy 119.252231 -32.658016)
			(xy 119.235051 -32.602948) (xy 119.226357 -32.545922) (xy 119.225822 -32.51708) (xy 115.212308 -32.51708)
			(xy 115.211859 -32.541664) (xy 115.203739 -32.59684) (xy 115.187671 -32.650247) (xy 115.163999 -32.700744)
			(xy 115.133226 -32.747257) (xy 115.096009 -32.788794) (xy 115.053141 -32.824469) (xy 115.005535 -32.853523)
			(xy 114.954206 -32.875335) (xy 114.900249 -32.889441) (xy 114.844812 -32.895541) (xy 114.789078 -32.893504)
			(xy 114.734235 -32.883374) (xy 114.681451 -32.865367) (xy 114.631851 -32.839866) (xy 114.586493 -32.807415)
			(xy 114.546344 -32.768706) (xy 114.512258 -32.724563) (xy 114.484962 -32.675928) (xy 114.465039 -32.623837)
			(xy 114.452913 -32.5694) (xy 114.448842 -32.513778) (xy 111.148368 -32.513778) (xy 111.147859 -32.541664)
			(xy 111.139739 -32.59684) (xy 111.123671 -32.650247) (xy 111.099999 -32.700744) (xy 111.069226 -32.747257)
			(xy 111.032009 -32.788794) (xy 110.989141 -32.824469) (xy 110.941535 -32.853523) (xy 110.890206 -32.875335)
			(xy 110.836249 -32.889441) (xy 110.780812 -32.895541) (xy 110.725078 -32.893504) (xy 110.670235 -32.883374)
			(xy 110.617451 -32.865367) (xy 110.567851 -32.839866) (xy 110.522493 -32.807415) (xy 110.482344 -32.768706)
			(xy 110.448258 -32.724563) (xy 110.420962 -32.675928) (xy 110.401039 -32.623837) (xy 110.388913 -32.5694)
			(xy 110.384842 -32.513778) (xy 106.537826 -32.513778) (xy 106.527305 -32.556476) (xy 106.505516 -32.613941)
			(xy 106.476959 -32.668361) (xy 106.442052 -32.718942) (xy 106.401301 -32.764946) (xy 106.355303 -32.805703)
			(xy 106.304728 -32.840619) (xy 106.250313 -32.869184) (xy 106.192851 -32.890982) (xy 106.133181 -32.905694)
			(xy 106.072173 -32.913107) (xy 106.041444 -32.913574) (xy 106.009294 -32.913087) (xy 105.945505 -32.904992)
			(xy 105.883247 -32.888913) (xy 105.823515 -32.865107) (xy 105.767265 -32.833955) (xy 105.715394 -32.795955)
			(xy 105.668733 -32.751713) (xy 105.647998 -32.727138) (xy 105.641528 -32.719892) (xy 105.624553 -32.710483)
			(xy 105.614978 -32.70885) (xy 105.545128 -32.700468) (xy 105.535402 -32.699791) (xy 105.516598 -32.70487)
			(xy 105.508552 -32.710374) (xy 105.508298 -32.710374) (xy 105.483352 -32.728265) (xy 105.428967 -32.756731)
			(xy 105.370728 -32.776129) (xy 105.310136 -32.785958) (xy 105.279444 -32.786574) (xy 105.252191 -32.786104)
			(xy 105.198238 -32.778352) (xy 105.145938 -32.763) (xy 105.096356 -32.74036) (xy 105.050501 -32.710893)
			(xy 105.009307 -32.6752) (xy 104.973613 -32.634007) (xy 104.944145 -32.588153) (xy 104.921504 -32.538571)
			(xy 104.90615 -32.486272) (xy 104.898397 -32.432319) (xy 104.897936 -32.405066) (xy 104.89836 -32.378686)
			(xy 104.905618 -32.326426) (xy 104.920004 -32.275665) (xy 104.941245 -32.227369) (xy 104.968936 -32.182459)
			(xy 105.002549 -32.141791) (xy 105.041442 -32.10614) (xy 105.084876 -32.076185) (xy 105.108248 -32.063944)
			(xy 105.121202 -32.057594) (xy 105.136442 -32.032956) (xy 105.136442 -31.913576) (xy 105.121202 -31.888938)
			(xy 105.108248 -31.882588) (xy 105.082188 -31.868906) (xy 105.034268 -31.834732) (xy 104.99216 -31.793609)
			(xy 104.956861 -31.746512) (xy 104.929208 -31.694556) (xy 104.919018 -31.666942) (xy 104.915716 -31.657036)
			(xy 104.901492 -31.641542) (xy 104.814116 -31.60268) (xy 104.793542 -31.602426) (xy 104.78389 -31.60649)
			(xy 104.760354 -31.615933) (xy 104.711425 -31.629269) (xy 104.661164 -31.636023) (xy 104.635808 -31.636462)
			(xy 104.608551 -31.636092) (xy 104.554593 -31.628335) (xy 104.502288 -31.612977) (xy 104.452701 -31.590333)
			(xy 104.406841 -31.560861) (xy 104.365642 -31.525163) (xy 104.329944 -31.483965) (xy 104.300471 -31.438106)
			(xy 104.277825 -31.38852) (xy 104.262467 -31.336215) (xy 104.254709 -31.282257) (xy 87.476524 -31.282257)
			(xy 87.46642 -31.304383) (xy 87.436954 -31.350237) (xy 87.401263 -31.391431) (xy 87.360072 -31.427128)
			(xy 87.314221 -31.456599) (xy 87.264643 -31.479246) (xy 87.212347 -31.494606) (xy 87.158397 -31.502369)
			(xy 87.131144 -31.502858) (xy 87.104397 -31.502376) (xy 87.051428 -31.494888) (xy 87.000023 -31.480079)
			(xy 86.951189 -31.458241) (xy 86.90588 -31.4298) (xy 86.864985 -31.395313) (xy 86.829304 -31.355456)
			(xy 86.799535 -31.311009) (xy 86.776261 -31.262842) (xy 86.759939 -31.211898) (xy 86.75497 -31.185612)
			(xy 86.753192 -31.174436) (xy 86.741 -31.156656) (xy 86.656418 -31.10484) (xy 86.634828 -31.1023)
			(xy 86.62416 -31.105856) (xy 86.586891 -31.116855) (xy 86.510102 -31.128721) (xy 86.471252 -31.129478)
			(xy 86.470744 -31.129478) (xy 86.4392 -31.129079) (xy 86.376596 -31.121281) (xy 86.315437 -31.105799)
			(xy 86.256663 -31.082871) (xy 86.201176 -31.052849) (xy 86.149829 -31.016194) (xy 86.103411 -30.97347)
			(xy 86.062633 -30.925332) (xy 86.028123 -30.87252) (xy 86.00041 -30.815844) (xy 85.979921 -30.756176)
			(xy 85.96697 -30.694432) (xy 85.961755 -30.63156) (xy 81.01838 -30.63156) (xy 81.01838 -32.42691)
			(xy 92.777816 -32.42691) (xy 92.781887 -32.371288) (xy 92.794013 -32.316851) (xy 92.813936 -32.26476)
			(xy 92.841232 -32.216125) (xy 92.875318 -32.171982) (xy 92.915467 -32.133273) (xy 92.960825 -32.100822)
			(xy 93.010425 -32.075321) (xy 93.063209 -32.057314) (xy 93.118052 -32.047184) (xy 93.173786 -32.045147)
			(xy 93.229223 -32.051247) (xy 93.28318 -32.065353) (xy 93.334509 -32.087165) (xy 93.382115 -32.116219)
			(xy 93.424983 -32.151894) (xy 93.4622 -32.193431) (xy 93.492973 -32.239944) (xy 93.516645 -32.290441)
			(xy 93.532713 -32.343848) (xy 93.540833 -32.399024) (xy 93.541342 -32.42691) (xy 93.540833 -32.454796)
			(xy 93.532713 -32.509972) (xy 93.516645 -32.563379) (xy 93.492973 -32.613876) (xy 93.4622 -32.660389)
			(xy 93.424983 -32.701926) (xy 93.382115 -32.737601) (xy 93.334509 -32.766655) (xy 93.28318 -32.788467)
			(xy 93.229223 -32.802573) (xy 93.173786 -32.808673) (xy 93.118052 -32.806636) (xy 93.063209 -32.796506)
			(xy 93.010425 -32.778499) (xy 92.960825 -32.752998) (xy 92.915467 -32.720547) (xy 92.875318 -32.681838)
			(xy 92.841232 -32.637695) (xy 92.813936 -32.58906) (xy 92.794013 -32.536969) (xy 92.781887 -32.482532)
			(xy 92.777816 -32.42691) (xy 81.01838 -32.42691) (xy 81.01838 -33.349141) (xy 86.727278 -33.349141)
			(xy 86.727278 -33.285219) (xy 86.735289 -33.221801) (xy 86.751186 -33.159887) (xy 86.774718 -33.100454)
			(xy 86.805512 -33.044439) (xy 86.843085 -32.992724) (xy 86.886842 -32.946127) (xy 86.936095 -32.905382)
			(xy 86.990066 -32.871131) (xy 87.047905 -32.843914) (xy 87.108698 -32.824161) (xy 87.171488 -32.812183)
			(xy 87.235284 -32.80817) (xy 87.29908 -32.812183) (xy 87.36187 -32.824161) (xy 87.422663 -32.843914)
			(xy 87.480502 -32.871131) (xy 87.500954 -32.88411) (xy 101.880416 -32.88411) (xy 101.880804 -32.857729)
			(xy 101.88807 -32.805468) (xy 101.902463 -32.754707) (xy 101.923709 -32.706411) (xy 101.951405 -32.661501)
			(xy 101.985021 -32.620834) (xy 102.023918 -32.585183) (xy 102.067354 -32.555229) (xy 102.090728 -32.542988)
			(xy 102.103682 -32.536638) (xy 102.118922 -32.512) (xy 102.118922 -32.39262) (xy 102.103682 -32.367982)
			(xy 102.090728 -32.361632) (xy 102.067345 -32.349414) (xy 102.023924 -32.319446) (xy 101.985041 -32.283786)
			(xy 101.951437 -32.243112) (xy 101.923752 -32.1982) (xy 101.902514 -32.149905) (xy 101.888125 -32.099146)
			(xy 101.880861 -32.04689) (xy 101.880416 -32.02051) (xy 101.880865 -31.993256) (xy 101.888621 -31.939304)
			(xy 101.903977 -31.887004) (xy 101.92662 -31.837422) (xy 101.956089 -31.791568) (xy 101.991785 -31.750375)
			(xy 102.032979 -31.714681) (xy 102.078835 -31.685213) (xy 102.128417 -31.662572) (xy 102.180717 -31.647218)
			(xy 102.23467 -31.639464) (xy 102.261924 -31.639002) (xy 102.288311 -31.639474) (xy 102.34058 -31.646749)
			(xy 102.391348 -31.661159) (xy 102.439646 -31.682427) (xy 102.484552 -31.710147) (xy 102.52521 -31.743792)
			(xy 102.543356 -31.762954) (xy 102.551484 -31.77159) (xy 102.573074 -31.780226) (xy 102.665022 -31.772606)
			(xy 102.676562 -31.771071) (xy 102.696539 -31.759168) (xy 102.703376 -31.749746) (xy 102.70363 -31.749492)
			(xy 102.718793 -31.726946) (xy 102.75448 -31.685978) (xy 102.795619 -31.650489) (xy 102.841378 -31.621196)
			(xy 102.89083 -31.598692) (xy 102.942975 -31.583433) (xy 102.996758 -31.575727) (xy 103.023924 -31.575248)
			(xy 103.051162 -31.575754) (xy 103.105085 -31.583506) (xy 103.157356 -31.59885) (xy 103.206914 -31.621472)
			(xy 103.252749 -31.650913) (xy 103.293932 -31.686574) (xy 103.329623 -31.727731) (xy 103.359097 -31.773546)
			(xy 103.381754 -31.823087) (xy 103.397135 -31.875347) (xy 103.404926 -31.929264) (xy 103.405432 -31.956502)
			(xy 103.405432 -32.94761) (xy 103.404986 -32.974869) (xy 103.397228 -33.028834) (xy 103.381873 -33.081146)
			(xy 103.359232 -33.130741) (xy 103.329766 -33.176611) (xy 103.294074 -33.217823) (xy 103.252882 -33.253538)
			(xy 103.207029 -33.283029) (xy 103.157446 -33.305698) (xy 103.105143 -33.321083) (xy 103.051183 -33.32887)
			(xy 103.023924 -33.329372) (xy 102.996758 -33.328887) (xy 102.942976 -33.321182) (xy 102.890831 -33.305923)
			(xy 102.841379 -33.283421) (xy 102.79562 -33.254129) (xy 102.754479 -33.218641) (xy 102.718791 -33.177675)
			(xy 102.70363 -33.155128) (xy 102.703376 -33.154874) (xy 102.696542 -33.145444) (xy 102.676569 -33.133523)
			(xy 102.665022 -33.132014) (xy 102.573074 -33.124394) (xy 102.551484 -33.13303) (xy 102.543356 -33.141666)
			(xy 102.52519 -33.16081) (xy 102.484542 -33.194467) (xy 102.439642 -33.222198) (xy 102.391347 -33.243475)
			(xy 102.34058 -33.25789) (xy 102.288311 -33.265169) (xy 102.261924 -33.265618) (xy 102.234672 -33.265122)
			(xy 102.180723 -33.257369) (xy 102.128426 -33.242016) (xy 102.078847 -33.219377) (xy 102.032994 -33.189913)
			(xy 101.991801 -33.154223) (xy 101.956107 -33.113033) (xy 101.926639 -33.067183) (xy 101.903995 -33.017606)
			(xy 101.888638 -32.96531) (xy 101.88088 -32.911362) (xy 101.880416 -32.88411) (xy 87.500954 -32.88411)
			(xy 87.534473 -32.905382) (xy 87.583726 -32.946127) (xy 87.627483 -32.992724) (xy 87.665056 -33.044439)
			(xy 87.69585 -33.100454) (xy 87.719382 -33.159887) (xy 87.735279 -33.221801) (xy 87.74329 -33.285219)
			(xy 87.743792 -33.31718) (xy 87.74329 -33.349141) (xy 87.735279 -33.412559) (xy 87.719382 -33.474473)
			(xy 87.69585 -33.533906) (xy 87.665056 -33.589921) (xy 87.627483 -33.641636) (xy 87.583726 -33.688233)
			(xy 87.546832 -33.718754) (xy 104.25379 -33.718754) (xy 104.257861 -33.663132) (xy 104.269987 -33.608695)
			(xy 104.28991 -33.556604) (xy 104.317206 -33.507969) (xy 104.351292 -33.463826) (xy 104.391441 -33.425117)
			(xy 104.436799 -33.392666) (xy 104.486399 -33.367165) (xy 104.539183 -33.349158) (xy 104.594026 -33.339028)
			(xy 104.64976 -33.336991) (xy 104.705197 -33.343091) (xy 104.759154 -33.357197) (xy 104.810483 -33.379009)
			(xy 104.858089 -33.408063) (xy 104.900957 -33.443738) (xy 104.938174 -33.485275) (xy 104.968947 -33.531788)
			(xy 104.992619 -33.582285) (xy 105.008687 -33.635692) (xy 105.016807 -33.690868) (xy 105.017316 -33.718754)
			(xy 105.016807 -33.74664) (xy 105.008687 -33.801816) (xy 104.992619 -33.855223) (xy 104.968947 -33.90572)
			(xy 104.938174 -33.952233) (xy 104.900957 -33.99377) (xy 104.858089 -34.029445) (xy 104.810483 -34.058499)
			(xy 104.759154 -34.080311) (xy 104.705197 -34.094417) (xy 104.64976 -34.100517) (xy 104.594026 -34.09848)
			(xy 104.539183 -34.08835) (xy 104.486399 -34.070343) (xy 104.436799 -34.044842) (xy 104.391441 -34.012391)
			(xy 104.351292 -33.973682) (xy 104.317206 -33.929539) (xy 104.28991 -33.880904) (xy 104.269987 -33.828813)
			(xy 104.257861 -33.774376) (xy 104.25379 -33.718754) (xy 87.546832 -33.718754) (xy 87.534473 -33.728978)
			(xy 87.480502 -33.763229) (xy 87.422663 -33.790446) (xy 87.36187 -33.810199) (xy 87.29908 -33.822177)
			(xy 87.235284 -33.826191) (xy 87.171488 -33.822177) (xy 87.108698 -33.810199) (xy 87.047905 -33.790446)
			(xy 86.990066 -33.763229) (xy 86.936095 -33.728978) (xy 86.886842 -33.688233) (xy 86.843085 -33.641636)
			(xy 86.805512 -33.589921) (xy 86.774718 -33.533906) (xy 86.751186 -33.474473) (xy 86.735289 -33.412559)
			(xy 86.727278 -33.349141) (xy 81.01838 -33.349141) (xy 81.01838 -33.77946) (xy 81.017945 -33.789525)
			(xy 81.010213 -33.808112) (xy 81.003394 -33.815528) (xy 80.489044 -34.329878) (xy 92.803978 -34.329878)
			(xy 92.808049 -34.274256) (xy 92.820175 -34.219819) (xy 92.840098 -34.167728) (xy 92.867394 -34.119093)
			(xy 92.90148 -34.07495) (xy 92.941629 -34.036241) (xy 92.986987 -34.00379) (xy 93.036587 -33.978289)
			(xy 93.089371 -33.960282) (xy 93.144214 -33.950152) (xy 93.199948 -33.948115) (xy 93.255385 -33.954215)
			(xy 93.309342 -33.968321) (xy 93.360671 -33.990133) (xy 93.408277 -34.019187) (xy 93.451145 -34.054862)
			(xy 93.488362 -34.096399) (xy 93.519135 -34.142912) (xy 93.542807 -34.193409) (xy 93.558875 -34.246816)
			(xy 93.566995 -34.301992) (xy 93.567504 -34.329878) (xy 93.566995 -34.357764) (xy 93.558875 -34.41294)
			(xy 93.542807 -34.466347) (xy 93.519135 -34.516844) (xy 93.488362 -34.563357) (xy 93.451145 -34.604894)
			(xy 93.408277 -34.640569) (xy 93.360671 -34.669623) (xy 93.309342 -34.691435) (xy 93.255385 -34.705541)
			(xy 93.199948 -34.711641) (xy 93.144214 -34.709604) (xy 93.089371 -34.699474) (xy 93.036587 -34.681467)
			(xy 92.986987 -34.655966) (xy 92.941629 -34.623515) (xy 92.90148 -34.584806) (xy 92.867394 -34.540663)
			(xy 92.840098 -34.492028) (xy 92.820175 -34.439937) (xy 92.808049 -34.3855) (xy 92.803978 -34.329878)
			(xy 80.489044 -34.329878) (xy 80.097122 -34.7218) (xy 106.905552 -34.7218) (xy 106.906068 -34.691435)
			(xy 106.913297 -34.631136) (xy 106.927654 -34.572127) (xy 106.948933 -34.515246) (xy 106.976833 -34.461303)
			(xy 107.010955 -34.411065) (xy 107.050816 -34.365247) (xy 107.095847 -34.324499) (xy 107.14541 -34.289402)
			(xy 107.198797 -34.260455) (xy 107.226862 -34.248852) (xy 107.237022 -34.244788) (xy 107.252516 -34.22904)
			(xy 107.281472 -34.145728) (xy 107.284501 -34.135236) (xy 107.28241 -34.113524) (xy 107.277408 -34.103818)
			(xy 107.277408 -34.103564) (xy 107.261239 -34.074458) (xy 107.235781 -34.012934) (xy 107.218563 -33.948616)
			(xy 107.209879 -33.882601) (xy 107.209336 -33.84931) (xy 107.209838 -33.817349) (xy 107.217849 -33.753931)
			(xy 107.233746 -33.692017) (xy 107.257278 -33.632584) (xy 107.288072 -33.576569) (xy 107.325645 -33.524854)
			(xy 107.369402 -33.478257) (xy 107.418655 -33.437512) (xy 107.472626 -33.403261) (xy 107.530465 -33.376044)
			(xy 107.591258 -33.356291) (xy 107.654048 -33.344313) (xy 107.717844 -33.3403) (xy 107.78164 -33.344313)
			(xy 107.84443 -33.356291) (xy 107.905223 -33.376044) (xy 107.963062 -33.403261) (xy 108.017033 -33.437512)
			(xy 108.066286 -33.478257) (xy 108.110043 -33.524854) (xy 108.11362 -33.529778) (xy 110.384842 -33.529778)
			(xy 110.388913 -33.474156) (xy 110.401039 -33.419719) (xy 110.420962 -33.367628) (xy 110.448258 -33.318993)
			(xy 110.482344 -33.27485) (xy 110.522493 -33.236141) (xy 110.567851 -33.20369) (xy 110.617451 -33.178189)
			(xy 110.670235 -33.160182) (xy 110.725078 -33.150052) (xy 110.780812 -33.148015) (xy 110.836249 -33.154115)
			(xy 110.890206 -33.168221) (xy 110.941535 -33.190033) (xy 110.989141 -33.219087) (xy 111.032009 -33.254762)
			(xy 111.069226 -33.296299) (xy 111.099999 -33.342812) (xy 111.123671 -33.393309) (xy 111.139739 -33.446716)
			(xy 111.147859 -33.501892) (xy 111.148368 -33.529778) (xy 111.400842 -33.529778) (xy 111.404913 -33.474156)
			(xy 111.417039 -33.419719) (xy 111.436962 -33.367628) (xy 111.464258 -33.318993) (xy 111.498344 -33.27485)
			(xy 111.538493 -33.236141) (xy 111.583851 -33.20369) (xy 111.633451 -33.178189) (xy 111.686235 -33.160182)
			(xy 111.741078 -33.150052) (xy 111.796812 -33.148015) (xy 111.852249 -33.154115) (xy 111.906206 -33.168221)
			(xy 111.957535 -33.190033) (xy 112.005141 -33.219087) (xy 112.048009 -33.254762) (xy 112.085226 -33.296299)
			(xy 112.115999 -33.342812) (xy 112.139671 -33.393309) (xy 112.155739 -33.446716) (xy 112.163859 -33.501892)
			(xy 112.164368 -33.529778) (xy 112.416842 -33.529778) (xy 112.420913 -33.474156) (xy 112.433039 -33.419719)
			(xy 112.452962 -33.367628) (xy 112.480258 -33.318993) (xy 112.514344 -33.27485) (xy 112.554493 -33.236141)
			(xy 112.599851 -33.20369) (xy 112.649451 -33.178189) (xy 112.702235 -33.160182) (xy 112.757078 -33.150052)
			(xy 112.812812 -33.148015) (xy 112.868249 -33.154115) (xy 112.922206 -33.168221) (xy 112.973535 -33.190033)
			(xy 113.021141 -33.219087) (xy 113.064009 -33.254762) (xy 113.101226 -33.296299) (xy 113.131999 -33.342812)
			(xy 113.155671 -33.393309) (xy 113.171739 -33.446716) (xy 113.179859 -33.501892) (xy 113.180368 -33.529778)
			(xy 114.448842 -33.529778) (xy 114.452913 -33.474156) (xy 114.465039 -33.419719) (xy 114.484962 -33.367628)
			(xy 114.512258 -33.318993) (xy 114.546344 -33.27485) (xy 114.586493 -33.236141) (xy 114.631851 -33.20369)
			(xy 114.681451 -33.178189) (xy 114.734235 -33.160182) (xy 114.789078 -33.150052) (xy 114.844812 -33.148015)
			(xy 114.900249 -33.154115) (xy 114.954206 -33.168221) (xy 115.005535 -33.190033) (xy 115.053141 -33.219087)
			(xy 115.096009 -33.254762) (xy 115.133226 -33.296299) (xy 115.163999 -33.342812) (xy 115.187671 -33.393309)
			(xy 115.203739 -33.446716) (xy 115.211859 -33.501892) (xy 115.212368 -33.529778) (xy 115.211859 -33.557664)
			(xy 115.203739 -33.61284) (xy 115.187671 -33.666247) (xy 115.163999 -33.716744) (xy 115.133226 -33.763257)
			(xy 115.096009 -33.804794) (xy 115.055642 -33.838388) (xy 121.984262 -33.838388) (xy 121.984845 -33.803433)
			(xy 121.994408 -33.73418) (xy 122.013365 -33.666889) (xy 122.041359 -33.602829) (xy 122.077864 -33.543206)
			(xy 122.099578 -33.515808) (xy 122.104821 -33.508868) (xy 122.110662 -33.492496) (xy 122.111008 -33.483804)
			(xy 122.111008 -33.329372) (xy 122.110597 -33.320692) (xy 122.104772 -33.304334) (xy 122.099578 -33.297368)
			(xy 122.077847 -33.269983) (xy 122.041353 -33.210353) (xy 122.013364 -33.146289) (xy 121.994408 -33.078997)
			(xy 121.98484 -33.009744) (xy 121.984262 -32.974788) (xy 121.984717 -32.944262) (xy 121.992028 -32.883649)
			(xy 122.006544 -32.824348) (xy 122.028055 -32.767211) (xy 122.056253 -32.713061) (xy 122.090731 -32.662676)
			(xy 122.130994 -32.616782) (xy 122.153426 -32.596074) (xy 122.16176 -32.587882) (xy 122.170473 -32.566219)
			(xy 122.168743 -32.542935) (xy 122.163332 -32.532574) (xy 122.150978 -32.510569) (xy 122.131508 -32.464012)
			(xy 122.118331 -32.415298) (xy 122.111676 -32.365274) (xy 122.111262 -32.340042) (xy 122.111262 -32.339788)
			(xy 122.111748 -32.312537) (xy 122.119504 -32.258589) (xy 122.134859 -32.206294) (xy 122.157501 -32.156717)
			(xy 122.186967 -32.110867) (xy 122.222658 -32.069676) (xy 122.263849 -32.033985) (xy 122.309699 -32.004519)
			(xy 122.359276 -31.981877) (xy 122.411571 -31.966522) (xy 122.465519 -31.958766) (xy 122.520021 -31.958766)
			(xy 122.573969 -31.966522) (xy 122.626264 -31.981877) (xy 122.656813 -31.995829) (xy 128.865878 -31.995829)
			(xy 128.865878 -31.931907) (xy 128.873889 -31.868489) (xy 128.889786 -31.806575) (xy 128.913318 -31.747142)
			(xy 128.944112 -31.691127) (xy 128.981685 -31.639412) (xy 129.025442 -31.592815) (xy 129.074695 -31.55207)
			(xy 129.128666 -31.517819) (xy 129.186505 -31.490602) (xy 129.247298 -31.470849) (xy 129.310088 -31.458871)
			(xy 129.373884 -31.454858) (xy 129.43768 -31.458871) (xy 129.50047 -31.470849) (xy 129.561263 -31.490602)
			(xy 129.619102 -31.517819) (xy 129.673073 -31.55207) (xy 129.722326 -31.592815) (xy 129.766083 -31.639412)
			(xy 129.779995 -31.65856) (xy 140.151612 -31.65856) (xy 140.152219 -31.623595) (xy 140.161813 -31.554327)
			(xy 140.180815 -31.487028) (xy 140.208865 -31.42297) (xy 140.245434 -31.363364) (xy 140.267182 -31.33598)
			(xy 140.27247 -31.328993) (xy 140.278304 -31.312481) (xy 140.278612 -31.303722) (xy 140.278612 -31.149798)
			(xy 140.278246 -31.141051) (xy 140.272411 -31.12456) (xy 140.267182 -31.11754) (xy 140.24546 -31.090137)
			(xy 140.208905 -31.030527) (xy 140.180855 -30.966474) (xy 140.161839 -30.899183) (xy 140.152216 -30.829923)
			(xy 140.151612 -30.79496) (xy 140.152031 -30.764433) (xy 140.159347 -30.703818) (xy 140.173867 -30.644515)
			(xy 140.195384 -30.587378) (xy 140.223587 -30.533228) (xy 140.258071 -30.482844) (xy 140.29834 -30.436953)
			(xy 140.320776 -30.416246) (xy 140.329052 -30.408005) (xy 140.337772 -30.38637) (xy 140.336072 -30.363105)
			(xy 140.330682 -30.352746) (xy 140.318312 -30.33075) (xy 140.298848 -30.284189) (xy 140.285675 -30.235472)
			(xy 140.279024 -30.185447) (xy 140.278612 -30.160214) (xy 140.278612 -30.15996) (xy 140.279098 -30.132709)
			(xy 140.286854 -30.078761) (xy 140.302209 -30.026466) (xy 140.324851 -29.976889) (xy 140.354317 -29.931039)
			(xy 140.390008 -29.889848) (xy 140.431199 -29.854157) (xy 140.477049 -29.824691) (xy 140.526626 -29.802049)
			(xy 140.578921 -29.786694) (xy 140.632869 -29.778938) (xy 140.687371 -29.778938) (xy 140.741319 -29.786694)
			(xy 140.793614 -29.802049) (xy 140.843191 -29.824691) (xy 140.889041 -29.854157) (xy 140.930232 -29.889848)
			(xy 140.965923 -29.931039) (xy 140.995389 -29.976889) (xy 141.018031 -30.026466) (xy 141.033386 -30.078761)
			(xy 141.041142 -30.132709) (xy 141.041628 -30.15996) (xy 141.041628 -30.160214) (xy 141.041233 -30.185449)
			(xy 141.034614 -30.235483) (xy 141.02144 -30.284204) (xy 141.001943 -30.330755) (xy 140.989558 -30.352746)
			(xy 140.984148 -30.363109) (xy 140.982396 -30.386391) (xy 140.99114 -30.40804) (xy 140.999464 -30.416246)
			(xy 141.021883 -30.436969) (xy 141.062147 -30.48286) (xy 141.096627 -30.533242) (xy 141.124827 -30.587389)
			(xy 141.146341 -30.644524) (xy 141.16086 -30.703823) (xy 141.168174 -30.764435) (xy 141.168628 -30.79496)
			(xy 141.168023 -30.829925) (xy 141.158427 -30.899193) (xy 141.139424 -30.966491) (xy 141.111374 -31.030549)
			(xy 141.074806 -31.090155) (xy 141.053058 -31.11754) (xy 141.047808 -31.124552) (xy 141.04195 -31.141045)
			(xy 141.041628 -31.149798) (xy 141.041628 -31.303722) (xy 141.041977 -31.31247) (xy 141.047823 -31.328962)
			(xy 141.053058 -31.33598) (xy 141.07478 -31.363383) (xy 141.111338 -31.422992) (xy 141.139388 -31.487045)
			(xy 141.158403 -31.554336) (xy 141.168025 -31.623597) (xy 141.168628 -31.65856) (xy 141.168141 -31.689085)
			(xy 141.160835 -31.749697) (xy 141.146325 -31.808997) (xy 141.124819 -31.866134) (xy 141.096627 -31.920285)
			(xy 141.070804 -31.958026) (xy 143.181322 -31.958026) (xy 143.185393 -31.902404) (xy 143.197519 -31.847967)
			(xy 143.217442 -31.795876) (xy 143.244738 -31.747241) (xy 143.278824 -31.703098) (xy 143.318973 -31.664389)
			(xy 143.364331 -31.631938) (xy 143.413931 -31.606437) (xy 143.466715 -31.58843) (xy 143.521558 -31.5783)
			(xy 143.577292 -31.576263) (xy 143.632729 -31.582363) (xy 143.686686 -31.596469) (xy 143.738015 -31.618281)
			(xy 143.785621 -31.647335) (xy 143.820474 -31.67634) (xy 144.489932 -31.67634) (xy 144.490523 -31.641375)
			(xy 144.500121 -31.572105) (xy 144.519126 -31.504806) (xy 144.547179 -31.440749) (xy 144.583752 -31.381144)
			(xy 144.605502 -31.35376) (xy 144.610748 -31.346744) (xy 144.616609 -31.330254) (xy 144.616932 -31.321502)
			(xy 144.616932 -31.167578) (xy 144.616571 -31.158831) (xy 144.610732 -31.14234) (xy 144.605502 -31.13532)
			(xy 144.583774 -31.107922) (xy 144.547219 -31.048311) (xy 144.51917 -30.984256) (xy 144.500156 -30.916964)
			(xy 144.490535 -30.847703) (xy 144.489932 -30.81274) (xy 144.490414 -30.780589) (xy 144.498509 -30.7168)
			(xy 144.514589 -30.654542) (xy 144.538396 -30.59481) (xy 144.569549 -30.53856) (xy 144.60755 -30.48669)
			(xy 144.651793 -30.440029) (xy 144.676368 -30.419294) (xy 144.683617 -30.412826) (xy 144.693024 -30.39585)
			(xy 144.694656 -30.386274) (xy 144.703038 -30.316424) (xy 144.703716 -30.306698) (xy 144.698636 -30.287894)
			(xy 144.693132 -30.279848) (xy 144.693132 -30.279594) (xy 144.67524 -30.254648) (xy 144.646774 -30.200263)
			(xy 144.627376 -30.142024) (xy 144.617548 -30.081432) (xy 144.616932 -30.05074) (xy 144.617418 -30.023489)
			(xy 144.625174 -29.969541) (xy 144.640529 -29.917246) (xy 144.663171 -29.867669) (xy 144.692637 -29.821819)
			(xy 144.728328 -29.780628) (xy 144.769519 -29.744937) (xy 144.815369 -29.715471) (xy 144.864946 -29.692829)
			(xy 144.917241 -29.677474) (xy 144.971189 -29.669718) (xy 145.025691 -29.669718) (xy 145.079639 -29.677474)
			(xy 145.131934 -29.692829) (xy 145.181511 -29.715471) (xy 145.227361 -29.744937) (xy 145.268552 -29.780628)
			(xy 145.304243 -29.821819) (xy 145.333709 -29.867669) (xy 145.356351 -29.917246) (xy 145.371706 -29.969541)
			(xy 145.379462 -30.023489) (xy 145.379948 -30.05074) (xy 145.379359 -30.081434) (xy 145.369529 -30.14203)
			(xy 145.35013 -30.200273) (xy 145.32166 -30.254661) (xy 145.303748 -30.279594) (xy 145.303748 -30.279848)
			(xy 145.298201 -30.287876) (xy 145.293104 -30.306694) (xy 145.293842 -30.316424) (xy 145.302224 -30.386274)
			(xy 145.302616 -30.38856) (xy 156.316172 -30.38856) (xy 156.316674 -30.356599) (xy 156.324685 -30.293181)
			(xy 156.340582 -30.231267) (xy 156.364114 -30.171834) (xy 156.394908 -30.115819) (xy 156.432481 -30.064104)
			(xy 156.476238 -30.017507) (xy 156.525491 -29.976762) (xy 156.579462 -29.942511) (xy 156.637301 -29.915294)
			(xy 156.698094 -29.895541) (xy 156.760884 -29.883563) (xy 156.82468 -29.87955) (xy 156.888476 -29.883563)
			(xy 156.951266 -29.895541) (xy 157.012059 -29.915294) (xy 157.069898 -29.942511) (xy 157.123869 -29.976762)
			(xy 157.173122 -30.017507) (xy 157.216879 -30.064104) (xy 157.254452 -30.115819) (xy 157.285246 -30.171834)
			(xy 157.308778 -30.231267) (xy 157.324675 -30.293181) (xy 157.332686 -30.356599) (xy 157.333188 -30.38856)
			(xy 157.332658 -30.421934) (xy 157.323881 -30.488103) (xy 157.306526 -30.552555) (xy 157.280891 -30.614185)
			(xy 157.264608 -30.643322) (xy 157.257774 -30.656089) (xy 157.250832 -30.684187) (xy 157.252047 -30.713105)
			(xy 157.261322 -30.740522) (xy 157.277913 -30.764239) (xy 157.300488 -30.782352) (xy 157.327237 -30.793407)
			(xy 157.34157 -30.795468) (xy 157.372356 -30.799226) (xy 157.432758 -30.813316) (xy 157.490997 -30.834652)
			(xy 157.546206 -30.862915) (xy 157.597566 -30.897687) (xy 157.644313 -30.93845) (xy 157.685753 -30.984599)
			(xy 157.703918 -31.010606) (xy 159.717232 -31.010606) (xy 159.717687 -30.980164) (xy 159.724949 -30.919715)
			(xy 159.739383 -30.860566) (xy 159.760781 -30.803566) (xy 159.788836 -30.749531) (xy 159.823147 -30.699236)
			(xy 159.863222 -30.653401) (xy 159.908486 -30.612683) (xy 159.933132 -30.594808) (xy 159.933386 -30.594554)
			(xy 159.941527 -30.58814) (xy 159.95228 -30.570446) (xy 159.954214 -30.560264) (xy 159.964374 -30.48635)
			(xy 159.965339 -30.47598) (xy 159.959825 -30.455916) (xy 159.953706 -30.447488) (xy 159.953452 -30.447234)
			(xy 159.937188 -30.426723) (xy 159.909882 -30.382061) (xy 159.888931 -30.334089) (xy 159.874729 -30.283705)
			(xy 159.867542 -30.231853) (xy 159.867092 -30.20568) (xy 159.867578 -30.178429) (xy 159.875334 -30.124481)
			(xy 159.890689 -30.072186) (xy 159.913331 -30.022609) (xy 159.942797 -29.976759) (xy 159.978488 -29.935568)
			(xy 160.019679 -29.899877) (xy 160.065529 -29.870411) (xy 160.115106 -29.847769) (xy 160.167401 -29.832414)
			(xy 160.221349 -29.824658) (xy 160.275851 -29.824658) (xy 160.329799 -29.832414) (xy 160.382094 -29.847769)
			(xy 160.431671 -29.870411) (xy 160.477521 -29.899877) (xy 160.518712 -29.935568) (xy 160.554403 -29.976759)
			(xy 160.583869 -30.022609) (xy 160.606511 -30.072186) (xy 160.621866 -30.124481) (xy 160.629622 -30.178429)
			(xy 160.630108 -30.20568) (xy 160.630108 -30.205934) (xy 160.629592 -30.234257) (xy 160.621202 -30.290277)
			(xy 160.604624 -30.344443) (xy 160.580224 -30.395564) (xy 160.548537 -30.442518) (xy 160.529778 -30.463744)
			(xy 160.522666 -30.471618) (xy 160.515808 -30.49143) (xy 160.522412 -30.576266) (xy 160.523707 -30.586583)
			(xy 160.533409 -30.604949) (xy 160.541208 -30.611826) (xy 160.541716 -30.612334) (xy 160.567023 -30.633055)
			(xy 160.612648 -30.679921) (xy 160.651884 -30.732253) (xy 160.684079 -30.789188) (xy 160.708704 -30.849782)
			(xy 160.725349 -30.913036) (xy 160.733741 -30.977902) (xy 160.734248 -31.010606) (xy 160.733746 -31.042567)
			(xy 160.725735 -31.105985) (xy 160.709838 -31.167899) (xy 160.686306 -31.227332) (xy 160.655512 -31.283347)
			(xy 160.617939 -31.335062) (xy 160.574182 -31.381659) (xy 160.524929 -31.422404) (xy 160.470958 -31.456655)
			(xy 160.413119 -31.483872) (xy 160.352326 -31.503625) (xy 160.289536 -31.515603) (xy 160.22574 -31.519617)
			(xy 160.161944 -31.515603) (xy 160.099154 -31.503625) (xy 160.038361 -31.483872) (xy 159.980522 -31.456655)
			(xy 159.926551 -31.422404) (xy 159.877298 -31.381659) (xy 159.833541 -31.335062) (xy 159.795968 -31.283347)
			(xy 159.765174 -31.227332) (xy 159.741642 -31.167899) (xy 159.725745 -31.105985) (xy 159.717734 -31.042567)
			(xy 159.717232 -31.010606) (xy 157.703918 -31.010606) (xy 157.721268 -31.035447) (xy 157.750333 -31.090239)
			(xy 157.772513 -31.148161) (xy 157.787481 -31.208352) (xy 157.795013 -31.269916) (xy 157.795468 -31.300928)
			(xy 157.794966 -31.332889) (xy 157.786955 -31.396307) (xy 157.771058 -31.458221) (xy 157.747526 -31.517654)
			(xy 157.716732 -31.573669) (xy 157.679159 -31.625384) (xy 157.635402 -31.671981) (xy 157.586149 -31.712726)
			(xy 157.532178 -31.746977) (xy 157.474339 -31.774194) (xy 157.413546 -31.793947) (xy 157.350756 -31.805925)
			(xy 157.28696 -31.809939) (xy 157.223164 -31.805925) (xy 157.160374 -31.793947) (xy 157.099581 -31.774194)
			(xy 157.041742 -31.746977) (xy 156.987771 -31.712726) (xy 156.938518 -31.671981) (xy 156.894761 -31.625384)
			(xy 156.857188 -31.573669) (xy 156.826394 -31.517654) (xy 156.802862 -31.458221) (xy 156.786965 -31.396307)
			(xy 156.778954 -31.332889) (xy 156.778452 -31.300928) (xy 156.779016 -31.267555) (xy 156.787782 -31.201387)
			(xy 156.805127 -31.136935) (xy 156.830753 -31.075304) (xy 156.847032 -31.046166) (xy 156.853925 -31.033426)
			(xy 156.860873 -31.005316) (xy 156.859657 -30.976385) (xy 156.850374 -30.948957) (xy 156.833769 -30.925234)
			(xy 156.811177 -30.907121) (xy 156.784411 -30.896074) (xy 156.77007 -30.89402) (xy 156.73929 -30.890225)
			(xy 156.678893 -30.876132) (xy 156.620659 -30.854795) (xy 156.565454 -30.826532) (xy 156.514098 -30.791762)
			(xy 156.467354 -30.751002) (xy 156.425916 -30.704858) (xy 156.390399 -30.654015) (xy 156.361333 -30.599229)
			(xy 156.339147 -30.541313) (xy 156.324173 -30.481129) (xy 156.316632 -30.41957) (xy 156.316172 -30.38856)
			(xy 145.302616 -30.38856) (xy 145.303866 -30.395845) (xy 145.313275 -30.412817) (xy 145.320512 -30.419294)
			(xy 145.345067 -30.440049) (xy 145.389296 -30.486717) (xy 145.427288 -30.538587) (xy 145.458438 -30.594834)
			(xy 145.482248 -30.654559) (xy 145.498338 -30.71681) (xy 145.506451 -30.780592) (xy 145.506948 -30.81274)
			(xy 145.50635 -30.847705) (xy 145.496755 -30.916974) (xy 145.477752 -30.984274) (xy 145.449699 -31.048331)
			(xy 145.413128 -31.107936) (xy 145.391378 -31.13532) (xy 145.386097 -31.142312) (xy 145.380257 -31.15882)
			(xy 145.379948 -31.167578) (xy 145.379948 -31.321502) (xy 145.380302 -31.33025) (xy 145.386144 -31.346742)
			(xy 145.391378 -31.35376) (xy 145.413094 -31.381168) (xy 145.449652 -31.440776) (xy 145.477703 -31.504828)
			(xy 145.49672 -31.572118) (xy 145.506344 -31.641378) (xy 145.506948 -31.67634) (xy 145.506493 -31.708285)
			(xy 145.498495 -31.771673) (xy 145.482618 -31.833559) (xy 145.459111 -31.892968) (xy 145.428346 -31.948964)
			(xy 145.421766 -31.958026) (xy 146.051522 -31.958026) (xy 146.055593 -31.902404) (xy 146.067719 -31.847967)
			(xy 146.087642 -31.795876) (xy 146.114938 -31.747241) (xy 146.149024 -31.703098) (xy 146.189173 -31.664389)
			(xy 146.234531 -31.631938) (xy 146.284131 -31.606437) (xy 146.336915 -31.58843) (xy 146.391758 -31.5783)
			(xy 146.447492 -31.576263) (xy 146.502929 -31.582363) (xy 146.556886 -31.596469) (xy 146.608215 -31.618281)
			(xy 146.655821 -31.647335) (xy 146.698689 -31.68301) (xy 146.735906 -31.724547) (xy 146.766679 -31.77106)
			(xy 146.790351 -31.821557) (xy 146.806419 -31.874964) (xy 146.814539 -31.93014) (xy 146.815048 -31.958026)
			(xy 146.814539 -31.985912) (xy 146.806419 -32.041088) (xy 146.790351 -32.094495) (xy 146.766679 -32.144992)
			(xy 146.735906 -32.191505) (xy 146.698689 -32.233042) (xy 146.655821 -32.268717) (xy 146.608215 -32.297771)
			(xy 146.592524 -32.304439) (xy 159.228784 -32.304439) (xy 159.228784 -32.240517) (xy 159.236795 -32.177099)
			(xy 159.252692 -32.115185) (xy 159.276224 -32.055752) (xy 159.307018 -31.999737) (xy 159.344591 -31.948022)
			(xy 159.388348 -31.901425) (xy 159.437601 -31.86068) (xy 159.491572 -31.826429) (xy 159.549411 -31.799212)
			(xy 159.610204 -31.779459) (xy 159.672994 -31.767481) (xy 159.73679 -31.763468) (xy 159.800586 -31.767481)
			(xy 159.863376 -31.779459) (xy 159.924169 -31.799212) (xy 159.982008 -31.826429) (xy 160.035979 -31.86068)
			(xy 160.085232 -31.901425) (xy 160.128989 -31.948022) (xy 160.166562 -31.999737) (xy 160.197356 -32.055752)
			(xy 160.220888 -32.115185) (xy 160.236785 -32.177099) (xy 160.244796 -32.240517) (xy 160.245298 -32.272478)
			(xy 160.244796 -32.304439) (xy 160.236785 -32.367857) (xy 160.220888 -32.429771) (xy 160.197356 -32.489204)
			(xy 160.166562 -32.545219) (xy 160.128989 -32.596934) (xy 160.085232 -32.643531) (xy 160.035979 -32.684276)
			(xy 159.982008 -32.718527) (xy 159.924169 -32.745744) (xy 159.863376 -32.765497) (xy 159.800586 -32.777475)
			(xy 159.73679 -32.781489) (xy 159.672994 -32.777475) (xy 159.610204 -32.765497) (xy 159.549411 -32.745744)
			(xy 159.491572 -32.718527) (xy 159.437601 -32.684276) (xy 159.388348 -32.643531) (xy 159.344591 -32.596934)
			(xy 159.307018 -32.545219) (xy 159.276224 -32.489204) (xy 159.252692 -32.429771) (xy 159.236795 -32.367857)
			(xy 159.228784 -32.304439) (xy 146.592524 -32.304439) (xy 146.556886 -32.319583) (xy 146.502929 -32.333689)
			(xy 146.447492 -32.339789) (xy 146.391758 -32.337752) (xy 146.336915 -32.327622) (xy 146.284131 -32.309615)
			(xy 146.234531 -32.284114) (xy 146.189173 -32.251663) (xy 146.149024 -32.212954) (xy 146.114938 -32.168811)
			(xy 146.087642 -32.120176) (xy 146.067719 -32.068085) (xy 146.055593 -32.013648) (xy 146.051522 -31.958026)
			(xy 145.421766 -31.958026) (xy 145.390807 -32.000663) (xy 145.347085 -32.047251) (xy 145.322798 -32.068008)
			(xy 145.315742 -32.074415) (xy 145.306602 -32.091122) (xy 145.305018 -32.10052) (xy 145.300954 -32.131508)
			(xy 145.300219 -32.140951) (xy 145.304778 -32.159319) (xy 145.309844 -32.167322) (xy 145.326343 -32.191618)
			(xy 145.352519 -32.24419) (xy 145.370338 -32.300149) (xy 145.379382 -32.358177) (xy 145.379948 -32.38754)
			(xy 145.379462 -32.414791) (xy 145.371706 -32.468739) (xy 145.356351 -32.521034) (xy 145.333709 -32.570611)
			(xy 145.304243 -32.616461) (xy 145.268552 -32.657652) (xy 145.227361 -32.693343) (xy 145.181511 -32.722809)
			(xy 145.131934 -32.745451) (xy 145.079639 -32.760806) (xy 145.025691 -32.768562) (xy 144.971189 -32.768562)
			(xy 144.917241 -32.760806) (xy 144.864946 -32.745451) (xy 144.815369 -32.722809) (xy 144.769519 -32.693343)
			(xy 144.728328 -32.657652) (xy 144.692637 -32.616461) (xy 144.663171 -32.570611) (xy 144.640529 -32.521034)
			(xy 144.625174 -32.468739) (xy 144.617418 -32.414791) (xy 144.616932 -32.38754) (xy 144.617468 -32.358173)
			(xy 144.626489 -32.300135) (xy 144.644308 -32.244169) (xy 144.670503 -32.1916) (xy 144.687036 -32.167322)
			(xy 144.692236 -32.15938) (xy 144.696791 -32.140963) (xy 144.695926 -32.131508) (xy 144.691862 -32.10052)
			(xy 144.690262 -32.091128) (xy 144.681127 -32.074423) (xy 144.674082 -32.068008) (xy 144.649806 -32.047242)
			(xy 144.606101 -32.000645) (xy 144.568576 -31.948943) (xy 144.53782 -31.892949) (xy 144.514318 -31.833544)
			(xy 144.498439 -31.771664) (xy 144.490434 -31.708282) (xy 144.489932 -31.67634) (xy 143.820474 -31.67634)
			(xy 143.828489 -31.68301) (xy 143.865706 -31.724547) (xy 143.896479 -31.77106) (xy 143.920151 -31.821557)
			(xy 143.936219 -31.874964) (xy 143.944339 -31.93014) (xy 143.944848 -31.958026) (xy 143.944339 -31.985912)
			(xy 143.936219 -32.041088) (xy 143.920151 -32.094495) (xy 143.896479 -32.144992) (xy 143.865706 -32.191505)
			(xy 143.828489 -32.233042) (xy 143.785621 -32.268717) (xy 143.738015 -32.297771) (xy 143.686686 -32.319583)
			(xy 143.632729 -32.333689) (xy 143.577292 -32.339789) (xy 143.521558 -32.337752) (xy 143.466715 -32.327622)
			(xy 143.413931 -32.309615) (xy 143.364331 -32.284114) (xy 143.318973 -32.251663) (xy 143.278824 -32.212954)
			(xy 143.244738 -32.168811) (xy 143.217442 -32.120176) (xy 143.197519 -32.068085) (xy 143.185393 -32.013648)
			(xy 143.181322 -31.958026) (xy 141.070804 -31.958026) (xy 141.062153 -31.97067) (xy 141.021895 -32.016565)
			(xy 140.999464 -32.037274) (xy 140.991173 -32.045503) (xy 140.982451 -32.067145) (xy 140.98416 -32.090415)
			(xy 140.989558 -32.100774) (xy 141.00193 -32.122769) (xy 141.021395 -32.16933) (xy 141.034567 -32.218047)
			(xy 141.041217 -32.268073) (xy 141.041628 -32.293306) (xy 141.041628 -32.29356) (xy 141.041142 -32.320811)
			(xy 141.033386 -32.374759) (xy 141.018031 -32.427054) (xy 140.995389 -32.476631) (xy 140.965923 -32.522481)
			(xy 140.930232 -32.563672) (xy 140.889041 -32.599363) (xy 140.843191 -32.628829) (xy 140.793614 -32.651471)
			(xy 140.741319 -32.666826) (xy 140.687371 -32.674582) (xy 140.632869 -32.674582) (xy 140.578921 -32.666826)
			(xy 140.526626 -32.651471) (xy 140.477049 -32.628829) (xy 140.431199 -32.599363) (xy 140.390008 -32.563672)
			(xy 140.354317 -32.522481) (xy 140.324851 -32.476631) (xy 140.302209 -32.427054) (xy 140.286854 -32.374759)
			(xy 140.279098 -32.320811) (xy 140.278612 -32.29356) (xy 140.278612 -32.293306) (xy 140.27901 -32.268071)
			(xy 140.285628 -32.218037) (xy 140.2988 -32.169316) (xy 140.318297 -32.122764) (xy 140.330682 -32.100774)
			(xy 140.336062 -32.090399) (xy 140.337819 -32.067127) (xy 140.32909 -32.045483) (xy 140.320776 -32.037274)
			(xy 140.298326 -32.016584) (xy 140.258063 -31.970688) (xy 140.223585 -31.9203) (xy 140.195388 -31.866147)
			(xy 140.173879 -31.809007) (xy 140.159368 -31.749703) (xy 140.152061 -31.689087) (xy 140.151612 -31.65856)
			(xy 129.779995 -31.65856) (xy 129.803656 -31.691127) (xy 129.83445 -31.747142) (xy 129.857982 -31.806575)
			(xy 129.873879 -31.868489) (xy 129.88189 -31.931907) (xy 129.882392 -31.963868) (xy 129.88189 -31.995829)
			(xy 129.873879 -32.059247) (xy 129.857982 -32.121161) (xy 129.83445 -32.180594) (xy 129.803656 -32.236609)
			(xy 129.766083 -32.288324) (xy 129.722326 -32.334921) (xy 129.673073 -32.375666) (xy 129.619102 -32.409917)
			(xy 129.561263 -32.437134) (xy 129.50047 -32.456887) (xy 129.43768 -32.468865) (xy 129.373884 -32.472879)
			(xy 129.310088 -32.468865) (xy 129.247298 -32.456887) (xy 129.186505 -32.437134) (xy 129.128666 -32.409917)
			(xy 129.074695 -32.375666) (xy 129.025442 -32.334921) (xy 128.981685 -32.288324) (xy 128.944112 -32.236609)
			(xy 128.913318 -32.180594) (xy 128.889786 -32.121161) (xy 128.873889 -32.059247) (xy 128.865878 -31.995829)
			(xy 122.656813 -31.995829) (xy 122.675841 -32.004519) (xy 122.721691 -32.033985) (xy 122.762882 -32.069676)
			(xy 122.798573 -32.110867) (xy 122.828039 -32.156717) (xy 122.850681 -32.206294) (xy 122.866036 -32.258589)
			(xy 122.873792 -32.312537) (xy 122.874278 -32.339788) (xy 122.874278 -32.340042) (xy 122.873889 -32.365277)
			(xy 122.867267 -32.415311) (xy 122.854091 -32.464031) (xy 122.834593 -32.510583) (xy 122.822208 -32.532574)
			(xy 122.816783 -32.542929) (xy 122.815043 -32.566215) (xy 122.823791 -32.587865) (xy 122.832114 -32.596074)
			(xy 122.854537 -32.616793) (xy 122.894802 -32.662684) (xy 122.929283 -32.713066) (xy 122.957483 -32.767214)
			(xy 122.978997 -32.82435) (xy 122.993514 -32.88365) (xy 123.000826 -32.944262) (xy 123.001278 -32.974788)
			(xy 123.000695 -33.009743) (xy 122.991134 -33.078997) (xy 122.972178 -33.146288) (xy 122.944183 -33.210348)
			(xy 122.907677 -33.26997) (xy 122.885962 -33.297368) (xy 122.880733 -33.304318) (xy 122.874883 -33.320682)
			(xy 122.874532 -33.329372) (xy 122.874532 -33.413556) (xy 123.540423 -33.413556) (xy 123.540423 -33.359044)
			(xy 123.548181 -33.305087) (xy 123.563539 -33.252783) (xy 123.586185 -33.203197) (xy 123.615658 -33.157339)
			(xy 123.651357 -33.116142) (xy 123.692555 -33.080446) (xy 123.738415 -33.050976) (xy 123.788002 -33.028332)
			(xy 123.840306 -33.012977) (xy 123.894264 -33.005222) (xy 123.92152 -33.00476) (xy 123.921774 -33.00476)
			(xy 123.94701 -33.00513) (xy 123.997045 -33.011757) (xy 124.045765 -33.024938) (xy 124.092316 -33.044442)
			(xy 124.114306 -33.05683) (xy 124.124643 -33.062302) (xy 124.147944 -33.064034) (xy 124.169601 -33.055262)
			(xy 124.177806 -33.046924) (xy 124.198495 -33.024474) (xy 124.244393 -32.984212) (xy 124.294781 -32.949735)
			(xy 124.348934 -32.92154) (xy 124.406074 -32.900031) (xy 124.465378 -32.885518) (xy 124.525993 -32.878211)
			(xy 124.55652 -32.87776) (xy 124.591486 -32.878334) (xy 124.660755 -32.887938) (xy 124.728054 -32.906948)
			(xy 124.792111 -32.935005) (xy 124.851716 -32.971579) (xy 124.8791 -32.99333) (xy 124.886097 -32.998604)
			(xy 124.902601 -33.004448) (xy 124.911358 -33.00476) (xy 125.065282 -33.00476) (xy 125.074029 -33.004395)
			(xy 125.090521 -32.998561) (xy 125.09754 -32.99333) (xy 125.124921 -32.971578) (xy 125.184536 -32.935026)
			(xy 125.248595 -32.906981) (xy 125.315891 -32.887973) (xy 125.385156 -32.878359) (xy 125.42012 -32.87776)
			(xy 125.450646 -32.87821) (xy 125.511259 -32.885522) (xy 125.570561 -32.900038) (xy 125.627697 -32.921551)
			(xy 125.681848 -32.949749) (xy 125.732232 -32.984228) (xy 125.778126 -33.024491) (xy 125.798834 -33.046924)
			(xy 125.807092 -33.055182) (xy 125.828717 -33.063914) (xy 125.851977 -33.062219) (xy 125.862334 -33.05683)
			(xy 125.884337 -33.044473) (xy 125.930895 -33.025004) (xy 125.97961 -33.011828) (xy 126.029634 -33.005173)
			(xy 126.054866 -33.00476) (xy 126.05512 -33.00476) (xy 126.082368 -33.005312) (xy 126.136309 -33.01307)
			(xy 126.188597 -33.028425) (xy 126.238167 -33.051066) (xy 126.284011 -33.08053) (xy 126.325196 -33.116218)
			(xy 126.360882 -33.157405) (xy 126.390344 -33.20325) (xy 126.412982 -33.252822) (xy 126.428335 -33.305111)
			(xy 126.43609 -33.359052) (xy 126.43609 -33.413548) (xy 126.428335 -33.467489) (xy 126.412982 -33.519778)
			(xy 126.390344 -33.56935) (xy 126.360882 -33.615195) (xy 126.325196 -33.656382) (xy 126.284011 -33.69207)
			(xy 126.238167 -33.721534) (xy 126.188597 -33.744175) (xy 126.136309 -33.75953) (xy 126.082368 -33.767288)
			(xy 126.05512 -33.767776) (xy 126.054866 -33.767776) (xy 126.029631 -33.767384) (xy 125.979597 -33.760763)
			(xy 125.930877 -33.747588) (xy 125.884325 -33.728091) (xy 125.862334 -33.715706) (xy 125.851975 -33.71029)
			(xy 125.828692 -33.708547) (xy 125.807043 -33.717291) (xy 125.798834 -33.725612) (xy 125.778111 -33.74803)
			(xy 125.732221 -33.788296) (xy 125.681839 -33.822778) (xy 125.627692 -33.850978) (xy 125.570557 -33.872492)
			(xy 125.511257 -33.88701) (xy 125.450646 -33.894323) (xy 125.42012 -33.894776) (xy 125.385154 -33.894194)
			(xy 125.315885 -33.884594) (xy 125.248586 -33.865587) (xy 125.184528 -33.837531) (xy 125.124923 -33.800957)
			(xy 125.09754 -33.779206) (xy 125.090529 -33.773953) (xy 125.074036 -33.768095) (xy 125.065282 -33.767776)
			(xy 124.911358 -33.767776) (xy 124.90261 -33.768126) (xy 124.886119 -33.773972) (xy 124.8791 -33.779206)
			(xy 124.85171 -33.800944) (xy 124.792096 -33.837498) (xy 124.72804 -33.865545) (xy 124.660746 -33.884556)
			(xy 124.591483 -33.894174) (xy 124.55652 -33.894776) (xy 124.525994 -33.894319) (xy 124.46538 -33.887011)
			(xy 124.406078 -33.872497) (xy 124.348941 -33.850987) (xy 124.294791 -33.822789) (xy 124.244406 -33.78831)
			(xy 124.198513 -33.748046) (xy 124.177806 -33.725612) (xy 124.169589 -33.717306) (xy 124.147941 -33.708581)
			(xy 124.124664 -33.7103) (xy 124.114306 -33.715706) (xy 124.092296 -33.728051) (xy 124.04574 -33.747522)
			(xy 123.997028 -33.760701) (xy 123.947006 -33.76736) (xy 123.921774 -33.767776) (xy 123.92152 -33.767776)
			(xy 123.894264 -33.767378) (xy 123.840306 -33.759623) (xy 123.788002 -33.744268) (xy 123.738415 -33.721624)
			(xy 123.692555 -33.692154) (xy 123.651357 -33.656458) (xy 123.615658 -33.615261) (xy 123.586185 -33.569403)
			(xy 123.563539 -33.519817) (xy 123.548181 -33.467513) (xy 123.540423 -33.413556) (xy 122.874532 -33.413556)
			(xy 122.874532 -33.483804) (xy 122.8749 -33.492489) (xy 122.880754 -33.508847) (xy 122.885962 -33.515808)
			(xy 122.907673 -33.543209) (xy 122.944172 -33.602833) (xy 122.972166 -33.666893) (xy 122.991127 -33.734182)
			(xy 123.000698 -33.803433) (xy 123.001278 -33.838388) (xy 123.000826 -33.868914) (xy 122.993517 -33.929528)
			(xy 122.979002 -33.98883) (xy 122.957491 -34.045967) (xy 122.929292 -34.100118) (xy 122.894813 -34.150502)
			(xy 122.854548 -34.196395) (xy 122.832114 -34.217102) (xy 122.823801 -34.225314) (xy 122.815077 -34.246965)
			(xy 122.8168 -34.270243) (xy 122.822208 -34.280602) (xy 122.834556 -34.30261) (xy 122.854026 -34.349167)
			(xy 122.867205 -34.397879) (xy 122.873863 -34.447902) (xy 122.874278 -34.473134) (xy 122.874278 -34.473388)
			(xy 122.874261 -34.474361) (xy 127.253994 -34.474361) (xy 127.253994 -34.410439) (xy 127.262005 -34.347021)
			(xy 127.277902 -34.285107) (xy 127.301434 -34.225674) (xy 127.332228 -34.169659) (xy 127.369801 -34.117944)
			(xy 127.413558 -34.071347) (xy 127.462811 -34.030602) (xy 127.516782 -33.996351) (xy 127.574621 -33.969134)
			(xy 127.635414 -33.949381) (xy 127.698204 -33.937403) (xy 127.762 -33.93339) (xy 127.825796 -33.937403)
			(xy 127.888586 -33.949381) (xy 127.949379 -33.969134) (xy 128.007218 -33.996351) (xy 128.061189 -34.030602)
			(xy 128.110442 -34.071347) (xy 128.154199 -34.117944) (xy 128.191772 -34.169659) (xy 128.222566 -34.225674)
			(xy 128.246098 -34.285107) (xy 128.261995 -34.347021) (xy 128.270006 -34.410439) (xy 128.270508 -34.4424)
			(xy 128.270006 -34.474361) (xy 128.261995 -34.537779) (xy 128.246098 -34.599693) (xy 128.222566 -34.659126)
			(xy 128.191772 -34.715141) (xy 128.154199 -34.766856) (xy 128.110442 -34.813453) (xy 128.076618 -34.841434)
			(xy 131.296154 -34.841434) (xy 131.300225 -34.785812) (xy 131.312351 -34.731375) (xy 131.332274 -34.679284)
			(xy 131.35957 -34.630649) (xy 131.393656 -34.586506) (xy 131.433805 -34.547797) (xy 131.479163 -34.515346)
			(xy 131.528763 -34.489845) (xy 131.581547 -34.471838) (xy 131.63639 -34.461708) (xy 131.692124 -34.459671)
			(xy 131.747561 -34.465771) (xy 131.801518 -34.479877) (xy 131.852847 -34.501689) (xy 131.900453 -34.530743)
			(xy 131.943321 -34.566418) (xy 131.980538 -34.607955) (xy 132.011311 -34.654468) (xy 132.034983 -34.704965)
			(xy 132.051051 -34.758372) (xy 132.059171 -34.813548) (xy 132.05968 -34.841434) (xy 132.312154 -34.841434)
			(xy 132.316225 -34.785812) (xy 132.328351 -34.731375) (xy 132.348274 -34.679284) (xy 132.37557 -34.630649)
			(xy 132.409656 -34.586506) (xy 132.449805 -34.547797) (xy 132.495163 -34.515346) (xy 132.544763 -34.489845)
			(xy 132.597547 -34.471838) (xy 132.65239 -34.461708) (xy 132.708124 -34.459671) (xy 132.763561 -34.465771)
			(xy 132.817518 -34.479877) (xy 132.868847 -34.501689) (xy 132.916453 -34.530743) (xy 132.959321 -34.566418)
			(xy 132.996538 -34.607955) (xy 133.027311 -34.654468) (xy 133.050983 -34.704965) (xy 133.067051 -34.758372)
			(xy 133.075171 -34.813548) (xy 133.07568 -34.841434) (xy 133.328154 -34.841434) (xy 133.332225 -34.785812)
			(xy 133.344351 -34.731375) (xy 133.364274 -34.679284) (xy 133.39157 -34.630649) (xy 133.425656 -34.586506)
			(xy 133.465805 -34.547797) (xy 133.511163 -34.515346) (xy 133.560763 -34.489845) (xy 133.613547 -34.471838)
			(xy 133.66839 -34.461708) (xy 133.724124 -34.459671) (xy 133.779561 -34.465771) (xy 133.833518 -34.479877)
			(xy 133.884847 -34.501689) (xy 133.932453 -34.530743) (xy 133.975321 -34.566418) (xy 134.012538 -34.607955)
			(xy 134.043311 -34.654468) (xy 134.066983 -34.704965) (xy 134.083051 -34.758372) (xy 134.091171 -34.813548)
			(xy 134.09168 -34.841434) (xy 134.091171 -34.86932) (xy 134.083051 -34.924496) (xy 134.066983 -34.977903)
			(xy 134.043311 -35.0284) (xy 134.012538 -35.074913) (xy 133.975321 -35.11645) (xy 133.932453 -35.152125)
			(xy 133.884847 -35.181179) (xy 133.833518 -35.202991) (xy 133.779561 -35.217097) (xy 133.724124 -35.223197)
			(xy 133.66839 -35.22116) (xy 133.613547 -35.21103) (xy 133.560763 -35.193023) (xy 133.511163 -35.167522)
			(xy 133.465805 -35.135071) (xy 133.425656 -35.096362) (xy 133.39157 -35.052219) (xy 133.364274 -35.003584)
			(xy 133.344351 -34.951493) (xy 133.332225 -34.897056) (xy 133.328154 -34.841434) (xy 133.07568 -34.841434)
			(xy 133.075171 -34.86932) (xy 133.067051 -34.924496) (xy 133.050983 -34.977903) (xy 133.027311 -35.0284)
			(xy 132.996538 -35.074913) (xy 132.959321 -35.11645) (xy 132.916453 -35.152125) (xy 132.868847 -35.181179)
			(xy 132.817518 -35.202991) (xy 132.763561 -35.217097) (xy 132.708124 -35.223197) (xy 132.65239 -35.22116)
			(xy 132.597547 -35.21103) (xy 132.544763 -35.193023) (xy 132.495163 -35.167522) (xy 132.449805 -35.135071)
			(xy 132.409656 -35.096362) (xy 132.37557 -35.052219) (xy 132.348274 -35.003584) (xy 132.328351 -34.951493)
			(xy 132.316225 -34.897056) (xy 132.312154 -34.841434) (xy 132.05968 -34.841434) (xy 132.059171 -34.86932)
			(xy 132.051051 -34.924496) (xy 132.034983 -34.977903) (xy 132.011311 -35.0284) (xy 131.980538 -35.074913)
			(xy 131.943321 -35.11645) (xy 131.900453 -35.152125) (xy 131.852847 -35.181179) (xy 131.801518 -35.202991)
			(xy 131.747561 -35.217097) (xy 131.692124 -35.223197) (xy 131.63639 -35.22116) (xy 131.581547 -35.21103)
			(xy 131.528763 -35.193023) (xy 131.479163 -35.167522) (xy 131.433805 -35.135071) (xy 131.393656 -35.096362)
			(xy 131.35957 -35.052219) (xy 131.332274 -35.003584) (xy 131.312351 -34.951493) (xy 131.300225 -34.897056)
			(xy 131.296154 -34.841434) (xy 128.076618 -34.841434) (xy 128.061189 -34.854198) (xy 128.007218 -34.888449)
			(xy 127.949379 -34.915666) (xy 127.888586 -34.935419) (xy 127.825796 -34.947397) (xy 127.762 -34.951411)
			(xy 127.698204 -34.947397) (xy 127.635414 -34.935419) (xy 127.574621 -34.915666) (xy 127.516782 -34.888449)
			(xy 127.462811 -34.854198) (xy 127.413558 -34.813453) (xy 127.369801 -34.766856) (xy 127.332228 -34.715141)
			(xy 127.301434 -34.659126) (xy 127.277902 -34.599693) (xy 127.262005 -34.537779) (xy 127.253994 -34.474361)
			(xy 122.874261 -34.474361) (xy 122.873792 -34.500639) (xy 122.866036 -34.554587) (xy 122.850681 -34.606882)
			(xy 122.828039 -34.656459) (xy 122.798573 -34.702309) (xy 122.762882 -34.7435) (xy 122.721691 -34.779191)
			(xy 122.675841 -34.808657) (xy 122.626264 -34.831299) (xy 122.573969 -34.846654) (xy 122.520021 -34.85441)
			(xy 122.465519 -34.85441) (xy 122.411571 -34.846654) (xy 122.359276 -34.831299) (xy 122.309699 -34.808657)
			(xy 122.263849 -34.779191) (xy 122.222658 -34.7435) (xy 122.186967 -34.702309) (xy 122.157501 -34.656459)
			(xy 122.134859 -34.606882) (xy 122.119504 -34.554587) (xy 122.111748 -34.500639) (xy 122.111262 -34.473388)
			(xy 122.111262 -34.473134) (xy 122.111635 -34.447898) (xy 122.118261 -34.397863) (xy 122.131441 -34.349143)
			(xy 122.150944 -34.302592) (xy 122.163332 -34.280602) (xy 122.168796 -34.270262) (xy 122.17053 -34.246963)
			(xy 122.161762 -34.225307) (xy 122.153426 -34.217102) (xy 122.13098 -34.196408) (xy 122.090718 -34.150511)
			(xy 122.056241 -34.100124) (xy 122.028045 -34.045972) (xy 122.006535 -33.988833) (xy 121.992022 -33.929529)
			(xy 121.984713 -33.868915) (xy 121.984262 -33.838388) (xy 115.055642 -33.838388) (xy 115.053141 -33.840469)
			(xy 115.005535 -33.869523) (xy 114.954206 -33.891335) (xy 114.900249 -33.905441) (xy 114.844812 -33.911541)
			(xy 114.789078 -33.909504) (xy 114.734235 -33.899374) (xy 114.681451 -33.881367) (xy 114.631851 -33.855866)
			(xy 114.586493 -33.823415) (xy 114.546344 -33.784706) (xy 114.512258 -33.740563) (xy 114.484962 -33.691928)
			(xy 114.465039 -33.639837) (xy 114.452913 -33.5854) (xy 114.448842 -33.529778) (xy 113.180368 -33.529778)
			(xy 113.179859 -33.557664) (xy 113.171739 -33.61284) (xy 113.155671 -33.666247) (xy 113.131999 -33.716744)
			(xy 113.101226 -33.763257) (xy 113.064009 -33.804794) (xy 113.021141 -33.840469) (xy 112.973535 -33.869523)
			(xy 112.922206 -33.891335) (xy 112.868249 -33.905441) (xy 112.812812 -33.911541) (xy 112.757078 -33.909504)
			(xy 112.702235 -33.899374) (xy 112.649451 -33.881367) (xy 112.599851 -33.855866) (xy 112.554493 -33.823415)
			(xy 112.514344 -33.784706) (xy 112.480258 -33.740563) (xy 112.452962 -33.691928) (xy 112.433039 -33.639837)
			(xy 112.420913 -33.5854) (xy 112.416842 -33.529778) (xy 112.164368 -33.529778) (xy 112.163859 -33.557664)
			(xy 112.155739 -33.61284) (xy 112.139671 -33.666247) (xy 112.115999 -33.716744) (xy 112.085226 -33.763257)
			(xy 112.048009 -33.804794) (xy 112.005141 -33.840469) (xy 111.957535 -33.869523) (xy 111.906206 -33.891335)
			(xy 111.852249 -33.905441) (xy 111.796812 -33.911541) (xy 111.741078 -33.909504) (xy 111.686235 -33.899374)
			(xy 111.633451 -33.881367) (xy 111.583851 -33.855866) (xy 111.538493 -33.823415) (xy 111.498344 -33.784706)
			(xy 111.464258 -33.740563) (xy 111.436962 -33.691928) (xy 111.417039 -33.639837) (xy 111.404913 -33.5854)
			(xy 111.400842 -33.529778) (xy 111.148368 -33.529778) (xy 111.147859 -33.557664) (xy 111.139739 -33.61284)
			(xy 111.123671 -33.666247) (xy 111.099999 -33.716744) (xy 111.069226 -33.763257) (xy 111.032009 -33.804794)
			(xy 110.989141 -33.840469) (xy 110.941535 -33.869523) (xy 110.890206 -33.891335) (xy 110.836249 -33.905441)
			(xy 110.780812 -33.911541) (xy 110.725078 -33.909504) (xy 110.670235 -33.899374) (xy 110.617451 -33.881367)
			(xy 110.567851 -33.855866) (xy 110.522493 -33.823415) (xy 110.482344 -33.784706) (xy 110.448258 -33.740563)
			(xy 110.420962 -33.691928) (xy 110.401039 -33.639837) (xy 110.388913 -33.5854) (xy 110.384842 -33.529778)
			(xy 108.11362 -33.529778) (xy 108.147616 -33.576569) (xy 108.17841 -33.632584) (xy 108.201942 -33.692017)
			(xy 108.217839 -33.753931) (xy 108.22585 -33.817349) (xy 108.226352 -33.84931) (xy 108.225905 -33.879678)
			(xy 108.218673 -33.939981) (xy 108.204312 -33.998995) (xy 108.183027 -34.055879) (xy 108.155121 -34.109824)
			(xy 108.12099 -34.160063) (xy 108.081121 -34.205881) (xy 108.03608 -34.246626) (xy 107.986508 -34.281718)
			(xy 107.933111 -34.310659) (xy 107.905042 -34.322258) (xy 107.894882 -34.326322) (xy 107.879388 -34.34207)
			(xy 107.850432 -34.425382) (xy 107.847396 -34.435872) (xy 107.849491 -34.457587) (xy 107.854496 -34.467292)
			(xy 107.854496 -34.467546) (xy 107.870669 -34.49665) (xy 107.896126 -34.558175) (xy 107.913343 -34.622494)
			(xy 107.922025 -34.688508) (xy 107.922568 -34.7218) (xy 107.922066 -34.753761) (xy 107.914055 -34.817179)
			(xy 107.898158 -34.879093) (xy 107.874626 -34.938526) (xy 107.843832 -34.994541) (xy 107.806259 -35.046256)
			(xy 107.762502 -35.092853) (xy 107.713249 -35.133598) (xy 107.659278 -35.167849) (xy 107.601439 -35.195066)
			(xy 107.540646 -35.214819) (xy 107.477856 -35.226797) (xy 107.41406 -35.230811) (xy 107.350264 -35.226797)
			(xy 107.287474 -35.214819) (xy 107.226681 -35.195066) (xy 107.168842 -35.167849) (xy 107.114871 -35.133598)
			(xy 107.065618 -35.092853) (xy 107.021861 -35.046256) (xy 106.984288 -34.994541) (xy 106.953494 -34.938526)
			(xy 106.929962 -34.879093) (xy 106.914065 -34.817179) (xy 106.906054 -34.753761) (xy 106.905552 -34.7218)
			(xy 80.097122 -34.7218) (xy 78.955181 -35.863741) (xy 118.874534 -35.863741) (xy 118.874534 -35.799819)
			(xy 118.882545 -35.736401) (xy 118.898442 -35.674487) (xy 118.921974 -35.615054) (xy 118.952768 -35.559039)
			(xy 118.990341 -35.507324) (xy 119.034098 -35.460727) (xy 119.083351 -35.419982) (xy 119.137322 -35.385731)
			(xy 119.195161 -35.358514) (xy 119.255954 -35.338761) (xy 119.318744 -35.326783) (xy 119.38254 -35.32277)
			(xy 119.446336 -35.326783) (xy 119.509126 -35.338761) (xy 119.569919 -35.358514) (xy 119.627758 -35.385731)
			(xy 119.681729 -35.419982) (xy 119.730982 -35.460727) (xy 119.774739 -35.507324) (xy 119.812312 -35.559039)
			(xy 119.843106 -35.615054) (xy 119.866638 -35.674487) (xy 119.882535 -35.736401) (xy 119.890546 -35.799819)
			(xy 119.891048 -35.83178) (xy 119.890546 -35.863741) (xy 119.882535 -35.927159) (xy 119.866638 -35.989073)
			(xy 119.843106 -36.048506) (xy 119.825487 -36.080556) (xy 121.444923 -36.080556) (xy 121.444923 -36.026044)
			(xy 121.452681 -35.972087) (xy 121.468039 -35.919783) (xy 121.490685 -35.870197) (xy 121.520158 -35.824339)
			(xy 121.555857 -35.783142) (xy 121.597055 -35.747446) (xy 121.642915 -35.717976) (xy 121.692502 -35.695332)
			(xy 121.744806 -35.679977) (xy 121.798764 -35.672222) (xy 121.82602 -35.67176) (xy 121.854336 -35.672305)
			(xy 121.910344 -35.680688) (xy 121.9645 -35.697251) (xy 122.015616 -35.721633) (xy 122.03938 -35.737038)
			(xy 122.047249 -35.741889) (xy 122.065218 -35.746177) (xy 122.074432 -35.74542) (xy 122.105166 -35.741102)
			(xy 122.114394 -35.739595) (xy 122.130832 -35.730706) (xy 122.13717 -35.72383) (xy 122.157912 -35.700163)
			(xy 122.204285 -35.657618) (xy 122.255555 -35.621122) (xy 122.310937 -35.591233) (xy 122.369585 -35.568407)
			(xy 122.430601 -35.552995) (xy 122.493054 -35.54523) (xy 122.52452 -35.54476) (xy 122.559486 -35.545334)
			(xy 122.628755 -35.554938) (xy 122.696054 -35.573948) (xy 122.760111 -35.602005) (xy 122.819716 -35.638579)
			(xy 122.8471 -35.66033) (xy 122.854097 -35.665604) (xy 122.870601 -35.671448) (xy 122.879358 -35.67176)
			(xy 123.033282 -35.67176) (xy 123.042029 -35.671395) (xy 123.058521 -35.665561) (xy 123.06554 -35.66033)
			(xy 123.092921 -35.638578) (xy 123.152536 -35.602026) (xy 123.216595 -35.573981) (xy 123.283891 -35.554973)
			(xy 123.353156 -35.545359) (xy 123.38812 -35.54476) (xy 123.420065 -35.545226) (xy 123.483452 -35.553222)
			(xy 123.545338 -35.569097) (xy 123.604747 -35.592602) (xy 123.660743 -35.623365) (xy 123.712442 -35.660903)
			(xy 123.759031 -35.704623) (xy 123.779788 -35.72891) (xy 123.786201 -35.73596) (xy 123.802904 -35.745103)
			(xy 123.8123 -35.74669) (xy 123.843288 -35.750754) (xy 123.852731 -35.751477) (xy 123.871098 -35.746926)
			(xy 123.879102 -35.741864) (xy 123.903377 -35.725331) (xy 123.955957 -35.699163) (xy 124.011922 -35.681353)
			(xy 124.069955 -35.67232) (xy 124.09932 -35.67176) (xy 124.126568 -35.672312) (xy 124.180509 -35.68007)
			(xy 124.232797 -35.695425) (xy 124.282367 -35.718066) (xy 124.328211 -35.74753) (xy 124.369396 -35.783218)
			(xy 124.405082 -35.824405) (xy 124.428402 -35.860693) (xy 126.526538 -35.860693) (xy 126.526538 -35.796771)
			(xy 126.534549 -35.733353) (xy 126.550446 -35.671439) (xy 126.573978 -35.612006) (xy 126.604772 -35.555991)
			(xy 126.642345 -35.504276) (xy 126.686102 -35.457679) (xy 126.735355 -35.416934) (xy 126.789326 -35.382683)
			(xy 126.847165 -35.355466) (xy 126.907958 -35.335713) (xy 126.970748 -35.323735) (xy 127.034544 -35.319722)
			(xy 127.09834 -35.323735) (xy 127.16113 -35.335713) (xy 127.221923 -35.355466) (xy 127.279762 -35.382683)
			(xy 127.333733 -35.416934) (xy 127.382986 -35.457679) (xy 127.426743 -35.504276) (xy 127.464316 -35.555991)
			(xy 127.49511 -35.612006) (xy 127.518642 -35.671439) (xy 127.534539 -35.733353) (xy 127.54255 -35.796771)
			(xy 127.543052 -35.828732) (xy 127.542601 -35.857434) (xy 130.280154 -35.857434) (xy 130.284225 -35.801812)
			(xy 130.296351 -35.747375) (xy 130.316274 -35.695284) (xy 130.34357 -35.646649) (xy 130.377656 -35.602506)
			(xy 130.417805 -35.563797) (xy 130.463163 -35.531346) (xy 130.512763 -35.505845) (xy 130.565547 -35.487838)
			(xy 130.62039 -35.477708) (xy 130.676124 -35.475671) (xy 130.731561 -35.481771) (xy 130.785518 -35.495877)
			(xy 130.836847 -35.517689) (xy 130.884453 -35.546743) (xy 130.927321 -35.582418) (xy 130.964538 -35.623955)
			(xy 130.995311 -35.670468) (xy 131.018983 -35.720965) (xy 131.035051 -35.774372) (xy 131.043171 -35.829548)
			(xy 131.04368 -35.857434) (xy 131.043171 -35.88532) (xy 131.035051 -35.940496) (xy 131.018983 -35.993903)
			(xy 130.995311 -36.0444) (xy 130.964538 -36.090913) (xy 130.927321 -36.13245) (xy 130.884453 -36.168125)
			(xy 130.836847 -36.197179) (xy 130.785518 -36.218991) (xy 130.731561 -36.233097) (xy 130.676124 -36.239197)
			(xy 130.62039 -36.23716) (xy 130.565547 -36.22703) (xy 130.512763 -36.209023) (xy 130.463163 -36.183522)
			(xy 130.417805 -36.151071) (xy 130.377656 -36.112362) (xy 130.34357 -36.068219) (xy 130.316274 -36.019584)
			(xy 130.296351 -35.967493) (xy 130.284225 -35.913056) (xy 130.280154 -35.857434) (xy 127.542601 -35.857434)
			(xy 127.54255 -35.860693) (xy 127.534539 -35.924111) (xy 127.518642 -35.986025) (xy 127.49511 -36.045458)
			(xy 127.464316 -36.101473) (xy 127.426743 -36.153188) (xy 127.382986 -36.199785) (xy 127.333733 -36.24053)
			(xy 127.279762 -36.274781) (xy 127.221923 -36.301998) (xy 127.16113 -36.321751) (xy 127.09834 -36.333729)
			(xy 127.034544 -36.337743) (xy 126.970748 -36.333729) (xy 126.907958 -36.321751) (xy 126.847165 -36.301998)
			(xy 126.789326 -36.274781) (xy 126.735355 -36.24053) (xy 126.686102 -36.199785) (xy 126.642345 -36.153188)
			(xy 126.604772 -36.101473) (xy 126.573978 -36.045458) (xy 126.550446 -35.986025) (xy 126.534549 -35.924111)
			(xy 126.526538 -35.860693) (xy 124.428402 -35.860693) (xy 124.434544 -35.87025) (xy 124.457182 -35.919822)
			(xy 124.472535 -35.972111) (xy 124.48029 -36.026052) (xy 124.48029 -36.080548) (xy 124.472535 -36.134489)
			(xy 124.457182 -36.186778) (xy 124.434544 -36.23635) (xy 124.405082 -36.282195) (xy 124.369396 -36.323382)
			(xy 124.328211 -36.35907) (xy 124.282367 -36.388534) (xy 124.232797 -36.411175) (xy 124.180509 -36.42653)
			(xy 124.126568 -36.434288) (xy 124.09932 -36.434776) (xy 124.069953 -36.434248) (xy 124.011915 -36.425224)
			(xy 123.955949 -36.407403) (xy 123.903379 -36.381206) (xy 123.879102 -36.364672) (xy 123.871138 -36.359511)
			(xy 123.852739 -36.354932) (xy 123.843288 -36.355782) (xy 123.8123 -36.359846) (xy 123.802905 -36.361434)
			(xy 123.786201 -36.370578) (xy 123.779788 -36.377626) (xy 123.759034 -36.401914) (xy 123.712436 -36.445617)
			(xy 123.660731 -36.483141) (xy 123.604735 -36.513896) (xy 123.545328 -36.537396) (xy 123.483446 -36.553272)
			(xy 123.420063 -36.561275) (xy 123.38812 -36.561776) (xy 123.353154 -36.561194) (xy 123.283885 -36.551594)
			(xy 123.216586 -36.532587) (xy 123.152528 -36.504531) (xy 123.092923 -36.467957) (xy 123.06554 -36.446206)
			(xy 123.058529 -36.440953) (xy 123.042036 -36.435095) (xy 123.033282 -36.434776) (xy 122.879358 -36.434776)
			(xy 122.87061 -36.435126) (xy 122.854119 -36.440972) (xy 122.8471 -36.446206) (xy 122.81971 -36.467944)
			(xy 122.760096 -36.504498) (xy 122.69604 -36.532545) (xy 122.628746 -36.551556) (xy 122.559483 -36.561174)
			(xy 122.52452 -36.561776) (xy 122.493053 -36.561327) (xy 122.430602 -36.553552) (xy 122.369587 -36.538132)
			(xy 122.310941 -36.515302) (xy 122.25556 -36.48541) (xy 122.20429 -36.448914) (xy 122.157914 -36.406371)
			(xy 122.13717 -36.382706) (xy 122.130771 -36.375913) (xy 122.114356 -36.367062) (xy 122.105166 -36.365434)
			(xy 122.074432 -36.361116) (xy 122.065214 -36.36028) (xy 122.047231 -36.364594) (xy 122.03938 -36.369498)
			(xy 122.015631 -36.384932) (xy 121.964517 -36.40933) (xy 121.910356 -36.425895) (xy 121.854339 -36.434264)
			(xy 121.82602 -36.434776) (xy 121.798764 -36.434378) (xy 121.744806 -36.426623) (xy 121.692502 -36.411268)
			(xy 121.642915 -36.388624) (xy 121.597055 -36.359154) (xy 121.555857 -36.323458) (xy 121.520158 -36.282261)
			(xy 121.490685 -36.236403) (xy 121.468039 -36.186817) (xy 121.452681 -36.134513) (xy 121.444923 -36.080556)
			(xy 119.825487 -36.080556) (xy 119.812312 -36.104521) (xy 119.774739 -36.156236) (xy 119.730982 -36.202833)
			(xy 119.681729 -36.243578) (xy 119.627758 -36.277829) (xy 119.569919 -36.305046) (xy 119.509126 -36.324799)
			(xy 119.446336 -36.336777) (xy 119.38254 -36.340791) (xy 119.318744 -36.336777) (xy 119.255954 -36.324799)
			(xy 119.195161 -36.305046) (xy 119.137322 -36.277829) (xy 119.083351 -36.243578) (xy 119.034098 -36.202833)
			(xy 118.990341 -36.156236) (xy 118.952768 -36.104521) (xy 118.921974 -36.048506) (xy 118.898442 -35.989073)
			(xy 118.882545 -35.927159) (xy 118.874534 -35.863741) (xy 78.955181 -35.863741) (xy 78.648306 -36.170616)
			(xy 78.640912 -36.177472) (xy 78.622313 -36.185222) (xy 78.612238 -36.185602) (xy 70.344792 -36.185602)
			(xy 70.341744 -36.185602) (xy 70.31355 -36.186618) (xy 70.313042 -36.186618) (xy 70.312026 -36.186618)
			(xy 70.311518 -36.186618) (xy 70.283324 -36.185602) (xy 65.891156 -36.185602) (xy 65.881089 -36.185171)
			(xy 65.862496 -36.177445) (xy 65.855088 -36.170616) (xy 65.338706 -35.654234) (xy 65.334015 -35.649884)
			(xy 65.322966 -35.643445) (xy 65.316862 -35.641534) (xy 65.3161 -35.64128) (xy 65.310766 -35.639756)
			(xy 65.29832 -35.639502) (xy 65.291462 -35.64128) (xy 65.262931 -35.647686) (xy 65.204874 -35.654686)
			(xy 65.175638 -35.65525) (xy 65.170304 -35.65525) (xy 65.137222 -35.654557) (xy 65.071652 -35.645653)
			(xy 65.007792 -35.628319) (xy 64.946719 -35.602849) (xy 64.889466 -35.569673) (xy 64.836999 -35.529352)
			(xy 64.790205 -35.482566) (xy 64.749875 -35.430106) (xy 64.716689 -35.372858) (xy 64.691209 -35.31179)
			(xy 64.673865 -35.247932) (xy 64.664949 -35.182365) (xy 64.664336 -35.149282) (xy 64.664336 -35.146234)
			(xy 64.664779 -35.116424) (xy 64.671784 -35.057216) (xy 64.678306 -35.028124) (xy 64.678306 -35.02787)
			(xy 64.679716 -35.021388) (xy 64.679466 -35.008128) (xy 64.677798 -35.001708) (xy 64.674496 -34.990024)
			(xy 63.790068 -34.105596) (xy 63.783215 -34.098201) (xy 63.775471 -34.079602) (xy 63.775082 -34.069528)
			(xy 63.775082 -30.634178) (xy 63.774918 -30.628168) (xy 63.772099 -30.616483) (xy 63.769494 -30.611064)
			(xy 63.767653 -30.607591) (xy 63.763058 -30.601214) (xy 63.76035 -30.598364) (xy 63.286894 -30.124908)
			(xy 63.284042 -30.122204) (xy 63.277662 -30.117613) (xy 63.274194 -30.115764) (xy 63.268769 -30.113174)
			(xy 63.257089 -30.110338) (xy 63.25108 -30.110176) (xy 60.163456 -30.110176) (xy 60.157614 -30.11043)
			(xy 60.148628 -30.11188) (xy 60.132451 -30.120194) (xy 60.120175 -30.133616) (xy 60.116466 -30.141926)
			(xy 60.080144 -30.23108) (xy 60.078065 -30.237736) (xy 60.077162 -30.251644) (xy 60.078366 -30.258512)
			(xy 60.07989 -30.265878) (xy 60.086494 -30.278578) (xy 60.09259 -30.28442) (xy 60.114569 -30.306524)
			(xy 60.15354 -30.355175) (xy 60.170314 -30.381448) (xy 60.175648 -30.38983) (xy 60.18276 -30.395164)
			(xy 60.186575 -30.397941) (xy 60.195012 -30.402165) (xy 60.199524 -30.403546) (xy 60.2107 -30.406848)
			(xy 60.240164 -30.41523) (xy 60.240672 -30.41523) (xy 60.267596 -30.423104) (xy 60.271664 -30.423968)
			(xy 60.279964 -30.424485) (xy 60.284106 -30.42412) (xy 60.29325 -30.423358) (xy 60.301886 -30.419294)
			(xy 60.32825 -30.40668) (xy 60.383248 -30.386902) (xy 60.440154 -30.37357) (xy 60.498215 -30.366862)
			(xy 60.527438 -30.366462) (xy 60.559399 -30.366966) (xy 60.622818 -30.374982) (xy 60.684731 -30.390883)
			(xy 60.744164 -30.414418) (xy 60.800178 -30.445216) (xy 60.851891 -30.482791) (xy 60.898487 -30.526551)
			(xy 60.939231 -30.575806) (xy 60.973481 -30.629779) (xy 61.000697 -30.687618) (xy 61.02045 -30.748413)
			(xy 61.032427 -30.811203) (xy 61.036441 -30.875) (xy 61.032427 -30.938797) (xy 61.02045 -31.001587)
			(xy 61.000697 -31.062382) (xy 60.973481 -31.120221) (xy 60.939231 -31.174194) (xy 60.898487 -31.223449)
			(xy 60.851891 -31.267209) (xy 60.800178 -31.304784) (xy 60.744164 -31.335582) (xy 60.684731 -31.359117)
			(xy 60.622818 -31.375018) (xy 60.559399 -31.383034) (xy 60.527438 -31.383478) (xy 60.497471 -31.383024)
			(xy 60.437956 -31.375951) (xy 60.379682 -31.361945) (xy 60.351416 -31.351982) (xy 60.351162 -31.351982)
			(xy 60.348876 -31.35122) (xy 60.34659 -31.350204) (xy 60.341901 -31.349165) (xy 60.332313 -31.348654)
			(xy 60.32754 -31.349188) (xy 60.32246 -31.350204) (xy 60.318904 -31.350712) (xy 60.317126 -31.35122)
			(xy 60.311284 -31.354268) (xy 60.301378 -31.360618) (xy 60.277502 -31.382462) (xy 60.233052 -31.423102)
			(xy 60.228575 -31.427318) (xy 60.22163 -31.437463) (xy 60.219336 -31.443168) (xy 60.216796 -31.452312)
			(xy 60.216542 -31.453074) (xy 60.216288 -31.466536) (xy 60.21832 -31.473902) (xy 60.225554 -31.502349)
			(xy 60.23421 -31.560406) (xy 60.235592 -31.589726) (xy 60.235846 -31.603442) (xy 60.235846 -31.60903)
			(xy 60.235143 -31.642217) (xy 60.226179 -31.707988) (xy 60.208734 -31.772034) (xy 60.183105 -31.833266)
			(xy 60.149726 -31.890643) (xy 60.109166 -31.943189) (xy 60.062113 -31.990011) (xy 60.009369 -32.030313)
			(xy 59.95183 -32.06341) (xy 59.890473 -32.08874) (xy 59.826342 -32.105871) (xy 59.760528 -32.114512)
			(xy 59.727338 -32.114998) (xy 59.696605 -32.114555) (xy 59.635586 -32.10715) (xy 59.575904 -32.092443)
			(xy 59.518431 -32.07065) (xy 59.464003 -32.042087) (xy 59.413416 -32.007172) (xy 59.367406 -31.966414)
			(xy 59.326645 -31.920406) (xy 59.291727 -31.869821) (xy 59.263162 -31.815395) (xy 59.241365 -31.757923)
			(xy 59.226655 -31.698242) (xy 59.219247 -31.637223) (xy 59.21883 -31.60649) (xy 59.219369 -31.573295)
			(xy 59.228011 -31.507468) (xy 59.245147 -31.443327) (xy 59.270486 -31.381962) (xy 59.303596 -31.324416)
			(xy 59.343914 -31.271669) (xy 59.390754 -31.224619) (xy 59.416696 -31.2039) (xy 59.421268 -31.200344)
			(xy 59.428888 -31.1912) (xy 59.431174 -31.186374) (xy 59.433579 -31.181163) (xy 59.436267 -31.17001)
			(xy 59.436508 -31.164276) (xy 59.437016 -31.123636) (xy 59.437016 -31.120588) (xy 59.437524 -31.079948)
			(xy 59.434476 -31.065978) (xy 59.432698 -31.062422) (xy 59.430129 -31.05743) (xy 59.42321 -31.04859)
			(xy 59.418982 -31.044896) (xy 59.418474 -31.044388) (xy 59.393503 -31.023643) (xy 59.348511 -30.976842)
			(xy 59.309844 -30.924693) (xy 59.278131 -30.868046) (xy 59.253889 -30.807822) (xy 59.237511 -30.745002)
			(xy 59.229264 -30.680608) (xy 59.228736 -30.648148) (xy 59.229287 -30.614358) (xy 59.238232 -30.547374)
			(xy 59.255972 -30.482165) (xy 59.282194 -30.41988) (xy 59.316435 -30.361618) (xy 59.358093 -30.308406)
			(xy 59.381898 -30.28442) (xy 59.382152 -30.284166) (xy 59.387231 -30.278752) (xy 59.394317 -30.265714)
			(xy 59.396122 -30.258512) (xy 59.397138 -30.254448) (xy 59.3979 -30.250638) (xy 59.397138 -30.243018)
			(xy 59.396702 -30.239425) (xy 59.394922 -30.23241) (xy 59.393582 -30.229048) (xy 59.358022 -30.141926)
			(xy 59.354281 -30.133633) (xy 59.342027 -30.1202) (xy 59.325855 -30.111892) (xy 59.316874 -30.11043)
			(xy 59.311032 -30.110176) (xy 48.376586 -30.110176) (xy 48.370575 -30.110339) (xy 48.358888 -30.113154)
			(xy 48.353472 -30.115764) (xy 48.349997 -30.117603) (xy 48.343617 -30.122195) (xy 48.340772 -30.124908)
			(xy 48.337724 -30.127956) (xy 48.319182 -30.135576) (xy 48.304704 -30.135576) (xy 46.308264 -32.132016)
			(xy 46.305558 -32.134867) (xy 46.300964 -32.141245) (xy 46.29912 -32.144716) (xy 46.296533 -32.150142)
			(xy 46.293702 -32.161822) (xy 46.293532 -32.16783) (xy 46.293532 -32.295084) (xy 56.527952 -32.295084)
			(xy 56.532023 -32.239462) (xy 56.544149 -32.185025) (xy 56.564072 -32.132934) (xy 56.591368 -32.084299)
			(xy 56.625454 -32.040156) (xy 56.665603 -32.001447) (xy 56.710961 -31.968996) (xy 56.760561 -31.943495)
			(xy 56.813345 -31.925488) (xy 56.868188 -31.915358) (xy 56.923922 -31.913321) (xy 56.979359 -31.919421)
			(xy 57.033316 -31.933527) (xy 57.084645 -31.955339) (xy 57.132251 -31.984393) (xy 57.175119 -32.020068)
			(xy 57.212336 -32.061605) (xy 57.243109 -32.108118) (xy 57.266781 -32.158615) (xy 57.282849 -32.212022)
			(xy 57.290969 -32.267198) (xy 57.291478 -32.295084) (xy 57.290969 -32.32297) (xy 57.282849 -32.378146)
			(xy 57.266781 -32.431553) (xy 57.243109 -32.48205) (xy 57.212336 -32.528563) (xy 57.175119 -32.5701)
			(xy 57.132251 -32.605775) (xy 57.084645 -32.634829) (xy 57.033316 -32.656641) (xy 56.979359 -32.670747)
			(xy 56.923922 -32.676847) (xy 56.868188 -32.67481) (xy 56.813345 -32.66468) (xy 56.760561 -32.646673)
			(xy 56.710961 -32.621172) (xy 56.665603 -32.588721) (xy 56.625454 -32.550012) (xy 56.591368 -32.505869)
			(xy 56.564072 -32.457234) (xy 56.544149 -32.405143) (xy 56.532023 -32.350706) (xy 56.527952 -32.295084)
			(xy 46.293532 -32.295084) (xy 46.293532 -32.937196) (xy 47.179482 -32.937196) (xy 47.183553 -32.881574)
			(xy 47.195679 -32.827137) (xy 47.215602 -32.775046) (xy 47.242898 -32.726411) (xy 47.276984 -32.682268)
			(xy 47.317133 -32.643559) (xy 47.362491 -32.611108) (xy 47.412091 -32.585607) (xy 47.464875 -32.5676)
			(xy 47.519718 -32.55747) (xy 47.575452 -32.555433) (xy 47.630889 -32.561533) (xy 47.684846 -32.575639)
			(xy 47.736175 -32.597451) (xy 47.783781 -32.626505) (xy 47.826649 -32.66218) (xy 47.863866 -32.703717)
			(xy 47.894639 -32.75023) (xy 47.918311 -32.800727) (xy 47.934379 -32.854134) (xy 47.942499 -32.90931)
			(xy 47.943008 -32.937196) (xy 47.942499 -32.965082) (xy 47.934379 -33.020258) (xy 47.918311 -33.073665)
			(xy 47.894639 -33.124162) (xy 47.863866 -33.170675) (xy 47.826649 -33.212212) (xy 47.783781 -33.247887)
			(xy 47.736175 -33.276941) (xy 47.684846 -33.298753) (xy 47.630889 -33.312859) (xy 47.61932 -33.314132)
			(xy 51.195476 -33.314132) (xy 51.199547 -33.25851) (xy 51.211673 -33.204073) (xy 51.231596 -33.151982)
			(xy 51.258892 -33.103347) (xy 51.292978 -33.059204) (xy 51.333127 -33.020495) (xy 51.378485 -32.988044)
			(xy 51.428085 -32.962543) (xy 51.480869 -32.944536) (xy 51.535712 -32.934406) (xy 51.591446 -32.932369)
			(xy 51.646883 -32.938469) (xy 51.70084 -32.952575) (xy 51.752169 -32.974387) (xy 51.799775 -33.003441)
			(xy 51.842643 -33.039116) (xy 51.87986 -33.080653) (xy 51.906951 -33.1216) (xy 60.09539 -33.1216)
			(xy 60.099403 -33.057804) (xy 60.111381 -32.995014) (xy 60.131134 -32.934221) (xy 60.158351 -32.876382)
			(xy 60.192602 -32.822411) (xy 60.233347 -32.773158) (xy 60.279944 -32.729401) (xy 60.331659 -32.691828)
			(xy 60.387674 -32.661034) (xy 60.447107 -32.637502) (xy 60.509021 -32.621605) (xy 60.572439 -32.613594)
			(xy 60.6044 -32.613092) (xy 60.637289 -32.613598) (xy 60.702518 -32.622091) (xy 60.766107 -32.638922)
			(xy 60.826995 -32.66381) (xy 60.884167 -32.696341) (xy 60.936668 -32.73597) (xy 60.960508 -32.758634)
			(xy 60.968849 -32.766054) (xy 60.989902 -32.773417) (xy 61.012096 -32.771203) (xy 61.021976 -32.766)
			(xy 61.051683 -32.748952) (xy 61.114683 -32.722076) (xy 61.180714 -32.703877) (xy 61.248588 -32.694684)
			(xy 61.282834 -32.694118) (xy 61.315995 -32.694707) (xy 61.381752 -32.703333) (xy 61.445831 -32.720434)
			(xy 61.507142 -32.745721) (xy 61.564646 -32.778764) (xy 61.617366 -32.819002) (xy 61.664408 -32.865752)
			(xy 61.704973 -32.91822) (xy 61.738373 -32.975517) (xy 61.764041 -33.03667) (xy 61.773308 -33.068514)
			(xy 61.776069 -33.077338) (xy 61.786891 -33.092313) (xy 61.79439 -33.097724) (xy 61.820044 -33.114234)
			(xy 61.827955 -33.118963) (xy 61.845923 -33.123004) (xy 61.855096 -33.122108) (xy 61.873344 -33.119603)
			(xy 61.910084 -33.116936) (xy 61.928502 -33.116774) (xy 61.960462 -33.117312) (xy 62.023877 -33.125323)
			(xy 62.085789 -33.14122) (xy 62.14522 -33.16475) (xy 62.201233 -33.195544) (xy 62.252945 -33.233115)
			(xy 62.29954 -33.276871) (xy 62.340284 -33.326122) (xy 62.374534 -33.380092) (xy 62.401749 -33.437928)
			(xy 62.421502 -33.498719) (xy 62.433479 -33.561506) (xy 62.437493 -33.6253) (xy 62.433479 -33.689094)
			(xy 62.421502 -33.751881) (xy 62.401749 -33.812672) (xy 62.374534 -33.870508) (xy 62.340284 -33.924478)
			(xy 62.29954 -33.973729) (xy 62.252945 -34.017485) (xy 62.201233 -34.055056) (xy 62.14522 -34.08585)
			(xy 62.085789 -34.10938) (xy 62.023877 -34.125277) (xy 61.960462 -34.133288) (xy 61.928502 -34.13379)
			(xy 61.89534 -34.133253) (xy 61.82958 -34.124619) (xy 61.765501 -34.10751) (xy 61.704189 -34.082216)
			(xy 61.646686 -34.049168) (xy 61.593966 -34.008924) (xy 61.546925 -33.962169) (xy 61.506361 -33.909696)
			(xy 61.472962 -33.852396) (xy 61.447295 -33.79124) (xy 61.438028 -33.759394) (xy 61.435252 -33.750576)
			(xy 61.42444 -33.735598) (xy 61.416946 -33.730184) (xy 61.391292 -33.713674) (xy 61.383396 -33.708915)
			(xy 61.365416 -33.704893) (xy 61.35624 -33.7058) (xy 61.337992 -33.708302) (xy 61.301252 -33.710971)
			(xy 61.282834 -33.711134) (xy 61.249946 -33.710599) (xy 61.184719 -33.702111) (xy 61.121131 -33.685285)
			(xy 61.060242 -33.660402) (xy 61.003069 -33.627877) (xy 60.950567 -33.588253) (xy 60.926726 -33.565592)
			(xy 60.918363 -33.558201) (xy 60.897322 -33.550827) (xy 60.875136 -33.553029) (xy 60.865258 -33.558226)
			(xy 60.835561 -33.575293) (xy 60.772558 -33.602166) (xy 60.706524 -33.62036) (xy 60.638647 -33.629546)
			(xy 60.6044 -33.630108) (xy 60.572439 -33.629606) (xy 60.509021 -33.621595) (xy 60.447107 -33.605698)
			(xy 60.387674 -33.582166) (xy 60.331659 -33.551372) (xy 60.279944 -33.513799) (xy 60.233347 -33.470042)
			(xy 60.192602 -33.420789) (xy 60.158351 -33.366818) (xy 60.131134 -33.308979) (xy 60.111381 -33.248186)
			(xy 60.099403 -33.185396) (xy 60.09539 -33.1216) (xy 51.906951 -33.1216) (xy 51.910633 -33.127166)
			(xy 51.934305 -33.177663) (xy 51.950373 -33.23107) (xy 51.958493 -33.286246) (xy 51.959002 -33.314132)
			(xy 51.958493 -33.342018) (xy 51.950373 -33.397194) (xy 51.934305 -33.450601) (xy 51.910633 -33.501098)
			(xy 51.87986 -33.547611) (xy 51.842643 -33.589148) (xy 51.799775 -33.624823) (xy 51.752169 -33.653877)
			(xy 51.70084 -33.675689) (xy 51.646883 -33.689795) (xy 51.591446 -33.695895) (xy 51.535712 -33.693858)
			(xy 51.480869 -33.683728) (xy 51.428085 -33.665721) (xy 51.378485 -33.64022) (xy 51.333127 -33.607769)
			(xy 51.292978 -33.56906) (xy 51.258892 -33.524917) (xy 51.231596 -33.476282) (xy 51.211673 -33.424191)
			(xy 51.199547 -33.369754) (xy 51.195476 -33.314132) (xy 47.61932 -33.314132) (xy 47.575452 -33.318959)
			(xy 47.519718 -33.316922) (xy 47.464875 -33.306792) (xy 47.412091 -33.288785) (xy 47.362491 -33.263284)
			(xy 47.317133 -33.230833) (xy 47.276984 -33.192124) (xy 47.242898 -33.147981) (xy 47.215602 -33.099346)
			(xy 47.195679 -33.047255) (xy 47.183553 -32.992818) (xy 47.179482 -32.937196) (xy 46.293532 -32.937196)
			(xy 46.293532 -35.315609) (xy 51.330346 -35.315609) (xy 51.330346 -35.251687) (xy 51.338357 -35.188269)
			(xy 51.354254 -35.126355) (xy 51.377786 -35.066922) (xy 51.40858 -35.010907) (xy 51.446153 -34.959192)
			(xy 51.48991 -34.912595) (xy 51.539163 -34.87185) (xy 51.593134 -34.837599) (xy 51.650973 -34.810382)
			(xy 51.711766 -34.790629) (xy 51.774556 -34.778651) (xy 51.838352 -34.774638) (xy 51.902148 -34.778651)
			(xy 51.964938 -34.790629) (xy 52.025731 -34.810382) (xy 52.08357 -34.837599) (xy 52.137541 -34.87185)
			(xy 52.146778 -34.879491) (xy 58.74613 -34.879491) (xy 58.74613 -34.815569) (xy 58.754141 -34.752151)
			(xy 58.770038 -34.690237) (xy 58.79357 -34.630804) (xy 58.824364 -34.574789) (xy 58.861937 -34.523074)
			(xy 58.905694 -34.476477) (xy 58.954947 -34.435732) (xy 59.008918 -34.401481) (xy 59.066757 -34.374264)
			(xy 59.12755 -34.354511) (xy 59.19034 -34.342533) (xy 59.254136 -34.33852) (xy 59.317932 -34.342533)
			(xy 59.380722 -34.354511) (xy 59.441515 -34.374264) (xy 59.499354 -34.401481) (xy 59.553325 -34.435732)
			(xy 59.602578 -34.476477) (xy 59.646335 -34.523074) (xy 59.683908 -34.574789) (xy 59.714702 -34.630804)
			(xy 59.738234 -34.690237) (xy 59.754131 -34.752151) (xy 59.762142 -34.815569) (xy 59.762644 -34.84753)
			(xy 59.762142 -34.879491) (xy 59.754131 -34.942909) (xy 59.738234 -35.004823) (xy 59.714702 -35.064256)
			(xy 59.683908 -35.120271) (xy 59.646335 -35.171986) (xy 59.602578 -35.218583) (xy 59.553325 -35.259328)
			(xy 59.499354 -35.293579) (xy 59.441515 -35.320796) (xy 59.380722 -35.340549) (xy 59.317932 -35.352527)
			(xy 59.254136 -35.356541) (xy 59.19034 -35.352527) (xy 59.12755 -35.340549) (xy 59.066757 -35.320796)
			(xy 59.008918 -35.293579) (xy 58.954947 -35.259328) (xy 58.905694 -35.218583) (xy 58.861937 -35.171986)
			(xy 58.824364 -35.120271) (xy 58.79357 -35.064256) (xy 58.770038 -35.004823) (xy 58.754141 -34.942909)
			(xy 58.74613 -34.879491) (xy 52.146778 -34.879491) (xy 52.186794 -34.912595) (xy 52.230551 -34.959192)
			(xy 52.268124 -35.010907) (xy 52.298918 -35.066922) (xy 52.32245 -35.126355) (xy 52.338347 -35.188269)
			(xy 52.346358 -35.251687) (xy 52.34686 -35.283648) (xy 52.346358 -35.315609) (xy 52.338347 -35.379027)
			(xy 52.32245 -35.440941) (xy 52.298918 -35.500374) (xy 52.268124 -35.556389) (xy 52.230551 -35.608104)
			(xy 52.186794 -35.654701) (xy 52.137541 -35.695446) (xy 52.08357 -35.729697) (xy 52.025731 -35.756914)
			(xy 51.964938 -35.776667) (xy 51.902148 -35.788645) (xy 51.838352 -35.792659) (xy 51.774556 -35.788645)
			(xy 51.711766 -35.776667) (xy 51.650973 -35.756914) (xy 51.593134 -35.729697) (xy 51.539163 -35.695446)
			(xy 51.48991 -35.654701) (xy 51.446153 -35.608104) (xy 51.40858 -35.556389) (xy 51.377786 -35.500374)
			(xy 51.354254 -35.440941) (xy 51.338357 -35.379027) (xy 51.330346 -35.315609) (xy 46.293532 -35.315609)
			(xy 46.293532 -36.353961) (xy 47.751994 -36.353961) (xy 47.751994 -36.290039) (xy 47.760005 -36.226621)
			(xy 47.775902 -36.164707) (xy 47.799434 -36.105274) (xy 47.830228 -36.049259) (xy 47.867801 -35.997544)
			(xy 47.911558 -35.950947) (xy 47.960811 -35.910202) (xy 48.014782 -35.875951) (xy 48.072621 -35.848734)
			(xy 48.133414 -35.828981) (xy 48.196204 -35.817003) (xy 48.26 -35.81299) (xy 48.323796 -35.817003)
			(xy 48.386586 -35.828981) (xy 48.447379 -35.848734) (xy 48.505218 -35.875951) (xy 48.559189 -35.910202)
			(xy 48.608442 -35.950947) (xy 48.652199 -35.997544) (xy 48.689772 -36.049259) (xy 48.720566 -36.105274)
			(xy 48.744098 -36.164707) (xy 48.759995 -36.226621) (xy 48.765305 -36.26866) (xy 51.812188 -36.26866)
			(xy 51.816259 -36.213038) (xy 51.828385 -36.158601) (xy 51.848308 -36.10651) (xy 51.875604 -36.057875)
			(xy 51.90969 -36.013732) (xy 51.949839 -35.975023) (xy 51.995197 -35.942572) (xy 52.044797 -35.917071)
			(xy 52.097581 -35.899064) (xy 52.152424 -35.888934) (xy 52.208158 -35.886897) (xy 52.263595 -35.892997)
			(xy 52.317552 -35.907103) (xy 52.368881 -35.928915) (xy 52.416487 -35.957969) (xy 52.459355 -35.993644)
			(xy 52.496572 -36.035181) (xy 52.527345 -36.081694) (xy 52.53911 -36.106792) (xy 60.067948 -36.106792)
			(xy 60.067948 -36.022096) (xy 60.075999 -35.937782) (xy 60.092028 -35.854616) (xy 60.115889 -35.773349)
			(xy 60.147368 -35.694719) (xy 60.186179 -35.619438) (xy 60.231969 -35.548186) (xy 60.284325 -35.48161)
			(xy 60.342773 -35.420312) (xy 60.406783 -35.364847) (xy 60.475775 -35.315718) (xy 60.549125 -35.273369)
			(xy 60.626168 -35.238185) (xy 60.706207 -35.210483) (xy 60.788516 -35.190515) (xy 60.872351 -35.178462)
			(xy 60.956952 -35.174432) (xy 61.041553 -35.178462) (xy 61.125388 -35.190515) (xy 61.207697 -35.210483)
			(xy 61.287736 -35.238185) (xy 61.364779 -35.273369) (xy 61.438129 -35.315718) (xy 61.507121 -35.364847)
			(xy 61.571131 -35.420312) (xy 61.629579 -35.48161) (xy 61.681935 -35.548186) (xy 61.727725 -35.619438)
			(xy 61.766536 -35.694719) (xy 61.798015 -35.773349) (xy 61.821876 -35.854616) (xy 61.837905 -35.937782)
			(xy 61.845956 -36.022096) (xy 61.84646 -36.064444) (xy 61.845956 -36.106792) (xy 61.837905 -36.191106)
			(xy 61.821876 -36.274272) (xy 61.798015 -36.355539) (xy 61.766536 -36.434169) (xy 61.727725 -36.50945)
			(xy 61.681935 -36.580702) (xy 61.629579 -36.647278) (xy 61.620042 -36.65728) (xy 63.675512 -36.65728)
			(xy 63.679583 -36.601658) (xy 63.691709 -36.547221) (xy 63.711632 -36.49513) (xy 63.738928 -36.446495)
			(xy 63.773014 -36.402352) (xy 63.813163 -36.363643) (xy 63.858521 -36.331192) (xy 63.908121 -36.305691)
			(xy 63.960905 -36.287684) (xy 64.015748 -36.277554) (xy 64.071482 -36.275517) (xy 64.126919 -36.281617)
			(xy 64.180876 -36.295723) (xy 64.232205 -36.317535) (xy 64.279811 -36.346589) (xy 64.322679 -36.382264)
			(xy 64.359896 -36.423801) (xy 64.390669 -36.470314) (xy 64.414341 -36.520811) (xy 64.430409 -36.574218)
			(xy 64.438529 -36.629394) (xy 64.438945 -36.6522) (xy 102.015796 -36.6522) (xy 102.019867 -36.596578)
			(xy 102.031993 -36.542141) (xy 102.051916 -36.49005) (xy 102.079212 -36.441415) (xy 102.113298 -36.397272)
			(xy 102.153447 -36.358563) (xy 102.198805 -36.326112) (xy 102.248405 -36.300611) (xy 102.301189 -36.282604)
			(xy 102.356032 -36.272474) (xy 102.411766 -36.270437) (xy 102.467203 -36.276537) (xy 102.52116 -36.290643)
			(xy 102.572489 -36.312455) (xy 102.620095 -36.341509) (xy 102.662963 -36.377184) (xy 102.70018 -36.418721)
			(xy 102.730953 -36.465234) (xy 102.754625 -36.515731) (xy 102.770693 -36.569138) (xy 102.778813 -36.624314)
			(xy 102.779322 -36.6522) (xy 102.778813 -36.680086) (xy 102.770693 -36.735262) (xy 102.754625 -36.788669)
			(xy 102.730953 -36.839166) (xy 102.708281 -36.873434) (xy 130.280154 -36.873434) (xy 130.284225 -36.817812)
			(xy 130.296351 -36.763375) (xy 130.316274 -36.711284) (xy 130.34357 -36.662649) (xy 130.377656 -36.618506)
			(xy 130.417805 -36.579797) (xy 130.463163 -36.547346) (xy 130.512763 -36.521845) (xy 130.565547 -36.503838)
			(xy 130.62039 -36.493708) (xy 130.676124 -36.491671) (xy 130.731561 -36.497771) (xy 130.785518 -36.511877)
			(xy 130.836847 -36.533689) (xy 130.884453 -36.562743) (xy 130.927321 -36.598418) (xy 130.964538 -36.639955)
			(xy 130.995311 -36.686468) (xy 131.018983 -36.736965) (xy 131.035051 -36.790372) (xy 131.043171 -36.845548)
			(xy 131.04368 -36.873434) (xy 131.043171 -36.90132) (xy 131.035051 -36.956496) (xy 131.018983 -37.009903)
			(xy 130.995311 -37.0604) (xy 130.964538 -37.106913) (xy 130.927321 -37.14845) (xy 130.884453 -37.184125)
			(xy 130.836847 -37.213179) (xy 130.785518 -37.234991) (xy 130.731561 -37.249097) (xy 130.676124 -37.255197)
			(xy 130.62039 -37.25316) (xy 130.565547 -37.24303) (xy 130.512763 -37.225023) (xy 130.463163 -37.199522)
			(xy 130.417805 -37.167071) (xy 130.377656 -37.128362) (xy 130.34357 -37.084219) (xy 130.316274 -37.035584)
			(xy 130.296351 -36.983493) (xy 130.284225 -36.929056) (xy 130.280154 -36.873434) (xy 102.708281 -36.873434)
			(xy 102.70018 -36.885679) (xy 102.662963 -36.927216) (xy 102.620095 -36.962891) (xy 102.572489 -36.991945)
			(xy 102.52116 -37.013757) (xy 102.467203 -37.027863) (xy 102.411766 -37.033963) (xy 102.356032 -37.031926)
			(xy 102.301189 -37.021796) (xy 102.248405 -37.003789) (xy 102.198805 -36.978288) (xy 102.153447 -36.945837)
			(xy 102.113298 -36.907128) (xy 102.079212 -36.862985) (xy 102.051916 -36.81435) (xy 102.031993 -36.762259)
			(xy 102.019867 -36.707822) (xy 102.015796 -36.6522) (xy 64.438945 -36.6522) (xy 64.439038 -36.65728)
			(xy 64.438529 -36.685166) (xy 64.430409 -36.740342) (xy 64.414341 -36.793749) (xy 64.390669 -36.844246)
			(xy 64.359896 -36.890759) (xy 64.322679 -36.932296) (xy 64.279811 -36.967971) (xy 64.232205 -36.997025)
			(xy 64.180876 -37.018837) (xy 64.126919 -37.032943) (xy 64.071482 -37.039043) (xy 64.015748 -37.037006)
			(xy 63.960905 -37.026876) (xy 63.908121 -37.008869) (xy 63.858521 -36.983368) (xy 63.813163 -36.950917)
			(xy 63.773014 -36.912208) (xy 63.738928 -36.868065) (xy 63.711632 -36.81943) (xy 63.691709 -36.767339)
			(xy 63.679583 -36.712902) (xy 63.675512 -36.65728) (xy 61.620042 -36.65728) (xy 61.571131 -36.708576)
			(xy 61.507121 -36.764041) (xy 61.438129 -36.81317) (xy 61.364779 -36.855519) (xy 61.287736 -36.890703)
			(xy 61.207697 -36.918405) (xy 61.125388 -36.938373) (xy 61.041553 -36.950426) (xy 60.956952 -36.954457)
			(xy 60.872351 -36.950426) (xy 60.788516 -36.938373) (xy 60.706207 -36.918405) (xy 60.626168 -36.890703)
			(xy 60.549125 -36.855519) (xy 60.475775 -36.81317) (xy 60.406783 -36.764041) (xy 60.342773 -36.708576)
			(xy 60.284325 -36.647278) (xy 60.231969 -36.580702) (xy 60.186179 -36.50945) (xy 60.147368 -36.434169)
			(xy 60.115889 -36.355539) (xy 60.092028 -36.274272) (xy 60.075999 -36.191106) (xy 60.067948 -36.106792)
			(xy 52.53911 -36.106792) (xy 52.551017 -36.132191) (xy 52.567085 -36.185598) (xy 52.575205 -36.240774)
			(xy 52.575714 -36.26866) (xy 52.575205 -36.296546) (xy 52.567085 -36.351722) (xy 52.551017 -36.405129)
			(xy 52.527345 -36.455626) (xy 52.496572 -36.502139) (xy 52.459355 -36.543676) (xy 52.416487 -36.579351)
			(xy 52.368881 -36.608405) (xy 52.317552 -36.630217) (xy 52.263595 -36.644323) (xy 52.208158 -36.650423)
			(xy 52.152424 -36.648386) (xy 52.097581 -36.638256) (xy 52.044797 -36.620249) (xy 51.995197 -36.594748)
			(xy 51.949839 -36.562297) (xy 51.90969 -36.523588) (xy 51.875604 -36.479445) (xy 51.848308 -36.43081)
			(xy 51.828385 -36.378719) (xy 51.816259 -36.324282) (xy 51.812188 -36.26866) (xy 48.765305 -36.26866)
			(xy 48.768006 -36.290039) (xy 48.768508 -36.322) (xy 48.768006 -36.353961) (xy 48.759995 -36.417379)
			(xy 48.744098 -36.479293) (xy 48.720566 -36.538726) (xy 48.689772 -36.594741) (xy 48.652199 -36.646456)
			(xy 48.608442 -36.693053) (xy 48.559189 -36.733798) (xy 48.505218 -36.768049) (xy 48.447379 -36.795266)
			(xy 48.386586 -36.815019) (xy 48.323796 -36.826997) (xy 48.26 -36.831011) (xy 48.196204 -36.826997)
			(xy 48.133414 -36.815019) (xy 48.072621 -36.795266) (xy 48.014782 -36.768049) (xy 47.960811 -36.733798)
			(xy 47.911558 -36.693053) (xy 47.867801 -36.646456) (xy 47.830228 -36.594741) (xy 47.799434 -36.538726)
			(xy 47.775902 -36.479293) (xy 47.760005 -36.417379) (xy 47.751994 -36.353961) (xy 46.293532 -36.353961)
			(xy 46.293532 -36.921948) (xy 46.294005 -36.931578) (xy 46.301197 -36.94945) (xy 46.307502 -36.956746)
			(xy 46.355508 -37.007546) (xy 46.362874 -37.013896) (xy 46.374304 -37.019992) (xy 46.385734 -37.022532)
			(xy 46.3931 -37.023548) (xy 46.420409 -37.025868) (xy 46.473999 -37.037349) (xy 46.525394 -37.056382)
			(xy 46.573536 -37.082576) (xy 46.617433 -37.11539) (xy 46.656181 -37.15415) (xy 46.688983 -37.198056)
			(xy 46.715162 -37.246205) (xy 46.734181 -37.297605) (xy 46.745647 -37.351199) (xy 46.749325 -37.405881)
			(xy 46.745137 -37.460527) (xy 46.733172 -37.514011) (xy 46.713675 -37.565232) (xy 46.687047 -37.613135)
			(xy 46.653837 -37.656733) (xy 46.614729 -37.695129) (xy 46.570528 -37.727533) (xy 46.522144 -37.753276)
			(xy 46.470573 -37.771829) (xy 46.416878 -37.78281) (xy 46.389544 -37.784786) (xy 46.389036 -37.784786)
			(xy 46.38421 -37.78504) (xy 52.135022 -37.78504) (xy 52.139093 -37.729418) (xy 52.151219 -37.674981)
			(xy 52.171142 -37.62289) (xy 52.198438 -37.574255) (xy 52.232524 -37.530112) (xy 52.272673 -37.491403)
			(xy 52.318031 -37.458952) (xy 52.367631 -37.433451) (xy 52.420415 -37.415444) (xy 52.475258 -37.405314)
			(xy 52.530992 -37.403277) (xy 52.586429 -37.409377) (xy 52.640386 -37.423483) (xy 52.691715 -37.445295)
			(xy 52.739321 -37.474349) (xy 52.782189 -37.510024) (xy 52.819406 -37.551561) (xy 52.850179 -37.598074)
			(xy 52.862314 -37.623961) (xy 58.927994 -37.623961) (xy 58.927994 -37.560039) (xy 58.936005 -37.496621)
			(xy 58.951902 -37.434707) (xy 58.975434 -37.375274) (xy 59.006228 -37.319259) (xy 59.043801 -37.267544)
			(xy 59.087558 -37.220947) (xy 59.136811 -37.180202) (xy 59.190782 -37.145951) (xy 59.248621 -37.118734)
			(xy 59.309414 -37.098981) (xy 59.372204 -37.087003) (xy 59.436 -37.08299) (xy 59.499796 -37.087003)
			(xy 59.562586 -37.098981) (xy 59.623379 -37.118734) (xy 59.681218 -37.145951) (xy 59.735189 -37.180202)
			(xy 59.784442 -37.220947) (xy 59.828199 -37.267544) (xy 59.865772 -37.319259) (xy 59.896566 -37.375274)
			(xy 59.920098 -37.434707) (xy 59.920767 -37.437314) (xy 66.391026 -37.437314) (xy 66.395097 -37.381692)
			(xy 66.407223 -37.327255) (xy 66.427146 -37.275164) (xy 66.454442 -37.226529) (xy 66.488528 -37.182386)
			(xy 66.528677 -37.143677) (xy 66.574035 -37.111226) (xy 66.623635 -37.085725) (xy 66.676419 -37.067718)
			(xy 66.731262 -37.057588) (xy 66.786996 -37.055551) (xy 66.842433 -37.061651) (xy 66.89639 -37.075757)
			(xy 66.947719 -37.097569) (xy 66.995325 -37.126623) (xy 67.038193 -37.162298) (xy 67.07541 -37.203835)
			(xy 67.106183 -37.250348) (xy 67.129855 -37.300845) (xy 67.145923 -37.354252) (xy 67.154043 -37.409428)
			(xy 67.154552 -37.437314) (xy 67.154043 -37.4652) (xy 67.145923 -37.520376) (xy 67.129855 -37.573783)
			(xy 67.106183 -37.62428) (xy 67.07541 -37.670793) (xy 67.038193 -37.71233) (xy 66.995325 -37.748005)
			(xy 66.947719 -37.777059) (xy 66.89639 -37.798871) (xy 66.842433 -37.812977) (xy 66.786996 -37.819077)
			(xy 66.731262 -37.81704) (xy 66.676419 -37.80691) (xy 66.623635 -37.788903) (xy 66.574035 -37.763402)
			(xy 66.528677 -37.730951) (xy 66.488528 -37.692242) (xy 66.454442 -37.648099) (xy 66.427146 -37.599464)
			(xy 66.407223 -37.547373) (xy 66.395097 -37.492936) (xy 66.391026 -37.437314) (xy 59.920767 -37.437314)
			(xy 59.935995 -37.496621) (xy 59.944006 -37.560039) (xy 59.944508 -37.592) (xy 59.944006 -37.623961)
			(xy 59.935995 -37.687379) (xy 59.920098 -37.749293) (xy 59.896566 -37.808726) (xy 59.865772 -37.864741)
			(xy 59.828199 -37.916456) (xy 59.784442 -37.963053) (xy 59.735189 -38.003798) (xy 59.681218 -38.038049)
			(xy 59.623379 -38.065266) (xy 59.562586 -38.085019) (xy 59.499796 -38.096997) (xy 59.436 -38.101011)
			(xy 59.372204 -38.096997) (xy 59.309414 -38.085019) (xy 59.248621 -38.065266) (xy 59.190782 -38.038049)
			(xy 59.136811 -38.003798) (xy 59.087558 -37.963053) (xy 59.043801 -37.916456) (xy 59.006228 -37.864741)
			(xy 58.975434 -37.808726) (xy 58.951902 -37.749293) (xy 58.936005 -37.687379) (xy 58.927994 -37.623961)
			(xy 52.862314 -37.623961) (xy 52.873851 -37.648571) (xy 52.889919 -37.701978) (xy 52.898039 -37.757154)
			(xy 52.898548 -37.78504) (xy 52.898039 -37.812926) (xy 52.889919 -37.868102) (xy 52.873851 -37.921509)
			(xy 52.850179 -37.972006) (xy 52.819406 -38.018519) (xy 52.782189 -38.060056) (xy 52.739321 -38.095731)
			(xy 52.691715 -38.124785) (xy 52.640386 -38.146597) (xy 52.586429 -38.160703) (xy 52.530992 -38.166803)
			(xy 52.475258 -38.164766) (xy 52.420415 -38.154636) (xy 52.367631 -38.136629) (xy 52.318031 -38.111128)
			(xy 52.272673 -38.078677) (xy 52.232524 -38.039968) (xy 52.198438 -37.995825) (xy 52.171142 -37.94719)
			(xy 52.151219 -37.895099) (xy 52.139093 -37.840662) (xy 52.135022 -37.78504) (xy 46.38421 -37.78504)
			(xy 46.379384 -37.785294) (xy 46.370748 -37.789358) (xy 46.366757 -37.791402) (xy 46.359476 -37.796636)
			(xy 46.35627 -37.799772) (xy 46.355762 -37.80028) (xy 46.307502 -37.851334) (xy 46.301161 -37.858604)
			(xy 46.293989 -37.876495) (xy 46.293532 -37.886132) (xy 46.293532 -38.638945) (xy 59.46241 -38.638945)
			(xy 59.46241 -38.575023) (xy 59.470421 -38.511605) (xy 59.486318 -38.449691) (xy 59.50985 -38.390258)
			(xy 59.540644 -38.334243) (xy 59.578217 -38.282528) (xy 59.621974 -38.235931) (xy 59.671227 -38.195186)
			(xy 59.725198 -38.160935) (xy 59.783037 -38.133718) (xy 59.84383 -38.113965) (xy 59.90662 -38.101987)
			(xy 59.970416 -38.097974) (xy 60.034212 -38.101987) (xy 60.097002 -38.113965) (xy 60.157795 -38.133718)
			(xy 60.215634 -38.160935) (xy 60.269605 -38.195186) (xy 60.318858 -38.235931) (xy 60.362615 -38.282528)
			(xy 60.400188 -38.334243) (xy 60.430982 -38.390258) (xy 60.454514 -38.449691) (xy 60.470411 -38.511605)
			(xy 60.475786 -38.554152) (xy 61.140592 -38.554152) (xy 61.144663 -38.49853) (xy 61.156789 -38.444093)
			(xy 61.176712 -38.392002) (xy 61.204008 -38.343367) (xy 61.238094 -38.299224) (xy 61.278243 -38.260515)
			(xy 61.323601 -38.228064) (xy 61.373201 -38.202563) (xy 61.425985 -38.184556) (xy 61.480828 -38.174426)
			(xy 61.536562 -38.172389) (xy 61.591999 -38.178489) (xy 61.645956 -38.192595) (xy 61.697285 -38.214407)
			(xy 61.744891 -38.243461) (xy 61.787759 -38.279136) (xy 61.824976 -38.320673) (xy 61.855749 -38.367186)
			(xy 61.857303 -38.3705) (xy 65.682399 -38.3705) (xy 65.686413 -38.306707) (xy 65.69839 -38.243919)
			(xy 65.718142 -38.183128) (xy 65.745357 -38.125292) (xy 65.779606 -38.071322) (xy 65.820349 -38.022071)
			(xy 65.866944 -37.978314) (xy 65.918655 -37.940742) (xy 65.974668 -37.909947) (xy 66.034098 -37.886416)
			(xy 66.096009 -37.870518) (xy 66.159424 -37.862505) (xy 66.191384 -37.862002) (xy 66.223571 -37.862511)
			(xy 66.287433 -37.870612) (xy 66.349761 -37.886712) (xy 66.376974 -37.897562) (xy 75.723494 -37.897562)
			(xy 75.727565 -37.84194) (xy 75.739691 -37.787503) (xy 75.759614 -37.735412) (xy 75.78691 -37.686777)
			(xy 75.820996 -37.642634) (xy 75.861145 -37.603925) (xy 75.906503 -37.571474) (xy 75.956103 -37.545973)
			(xy 76.008887 -37.527966) (xy 76.06373 -37.517836) (xy 76.119464 -37.515799) (xy 76.174901 -37.521899)
			(xy 76.228858 -37.536005) (xy 76.280187 -37.557817) (xy 76.327793 -37.586871) (xy 76.370661 -37.622546)
			(xy 76.394687 -37.649361) (xy 77.784954 -37.649361) (xy 77.784954 -37.585439) (xy 77.792965 -37.522021)
			(xy 77.808862 -37.460107) (xy 77.832394 -37.400674) (xy 77.863188 -37.344659) (xy 77.900761 -37.292944)
			(xy 77.944518 -37.246347) (xy 77.993771 -37.205602) (xy 78.047742 -37.171351) (xy 78.105581 -37.144134)
			(xy 78.166374 -37.124381) (xy 78.229164 -37.112403) (xy 78.29296 -37.10839) (xy 78.356756 -37.112403)
			(xy 78.419546 -37.124381) (xy 78.480339 -37.144134) (xy 78.538178 -37.171351) (xy 78.592149 -37.205602)
			(xy 78.641402 -37.246347) (xy 78.685159 -37.292944) (xy 78.722732 -37.344659) (xy 78.753398 -37.400441)
			(xy 81.698078 -37.400441) (xy 81.698078 -37.336519) (xy 81.706089 -37.273101) (xy 81.721986 -37.211187)
			(xy 81.745518 -37.151754) (xy 81.776312 -37.095739) (xy 81.813885 -37.044024) (xy 81.857642 -36.997427)
			(xy 81.906895 -36.956682) (xy 81.960866 -36.922431) (xy 82.018705 -36.895214) (xy 82.079498 -36.875461)
			(xy 82.142288 -36.863483) (xy 82.206084 -36.85947) (xy 82.26988 -36.863483) (xy 82.33267 -36.875461)
			(xy 82.393463 -36.895214) (xy 82.451302 -36.922431) (xy 82.505273 -36.956682) (xy 82.554526 -36.997427)
			(xy 82.598283 -37.044024) (xy 82.635856 -37.095739) (xy 82.66665 -37.151754) (xy 82.690182 -37.211187)
			(xy 82.695156 -37.230558) (xy 95.101662 -37.230558) (xy 95.105733 -37.174936) (xy 95.117859 -37.120499)
			(xy 95.137782 -37.068408) (xy 95.165078 -37.019773) (xy 95.199164 -36.97563) (xy 95.239313 -36.936921)
			(xy 95.284671 -36.90447) (xy 95.334271 -36.878969) (xy 95.387055 -36.860962) (xy 95.441898 -36.850832)
			(xy 95.497632 -36.848795) (xy 95.553069 -36.854895) (xy 95.607026 -36.869001) (xy 95.658355 -36.890813)
			(xy 95.705961 -36.919867) (xy 95.748829 -36.955542) (xy 95.786046 -36.997079) (xy 95.816819 -37.043592)
			(xy 95.840491 -37.094089) (xy 95.856559 -37.147496) (xy 95.864679 -37.202672) (xy 95.865188 -37.230558)
			(xy 95.864679 -37.258444) (xy 95.856559 -37.31362) (xy 95.840491 -37.367027) (xy 95.816819 -37.417524)
			(xy 95.795324 -37.450014) (xy 98.09683 -37.450014) (xy 98.100901 -37.394392) (xy 98.113027 -37.339955)
			(xy 98.13295 -37.287864) (xy 98.160246 -37.239229) (xy 98.194332 -37.195086) (xy 98.234481 -37.156377)
			(xy 98.279839 -37.123926) (xy 98.329439 -37.098425) (xy 98.382223 -37.080418) (xy 98.437066 -37.070288)
			(xy 98.4928 -37.068251) (xy 98.548237 -37.074351) (xy 98.602194 -37.088457) (xy 98.653523 -37.110269)
			(xy 98.701129 -37.139323) (xy 98.743997 -37.174998) (xy 98.781214 -37.216535) (xy 98.811987 -37.263048)
			(xy 98.835659 -37.313545) (xy 98.851727 -37.366952) (xy 98.852544 -37.372501) (xy 99.971854 -37.372501)
			(xy 99.971854 -37.308579) (xy 99.979865 -37.245161) (xy 99.995762 -37.183247) (xy 100.019294 -37.123814)
			(xy 100.050088 -37.067799) (xy 100.087661 -37.016084) (xy 100.131418 -36.969487) (xy 100.180671 -36.928742)
			(xy 100.234642 -36.894491) (xy 100.292481 -36.867274) (xy 100.353274 -36.847521) (xy 100.416064 -36.835543)
			(xy 100.47986 -36.83153) (xy 100.543656 -36.835543) (xy 100.606446 -36.847521) (xy 100.667239 -36.867274)
			(xy 100.725078 -36.894491) (xy 100.779049 -36.928742) (xy 100.828302 -36.969487) (xy 100.872059 -37.016084)
			(xy 100.909632 -37.067799) (xy 100.940426 -37.123814) (xy 100.963958 -37.183247) (xy 100.979855 -37.245161)
			(xy 100.987866 -37.308579) (xy 100.988368 -37.34054) (xy 100.987866 -37.372501) (xy 100.979855 -37.435919)
			(xy 100.963958 -37.497833) (xy 100.940426 -37.557266) (xy 100.909632 -37.613281) (xy 100.872059 -37.664996)
			(xy 100.828302 -37.711593) (xy 100.779049 -37.752338) (xy 100.725078 -37.786589) (xy 100.667239 -37.813806)
			(xy 100.606446 -37.833559) (xy 100.543656 -37.845537) (xy 100.47986 -37.849551) (xy 100.416064 -37.845537)
			(xy 100.353274 -37.833559) (xy 100.292481 -37.813806) (xy 100.234642 -37.786589) (xy 100.180671 -37.752338)
			(xy 100.131418 -37.711593) (xy 100.087661 -37.664996) (xy 100.050088 -37.613281) (xy 100.019294 -37.557266)
			(xy 99.995762 -37.497833) (xy 99.979865 -37.435919) (xy 99.971854 -37.372501) (xy 98.852544 -37.372501)
			(xy 98.859847 -37.422128) (xy 98.860356 -37.450014) (xy 98.859847 -37.4779) (xy 98.851727 -37.533076)
			(xy 98.835659 -37.586483) (xy 98.811987 -37.63698) (xy 98.781214 -37.683493) (xy 98.743997 -37.72503)
			(xy 98.701129 -37.760705) (xy 98.653523 -37.789759) (xy 98.602194 -37.811571) (xy 98.548237 -37.825677)
			(xy 98.4928 -37.831777) (xy 98.437066 -37.82974) (xy 98.382223 -37.81961) (xy 98.329439 -37.801603)
			(xy 98.279839 -37.776102) (xy 98.234481 -37.743651) (xy 98.194332 -37.704942) (xy 98.160246 -37.660799)
			(xy 98.13295 -37.612164) (xy 98.113027 -37.560073) (xy 98.100901 -37.505636) (xy 98.09683 -37.450014)
			(xy 95.795324 -37.450014) (xy 95.786046 -37.464037) (xy 95.748829 -37.505574) (xy 95.705961 -37.541249)
			(xy 95.658355 -37.570303) (xy 95.607026 -37.592115) (xy 95.553069 -37.606221) (xy 95.497632 -37.612321)
			(xy 95.441898 -37.610284) (xy 95.387055 -37.600154) (xy 95.334271 -37.582147) (xy 95.284671 -37.556646)
			(xy 95.239313 -37.524195) (xy 95.199164 -37.485486) (xy 95.165078 -37.441343) (xy 95.137782 -37.392708)
			(xy 95.117859 -37.340617) (xy 95.105733 -37.28618) (xy 95.101662 -37.230558) (xy 82.695156 -37.230558)
			(xy 82.706079 -37.273101) (xy 82.71409 -37.336519) (xy 82.714592 -37.36848) (xy 82.71409 -37.400441)
			(xy 82.706079 -37.463859) (xy 82.690182 -37.525773) (xy 82.66665 -37.585206) (xy 82.635856 -37.641221)
			(xy 82.598283 -37.692936) (xy 82.554526 -37.739533) (xy 82.505273 -37.780278) (xy 82.451302 -37.814529)
			(xy 82.393463 -37.841746) (xy 82.33267 -37.861499) (xy 82.26988 -37.873477) (xy 82.206084 -37.877491)
			(xy 82.142288 -37.873477) (xy 82.079498 -37.861499) (xy 82.018705 -37.841746) (xy 81.960866 -37.814529)
			(xy 81.906895 -37.780278) (xy 81.857642 -37.739533) (xy 81.813885 -37.692936) (xy 81.776312 -37.641221)
			(xy 81.745518 -37.585206) (xy 81.721986 -37.525773) (xy 81.706089 -37.463859) (xy 81.698078 -37.400441)
			(xy 78.753398 -37.400441) (xy 78.753526 -37.400674) (xy 78.777058 -37.460107) (xy 78.792955 -37.522021)
			(xy 78.800966 -37.585439) (xy 78.801468 -37.6174) (xy 78.800966 -37.649361) (xy 78.792955 -37.712779)
			(xy 78.777058 -37.774693) (xy 78.753526 -37.834126) (xy 78.722732 -37.890141) (xy 78.685159 -37.941856)
			(xy 78.641402 -37.988453) (xy 78.592149 -38.029198) (xy 78.538178 -38.063449) (xy 78.51718 -38.07333)
			(xy 127.420876 -38.07333) (xy 127.424947 -38.017708) (xy 127.437073 -37.963271) (xy 127.456996 -37.91118)
			(xy 127.484292 -37.862545) (xy 127.518378 -37.818402) (xy 127.558527 -37.779693) (xy 127.603885 -37.747242)
			(xy 127.653485 -37.721741) (xy 127.706269 -37.703734) (xy 127.761112 -37.693604) (xy 127.816846 -37.691567)
			(xy 127.872283 -37.697667) (xy 127.92624 -37.711773) (xy 127.977569 -37.733585) (xy 128.025175 -37.762639)
			(xy 128.068043 -37.798314) (xy 128.10526 -37.839851) (xy 128.136033 -37.886364) (xy 128.137472 -37.889434)
			(xy 130.280154 -37.889434) (xy 130.284225 -37.833812) (xy 130.296351 -37.779375) (xy 130.316274 -37.727284)
			(xy 130.34357 -37.678649) (xy 130.377656 -37.634506) (xy 130.417805 -37.595797) (xy 130.463163 -37.563346)
			(xy 130.512763 -37.537845) (xy 130.565547 -37.519838) (xy 130.62039 -37.509708) (xy 130.676124 -37.507671)
			(xy 130.731561 -37.513771) (xy 130.785518 -37.527877) (xy 130.836847 -37.549689) (xy 130.884453 -37.578743)
			(xy 130.927321 -37.614418) (xy 130.964538 -37.655955) (xy 130.995311 -37.702468) (xy 131.018983 -37.752965)
			(xy 131.035051 -37.806372) (xy 131.043171 -37.861548) (xy 131.04368 -37.889434) (xy 131.043171 -37.91732)
			(xy 131.035051 -37.972496) (xy 131.018983 -38.025903) (xy 130.995311 -38.0764) (xy 130.964538 -38.122913)
			(xy 130.927321 -38.16445) (xy 130.884453 -38.200125) (xy 130.836847 -38.229179) (xy 130.785518 -38.250991)
			(xy 130.731561 -38.265097) (xy 130.676124 -38.271197) (xy 130.62039 -38.26916) (xy 130.565547 -38.25903)
			(xy 130.512763 -38.241023) (xy 130.463163 -38.215522) (xy 130.417805 -38.183071) (xy 130.377656 -38.144362)
			(xy 130.34357 -38.100219) (xy 130.316274 -38.051584) (xy 130.296351 -37.999493) (xy 130.284225 -37.945056)
			(xy 130.280154 -37.889434) (xy 128.137472 -37.889434) (xy 128.159705 -37.936861) (xy 128.175773 -37.990268)
			(xy 128.183893 -38.045444) (xy 128.184402 -38.07333) (xy 128.183893 -38.101216) (xy 128.175773 -38.156392)
			(xy 128.159705 -38.209799) (xy 128.136033 -38.260296) (xy 128.10526 -38.306809) (xy 128.068043 -38.348346)
			(xy 128.025175 -38.384021) (xy 127.977569 -38.413075) (xy 127.92624 -38.434887) (xy 127.872283 -38.448993)
			(xy 127.816846 -38.455093) (xy 127.761112 -38.453056) (xy 127.706269 -38.442926) (xy 127.653485 -38.424919)
			(xy 127.603885 -38.399418) (xy 127.558527 -38.366967) (xy 127.518378 -38.328258) (xy 127.484292 -38.284115)
			(xy 127.456996 -38.23548) (xy 127.437073 -38.183389) (xy 127.424947 -38.128952) (xy 127.420876 -38.07333)
			(xy 78.51718 -38.07333) (xy 78.480339 -38.090666) (xy 78.419546 -38.110419) (xy 78.356756 -38.122397)
			(xy 78.29296 -38.126411) (xy 78.229164 -38.122397) (xy 78.166374 -38.110419) (xy 78.105581 -38.090666)
			(xy 78.047742 -38.063449) (xy 77.993771 -38.029198) (xy 77.944518 -37.988453) (xy 77.900761 -37.941856)
			(xy 77.863188 -37.890141) (xy 77.832394 -37.834126) (xy 77.808862 -37.774693) (xy 77.792965 -37.712779)
			(xy 77.784954 -37.649361) (xy 76.394687 -37.649361) (xy 76.407878 -37.664083) (xy 76.438651 -37.710596)
			(xy 76.462323 -37.761093) (xy 76.478391 -37.8145) (xy 76.486511 -37.869676) (xy 76.48702 -37.897562)
			(xy 76.486511 -37.925448) (xy 76.478391 -37.980624) (xy 76.462323 -38.034031) (xy 76.438651 -38.084528)
			(xy 76.407878 -38.131041) (xy 76.370661 -38.172578) (xy 76.327793 -38.208253) (xy 76.280187 -38.237307)
			(xy 76.228858 -38.259119) (xy 76.174901 -38.273225) (xy 76.119464 -38.279325) (xy 76.06373 -38.277288)
			(xy 76.008887 -38.267158) (xy 75.956103 -38.249151) (xy 75.906503 -38.22365) (xy 75.861145 -38.191199)
			(xy 75.820996 -38.15249) (xy 75.78691 -38.108347) (xy 75.759614 -38.059712) (xy 75.739691 -38.007621)
			(xy 75.727565 -37.953184) (xy 75.723494 -37.897562) (xy 66.376974 -37.897562) (xy 66.409557 -37.910553)
			(xy 66.465864 -37.941754) (xy 66.517781 -37.979815) (xy 66.564476 -38.024127) (xy 66.605203 -38.07398)
			(xy 66.622676 -38.101016) (xy 66.62928 -38.111684) (xy 66.651124 -38.124384) (xy 66.747898 -38.127686)
			(xy 66.760389 -38.127528) (xy 66.782895 -38.116763) (xy 66.790824 -38.107112) (xy 66.790824 -38.106858)
			(xy 66.8088 -38.082939) (xy 66.849469 -38.039048) (xy 66.895008 -38.000234) (xy 66.944788 -37.967032)
			(xy 66.99812 -37.939903) (xy 67.054268 -37.919221) (xy 67.112456 -37.905272) (xy 67.171878 -37.898249)
			(xy 67.201796 -37.897816) (xy 67.23376 -37.898249) (xy 67.297184 -37.906261) (xy 67.359104 -37.922158)
			(xy 67.418543 -37.945692) (xy 67.474563 -37.976489) (xy 67.526282 -38.014065) (xy 67.572884 -38.057826)
			(xy 67.613634 -38.107083) (xy 67.647888 -38.16106) (xy 67.675107 -38.218903) (xy 67.694862 -38.279702)
			(xy 67.706841 -38.342498) (xy 67.710856 -38.4063) (xy 67.706841 -38.470102) (xy 67.694862 -38.532898)
			(xy 67.675107 -38.593697) (xy 67.647888 -38.65154) (xy 67.613634 -38.705517) (xy 67.587982 -38.736524)
			(xy 71.741028 -38.736524) (xy 71.745099 -38.680902) (xy 71.757225 -38.626465) (xy 71.777148 -38.574374)
			(xy 71.804444 -38.525739) (xy 71.83853 -38.481596) (xy 71.878679 -38.442887) (xy 71.924037 -38.410436)
			(xy 71.973637 -38.384935) (xy 72.026421 -38.366928) (xy 72.081264 -38.356798) (xy 72.136998 -38.354761)
			(xy 72.192435 -38.360861) (xy 72.246392 -38.374967) (xy 72.297721 -38.396779) (xy 72.345327 -38.425833)
			(xy 72.388195 -38.461508) (xy 72.425412 -38.503045) (xy 72.456185 -38.549558) (xy 72.479857 -38.600055)
			(xy 72.495925 -38.653462) (xy 72.504045 -38.708638) (xy 72.504554 -38.736524) (xy 72.504045 -38.76441)
			(xy 72.495925 -38.819586) (xy 72.479857 -38.872993) (xy 72.456185 -38.92349) (xy 72.425412 -38.970003)
			(xy 72.388195 -39.01154) (xy 72.345327 -39.047215) (xy 72.30795 -39.070026) (xy 74.434444 -39.070026)
			(xy 74.438515 -39.014404) (xy 74.450641 -38.959967) (xy 74.470564 -38.907876) (xy 74.49786 -38.859241)
			(xy 74.531946 -38.815098) (xy 74.572095 -38.776389) (xy 74.617453 -38.743938) (xy 74.667053 -38.718437)
			(xy 74.719837 -38.70043) (xy 74.77468 -38.6903) (xy 74.830414 -38.688263) (xy 74.885851 -38.694363)
			(xy 74.939808 -38.708469) (xy 74.991137 -38.730281) (xy 75.038743 -38.759335) (xy 75.081611 -38.79501)
			(xy 75.118828 -38.836547) (xy 75.149601 -38.88306) (xy 75.173273 -38.933557) (xy 75.189341 -38.986964)
			(xy 75.197461 -39.04214) (xy 75.19797 -39.070026) (xy 75.197461 -39.097912) (xy 75.189341 -39.153088)
			(xy 75.173273 -39.206495) (xy 75.149601 -39.256992) (xy 75.118828 -39.303505) (xy 75.081611 -39.345042)
			(xy 75.038743 -39.380717) (xy 74.991137 -39.409771) (xy 74.939808 -39.431583) (xy 74.885851 -39.445689)
			(xy 74.830414 -39.451789) (xy 74.77468 -39.449752) (xy 74.719837 -39.439622) (xy 74.667053 -39.421615)
			(xy 74.617453 -39.396114) (xy 74.572095 -39.363663) (xy 74.531946 -39.324954) (xy 74.49786 -39.280811)
			(xy 74.470564 -39.232176) (xy 74.450641 -39.180085) (xy 74.438515 -39.125648) (xy 74.434444 -39.070026)
			(xy 72.30795 -39.070026) (xy 72.297721 -39.076269) (xy 72.246392 -39.098081) (xy 72.192435 -39.112187)
			(xy 72.136998 -39.118287) (xy 72.081264 -39.11625) (xy 72.026421 -39.10612) (xy 71.973637 -39.088113)
			(xy 71.924037 -39.062612) (xy 71.878679 -39.030161) (xy 71.83853 -38.991452) (xy 71.804444 -38.947309)
			(xy 71.777148 -38.898674) (xy 71.757225 -38.846583) (xy 71.745099 -38.792146) (xy 71.741028 -38.736524)
			(xy 67.587982 -38.736524) (xy 67.572884 -38.754774) (xy 67.526282 -38.798535) (xy 67.474563 -38.836111)
			(xy 67.418543 -38.866908) (xy 67.359104 -38.890442) (xy 67.297184 -38.906339) (xy 67.23376 -38.914351)
			(xy 67.201796 -38.914832) (xy 67.169609 -38.914324) (xy 67.105748 -38.906221) (xy 67.04342 -38.890119)
			(xy 66.983625 -38.866277) (xy 66.927318 -38.835076) (xy 66.875401 -38.797016) (xy 66.828705 -38.752705)
			(xy 66.787978 -38.702853) (xy 66.770504 -38.675818) (xy 66.7639 -38.66515) (xy 66.742056 -38.65245)
			(xy 66.645282 -38.649148) (xy 66.632788 -38.649281) (xy 66.610281 -38.660063) (xy 66.602356 -38.669722)
			(xy 66.602356 -38.669976) (xy 66.584402 -38.693912) (xy 66.543729 -38.737801) (xy 66.498186 -38.776614)
			(xy 66.448403 -38.809812) (xy 66.395067 -38.836939) (xy 66.338917 -38.857619) (xy 66.280727 -38.871565)
			(xy 66.221303 -38.878586) (xy 66.191384 -38.879018) (xy 66.159424 -38.878495) (xy 66.096009 -38.870482)
			(xy 66.034098 -38.854584) (xy 65.974668 -38.831053) (xy 65.918655 -38.800258) (xy 65.866944 -38.762686)
			(xy 65.820349 -38.718929) (xy 65.779606 -38.669678) (xy 65.745357 -38.615708) (xy 65.718142 -38.557872)
			(xy 65.69839 -38.497081) (xy 65.686413 -38.434293) (xy 65.682399 -38.3705) (xy 61.857303 -38.3705)
			(xy 61.879421 -38.417683) (xy 61.895489 -38.47109) (xy 61.903609 -38.526266) (xy 61.904118 -38.554152)
			(xy 61.903609 -38.582038) (xy 61.895489 -38.637214) (xy 61.879421 -38.690621) (xy 61.855749 -38.741118)
			(xy 61.827196 -38.784276) (xy 63.050672 -38.784276) (xy 63.054743 -38.728654) (xy 63.066869 -38.674217)
			(xy 63.086792 -38.622126) (xy 63.114088 -38.573491) (xy 63.148174 -38.529348) (xy 63.188323 -38.490639)
			(xy 63.233681 -38.458188) (xy 63.283281 -38.432687) (xy 63.336065 -38.41468) (xy 63.390908 -38.40455)
			(xy 63.446642 -38.402513) (xy 63.502079 -38.408613) (xy 63.556036 -38.422719) (xy 63.607365 -38.444531)
			(xy 63.654971 -38.473585) (xy 63.697839 -38.50926) (xy 63.735056 -38.550797) (xy 63.765829 -38.59731)
			(xy 63.789501 -38.647807) (xy 63.805569 -38.701214) (xy 63.813689 -38.75639) (xy 63.814198 -38.784276)
			(xy 63.813689 -38.812162) (xy 63.805569 -38.867338) (xy 63.789501 -38.920745) (xy 63.765829 -38.971242)
			(xy 63.735056 -39.017755) (xy 63.697839 -39.059292) (xy 63.654971 -39.094967) (xy 63.607365 -39.124021)
			(xy 63.556036 -39.145833) (xy 63.502079 -39.159939) (xy 63.446642 -39.166039) (xy 63.390908 -39.164002)
			(xy 63.336065 -39.153872) (xy 63.283281 -39.135865) (xy 63.233681 -39.110364) (xy 63.188323 -39.077913)
			(xy 63.148174 -39.039204) (xy 63.114088 -38.995061) (xy 63.086792 -38.946426) (xy 63.066869 -38.894335)
			(xy 63.054743 -38.839898) (xy 63.050672 -38.784276) (xy 61.827196 -38.784276) (xy 61.824976 -38.787631)
			(xy 61.787759 -38.829168) (xy 61.744891 -38.864843) (xy 61.697285 -38.893897) (xy 61.645956 -38.915709)
			(xy 61.591999 -38.929815) (xy 61.536562 -38.935915) (xy 61.480828 -38.933878) (xy 61.425985 -38.923748)
			(xy 61.373201 -38.905741) (xy 61.323601 -38.88024) (xy 61.278243 -38.847789) (xy 61.238094 -38.80908)
			(xy 61.204008 -38.764937) (xy 61.176712 -38.716302) (xy 61.156789 -38.664211) (xy 61.144663 -38.609774)
			(xy 61.140592 -38.554152) (xy 60.475786 -38.554152) (xy 60.478422 -38.575023) (xy 60.478924 -38.606984)
			(xy 60.478422 -38.638945) (xy 60.470411 -38.702363) (xy 60.454514 -38.764277) (xy 60.430982 -38.82371)
			(xy 60.400188 -38.879725) (xy 60.362615 -38.93144) (xy 60.318858 -38.978037) (xy 60.269605 -39.018782)
			(xy 60.215634 -39.053033) (xy 60.157795 -39.08025) (xy 60.097002 -39.100003) (xy 60.034212 -39.111981)
			(xy 59.970416 -39.115995) (xy 59.90662 -39.111981) (xy 59.84383 -39.100003) (xy 59.783037 -39.08025)
			(xy 59.725198 -39.053033) (xy 59.671227 -39.018782) (xy 59.621974 -38.978037) (xy 59.578217 -38.93144)
			(xy 59.540644 -38.879725) (xy 59.50985 -38.82371) (xy 59.486318 -38.764277) (xy 59.470421 -38.702363)
			(xy 59.46241 -38.638945) (xy 46.293532 -38.638945) (xy 46.293532 -39.851768) (xy 64.453004 -39.851768)
			(xy 64.453004 -39.767072) (xy 64.461055 -39.682758) (xy 64.477084 -39.599592) (xy 64.500945 -39.518325)
			(xy 64.532424 -39.439695) (xy 64.571235 -39.364414) (xy 64.617025 -39.293162) (xy 64.669381 -39.226586)
			(xy 64.727829 -39.165288) (xy 64.791839 -39.109823) (xy 64.860831 -39.060694) (xy 64.934181 -39.018345)
			(xy 65.011224 -38.983161) (xy 65.091263 -38.955459) (xy 65.173572 -38.935491) (xy 65.257407 -38.923438)
			(xy 65.342008 -38.919408) (xy 65.426609 -38.923438) (xy 65.510444 -38.935491) (xy 65.592753 -38.955459)
			(xy 65.672792 -38.983161) (xy 65.749835 -39.018345) (xy 65.823185 -39.060694) (xy 65.892177 -39.109823)
			(xy 65.956187 -39.165288) (xy 66.014635 -39.226586) (xy 66.066991 -39.293162) (xy 66.112781 -39.364414)
			(xy 66.142636 -39.422324) (xy 66.819778 -39.422324) (xy 66.823849 -39.366702) (xy 66.835975 -39.312265)
			(xy 66.855898 -39.260174) (xy 66.883194 -39.211539) (xy 66.91728 -39.167396) (xy 66.957429 -39.128687)
			(xy 67.002787 -39.096236) (xy 67.052387 -39.070735) (xy 67.105171 -39.052728) (xy 67.160014 -39.042598)
			(xy 67.215748 -39.040561) (xy 67.271185 -39.046661) (xy 67.325142 -39.060767) (xy 67.376471 -39.082579)
			(xy 67.424077 -39.111633) (xy 67.466945 -39.147308) (xy 67.504162 -39.188845) (xy 67.534935 -39.235358)
			(xy 67.558607 -39.285855) (xy 67.574675 -39.339262) (xy 67.582795 -39.394438) (xy 67.583304 -39.422324)
			(xy 67.582795 -39.45021) (xy 67.574675 -39.505386) (xy 67.558607 -39.558793) (xy 67.534935 -39.60929)
			(xy 67.504162 -39.655803) (xy 67.466945 -39.69734) (xy 67.424077 -39.733015) (xy 67.376471 -39.762069)
			(xy 67.325142 -39.783881) (xy 67.271185 -39.797987) (xy 67.215748 -39.804087) (xy 67.160014 -39.80205)
			(xy 67.105171 -39.79192) (xy 67.052387 -39.773913) (xy 67.002787 -39.748412) (xy 66.957429 -39.715961)
			(xy 66.91728 -39.677252) (xy 66.883194 -39.633109) (xy 66.855898 -39.584474) (xy 66.835975 -39.532383)
			(xy 66.823849 -39.477946) (xy 66.819778 -39.422324) (xy 66.142636 -39.422324) (xy 66.151592 -39.439695)
			(xy 66.183071 -39.518325) (xy 66.206932 -39.599592) (xy 66.222961 -39.682758) (xy 66.231012 -39.767072)
			(xy 66.231516 -39.80942) (xy 66.231012 -39.851768) (xy 66.226931 -39.89451) (xy 72.901046 -39.89451)
			(xy 72.905117 -39.838888) (xy 72.917243 -39.784451) (xy 72.937166 -39.73236) (xy 72.964462 -39.683725)
			(xy 72.998548 -39.639582) (xy 73.038697 -39.600873) (xy 73.084055 -39.568422) (xy 73.133655 -39.542921)
			(xy 73.186439 -39.524914) (xy 73.241282 -39.514784) (xy 73.297016 -39.512747) (xy 73.352453 -39.518847)
			(xy 73.40641 -39.532953) (xy 73.457739 -39.554765) (xy 73.505345 -39.583819) (xy 73.548213 -39.619494)
			(xy 73.58543 -39.661031) (xy 73.616203 -39.707544) (xy 73.639875 -39.758041) (xy 73.655943 -39.811448)
			(xy 73.664063 -39.866624) (xy 73.664572 -39.89451) (xy 73.664063 -39.922396) (xy 73.655943 -39.977572)
			(xy 73.639875 -40.030979) (xy 73.616203 -40.081476) (xy 73.58543 -40.127989) (xy 73.548213 -40.169526)
			(xy 73.505345 -40.205201) (xy 73.457739 -40.234255) (xy 73.40641 -40.256067) (xy 73.352453 -40.270173)
			(xy 73.297016 -40.276273) (xy 73.241282 -40.274236) (xy 73.186439 -40.264106) (xy 73.133655 -40.246099)
			(xy 73.084055 -40.220598) (xy 73.038697 -40.188147) (xy 72.998548 -40.149438) (xy 72.964462 -40.105295)
			(xy 72.937166 -40.05666) (xy 72.917243 -40.004569) (xy 72.905117 -39.950132) (xy 72.901046 -39.89451)
			(xy 66.226931 -39.89451) (xy 66.222961 -39.936082) (xy 66.206932 -40.019248) (xy 66.183071 -40.100515)
			(xy 66.151592 -40.179145) (xy 66.112781 -40.254426) (xy 66.066991 -40.325678) (xy 66.014635 -40.392254)
			(xy 65.956187 -40.453552) (xy 65.892177 -40.509017) (xy 65.823185 -40.558146) (xy 65.749835 -40.600495)
			(xy 65.672792 -40.635679) (xy 65.592753 -40.663381) (xy 65.510444 -40.683349) (xy 65.426609 -40.695402)
			(xy 65.342008 -40.699433) (xy 65.257407 -40.695402) (xy 65.173572 -40.683349) (xy 65.091263 -40.663381)
			(xy 65.011224 -40.635679) (xy 64.934181 -40.600495) (xy 64.860831 -40.558146) (xy 64.791839 -40.509017)
			(xy 64.727829 -40.453552) (xy 64.669381 -40.392254) (xy 64.617025 -40.325678) (xy 64.571235 -40.254426)
			(xy 64.532424 -40.179145) (xy 64.500945 -40.100515) (xy 64.477084 -40.019248) (xy 64.461055 -39.936082)
			(xy 64.453004 -39.851768) (xy 46.293532 -39.851768) (xy 46.293532 -39.981632) (xy 46.294548 -39.991284)
			(xy 46.298104 -40.002714) (xy 46.304454 -40.016684) (xy 46.309788 -40.02532) (xy 46.316138 -40.033956)
			(xy 46.322742 -40.041322) (xy 46.346468 -40.063622) (xy 46.388629 -40.113243) (xy 46.424107 -40.167842)
			(xy 46.452321 -40.226525) (xy 46.47281 -40.288331) (xy 46.485237 -40.352248) (xy 46.4894 -40.417228)
			(xy 46.48523 -40.482208) (xy 46.472795 -40.546123) (xy 46.4523 -40.607927) (xy 46.436875 -40.64)
			(xy 56.005982 -40.64) (xy 56.010053 -40.584378) (xy 56.022179 -40.529941) (xy 56.042102 -40.47785)
			(xy 56.069398 -40.429215) (xy 56.103484 -40.385072) (xy 56.143633 -40.346363) (xy 56.188991 -40.313912)
			(xy 56.238591 -40.288411) (xy 56.291375 -40.270404) (xy 56.346218 -40.260274) (xy 56.401952 -40.258237)
			(xy 56.457389 -40.264337) (xy 56.511346 -40.278443) (xy 56.562675 -40.300255) (xy 56.610281 -40.329309)
			(xy 56.653149 -40.364984) (xy 56.690366 -40.406521) (xy 56.721139 -40.453034) (xy 56.744811 -40.503531)
			(xy 56.760879 -40.556938) (xy 56.766779 -40.597031) (xy 61.845438 -40.597031) (xy 61.845438 -40.533109)
			(xy 61.853449 -40.469691) (xy 61.869346 -40.407777) (xy 61.892878 -40.348344) (xy 61.923672 -40.292329)
			(xy 61.961245 -40.240614) (xy 62.005002 -40.194017) (xy 62.054255 -40.153272) (xy 62.108226 -40.119021)
			(xy 62.166065 -40.091804) (xy 62.226858 -40.072051) (xy 62.289648 -40.060073) (xy 62.353444 -40.05606)
			(xy 62.41724 -40.060073) (xy 62.48003 -40.072051) (xy 62.540823 -40.091804) (xy 62.598662 -40.119021)
			(xy 62.652633 -40.153272) (xy 62.701886 -40.194017) (xy 62.745643 -40.240614) (xy 62.783216 -40.292329)
			(xy 62.81401 -40.348344) (xy 62.837542 -40.407777) (xy 62.853439 -40.469691) (xy 62.86145 -40.533109)
			(xy 62.861952 -40.56507) (xy 62.86145 -40.597031) (xy 62.853439 -40.660449) (xy 62.837542 -40.722363)
			(xy 62.81401 -40.781796) (xy 62.783216 -40.837811) (xy 62.745643 -40.889526) (xy 62.727469 -40.90888)
			(xy 66.166098 -40.90888) (xy 66.171307 -40.846014) (xy 66.184253 -40.784274) (xy 66.204736 -40.72461)
			(xy 66.232441 -40.667938) (xy 66.266944 -40.615128) (xy 66.307714 -40.566991) (xy 66.354125 -40.524266)
			(xy 66.405464 -40.487611) (xy 66.460943 -40.457587) (xy 66.51971 -40.434656) (xy 66.580861 -40.41917)
			(xy 66.643459 -40.411368) (xy 66.675 -40.410892) (xy 66.687595 -40.410978) (xy 66.712753 -40.412249)
			(xy 66.725292 -40.413432) (xy 66.734211 -40.413966) (xy 66.751512 -40.409554) (xy 66.759074 -40.404796)
			(xy 66.820796 -40.362378) (xy 66.83121 -40.347392) (xy 66.833496 -40.338756) (xy 66.841174 -40.312126)
			(xy 66.863235 -40.261285) (xy 66.892418 -40.21417) (xy 66.928111 -40.171772) (xy 66.969561 -40.134984)
			(xy 67.015898 -40.104579) (xy 67.066146 -40.081197) (xy 67.119247 -40.06533) (xy 67.174085 -40.057312)
			(xy 67.201796 -40.056816) (xy 67.22905 -40.057259) (xy 67.283003 -40.065016) (xy 67.335302 -40.080373)
			(xy 67.384884 -40.103017) (xy 67.430738 -40.132487) (xy 67.471932 -40.168182) (xy 67.507625 -40.209378)
			(xy 67.537093 -40.255233) (xy 67.559734 -40.304816) (xy 67.561638 -40.3113) (xy 74.795413 -40.3113)
			(xy 74.799427 -40.247507) (xy 74.811404 -40.184721) (xy 74.831156 -40.12393) (xy 74.858371 -40.066095)
			(xy 74.89262 -40.012127) (xy 74.933363 -39.962876) (xy 74.979958 -39.919121) (xy 75.031669 -39.88155)
			(xy 75.087681 -39.850756) (xy 75.147111 -39.827226) (xy 75.209022 -39.81133) (xy 75.272437 -39.803318)
			(xy 75.304396 -39.802816) (xy 75.337952 -39.803401) (xy 75.40448 -39.812239) (xy 75.469268 -39.82975)
			(xy 75.531191 -39.855629) (xy 75.589172 -39.889427) (xy 75.642204 -39.930557) (xy 75.689368 -39.978303)
			(xy 75.710034 -40.004746) (xy 75.71671 -40.012731) (xy 75.734801 -40.022973) (xy 75.745086 -40.024558)
			(xy 75.818492 -40.03294) (xy 75.828916 -40.033571) (xy 75.848846 -40.0274) (xy 75.8571 -40.021002)
			(xy 75.877896 -40.003879) (xy 75.923392 -39.975035) (xy 75.972496 -39.952883) (xy 76.024229 -39.937866)
			(xy 76.077562 -39.930281) (xy 76.104496 -39.929816) (xy 76.131751 -39.930231) (xy 76.185706 -39.937988)
			(xy 76.238007 -39.953344) (xy 76.287591 -39.975988) (xy 76.333448 -40.005458) (xy 76.374643 -40.041154)
			(xy 76.41034 -40.082349) (xy 76.43981 -40.128205) (xy 76.462454 -40.177789) (xy 76.477812 -40.23009)
			(xy 76.485569 -40.284045) (xy 76.485569 -40.338555) (xy 76.477812 -40.39251) (xy 76.462454 -40.444811)
			(xy 76.43981 -40.494395) (xy 76.41034 -40.540251) (xy 76.374643 -40.581446) (xy 76.333448 -40.617142)
			(xy 76.287591 -40.646612) (xy 76.238007 -40.669256) (xy 76.233838 -40.67048) (xy 81.697576 -40.67048)
			(xy 81.698083 -40.639193) (xy 81.705756 -40.577093) (xy 81.720995 -40.516404) (xy 81.743571 -40.458045)
			(xy 81.773141 -40.4029) (xy 81.809257 -40.351802) (xy 81.851375 -40.305526) (xy 81.898855 -40.264771)
			(xy 81.924652 -40.247062) (xy 81.9348 -40.239536) (xy 81.946663 -40.217265) (xy 81.947258 -40.204644)
			(xy 81.947258 -40.120316) (xy 81.946615 -40.10771) (xy 81.934756 -40.085463) (xy 81.924652 -40.077898)
			(xy 81.898846 -40.060208) (xy 81.851384 -40.019439) (xy 81.809283 -39.973154) (xy 81.77318 -39.922053)
			(xy 81.743621 -39.866908) (xy 81.721052 -39.808552) (xy 81.705814 -39.747868) (xy 81.698137 -39.685773)
			(xy 81.698139 -39.623205) (xy 81.705818 -39.56111) (xy 81.721058 -39.500427) (xy 81.74363 -39.442072)
			(xy 81.773192 -39.386928) (xy 81.809297 -39.335828) (xy 81.8514 -39.289545) (xy 81.898864 -39.248779)
			(xy 81.924652 -39.231062) (xy 81.9348 -39.223536) (xy 81.946663 -39.201265) (xy 81.947258 -39.188644)
			(xy 81.947258 -39.104316) (xy 81.946615 -39.09171) (xy 81.934756 -39.069463) (xy 81.924652 -39.061898)
			(xy 81.898841 -39.044208) (xy 81.851362 -39.003448) (xy 81.809245 -38.957168) (xy 81.773127 -38.906068)
			(xy 81.743556 -38.850921) (xy 81.720977 -38.792561) (xy 81.705733 -38.73187) (xy 81.698055 -38.669768)
			(xy 81.697576 -38.63848) (xy 81.698078 -38.606519) (xy 81.706089 -38.543101) (xy 81.721986 -38.481187)
			(xy 81.745518 -38.421754) (xy 81.776312 -38.365739) (xy 81.813885 -38.314024) (xy 81.857642 -38.267427)
			(xy 81.906895 -38.226682) (xy 81.960866 -38.192431) (xy 82.018705 -38.165214) (xy 82.079498 -38.145461)
			(xy 82.142288 -38.133483) (xy 82.206084 -38.12947) (xy 82.26988 -38.133483) (xy 82.33267 -38.145461)
			(xy 82.393463 -38.165214) (xy 82.451302 -38.192431) (xy 82.505273 -38.226682) (xy 82.554526 -38.267427)
			(xy 82.598283 -38.314024) (xy 82.635856 -38.365739) (xy 82.66665 -38.421754) (xy 82.690182 -38.481187)
			(xy 82.706079 -38.543101) (xy 82.71409 -38.606519) (xy 82.714592 -38.63848) (xy 82.714146 -38.669768)
			(xy 82.709099 -38.710573) (xy 103.277156 -38.710573) (xy 103.277156 -38.646651) (xy 103.285167 -38.583233)
			(xy 103.301064 -38.521319) (xy 103.324596 -38.461886) (xy 103.35539 -38.405871) (xy 103.392963 -38.354156)
			(xy 103.43672 -38.307559) (xy 103.485973 -38.266814) (xy 103.539944 -38.232563) (xy 103.597783 -38.205346)
			(xy 103.658576 -38.185593) (xy 103.721366 -38.173615) (xy 103.785162 -38.169602) (xy 103.848958 -38.173615)
			(xy 103.911748 -38.185593) (xy 103.972541 -38.205346) (xy 104.03038 -38.232563) (xy 104.084351 -38.266814)
			(xy 104.133604 -38.307559) (xy 104.177361 -38.354156) (xy 104.214934 -38.405871) (xy 104.245728 -38.461886)
			(xy 104.26926 -38.521319) (xy 104.285157 -38.583233) (xy 104.293168 -38.646651) (xy 104.29367 -38.678612)
			(xy 104.293168 -38.710573) (xy 104.285157 -38.773991) (xy 104.26926 -38.835905) (xy 104.245728 -38.895338)
			(xy 104.214934 -38.951353) (xy 104.177361 -39.003068) (xy 104.133604 -39.049665) (xy 104.084351 -39.09041)
			(xy 104.03038 -39.124661) (xy 103.972541 -39.151878) (xy 103.911748 -39.171631) (xy 103.848958 -39.183609)
			(xy 103.785162 -39.187623) (xy 103.721366 -39.183609) (xy 103.658576 -39.171631) (xy 103.597783 -39.151878)
			(xy 103.539944 -39.124661) (xy 103.485973 -39.09041) (xy 103.43672 -39.049665) (xy 103.392963 -39.003068)
			(xy 103.35539 -38.951353) (xy 103.324596 -38.895338) (xy 103.301064 -38.835905) (xy 103.285167 -38.773991)
			(xy 103.277156 -38.710573) (xy 82.709099 -38.710573) (xy 82.706465 -38.731872) (xy 82.691217 -38.792563)
			(xy 82.668633 -38.850923) (xy 82.639055 -38.906068) (xy 82.60293 -38.957165) (xy 82.560805 -39.003439)
			(xy 82.513317 -39.044191) (xy 82.487516 -39.061898) (xy 82.47738 -39.069437) (xy 82.465513 -39.091699)
			(xy 82.46491 -39.104316) (xy 82.46491 -39.188644) (xy 82.465589 -39.201244) (xy 82.477423 -39.223492)
			(xy 82.487516 -39.231062) (xy 82.513286 -39.248804) (xy 82.560749 -39.289567) (xy 82.602852 -39.335846)
			(xy 82.638957 -39.386942) (xy 82.668519 -39.442083) (xy 82.691091 -39.500434) (xy 82.706331 -39.561114)
			(xy 82.71401 -39.623206) (xy 82.714012 -39.685771) (xy 82.706335 -39.747864) (xy 82.691097 -39.808545)
			(xy 82.668528 -39.866897) (xy 82.638968 -39.922039) (xy 82.602866 -39.973137) (xy 82.560765 -40.019418)
			(xy 82.513303 -40.060182) (xy 82.487516 -40.077898) (xy 82.47738 -40.085437) (xy 82.465513 -40.107699)
			(xy 82.46491 -40.120316) (xy 82.46491 -40.204644) (xy 82.465589 -40.217244) (xy 82.477423 -40.239492)
			(xy 82.487516 -40.247062) (xy 82.513324 -40.264755) (xy 82.5608 -40.305517) (xy 82.602915 -40.351798)
			(xy 82.639031 -40.402898) (xy 82.666178 -40.453521) (xy 103.804206 -40.453521) (xy 103.804206 -40.389599)
			(xy 103.812217 -40.326181) (xy 103.828114 -40.264267) (xy 103.851646 -40.204834) (xy 103.88244 -40.148819)
			(xy 103.920013 -40.097104) (xy 103.96377 -40.050507) (xy 104.013023 -40.009762) (xy 104.066994 -39.975511)
			(xy 104.124833 -39.948294) (xy 104.185626 -39.928541) (xy 104.248416 -39.916563) (xy 104.312212 -39.91255)
			(xy 104.376008 -39.916563) (xy 104.438798 -39.928541) (xy 104.499591 -39.948294) (xy 104.55743 -39.975511)
			(xy 104.611401 -40.009762) (xy 104.660654 -40.050507) (xy 104.704411 -40.097104) (xy 104.741984 -40.148819)
			(xy 104.772778 -40.204834) (xy 104.79631 -40.264267) (xy 104.809294 -40.314837) (xy 110.262156 -40.314837)
			(xy 110.262156 -40.250915) (xy 110.270167 -40.187497) (xy 110.286064 -40.125583) (xy 110.309596 -40.06615)
			(xy 110.34039 -40.010135) (xy 110.377963 -39.95842) (xy 110.42172 -39.911823) (xy 110.470973 -39.871078)
			(xy 110.524944 -39.836827) (xy 110.582783 -39.80961) (xy 110.643576 -39.789857) (xy 110.706366 -39.777879)
			(xy 110.770162 -39.773866) (xy 110.833958 -39.777879) (xy 110.896748 -39.789857) (xy 110.957541 -39.80961)
			(xy 111.01538 -39.836827) (xy 111.069351 -39.871078) (xy 111.118604 -39.911823) (xy 111.162361 -39.95842)
			(xy 111.199934 -40.010135) (xy 111.230728 -40.06615) (xy 111.25426 -40.125583) (xy 111.270157 -40.187497)
			(xy 111.278168 -40.250915) (xy 111.27867 -40.282876) (xy 111.278168 -40.314837) (xy 111.276082 -40.331347)
			(xy 113.293646 -40.331347) (xy 113.293646 -40.267425) (xy 113.301657 -40.204007) (xy 113.317554 -40.142093)
			(xy 113.341086 -40.08266) (xy 113.37188 -40.026645) (xy 113.409453 -39.97493) (xy 113.45321 -39.928333)
			(xy 113.502463 -39.887588) (xy 113.556434 -39.853337) (xy 113.614273 -39.82612) (xy 113.675066 -39.806367)
			(xy 113.737856 -39.794389) (xy 113.801652 -39.790376) (xy 113.865448 -39.794389) (xy 113.928238 -39.806367)
			(xy 113.989031 -39.82612) (xy 114.04687 -39.853337) (xy 114.100841 -39.887588) (xy 114.150094 -39.928333)
			(xy 114.193851 -39.97493) (xy 114.231424 -40.026645) (xy 114.262218 -40.08266) (xy 114.28575 -40.142093)
			(xy 114.301647 -40.204007) (xy 114.309658 -40.267425) (xy 114.31016 -40.299386) (xy 114.309658 -40.331347)
			(xy 114.301647 -40.394765) (xy 114.28575 -40.456679) (xy 114.262218 -40.516112) (xy 114.231424 -40.572127)
			(xy 114.193851 -40.623842) (xy 114.150094 -40.670439) (xy 114.100841 -40.711184) (xy 114.04687 -40.745435)
			(xy 113.989031 -40.772652) (xy 113.928238 -40.792405) (xy 113.865448 -40.804383) (xy 113.801652 -40.808397)
			(xy 113.737856 -40.804383) (xy 113.675066 -40.792405) (xy 113.614273 -40.772652) (xy 113.556434 -40.745435)
			(xy 113.502463 -40.711184) (xy 113.45321 -40.670439) (xy 113.409453 -40.623842) (xy 113.37188 -40.572127)
			(xy 113.341086 -40.516112) (xy 113.317554 -40.456679) (xy 113.301657 -40.394765) (xy 113.293646 -40.331347)
			(xy 111.276082 -40.331347) (xy 111.270157 -40.378255) (xy 111.25426 -40.440169) (xy 111.230728 -40.499602)
			(xy 111.199934 -40.555617) (xy 111.162361 -40.607332) (xy 111.118604 -40.653929) (xy 111.069351 -40.694674)
			(xy 111.01538 -40.728925) (xy 110.957541 -40.756142) (xy 110.896748 -40.775895) (xy 110.833958 -40.787873)
			(xy 110.770162 -40.791887) (xy 110.706366 -40.787873) (xy 110.643576 -40.775895) (xy 110.582783 -40.756142)
			(xy 110.524944 -40.728925) (xy 110.470973 -40.694674) (xy 110.42172 -40.653929) (xy 110.377963 -40.607332)
			(xy 110.34039 -40.555617) (xy 110.309596 -40.499602) (xy 110.286064 -40.440169) (xy 110.270167 -40.378255)
			(xy 110.262156 -40.314837) (xy 104.809294 -40.314837) (xy 104.812207 -40.326181) (xy 104.820218 -40.389599)
			(xy 104.82072 -40.42156) (xy 104.820218 -40.453521) (xy 104.812207 -40.516939) (xy 104.79631 -40.578853)
			(xy 104.772778 -40.638286) (xy 104.741984 -40.694301) (xy 104.704411 -40.746016) (xy 104.660654 -40.792613)
			(xy 104.611401 -40.833358) (xy 104.55743 -40.867609) (xy 104.504585 -40.892476) (xy 124.633482 -40.892476)
			(xy 124.63393 -40.861749) (xy 124.641347 -40.800743) (xy 124.656057 -40.741075) (xy 124.677847 -40.683614)
			(xy 124.706399 -40.629195) (xy 124.741298 -40.578611) (xy 124.782036 -40.532598) (xy 124.828018 -40.491827)
			(xy 124.878577 -40.456892) (xy 124.932975 -40.4283) (xy 124.990421 -40.406468) (xy 125.050078 -40.391714)
			(xy 125.080522 -40.387524) (xy 125.089412 -40.386115) (xy 125.105421 -40.377909) (xy 125.111764 -40.371522)
			(xy 125.132338 -40.34917) (xy 125.138076 -40.342381) (xy 125.14497 -40.326015) (xy 125.1458 -40.317166)
			(xy 125.147407 -40.29078) (xy 125.157162 -40.238823) (xy 125.174 -40.188711) (xy 125.197596 -40.141405)
			(xy 125.2275 -40.09781) (xy 125.263137 -40.058763) (xy 125.303826 -40.025012) (xy 125.348786 -39.997204)
			(xy 125.397155 -39.975871) (xy 125.448007 -39.961423) (xy 125.500367 -39.954135) (xy 125.5268 -39.953692)
			(xy 125.556168 -39.954215) (xy 125.614205 -39.963241) (xy 125.670172 -39.981064) (xy 125.722741 -40.007262)
			(xy 125.747018 -40.023796) (xy 125.747272 -40.023796) (xy 125.755138 -40.028785) (xy 125.773197 -40.03329)
			(xy 125.791676 -40.031066) (xy 125.800104 -40.027098) (xy 125.893322 -39.977822) (xy 125.907546 -39.953184)
			(xy 125.907292 -39.938706) (xy 125.907292 -39.9288) (xy 125.907756 -39.898069) (xy 125.915165 -39.837055)
			(xy 125.929873 -39.777379) (xy 125.951668 -39.719911) (xy 125.980231 -39.665489) (xy 126.015145 -39.614907)
			(xy 126.055902 -39.568902) (xy 126.101907 -39.528145) (xy 126.152489 -39.493231) (xy 126.206911 -39.464668)
			(xy 126.264379 -39.442873) (xy 126.324055 -39.428165) (xy 126.385069 -39.420756) (xy 126.4158 -39.420292)
			(xy 126.448849 -39.420835) (xy 126.51439 -39.429394) (xy 126.578267 -39.446379) (xy 126.639403 -39.471504)
			(xy 126.696764 -39.504345) (xy 126.723394 -39.523924) (xy 126.730561 -39.528911) (xy 126.747176 -39.534236)
			(xy 126.755906 -39.534338) (xy 126.785878 -39.533068) (xy 126.79458 -39.53244) (xy 126.81081 -39.526067)
			(xy 126.817628 -39.520622) (xy 126.840845 -39.500898) (xy 126.89117 -39.466563) (xy 126.945236 -39.438485)
			(xy 127.00227 -39.417068) (xy 127.061453 -39.402617) (xy 127.121939 -39.395339) (xy 127.1524 -39.394892)
			(xy 127.186436 -39.395908) (xy 127.197104 -39.39667) (xy 127.21717 -39.389304) (xy 127.28702 -39.32174)
			(xy 127.294894 -39.301928) (xy 127.29464 -39.29126) (xy 127.294386 -39.27348) (xy 127.294889 -39.24194)
			(xy 127.302694 -39.179346) (xy 127.318181 -39.118197) (xy 127.341113 -39.059434) (xy 127.371137 -39.003959)
			(xy 127.407793 -38.952623) (xy 127.450517 -38.906216) (xy 127.498653 -38.865449) (xy 127.551462 -38.83095)
			(xy 127.608133 -38.803248) (xy 127.667795 -38.782768) (xy 127.729532 -38.769825) (xy 127.792396 -38.764618)
			(xy 127.855421 -38.767227) (xy 127.91764 -38.777611) (xy 127.978096 -38.795611) (xy 128.035862 -38.820952)
			(xy 128.09005 -38.853242) (xy 128.139827 -38.891988) (xy 128.153272 -38.905434) (xy 130.280154 -38.905434)
			(xy 130.284225 -38.849812) (xy 130.296351 -38.795375) (xy 130.316274 -38.743284) (xy 130.34357 -38.694649)
			(xy 130.377656 -38.650506) (xy 130.417805 -38.611797) (xy 130.463163 -38.579346) (xy 130.512763 -38.553845)
			(xy 130.565547 -38.535838) (xy 130.62039 -38.525708) (xy 130.676124 -38.523671) (xy 130.731561 -38.529771)
			(xy 130.785518 -38.543877) (xy 130.836847 -38.565689) (xy 130.884453 -38.594743) (xy 130.927321 -38.630418)
			(xy 130.964538 -38.671955) (xy 130.995311 -38.718468) (xy 131.018983 -38.768965) (xy 131.035051 -38.822372)
			(xy 131.043171 -38.877548) (xy 131.04368 -38.905434) (xy 132.312154 -38.905434) (xy 132.316225 -38.849812)
			(xy 132.328351 -38.795375) (xy 132.348274 -38.743284) (xy 132.37557 -38.694649) (xy 132.409656 -38.650506)
			(xy 132.449805 -38.611797) (xy 132.495163 -38.579346) (xy 132.544763 -38.553845) (xy 132.597547 -38.535838)
			(xy 132.65239 -38.525708) (xy 132.708124 -38.523671) (xy 132.763561 -38.529771) (xy 132.817518 -38.543877)
			(xy 132.868847 -38.565689) (xy 132.916453 -38.594743) (xy 132.959321 -38.630418) (xy 132.996538 -38.671955)
			(xy 133.027311 -38.718468) (xy 133.050983 -38.768965) (xy 133.067051 -38.822372) (xy 133.075171 -38.877548)
			(xy 133.07568 -38.905434) (xy 133.075171 -38.93332) (xy 133.067051 -38.988496) (xy 133.050983 -39.041903)
			(xy 133.027311 -39.0924) (xy 132.996538 -39.138913) (xy 132.959321 -39.18045) (xy 132.916453 -39.216125)
			(xy 132.868847 -39.245179) (xy 132.817518 -39.266991) (xy 132.763561 -39.281097) (xy 132.708124 -39.287197)
			(xy 132.65239 -39.28516) (xy 132.597547 -39.27503) (xy 132.544763 -39.257023) (xy 132.495163 -39.231522)
			(xy 132.449805 -39.199071) (xy 132.409656 -39.160362) (xy 132.37557 -39.116219) (xy 132.348274 -39.067584)
			(xy 132.328351 -39.015493) (xy 132.316225 -38.961056) (xy 132.312154 -38.905434) (xy 131.04368 -38.905434)
			(xy 131.043171 -38.93332) (xy 131.035051 -38.988496) (xy 131.018983 -39.041903) (xy 130.995311 -39.0924)
			(xy 130.964538 -39.138913) (xy 130.927321 -39.18045) (xy 130.884453 -39.216125) (xy 130.836847 -39.245179)
			(xy 130.785518 -39.266991) (xy 130.731561 -39.281097) (xy 130.676124 -39.287197) (xy 130.62039 -39.28516)
			(xy 130.565547 -39.27503) (xy 130.512763 -39.257023) (xy 130.463163 -39.231522) (xy 130.417805 -39.199071)
			(xy 130.377656 -39.160362) (xy 130.34357 -39.116219) (xy 130.316274 -39.067584) (xy 130.296351 -39.015493)
			(xy 130.284225 -38.961056) (xy 130.280154 -38.905434) (xy 128.153272 -38.905434) (xy 128.184429 -38.936593)
			(xy 128.223172 -38.986372) (xy 128.25546 -39.040561) (xy 128.280798 -39.098328) (xy 128.298795 -39.158785)
			(xy 128.309176 -39.221004) (xy 128.311782 -39.28403) (xy 128.306571 -39.346894) (xy 128.293625 -39.40863)
			(xy 128.273142 -39.468291) (xy 128.245437 -39.52496) (xy 128.210935 -39.577768) (xy 128.170166 -39.625902)
			(xy 128.123757 -39.668623) (xy 128.072419 -39.705276) (xy 128.016942 -39.735298) (xy 127.958178 -39.758227)
			(xy 127.897029 -39.773711) (xy 127.834434 -39.781513) (xy 127.802894 -39.781988) (xy 127.768858 -39.780972)
			(xy 127.75819 -39.78021) (xy 127.738124 -39.787576) (xy 127.668274 -39.85514) (xy 127.6604 -39.874952)
			(xy 127.660654 -39.88562) (xy 127.660908 -39.9034) (xy 127.660444 -39.934131) (xy 127.653035 -39.995145)
			(xy 127.638327 -40.054821) (xy 127.616532 -40.112289) (xy 127.587969 -40.166711) (xy 127.553055 -40.217293)
			(xy 127.512298 -40.263298) (xy 127.466293 -40.304055) (xy 127.415711 -40.338969) (xy 127.361289 -40.367532)
			(xy 127.303821 -40.389327) (xy 127.244145 -40.404035) (xy 127.183131 -40.411444) (xy 127.1524 -40.411908)
			(xy 127.119351 -40.411365) (xy 127.05381 -40.402806) (xy 126.989933 -40.385821) (xy 126.928797 -40.360696)
			(xy 126.871436 -40.327855) (xy 126.844806 -40.308276) (xy 126.837639 -40.303289) (xy 126.821024 -40.297964)
			(xy 126.812294 -40.297862) (xy 126.782322 -40.299132) (xy 126.77362 -40.29976) (xy 126.75739 -40.306133)
			(xy 126.750572 -40.311578) (xy 126.727355 -40.331302) (xy 126.67703 -40.365637) (xy 126.622964 -40.393715)
			(xy 126.56593 -40.415132) (xy 126.506747 -40.429583) (xy 126.446261 -40.436861) (xy 126.4158 -40.437308)
			(xy 126.38474 -40.436859) (xy 126.323083 -40.429288) (xy 126.262809 -40.414258) (xy 126.204816 -40.391993)
			(xy 126.149969 -40.362826) (xy 126.099086 -40.327191) (xy 126.075694 -40.306752) (xy 126.07544 -40.306498)
			(xy 126.068223 -40.300614) (xy 126.050806 -40.294063) (xy 126.032199 -40.294136) (xy 126.02337 -40.2971)
			(xy 125.925326 -40.3352) (xy 125.908054 -40.35806) (xy 125.90653 -40.372284) (xy 125.903187 -40.401119)
			(xy 125.888823 -40.457362) (xy 125.866111 -40.510783) (xy 125.835574 -40.56015) (xy 125.797916 -40.604326)
			(xy 125.754005 -40.642292) (xy 125.704853 -40.673173) (xy 125.678438 -40.685212) (xy 125.670466 -40.689112)
			(xy 125.657613 -40.701335) (xy 125.653292 -40.709088) (xy 125.63983 -40.736012) (xy 125.636085 -40.744243)
			(xy 125.634001 -40.762195) (xy 125.635766 -40.771064) (xy 125.642615 -40.800757) (xy 125.650004 -40.861246)
			(xy 125.650498 -40.891714) (xy 125.650498 -40.892476) (xy 125.650295 -40.905387) (xy 128.510024 -40.905387)
			(xy 128.510024 -40.841465) (xy 128.518035 -40.778047) (xy 128.533932 -40.716133) (xy 128.557464 -40.6567)
			(xy 128.588258 -40.600685) (xy 128.625831 -40.54897) (xy 128.669588 -40.502373) (xy 128.718841 -40.461628)
			(xy 128.772812 -40.427377) (xy 128.830651 -40.40016) (xy 128.891444 -40.380407) (xy 128.954234 -40.368429)
			(xy 129.01803 -40.364416) (xy 129.081826 -40.368429) (xy 129.144616 -40.380407) (xy 129.205409 -40.40016)
			(xy 129.263248 -40.427377) (xy 129.317219 -40.461628) (xy 129.366472 -40.502373) (xy 129.410229 -40.54897)
			(xy 129.447802 -40.600685) (xy 129.478596 -40.6567) (xy 129.502128 -40.716133) (xy 129.518025 -40.778047)
			(xy 129.526036 -40.841465) (xy 129.526538 -40.873426) (xy 129.526036 -40.905387) (xy 129.518025 -40.968805)
			(xy 129.502128 -41.030719) (xy 129.478596 -41.090152) (xy 129.447802 -41.146167) (xy 129.410229 -41.197882)
			(xy 129.366472 -41.244479) (xy 129.317219 -41.285224) (xy 129.263248 -41.319475) (xy 129.205409 -41.346692)
			(xy 129.144616 -41.366445) (xy 129.081826 -41.378423) (xy 129.01803 -41.382437) (xy 128.954234 -41.378423)
			(xy 128.891444 -41.366445) (xy 128.830651 -41.346692) (xy 128.772812 -41.319475) (xy 128.718841 -41.285224)
			(xy 128.669588 -41.244479) (xy 128.625831 -41.197882) (xy 128.588258 -41.146167) (xy 128.557464 -41.090152)
			(xy 128.533932 -41.030719) (xy 128.518035 -40.968805) (xy 128.510024 -40.905387) (xy 125.650295 -40.905387)
			(xy 125.649996 -40.924437) (xy 125.641985 -40.987855) (xy 125.626088 -41.049769) (xy 125.602556 -41.109202)
			(xy 125.571762 -41.165217) (xy 125.534189 -41.216932) (xy 125.490432 -41.263529) (xy 125.441179 -41.304274)
			(xy 125.387208 -41.338525) (xy 125.329369 -41.365742) (xy 125.268576 -41.385495) (xy 125.205786 -41.397473)
			(xy 125.14199 -41.401487) (xy 125.078194 -41.397473) (xy 125.015404 -41.385495) (xy 124.954611 -41.365742)
			(xy 124.896772 -41.338525) (xy 124.842801 -41.304274) (xy 124.793548 -41.263529) (xy 124.749791 -41.216932)
			(xy 124.712218 -41.165217) (xy 124.681424 -41.109202) (xy 124.657892 -41.049769) (xy 124.641995 -40.987855)
			(xy 124.633984 -40.924437) (xy 124.633482 -40.892476) (xy 104.504585 -40.892476) (xy 104.499591 -40.894826)
			(xy 104.438798 -40.914579) (xy 104.376008 -40.926557) (xy 104.312212 -40.930571) (xy 104.248416 -40.926557)
			(xy 104.185626 -40.914579) (xy 104.124833 -40.894826) (xy 104.066994 -40.867609) (xy 104.013023 -40.833358)
			(xy 103.96377 -40.792613) (xy 103.920013 -40.746016) (xy 103.88244 -40.694301) (xy 103.851646 -40.638286)
			(xy 103.828114 -40.578853) (xy 103.812217 -40.516939) (xy 103.804206 -40.453521) (xy 82.666178 -40.453521)
			(xy 82.668603 -40.458044) (xy 82.691182 -40.516403) (xy 82.706429 -40.577092) (xy 82.714111 -40.639193)
			(xy 82.714592 -40.67048) (xy 82.71409 -40.702441) (xy 82.706079 -40.765859) (xy 82.690182 -40.827773)
			(xy 82.66665 -40.887206) (xy 82.650208 -40.917114) (xy 99.093272 -40.917114) (xy 99.097343 -40.861492)
			(xy 99.109469 -40.807055) (xy 99.129392 -40.754964) (xy 99.156688 -40.706329) (xy 99.190774 -40.662186)
			(xy 99.230923 -40.623477) (xy 99.276281 -40.591026) (xy 99.325881 -40.565525) (xy 99.378665 -40.547518)
			(xy 99.433508 -40.537388) (xy 99.489242 -40.535351) (xy 99.544679 -40.541451) (xy 99.598636 -40.555557)
			(xy 99.649965 -40.577369) (xy 99.697571 -40.606423) (xy 99.740439 -40.642098) (xy 99.777656 -40.683635)
			(xy 99.808429 -40.730148) (xy 99.832101 -40.780645) (xy 99.848169 -40.834052) (xy 99.856289 -40.889228)
			(xy 99.856798 -40.917114) (xy 99.856289 -40.945) (xy 99.848169 -41.000176) (xy 99.832101 -41.053583)
			(xy 99.808429 -41.10408) (xy 99.777656 -41.150593) (xy 99.740439 -41.19213) (xy 99.697571 -41.227805)
			(xy 99.649965 -41.256859) (xy 99.598636 -41.278671) (xy 99.544679 -41.292777) (xy 99.489242 -41.298877)
			(xy 99.433508 -41.29684) (xy 99.378665 -41.28671) (xy 99.325881 -41.268703) (xy 99.276281 -41.243202)
			(xy 99.230923 -41.210751) (xy 99.190774 -41.172042) (xy 99.156688 -41.127899) (xy 99.129392 -41.079264)
			(xy 99.109469 -41.027173) (xy 99.097343 -40.972736) (xy 99.093272 -40.917114) (xy 82.650208 -40.917114)
			(xy 82.635856 -40.943221) (xy 82.598283 -40.994936) (xy 82.554526 -41.041533) (xy 82.505273 -41.082278)
			(xy 82.451302 -41.116529) (xy 82.393463 -41.143746) (xy 82.33267 -41.163499) (xy 82.26988 -41.175477)
			(xy 82.206084 -41.179491) (xy 82.142288 -41.175477) (xy 82.079498 -41.163499) (xy 82.018705 -41.143746)
			(xy 81.960866 -41.116529) (xy 81.906895 -41.082278) (xy 81.857642 -41.041533) (xy 81.813885 -40.994936)
			(xy 81.776312 -40.943221) (xy 81.745518 -40.887206) (xy 81.721986 -40.827773) (xy 81.706089 -40.765859)
			(xy 81.698078 -40.702441) (xy 81.697576 -40.67048) (xy 76.233838 -40.67048) (xy 76.185706 -40.684612)
			(xy 76.131751 -40.692369) (xy 76.104496 -40.692832) (xy 76.077561 -40.692396) (xy 76.024228 -40.6848)
			(xy 75.972495 -40.669775) (xy 75.923391 -40.647619) (xy 75.877894 -40.618773) (xy 75.8571 -40.601646)
			(xy 75.848853 -40.595232) (xy 75.828919 -40.58906) (xy 75.818492 -40.589708) (xy 75.745086 -40.59809)
			(xy 75.734817 -40.599731) (xy 75.716726 -40.609943) (xy 75.710034 -40.617902) (xy 75.689393 -40.644369)
			(xy 75.64224 -40.692138) (xy 75.58921 -40.733285) (xy 75.531225 -40.767093) (xy 75.469294 -40.792974)
			(xy 75.404496 -40.810478) (xy 75.337957 -40.819299) (xy 75.304396 -40.819832) (xy 75.272437 -40.819282)
			(xy 75.209022 -40.81127) (xy 75.147111 -40.795374) (xy 75.087681 -40.771844) (xy 75.031669 -40.74105)
			(xy 74.979958 -40.703479) (xy 74.933363 -40.659724) (xy 74.89262 -40.610473) (xy 74.858371 -40.556505)
			(xy 74.831156 -40.49867) (xy 74.811404 -40.437879) (xy 74.799427 -40.375093) (xy 74.795413 -40.3113)
			(xy 67.561638 -40.3113) (xy 67.575088 -40.357117) (xy 67.582842 -40.41107) (xy 67.583304 -40.438324)
			(xy 67.58275 -40.464991) (xy 67.57531 -40.517804) (xy 67.560592 -40.569067) (xy 67.538883 -40.617783)
			(xy 67.510606 -40.663004) (xy 67.47631 -40.703849) (xy 67.436664 -40.739524) (xy 67.392438 -40.769334)
			(xy 67.344494 -40.792699) (xy 67.293765 -40.809164) (xy 67.267582 -40.814244) (xy 67.258692 -40.815768)
			(xy 67.243198 -40.824658) (xy 67.18935 -40.889174) (xy 67.183508 -40.906192) (xy 67.183508 -40.9194)
			(xy 67.183032 -40.950941) (xy 67.17523 -41.013539) (xy 67.159744 -41.07469) (xy 67.136813 -41.133457)
			(xy 67.106789 -41.188936) (xy 67.070134 -41.240275) (xy 67.027409 -41.286686) (xy 66.979272 -41.327456)
			(xy 66.926462 -41.361959) (xy 66.86979 -41.389664) (xy 66.810126 -41.410147) (xy 66.748386 -41.423093)
			(xy 66.68552 -41.428302) (xy 66.622491 -41.425695) (xy 66.56027 -41.415312) (xy 66.49981 -41.397312)
			(xy 66.442041 -41.371973) (xy 66.38785 -41.339682) (xy 66.33807 -41.300936) (xy 66.293464 -41.25633)
			(xy 66.254718 -41.20655) (xy 66.222427 -41.152359) (xy 66.197088 -41.09459) (xy 66.179088 -41.03413)
			(xy 66.168705 -40.971909) (xy 66.166098 -40.90888) (xy 62.727469 -40.90888) (xy 62.701886 -40.936123)
			(xy 62.652633 -40.976868) (xy 62.598662 -41.011119) (xy 62.540823 -41.038336) (xy 62.48003 -41.058089)
			(xy 62.41724 -41.070067) (xy 62.353444 -41.074081) (xy 62.289648 -41.070067) (xy 62.226858 -41.058089)
			(xy 62.166065 -41.038336) (xy 62.108226 -41.011119) (xy 62.054255 -40.976868) (xy 62.005002 -40.936123)
			(xy 61.961245 -40.889526) (xy 61.923672 -40.837811) (xy 61.892878 -40.781796) (xy 61.869346 -40.722363)
			(xy 61.853449 -40.660449) (xy 61.845438 -40.597031) (xy 56.766779 -40.597031) (xy 56.768999 -40.612114)
			(xy 56.769508 -40.64) (xy 56.768999 -40.667886) (xy 56.760879 -40.723062) (xy 56.744811 -40.776469)
			(xy 56.721139 -40.826966) (xy 56.690366 -40.873479) (xy 56.653149 -40.915016) (xy 56.610281 -40.950691)
			(xy 56.562675 -40.979745) (xy 56.511346 -41.001557) (xy 56.457389 -41.015663) (xy 56.401952 -41.021763)
			(xy 56.346218 -41.019726) (xy 56.291375 -41.009596) (xy 56.238591 -40.991589) (xy 56.188991 -40.966088)
			(xy 56.143633 -40.933637) (xy 56.103484 -40.894928) (xy 56.069398 -40.850785) (xy 56.042102 -40.80215)
			(xy 56.022179 -40.750059) (xy 56.010053 -40.695622) (xy 56.005982 -40.64) (xy 46.436875 -40.64) (xy 46.424079 -40.666607)
			(xy 46.388595 -40.721202) (xy 46.346429 -40.770819) (xy 46.322742 -40.793162) (xy 46.316138 -40.800528)
			(xy 46.309788 -40.809164) (xy 46.304454 -40.8178) (xy 46.298358 -40.831516) (xy 46.296634 -40.835395)
			(xy 46.294328 -40.843563) (xy 46.293786 -40.847772) (xy 46.293532 -40.852598) (xy 46.293532 -41.166796)
			(xy 58.965844 -41.166796) (xy 58.969915 -41.111174) (xy 58.982041 -41.056737) (xy 59.001964 -41.004646)
			(xy 59.02926 -40.956011) (xy 59.063346 -40.911868) (xy 59.103495 -40.873159) (xy 59.148853 -40.840708)
			(xy 59.198453 -40.815207) (xy 59.251237 -40.7972) (xy 59.30608 -40.78707) (xy 59.361814 -40.785033)
			(xy 59.417251 -40.791133) (xy 59.471208 -40.805239) (xy 59.522537 -40.827051) (xy 59.570143 -40.856105)
			(xy 59.613011 -40.89178) (xy 59.650228 -40.933317) (xy 59.681001 -40.97983) (xy 59.704673 -41.030327)
			(xy 59.720741 -41.083734) (xy 59.728861 -41.13891) (xy 59.72937 -41.166796) (xy 59.728861 -41.194682)
			(xy 59.720741 -41.249858) (xy 59.712031 -41.27881) (xy 61.149736 -41.27881) (xy 61.153807 -41.223188)
			(xy 61.165933 -41.168751) (xy 61.185856 -41.11666) (xy 61.213152 -41.068025) (xy 61.247238 -41.023882)
			(xy 61.287387 -40.985173) (xy 61.332745 -40.952722) (xy 61.382345 -40.927221) (xy 61.435129 -40.909214)
			(xy 61.489972 -40.899084) (xy 61.545706 -40.897047) (xy 61.601143 -40.903147) (xy 61.6551 -40.917253)
			(xy 61.706429 -40.939065) (xy 61.754035 -40.968119) (xy 61.796903 -41.003794) (xy 61.83412 -41.045331)
			(xy 61.864893 -41.091844) (xy 61.888565 -41.142341) (xy 61.904633 -41.195748) (xy 61.912753 -41.250924)
			(xy 61.913262 -41.27881) (xy 61.912753 -41.306696) (xy 61.904633 -41.361872) (xy 61.888565 -41.415279)
			(xy 61.864893 -41.465776) (xy 61.83412 -41.512289) (xy 61.796903 -41.553826) (xy 61.754035 -41.589501)
			(xy 61.706429 -41.618555) (xy 61.6551 -41.640367) (xy 61.601143 -41.654473) (xy 61.545706 -41.660573)
			(xy 61.489972 -41.658536) (xy 61.435129 -41.648406) (xy 61.382345 -41.630399) (xy 61.332745 -41.604898)
			(xy 61.287387 -41.572447) (xy 61.247238 -41.533738) (xy 61.213152 -41.489595) (xy 61.185856 -41.44096)
			(xy 61.165933 -41.388869) (xy 61.153807 -41.334432) (xy 61.149736 -41.27881) (xy 59.712031 -41.27881)
			(xy 59.704673 -41.303265) (xy 59.681001 -41.353762) (xy 59.650228 -41.400275) (xy 59.613011 -41.441812)
			(xy 59.570143 -41.477487) (xy 59.522537 -41.506541) (xy 59.471208 -41.528353) (xy 59.417251 -41.542459)
			(xy 59.361814 -41.548559) (xy 59.30608 -41.546522) (xy 59.251237 -41.536392) (xy 59.198453 -41.518385)
			(xy 59.148853 -41.492884) (xy 59.103495 -41.460433) (xy 59.063346 -41.421724) (xy 59.02926 -41.377581)
			(xy 59.001964 -41.328946) (xy 58.982041 -41.276855) (xy 58.969915 -41.222418) (xy 58.965844 -41.166796)
			(xy 46.293532 -41.166796) (xy 46.293532 -42.382651) (xy 59.087506 -42.382651) (xy 59.087506 -42.318729)
			(xy 59.095517 -42.255311) (xy 59.111414 -42.193397) (xy 59.134946 -42.133964) (xy 59.16574 -42.077949)
			(xy 59.203313 -42.026234) (xy 59.24707 -41.979637) (xy 59.296323 -41.938892) (xy 59.350294 -41.904641)
			(xy 59.408133 -41.877424) (xy 59.468926 -41.857671) (xy 59.531716 -41.845693) (xy 59.595512 -41.84168)
			(xy 59.659308 -41.845693) (xy 59.722098 -41.857671) (xy 59.782891 -41.877424) (xy 59.84073 -41.904641)
			(xy 59.894701 -41.938892) (xy 59.943954 -41.979637) (xy 59.987711 -42.026234) (xy 60.025284 -42.077949)
			(xy 60.04827 -42.119761) (xy 62.572894 -42.119761) (xy 62.572894 -42.055839) (xy 62.580905 -41.992421)
			(xy 62.596802 -41.930507) (xy 62.620334 -41.871074) (xy 62.651128 -41.815059) (xy 62.688701 -41.763344)
			(xy 62.732458 -41.716747) (xy 62.781711 -41.676002) (xy 62.835682 -41.641751) (xy 62.893521 -41.614534)
			(xy 62.954314 -41.594781) (xy 63.017104 -41.582803) (xy 63.0809 -41.57879) (xy 63.144696 -41.582803)
			(xy 63.207486 -41.594781) (xy 63.268279 -41.614534) (xy 63.326118 -41.641751) (xy 63.380089 -41.676002)
			(xy 63.429342 -41.716747) (xy 63.473099 -41.763344) (xy 63.510672 -41.815059) (xy 63.541466 -41.871074)
			(xy 63.564998 -41.930507) (xy 63.57082 -41.95318) (xy 85.956138 -41.95318) (xy 85.960209 -41.897558)
			(xy 85.972335 -41.843121) (xy 85.992258 -41.79103) (xy 86.019554 -41.742395) (xy 86.05364 -41.698252)
			(xy 86.093789 -41.659543) (xy 86.139147 -41.627092) (xy 86.188747 -41.601591) (xy 86.241531 -41.583584)
			(xy 86.296374 -41.573454) (xy 86.352108 -41.571417) (xy 86.407545 -41.577517) (xy 86.461502 -41.591623)
			(xy 86.512831 -41.613435) (xy 86.560437 -41.642489) (xy 86.603305 -41.678164) (xy 86.640522 -41.719701)
			(xy 86.671295 -41.766214) (xy 86.694967 -41.816711) (xy 86.711035 -41.870118) (xy 86.719155 -41.925294)
			(xy 86.719664 -41.95318) (xy 86.719155 -41.981066) (xy 86.711035 -42.036242) (xy 86.694967 -42.089649)
			(xy 86.671295 -42.140146) (xy 86.640522 -42.186659) (xy 86.603305 -42.228196) (xy 86.560437 -42.263871)
			(xy 86.557604 -42.2656) (xy 108.83722 -42.2656) (xy 108.841291 -42.209978) (xy 108.853417 -42.155541)
			(xy 108.87334 -42.10345) (xy 108.900636 -42.054815) (xy 108.934722 -42.010672) (xy 108.974871 -41.971963)
			(xy 109.020229 -41.939512) (xy 109.069829 -41.914011) (xy 109.122613 -41.896004) (xy 109.177456 -41.885874)
			(xy 109.23319 -41.883837) (xy 109.288627 -41.889937) (xy 109.342584 -41.904043) (xy 109.393913 -41.925855)
			(xy 109.441519 -41.954909) (xy 109.484387 -41.990584) (xy 109.521604 -42.032121) (xy 109.552377 -42.078634)
			(xy 109.576049 -42.129131) (xy 109.592117 -42.182538) (xy 109.600237 -42.237714) (xy 109.600746 -42.2656)
			(xy 111.88522 -42.2656) (xy 111.889291 -42.209978) (xy 111.901417 -42.155541) (xy 111.92134 -42.10345)
			(xy 111.948636 -42.054815) (xy 111.982722 -42.010672) (xy 112.022871 -41.971963) (xy 112.068229 -41.939512)
			(xy 112.117829 -41.914011) (xy 112.170613 -41.896004) (xy 112.225456 -41.885874) (xy 112.28119 -41.883837)
			(xy 112.336627 -41.889937) (xy 112.390584 -41.904043) (xy 112.441913 -41.925855) (xy 112.489519 -41.954909)
			(xy 112.532387 -41.990584) (xy 112.569604 -42.032121) (xy 112.600377 -42.078634) (xy 112.624049 -42.129131)
			(xy 112.640117 -42.182538) (xy 112.648237 -42.237714) (xy 112.648746 -42.2656) (xy 115.94922 -42.2656)
			(xy 115.953291 -42.209978) (xy 115.965417 -42.155541) (xy 115.98534 -42.10345) (xy 116.012636 -42.054815)
			(xy 116.046722 -42.010672) (xy 116.086871 -41.971963) (xy 116.132229 -41.939512) (xy 116.181829 -41.914011)
			(xy 116.234613 -41.896004) (xy 116.289456 -41.885874) (xy 116.34519 -41.883837) (xy 116.400627 -41.889937)
			(xy 116.454584 -41.904043) (xy 116.505913 -41.925855) (xy 116.553519 -41.954909) (xy 116.596387 -41.990584)
			(xy 116.633604 -42.032121) (xy 116.664377 -42.078634) (xy 116.688049 -42.129131) (xy 116.704117 -42.182538)
			(xy 116.712237 -42.237714) (xy 116.712746 -42.2656) (xy 117.98122 -42.2656) (xy 117.985291 -42.209978)
			(xy 117.997417 -42.155541) (xy 118.01734 -42.10345) (xy 118.044636 -42.054815) (xy 118.078722 -42.010672)
			(xy 118.118871 -41.971963) (xy 118.164229 -41.939512) (xy 118.213829 -41.914011) (xy 118.266613 -41.896004)
			(xy 118.321456 -41.885874) (xy 118.37719 -41.883837) (xy 118.432627 -41.889937) (xy 118.486584 -41.904043)
			(xy 118.537913 -41.925855) (xy 118.585519 -41.954909) (xy 118.628387 -41.990584) (xy 118.665604 -42.032121)
			(xy 118.696377 -42.078634) (xy 118.720049 -42.129131) (xy 118.733367 -42.173398) (xy 131.941316 -42.173398)
			(xy 131.941316 -41.110662) (xy 131.941687 -41.100617) (xy 131.949275 -41.082021) (xy 131.956048 -41.074594)
			(xy 132.135372 -40.89527) (xy 132.142784 -40.888445) (xy 132.161374 -40.880718) (xy 132.17144 -40.880284)
			(xy 133.616954 -40.880284) (xy 133.627021 -40.879838) (xy 133.645619 -40.872132) (xy 133.653022 -40.865298)
			(xy 135.162798 -39.355268) (xy 135.169644 -39.347873) (xy 135.17736 -39.32927) (xy 135.177784 -39.3192)
			(xy 135.177784 -39.238174) (xy 135.177319 -39.22807) (xy 135.169459 -39.20945) (xy 135.155012 -39.195317)
			(xy 135.14578 -39.191184) (xy 135.043926 -39.15029) (xy 135.013446 -39.157148) (xy 135.002778 -39.168324)
			(xy 134.984662 -39.186684) (xy 134.944405 -39.218927) (xy 134.900173 -39.245457) (xy 134.852773 -39.265791)
			(xy 134.803068 -39.27956) (xy 134.751961 -39.286512) (xy 134.726172 -39.286942) (xy 134.698925 -39.286386)
			(xy 134.644985 -39.278627) (xy 134.592698 -39.263271) (xy 134.543129 -39.24063) (xy 134.497286 -39.211166)
			(xy 134.456103 -39.175477) (xy 134.420418 -39.134292) (xy 134.390957 -39.088447) (xy 134.36832 -39.038876)
			(xy 134.352967 -38.986588) (xy 134.345212 -38.932648) (xy 134.345212 -38.878152) (xy 134.352967 -38.824212)
			(xy 134.36832 -38.771924) (xy 134.390957 -38.722353) (xy 134.420418 -38.676508) (xy 134.456103 -38.635323)
			(xy 134.497286 -38.599634) (xy 134.543129 -38.57017) (xy 134.592698 -38.547529) (xy 134.644985 -38.532173)
			(xy 134.698925 -38.524414) (xy 134.726172 -38.523926) (xy 134.751964 -38.524325) (xy 134.803078 -38.531268)
			(xy 134.852792 -38.545032) (xy 134.900198 -38.565366) (xy 134.944435 -38.591899) (xy 134.984695 -38.624148)
			(xy 135.002778 -38.642544) (xy 135.013446 -38.65372) (xy 135.043926 -38.660578) (xy 135.14578 -38.619684)
			(xy 135.155007 -38.615553) (xy 135.169425 -38.6014) (xy 135.177296 -38.582793) (xy 135.177784 -38.572694)
			(xy 135.177784 -38.222174) (xy 135.177319 -38.21207) (xy 135.169459 -38.19345) (xy 135.155012 -38.179317)
			(xy 135.14578 -38.175184) (xy 135.043926 -38.13429) (xy 135.013446 -38.141148) (xy 135.002778 -38.152324)
			(xy 134.984662 -38.170684) (xy 134.944405 -38.202927) (xy 134.900173 -38.229457) (xy 134.852773 -38.249791)
			(xy 134.803068 -38.26356) (xy 134.751961 -38.270512) (xy 134.726172 -38.270942) (xy 134.698925 -38.270386)
			(xy 134.644985 -38.262627) (xy 134.592698 -38.247271) (xy 134.543129 -38.22463) (xy 134.497286 -38.195166)
			(xy 134.456103 -38.159477) (xy 134.420418 -38.118292) (xy 134.390957 -38.072447) (xy 134.36832 -38.022876)
			(xy 134.352967 -37.970588) (xy 134.345212 -37.916648) (xy 134.345212 -37.862152) (xy 134.352967 -37.808212)
			(xy 134.36832 -37.755924) (xy 134.390957 -37.706353) (xy 134.420418 -37.660508) (xy 134.456103 -37.619323)
			(xy 134.497286 -37.583634) (xy 134.543129 -37.55417) (xy 134.592698 -37.531529) (xy 134.644985 -37.516173)
			(xy 134.698925 -37.508414) (xy 134.726172 -37.507926) (xy 134.751964 -37.508325) (xy 134.803078 -37.515268)
			(xy 134.852792 -37.529032) (xy 134.900198 -37.549366) (xy 134.944435 -37.575899) (xy 134.984695 -37.608148)
			(xy 135.002778 -37.626544) (xy 135.013446 -37.63772) (xy 135.043926 -37.644578) (xy 135.14578 -37.603684)
			(xy 135.155007 -37.599553) (xy 135.169425 -37.5854) (xy 135.177296 -37.566793) (xy 135.177784 -37.556694)
			(xy 135.177784 -37.206174) (xy 135.177319 -37.19607) (xy 135.169459 -37.17745) (xy 135.155012 -37.163317)
			(xy 135.14578 -37.159184) (xy 135.043926 -37.11829) (xy 135.013446 -37.125148) (xy 135.002778 -37.136324)
			(xy 134.984662 -37.154684) (xy 134.944405 -37.186927) (xy 134.900173 -37.213457) (xy 134.852773 -37.233791)
			(xy 134.803068 -37.24756) (xy 134.751961 -37.254512) (xy 134.726172 -37.254942) (xy 134.698925 -37.254386)
			(xy 134.644985 -37.246627) (xy 134.592698 -37.231271) (xy 134.543129 -37.20863) (xy 134.497286 -37.179166)
			(xy 134.456103 -37.143477) (xy 134.420418 -37.102292) (xy 134.390957 -37.056447) (xy 134.36832 -37.006876)
			(xy 134.352967 -36.954588) (xy 134.345212 -36.900648) (xy 134.345212 -36.846152) (xy 134.352967 -36.792212)
			(xy 134.36832 -36.739924) (xy 134.390957 -36.690353) (xy 134.420418 -36.644508) (xy 134.456103 -36.603323)
			(xy 134.497286 -36.567634) (xy 134.543129 -36.53817) (xy 134.592698 -36.515529) (xy 134.644985 -36.500173)
			(xy 134.698925 -36.492414) (xy 134.726172 -36.491926) (xy 134.751964 -36.492325) (xy 134.803078 -36.499268)
			(xy 134.852792 -36.513032) (xy 134.900198 -36.533366) (xy 134.944435 -36.559899) (xy 134.984695 -36.592148)
			(xy 135.002778 -36.610544) (xy 135.013446 -36.62172) (xy 135.043926 -36.628578) (xy 135.14578 -36.587684)
			(xy 135.155007 -36.583553) (xy 135.169425 -36.5694) (xy 135.177296 -36.550793) (xy 135.177784 -36.540694)
			(xy 135.177784 -36.190174) (xy 135.177319 -36.18007) (xy 135.169459 -36.16145) (xy 135.155012 -36.147317)
			(xy 135.14578 -36.143184) (xy 135.043926 -36.10229) (xy 135.013446 -36.109148) (xy 135.002778 -36.120324)
			(xy 134.984662 -36.138684) (xy 134.944405 -36.170927) (xy 134.900173 -36.197457) (xy 134.852773 -36.217791)
			(xy 134.803068 -36.23156) (xy 134.751961 -36.238512) (xy 134.726172 -36.238942) (xy 134.698925 -36.238386)
			(xy 134.644985 -36.230627) (xy 134.592698 -36.215271) (xy 134.543129 -36.19263) (xy 134.497286 -36.163166)
			(xy 134.456103 -36.127477) (xy 134.420418 -36.086292) (xy 134.390957 -36.040447) (xy 134.36832 -35.990876)
			(xy 134.352967 -35.938588) (xy 134.345212 -35.884648) (xy 134.345212 -35.830152) (xy 134.352967 -35.776212)
			(xy 134.36832 -35.723924) (xy 134.390957 -35.674353) (xy 134.420418 -35.628508) (xy 134.456103 -35.587323)
			(xy 134.497286 -35.551634) (xy 134.543129 -35.52217) (xy 134.592698 -35.499529) (xy 134.644985 -35.484173)
			(xy 134.698925 -35.476414) (xy 134.726172 -35.475926) (xy 134.751964 -35.476325) (xy 134.803078 -35.483268)
			(xy 134.852792 -35.497032) (xy 134.900198 -35.517366) (xy 134.944435 -35.543899) (xy 134.984695 -35.576148)
			(xy 135.002778 -35.594544) (xy 135.013446 -35.60572) (xy 135.043926 -35.612578) (xy 135.14578 -35.571684)
			(xy 135.155007 -35.567553) (xy 135.169425 -35.5534) (xy 135.177296 -35.534793) (xy 135.177784 -35.524694)
			(xy 135.177784 -35.174174) (xy 135.177319 -35.16407) (xy 135.169459 -35.14545) (xy 135.155012 -35.131317)
			(xy 135.14578 -35.127184) (xy 135.043926 -35.08629) (xy 135.013446 -35.093148) (xy 135.002778 -35.104324)
			(xy 134.984662 -35.122684) (xy 134.944405 -35.154927) (xy 134.900173 -35.181457) (xy 134.852773 -35.201791)
			(xy 134.803068 -35.21556) (xy 134.751961 -35.222512) (xy 134.726172 -35.222942) (xy 134.698925 -35.222386)
			(xy 134.644985 -35.214627) (xy 134.592698 -35.199271) (xy 134.543129 -35.17663) (xy 134.497286 -35.147166)
			(xy 134.456103 -35.111477) (xy 134.420418 -35.070292) (xy 134.390957 -35.024447) (xy 134.36832 -34.974876)
			(xy 134.352967 -34.922588) (xy 134.345212 -34.868648) (xy 134.345212 -34.814152) (xy 134.352967 -34.760212)
			(xy 134.36832 -34.707924) (xy 134.390957 -34.658353) (xy 134.420418 -34.612508) (xy 134.456103 -34.571323)
			(xy 134.497286 -34.535634) (xy 134.543129 -34.50617) (xy 134.592698 -34.483529) (xy 134.644985 -34.468173)
			(xy 134.698925 -34.460414) (xy 134.726172 -34.459926) (xy 134.751964 -34.460325) (xy 134.803078 -34.467268)
			(xy 134.852792 -34.481032) (xy 134.900198 -34.501366) (xy 134.944435 -34.527899) (xy 134.984695 -34.560148)
			(xy 135.002778 -34.578544) (xy 135.013446 -34.58972) (xy 135.043926 -34.596578) (xy 135.14578 -34.555684)
			(xy 135.155007 -34.551553) (xy 135.169425 -34.5374) (xy 135.177296 -34.518793) (xy 135.177784 -34.508694)
			(xy 135.177784 -34.00298) (xy 135.178177 -33.992907) (xy 135.185918 -33.974308) (xy 135.19277 -33.966912)
			(xy 136.457944 -32.701738) (xy 136.465339 -32.694892) (xy 136.483942 -32.687174) (xy 136.494012 -32.686752)
			(xy 137.422128 -32.686752) (xy 137.432201 -32.687149) (xy 137.450799 -32.694888) (xy 137.458196 -32.701738)
			(xy 138.074146 -33.317688) (xy 162.786058 -33.317688) (xy 162.790129 -33.262066) (xy 162.802255 -33.207629)
			(xy 162.822178 -33.155538) (xy 162.849474 -33.106903) (xy 162.88356 -33.06276) (xy 162.923709 -33.024051)
			(xy 162.969067 -32.9916) (xy 163.018667 -32.966099) (xy 163.071451 -32.948092) (xy 163.126294 -32.937962)
			(xy 163.182028 -32.935925) (xy 163.237465 -32.942025) (xy 163.291422 -32.956131) (xy 163.342751 -32.977943)
			(xy 163.390357 -33.006997) (xy 163.433225 -33.042672) (xy 163.470442 -33.084209) (xy 163.501215 -33.130722)
			(xy 163.524887 -33.181219) (xy 163.540955 -33.234626) (xy 163.549075 -33.289802) (xy 163.549584 -33.317688)
			(xy 163.549075 -33.345574) (xy 163.540955 -33.40075) (xy 163.524887 -33.454157) (xy 163.501215 -33.504654)
			(xy 163.470442 -33.551167) (xy 163.433225 -33.592704) (xy 163.390357 -33.628379) (xy 163.342751 -33.657433)
			(xy 163.291422 -33.679245) (xy 163.237465 -33.693351) (xy 163.182028 -33.699451) (xy 163.126294 -33.697414)
			(xy 163.071451 -33.687284) (xy 163.018667 -33.669277) (xy 162.969067 -33.643776) (xy 162.923709 -33.611325)
			(xy 162.88356 -33.572616) (xy 162.849474 -33.528473) (xy 162.822178 -33.479838) (xy 162.802255 -33.427747)
			(xy 162.790129 -33.37331) (xy 162.786058 -33.317688) (xy 138.074146 -33.317688) (xy 138.534902 -33.778444)
			(xy 138.541754 -33.785835) (xy 138.549467 -33.804441) (xy 138.549888 -33.814512) (xy 138.549888 -34.201608)
			(xy 138.54947 -34.211678) (xy 138.541744 -34.230276) (xy 138.534902 -34.237676) (xy 138.453665 -34.318913)
			(xy 163.513002 -34.318913) (xy 163.513002 -34.254991) (xy 163.521013 -34.191573) (xy 163.53691 -34.129659)
			(xy 163.560442 -34.070226) (xy 163.591236 -34.014211) (xy 163.628809 -33.962496) (xy 163.672566 -33.915899)
			(xy 163.721819 -33.875154) (xy 163.77579 -33.840903) (xy 163.833629 -33.813686) (xy 163.894422 -33.793933)
			(xy 163.957212 -33.781955) (xy 164.021008 -33.777942) (xy 164.084804 -33.781955) (xy 164.147594 -33.793933)
			(xy 164.208387 -33.813686) (xy 164.266226 -33.840903) (xy 164.320197 -33.875154) (xy 164.36945 -33.915899)
			(xy 164.413207 -33.962496) (xy 164.45078 -34.014211) (xy 164.481574 -34.070226) (xy 164.505106 -34.129659)
			(xy 164.521003 -34.191573) (xy 164.529014 -34.254991) (xy 164.529516 -34.286952) (xy 164.529014 -34.318913)
			(xy 164.521003 -34.382331) (xy 164.505106 -34.444245) (xy 164.481574 -34.503678) (xy 164.45078 -34.559693)
			(xy 164.413207 -34.611408) (xy 164.36945 -34.658005) (xy 164.320197 -34.69875) (xy 164.266226 -34.733001)
			(xy 164.208387 -34.760218) (xy 164.147594 -34.779971) (xy 164.084804 -34.791949) (xy 164.021008 -34.795963)
			(xy 163.957212 -34.791949) (xy 163.894422 -34.779971) (xy 163.833629 -34.760218) (xy 163.77579 -34.733001)
			(xy 163.721819 -34.69875) (xy 163.672566 -34.658005) (xy 163.628809 -34.611408) (xy 163.591236 -34.559693)
			(xy 163.560442 -34.503678) (xy 163.53691 -34.444245) (xy 163.521013 -34.382331) (xy 163.513002 -34.318913)
			(xy 138.453665 -34.318913) (xy 138.263376 -34.509202) (xy 138.255978 -34.516045) (xy 138.237377 -34.523763)
			(xy 138.227308 -34.524188) (xy 138.156442 -34.524188) (xy 138.144091 -34.524894) (xy 138.122191 -34.536316)
			(xy 138.114532 -34.546032) (xy 138.059668 -34.62528) (xy 138.05662 -34.649664) (xy 138.061192 -34.661602)
			(xy 138.071553 -34.690352) (xy 138.08613 -34.749701) (xy 138.093488 -34.81037) (xy 138.093958 -34.840926)
			(xy 138.093468 -34.871656) (xy 138.086058 -34.932667) (xy 138.071348 -34.992339) (xy 138.049553 -35.049805)
			(xy 138.020992 -35.104224) (xy 137.986079 -35.154804) (xy 137.945325 -35.200808) (xy 137.899323 -35.241564)
			(xy 137.848744 -35.276479) (xy 137.794326 -35.305044) (xy 137.736862 -35.326841) (xy 137.67719 -35.341554)
			(xy 137.61618 -35.348967) (xy 137.58545 -35.349434) (xy 137.552562 -35.348889) (xy 137.487336 -35.340403)
			(xy 137.423748 -35.323579) (xy 137.362859 -35.298698) (xy 137.305686 -35.266175) (xy 137.253183 -35.226552)
			(xy 137.229342 -35.203892) (xy 137.22194 -35.197222) (xy 137.203499 -35.189723) (xy 137.183592 -35.189824)
			(xy 137.174224 -35.193224) (xy 137.08761 -35.229546) (xy 137.078544 -35.233748) (xy 137.064411 -35.247851)
			(xy 137.056775 -35.266298) (xy 137.056368 -35.276282) (xy 137.056368 -35.371235) (xy 152.74137 -35.371235)
			(xy 152.74137 -35.307313) (xy 152.749381 -35.243895) (xy 152.765278 -35.181981) (xy 152.78881 -35.122548)
			(xy 152.819604 -35.066533) (xy 152.857177 -35.014818) (xy 152.900934 -34.968221) (xy 152.950187 -34.927476)
			(xy 153.004158 -34.893225) (xy 153.061997 -34.866008) (xy 153.12279 -34.846255) (xy 153.18558 -34.834277)
			(xy 153.249376 -34.830264) (xy 153.313172 -34.834277) (xy 153.375962 -34.846255) (xy 153.436755 -34.866008)
			(xy 153.494594 -34.893225) (xy 153.548565 -34.927476) (xy 153.597818 -34.968221) (xy 153.641575 -35.014818)
			(xy 153.679148 -35.066533) (xy 153.709942 -35.122548) (xy 153.733474 -35.181981) (xy 153.749371 -35.243895)
			(xy 153.757382 -35.307313) (xy 153.757884 -35.339274) (xy 153.757382 -35.371235) (xy 153.749371 -35.434653)
			(xy 153.733474 -35.496567) (xy 153.711795 -35.551321) (xy 166.86504 -35.551321) (xy 166.86504 -35.487399)
			(xy 166.873051 -35.423981) (xy 166.888948 -35.362067) (xy 166.91248 -35.302634) (xy 166.943274 -35.246619)
			(xy 166.980847 -35.194904) (xy 167.024604 -35.148307) (xy 167.073857 -35.107562) (xy 167.127828 -35.073311)
			(xy 167.185667 -35.046094) (xy 167.24646 -35.026341) (xy 167.30925 -35.014363) (xy 167.373046 -35.01035)
			(xy 167.436842 -35.014363) (xy 167.499632 -35.026341) (xy 167.560425 -35.046094) (xy 167.618264 -35.073311)
			(xy 167.672235 -35.107562) (xy 167.721488 -35.148307) (xy 167.765245 -35.194904) (xy 167.802818 -35.246619)
			(xy 167.833612 -35.302634) (xy 167.857144 -35.362067) (xy 167.873041 -35.423981) (xy 167.881052 -35.487399)
			(xy 167.881554 -35.51936) (xy 167.881052 -35.551321) (xy 167.873041 -35.614739) (xy 167.857144 -35.676653)
			(xy 167.833612 -35.736086) (xy 167.802818 -35.792101) (xy 167.765245 -35.843816) (xy 167.721488 -35.890413)
			(xy 167.672235 -35.931158) (xy 167.618264 -35.965409) (xy 167.560425 -35.992626) (xy 167.499632 -36.012379)
			(xy 167.436842 -36.024357) (xy 167.373046 -36.028371) (xy 167.30925 -36.024357) (xy 167.24646 -36.012379)
			(xy 167.185667 -35.992626) (xy 167.127828 -35.965409) (xy 167.073857 -35.931158) (xy 167.024604 -35.890413)
			(xy 166.980847 -35.843816) (xy 166.943274 -35.792101) (xy 166.91248 -35.736086) (xy 166.888948 -35.676653)
			(xy 166.873051 -35.614739) (xy 166.86504 -35.551321) (xy 153.711795 -35.551321) (xy 153.709942 -35.556)
			(xy 153.679148 -35.612015) (xy 153.641575 -35.66373) (xy 153.597818 -35.710327) (xy 153.548565 -35.751072)
			(xy 153.494594 -35.785323) (xy 153.436755 -35.81254) (xy 153.375962 -35.832293) (xy 153.313172 -35.844271)
			(xy 153.249376 -35.848285) (xy 153.18558 -35.844271) (xy 153.12279 -35.832293) (xy 153.061997 -35.81254)
			(xy 153.004158 -35.785323) (xy 152.950187 -35.751072) (xy 152.900934 -35.710327) (xy 152.857177 -35.66373)
			(xy 152.819604 -35.612015) (xy 152.78881 -35.556) (xy 152.765278 -35.496567) (xy 152.749381 -35.434653)
			(xy 152.74137 -35.371235) (xy 137.056368 -35.371235) (xy 137.056368 -35.637978) (xy 137.056844 -35.647937)
			(xy 137.064529 -35.666321) (xy 137.078607 -35.680422) (xy 137.08761 -35.684714) (xy 137.174224 -35.721036)
			(xy 137.183595 -35.724391) (xy 137.203478 -35.724455) (xy 137.221904 -35.716981) (xy 137.229342 -35.710368)
			(xy 137.253167 -35.687687) (xy 137.305667 -35.648054) (xy 137.362842 -35.615525) (xy 137.423734 -35.590641)
			(xy 137.487328 -35.57382) (xy 137.55256 -35.565341) (xy 137.58545 -35.564826) (xy 137.617417 -35.565236)
			(xy 137.680846 -35.573243) (xy 137.742772 -35.589138) (xy 137.802217 -35.612668) (xy 137.858244 -35.643465)
			(xy 137.909969 -35.68104) (xy 137.956576 -35.724803) (xy 137.997331 -35.774063) (xy 138.03159 -35.828042)
			(xy 138.058813 -35.885889) (xy 138.07857 -35.946693) (xy 138.090551 -36.009493) (xy 138.094566 -36.0733)
			(xy 138.090551 -36.137107) (xy 138.07857 -36.199907) (xy 138.058813 -36.260711) (xy 138.03159 -36.318558)
			(xy 137.997331 -36.372537) (xy 137.956576 -36.421797) (xy 137.909969 -36.46556) (xy 137.858244 -36.503135)
			(xy 137.802217 -36.533932) (xy 137.742772 -36.557462) (xy 137.680846 -36.573357) (xy 137.617417 -36.581364)
			(xy 137.58545 -36.581842) (xy 137.552562 -36.581295) (xy 137.487336 -36.572809) (xy 137.423748 -36.555985)
			(xy 137.362859 -36.531104) (xy 137.305686 -36.498582) (xy 137.253183 -36.45896) (xy 137.229342 -36.4363)
			(xy 137.22194 -36.429631) (xy 137.203499 -36.422131) (xy 137.183591 -36.422232) (xy 137.174224 -36.425632)
			(xy 137.08761 -36.461954) (xy 137.078541 -36.46615) (xy 137.064408 -36.480255) (xy 137.056774 -36.498706)
			(xy 137.056368 -36.50869) (xy 137.056368 -36.87064) (xy 137.056872 -36.880597) (xy 137.064544 -36.898979)
			(xy 137.078611 -36.913082) (xy 137.08761 -36.917376) (xy 137.174224 -36.953698) (xy 137.183598 -36.957037)
			(xy 137.203477 -36.957101) (xy 137.221901 -36.949637) (xy 137.229342 -36.94303) (xy 137.253177 -36.92036)
			(xy 137.305674 -36.880724) (xy 137.362846 -36.848191) (xy 137.423737 -36.823306) (xy 137.487329 -36.806482)
			(xy 137.55256 -36.798003) (xy 137.58545 -36.797488) (xy 137.617414 -36.797974) (xy 137.680839 -36.805981)
			(xy 137.74276 -36.821874) (xy 137.802201 -36.845403) (xy 137.858224 -36.876197) (xy 137.909945 -36.91377)
			(xy 137.956549 -36.957529) (xy 137.9973 -37.006785) (xy 138.031556 -37.06076) (xy 138.058777 -37.118603)
			(xy 138.078533 -37.179402) (xy 138.090513 -37.242198) (xy 138.094528 -37.306) (xy 138.092514 -37.338)
			(xy 139.267182 -37.338) (xy 139.271253 -37.282378) (xy 139.283379 -37.227941) (xy 139.303302 -37.17585)
			(xy 139.330598 -37.127215) (xy 139.364684 -37.083072) (xy 139.404833 -37.044363) (xy 139.450191 -37.011912)
			(xy 139.499791 -36.986411) (xy 139.552575 -36.968404) (xy 139.607418 -36.958274) (xy 139.663152 -36.956237)
			(xy 139.718589 -36.962337) (xy 139.772546 -36.976443) (xy 139.823875 -36.998255) (xy 139.871481 -37.027309)
			(xy 139.914349 -37.062984) (xy 139.951566 -37.104521) (xy 139.982339 -37.151034) (xy 140.006011 -37.201531)
			(xy 140.022079 -37.254938) (xy 140.030199 -37.310114) (xy 140.030708 -37.338) (xy 140.030199 -37.365886)
			(xy 140.022079 -37.421062) (xy 140.006011 -37.474469) (xy 139.982339 -37.524966) (xy 139.951566 -37.571479)
			(xy 139.914349 -37.613016) (xy 139.871481 -37.648691) (xy 139.823875 -37.677745) (xy 139.772546 -37.699557)
			(xy 139.718589 -37.713663) (xy 139.663152 -37.719763) (xy 139.607418 -37.717726) (xy 139.552575 -37.707596)
			(xy 139.499791 -37.689589) (xy 139.450191 -37.664088) (xy 139.404833 -37.631637) (xy 139.364684 -37.592928)
			(xy 139.330598 -37.548785) (xy 139.303302 -37.50015) (xy 139.283379 -37.448059) (xy 139.271253 -37.393622)
			(xy 139.267182 -37.338) (xy 138.092514 -37.338) (xy 138.090513 -37.369802) (xy 138.078533 -37.432598)
			(xy 138.058777 -37.493397) (xy 138.031556 -37.55124) (xy 137.9973 -37.605215) (xy 137.956549 -37.654471)
			(xy 137.909945 -37.69823) (xy 137.858224 -37.735803) (xy 137.802201 -37.766597) (xy 137.751867 -37.786521)
			(xy 142.735548 -37.786521) (xy 142.735548 -37.722599) (xy 142.743559 -37.659181) (xy 142.759456 -37.597267)
			(xy 142.782988 -37.537834) (xy 142.813782 -37.481819) (xy 142.851355 -37.430104) (xy 142.895112 -37.383507)
			(xy 142.944365 -37.342762) (xy 142.998336 -37.308511) (xy 143.056175 -37.281294) (xy 143.116968 -37.261541)
			(xy 143.179758 -37.249563) (xy 143.243554 -37.24555) (xy 143.30735 -37.249563) (xy 143.37014 -37.261541)
			(xy 143.430933 -37.281294) (xy 143.488772 -37.308511) (xy 143.542743 -37.342762) (xy 143.591996 -37.383507)
			(xy 143.635753 -37.430104) (xy 143.673326 -37.481819) (xy 143.70412 -37.537834) (xy 143.727652 -37.597267)
			(xy 143.743549 -37.659181) (xy 143.75156 -37.722599) (xy 143.752062 -37.75456) (xy 143.75156 -37.786521)
			(xy 143.743549 -37.849939) (xy 143.729821 -37.903404) (xy 144.00987 -37.903404) (xy 144.013941 -37.847782)
			(xy 144.026067 -37.793345) (xy 144.04599 -37.741254) (xy 144.073286 -37.692619) (xy 144.107372 -37.648476)
			(xy 144.147521 -37.609767) (xy 144.192879 -37.577316) (xy 144.242479 -37.551815) (xy 144.295263 -37.533808)
			(xy 144.350106 -37.523678) (xy 144.40584 -37.521641) (xy 144.461277 -37.527741) (xy 144.515234 -37.541847)
			(xy 144.566563 -37.563659) (xy 144.614169 -37.592713) (xy 144.657037 -37.628388) (xy 144.694254 -37.669925)
			(xy 144.725027 -37.716438) (xy 144.748699 -37.766935) (xy 144.754592 -37.786521) (xy 151.32532 -37.786521)
			(xy 151.32532 -37.722599) (xy 151.333331 -37.659181) (xy 151.349228 -37.597267) (xy 151.37276 -37.537834)
			(xy 151.403554 -37.481819) (xy 151.441127 -37.430104) (xy 151.484884 -37.383507) (xy 151.534137 -37.342762)
			(xy 151.588108 -37.308511) (xy 151.645947 -37.281294) (xy 151.70674 -37.261541) (xy 151.76953 -37.249563)
			(xy 151.833326 -37.24555) (xy 151.897122 -37.249563) (xy 151.959912 -37.261541) (xy 152.020705 -37.281294)
			(xy 152.078544 -37.308511) (xy 152.132515 -37.342762) (xy 152.181768 -37.383507) (xy 152.225525 -37.430104)
			(xy 152.263098 -37.481819) (xy 152.293892 -37.537834) (xy 152.317424 -37.597267) (xy 152.333321 -37.659181)
			(xy 152.341332 -37.722599) (xy 152.341834 -37.75456) (xy 152.341332 -37.786521) (xy 152.333321 -37.849939)
			(xy 152.317424 -37.911853) (xy 152.293892 -37.971286) (xy 152.263098 -38.027301) (xy 152.225525 -38.079016)
			(xy 152.181768 -38.125613) (xy 152.132515 -38.166358) (xy 152.078544 -38.200609) (xy 152.020705 -38.227826)
			(xy 151.959912 -38.247579) (xy 151.897122 -38.259557) (xy 151.833326 -38.263571) (xy 151.76953 -38.259557)
			(xy 151.70674 -38.247579) (xy 151.645947 -38.227826) (xy 151.588108 -38.200609) (xy 151.534137 -38.166358)
			(xy 151.484884 -38.125613) (xy 151.441127 -38.079016) (xy 151.403554 -38.027301) (xy 151.37276 -37.971286)
			(xy 151.349228 -37.911853) (xy 151.333331 -37.849939) (xy 151.32532 -37.786521) (xy 144.754592 -37.786521)
			(xy 144.764767 -37.820342) (xy 144.772887 -37.875518) (xy 144.773396 -37.903404) (xy 144.772887 -37.93129)
			(xy 144.764767 -37.986466) (xy 144.748699 -38.039873) (xy 144.725027 -38.09037) (xy 144.694254 -38.136883)
			(xy 144.657037 -38.17842) (xy 144.614169 -38.214095) (xy 144.566563 -38.243149) (xy 144.515234 -38.264961)
			(xy 144.461277 -38.279067) (xy 144.40584 -38.285167) (xy 144.350106 -38.28313) (xy 144.295263 -38.273)
			(xy 144.242479 -38.254993) (xy 144.192879 -38.229492) (xy 144.147521 -38.197041) (xy 144.107372 -38.158332)
			(xy 144.073286 -38.114189) (xy 144.04599 -38.065554) (xy 144.026067 -38.013463) (xy 144.013941 -37.959026)
			(xy 144.00987 -37.903404) (xy 143.729821 -37.903404) (xy 143.727652 -37.911853) (xy 143.70412 -37.971286)
			(xy 143.673326 -38.027301) (xy 143.635753 -38.079016) (xy 143.591996 -38.125613) (xy 143.542743 -38.166358)
			(xy 143.488772 -38.200609) (xy 143.430933 -38.227826) (xy 143.37014 -38.247579) (xy 143.30735 -38.259557)
			(xy 143.243554 -38.263571) (xy 143.179758 -38.259557) (xy 143.116968 -38.247579) (xy 143.056175 -38.227826)
			(xy 142.998336 -38.200609) (xy 142.944365 -38.166358) (xy 142.895112 -38.125613) (xy 142.851355 -38.079016)
			(xy 142.813782 -38.027301) (xy 142.782988 -37.971286) (xy 142.759456 -37.911853) (xy 142.743559 -37.849939)
			(xy 142.735548 -37.786521) (xy 137.751867 -37.786521) (xy 137.74276 -37.790126) (xy 137.680839 -37.806019)
			(xy 137.617414 -37.814026) (xy 137.58545 -37.814504) (xy 137.552562 -37.813968) (xy 137.487335 -37.805481)
			(xy 137.423746 -37.788656) (xy 137.362857 -37.763773) (xy 137.305685 -37.731248) (xy 137.253182 -37.691624)
			(xy 137.229342 -37.668962) (xy 137.221943 -37.66229) (xy 137.2035 -37.654795) (xy 137.183592 -37.654895)
			(xy 137.174224 -37.658294) (xy 137.08761 -37.694616) (xy 137.078516 -37.698767) (xy 137.064383 -37.712891)
			(xy 137.056762 -37.731361) (xy 137.056368 -37.741352) (xy 137.056368 -38.038024) (xy 137.056883 -38.047979)
			(xy 137.06455 -38.066361) (xy 137.078613 -38.080465) (xy 137.08761 -38.08476) (xy 137.174224 -38.121082)
			(xy 137.183597 -38.124426) (xy 137.203478 -38.12449) (xy 137.221902 -38.117022) (xy 137.229342 -38.110414)
			(xy 137.253174 -38.087741) (xy 137.305672 -38.048106) (xy 137.362845 -38.015574) (xy 137.423736 -37.990689)
			(xy 137.487329 -37.973866) (xy 137.55256 -37.965387) (xy 137.58545 -37.964872) (xy 137.617413 -37.96539)
			(xy 137.680836 -37.973396) (xy 137.742755 -37.989289) (xy 137.802194 -38.012817) (xy 137.858215 -38.04361)
			(xy 137.909935 -38.081182) (xy 137.956537 -38.12494) (xy 137.997287 -38.174194) (xy 138.031542 -38.228168)
			(xy 138.058763 -38.286009) (xy 138.078518 -38.346806) (xy 138.090497 -38.4096) (xy 138.094512 -38.4734)
			(xy 138.090497 -38.5372) (xy 138.078518 -38.599994) (xy 138.058763 -38.660791) (xy 138.031542 -38.718632)
			(xy 137.997287 -38.772606) (xy 137.977545 -38.796468) (xy 141.047976 -38.796468) (xy 141.052047 -38.740846)
			(xy 141.064173 -38.686409) (xy 141.084096 -38.634318) (xy 141.111392 -38.585683) (xy 141.145478 -38.54154)
			(xy 141.185627 -38.502831) (xy 141.230985 -38.47038) (xy 141.280585 -38.444879) (xy 141.333369 -38.426872)
			(xy 141.388212 -38.416742) (xy 141.443946 -38.414705) (xy 141.499383 -38.420805) (xy 141.55334 -38.434911)
			(xy 141.604669 -38.456723) (xy 141.652275 -38.485777) (xy 141.695143 -38.521452) (xy 141.73236 -38.562989)
			(xy 141.763133 -38.609502) (xy 141.786805 -38.659999) (xy 141.802873 -38.713406) (xy 141.810993 -38.768582)
			(xy 141.811502 -38.796468) (xy 141.810993 -38.824354) (xy 141.802873 -38.87953) (xy 141.786805 -38.932937)
			(xy 141.763133 -38.983434) (xy 141.73236 -39.029947) (xy 141.70855 -39.056521) (xy 142.735548 -39.056521)
			(xy 142.735548 -38.992599) (xy 142.743559 -38.929181) (xy 142.759456 -38.867267) (xy 142.782988 -38.807834)
			(xy 142.813782 -38.751819) (xy 142.851355 -38.700104) (xy 142.895112 -38.653507) (xy 142.944365 -38.612762)
			(xy 142.998336 -38.578511) (xy 143.056175 -38.551294) (xy 143.116968 -38.531541) (xy 143.179758 -38.519563)
			(xy 143.243554 -38.51555) (xy 143.30735 -38.519563) (xy 143.37014 -38.531541) (xy 143.430933 -38.551294)
			(xy 143.488772 -38.578511) (xy 143.542743 -38.612762) (xy 143.591996 -38.653507) (xy 143.635753 -38.700104)
			(xy 143.673326 -38.751819) (xy 143.70412 -38.807834) (xy 143.727652 -38.867267) (xy 143.743549 -38.929181)
			(xy 143.75156 -38.992599) (xy 143.752062 -39.02456) (xy 143.75156 -39.056521) (xy 151.32532 -39.056521)
			(xy 151.32532 -38.992599) (xy 151.333331 -38.929181) (xy 151.349228 -38.867267) (xy 151.37276 -38.807834)
			(xy 151.403554 -38.751819) (xy 151.441127 -38.700104) (xy 151.484884 -38.653507) (xy 151.534137 -38.612762)
			(xy 151.588108 -38.578511) (xy 151.645947 -38.551294) (xy 151.70674 -38.531541) (xy 151.76953 -38.519563)
			(xy 151.833326 -38.51555) (xy 151.897122 -38.519563) (xy 151.959912 -38.531541) (xy 152.020705 -38.551294)
			(xy 152.078544 -38.578511) (xy 152.132515 -38.612762) (xy 152.181768 -38.653507) (xy 152.225525 -38.700104)
			(xy 152.263098 -38.751819) (xy 152.293892 -38.807834) (xy 152.317424 -38.867267) (xy 152.333321 -38.929181)
			(xy 152.341332 -38.992599) (xy 152.341834 -39.02456) (xy 152.341332 -39.056521) (xy 152.333321 -39.119939)
			(xy 152.317424 -39.181853) (xy 152.293892 -39.241286) (xy 152.263098 -39.297301) (xy 152.225525 -39.349016)
			(xy 152.181768 -39.395613) (xy 152.172507 -39.403274) (xy 153.378154 -39.403274) (xy 153.378614 -39.373147)
			(xy 153.38574 -39.313315) (xy 153.39989 -39.254746) (xy 153.420864 -39.19826) (xy 153.44837 -39.14465)
			(xy 153.48202 -39.094668) (xy 153.501344 -39.07155) (xy 153.506921 -39.064457) (xy 153.513172 -39.047545)
			(xy 153.513536 -39.03853) (xy 153.513536 -39.008304) (xy 153.513169 -38.999288) (xy 153.506927 -38.982372)
			(xy 153.501344 -38.975284) (xy 153.482011 -38.952173) (xy 153.448354 -38.902192) (xy 153.420844 -38.848582)
			(xy 153.399868 -38.792094) (xy 153.38572 -38.733522) (xy 153.378598 -38.673688) (xy 153.378154 -38.64356)
			(xy 153.378596 -38.612839) (xy 153.386001 -38.551843) (xy 153.400698 -38.492184) (xy 153.422473 -38.434729)
			(xy 153.45101 -38.380315) (xy 153.46807 -38.354762) (xy 153.4735 -38.346096) (xy 153.477553 -38.326067)
			(xy 153.473474 -38.306042) (xy 153.46807 -38.297358) (xy 153.450995 -38.271815) (xy 153.422465 -38.217397)
			(xy 153.400698 -38.159939) (xy 153.38601 -38.100278) (xy 153.378614 -38.039282) (xy 153.378154 -38.00856)
			(xy 153.378611 -37.977272) (xy 153.386287 -37.915168) (xy 153.401532 -37.854476) (xy 153.424113 -37.796116)
			(xy 153.45369 -37.74097) (xy 153.489815 -37.689873) (xy 153.53194 -37.643599) (xy 153.579429 -37.602848)
			(xy 153.60523 -37.585142) (xy 153.615383 -37.577621) (xy 153.627244 -37.555347) (xy 153.627836 -37.542724)
			(xy 153.627836 -37.458396) (xy 153.627214 -37.445787) (xy 153.615341 -37.423539) (xy 153.60523 -37.415978)
			(xy 153.579451 -37.398244) (xy 153.531972 -37.357489) (xy 153.489855 -37.311215) (xy 153.453735 -37.260122)
			(xy 153.424159 -37.204981) (xy 153.401576 -37.146627) (xy 153.386325 -37.085943) (xy 153.378637 -37.023846)
			(xy 153.378154 -36.99256) (xy 153.378656 -36.960599) (xy 153.386667 -36.897181) (xy 153.402564 -36.835267)
			(xy 153.426096 -36.775834) (xy 153.45689 -36.719819) (xy 153.494463 -36.668104) (xy 153.53822 -36.621507)
			(xy 153.587473 -36.580762) (xy 153.641444 -36.546511) (xy 153.699283 -36.519294) (xy 153.760076 -36.499541)
			(xy 153.822866 -36.487563) (xy 153.886662 -36.48355) (xy 153.950458 -36.487563) (xy 154.013248 -36.499541)
			(xy 154.074041 -36.519294) (xy 154.13188 -36.546511) (xy 154.185851 -36.580762) (xy 154.235104 -36.621507)
			(xy 154.278861 -36.668104) (xy 154.316434 -36.719819) (xy 154.347228 -36.775834) (xy 154.37076 -36.835267)
			(xy 154.386657 -36.897181) (xy 154.394668 -36.960599) (xy 154.39517 -36.99256) (xy 154.394718 -37.023848)
			(xy 154.387039 -37.085952) (xy 154.371793 -37.146643) (xy 154.349211 -37.205003) (xy 154.319633 -37.260149)
			(xy 154.283508 -37.311246) (xy 154.241383 -37.35752) (xy 154.193895 -37.398272) (xy 154.168094 -37.415978)
			(xy 154.157964 -37.423523) (xy 154.146094 -37.44578) (xy 154.145488 -37.458396) (xy 154.145488 -37.542724)
			(xy 154.146088 -37.555336) (xy 154.157975 -37.577584) (xy 154.168094 -37.585142) (xy 154.193888 -37.602856)
			(xy 154.241365 -37.643614) (xy 154.283481 -37.689891) (xy 154.319599 -37.740988) (xy 154.349173 -37.796132)
			(xy 154.371754 -37.854488) (xy 154.387003 -37.915174) (xy 154.394688 -37.977274) (xy 154.39517 -38.00856)
			(xy 154.394734 -38.039282) (xy 154.387327 -38.100277) (xy 154.372629 -38.159936) (xy 154.350852 -38.217391)
			(xy 154.322315 -38.271805) (xy 154.305254 -38.297358) (xy 154.299898 -38.306062) (xy 154.295829 -38.326067)
			(xy 154.299872 -38.346077) (xy 154.305254 -38.354762) (xy 154.322298 -38.380325) (xy 154.350832 -38.434738)
			(xy 154.372605 -38.49219) (xy 154.387301 -38.551847) (xy 154.394705 -38.61284) (xy 154.39517 -38.64356)
			(xy 154.394749 -38.673688) (xy 154.387617 -38.733522) (xy 154.376026 -38.781482) (xy 158.381954 -38.781482)
			(xy 158.382446 -38.750582) (xy 158.38994 -38.689239) (xy 158.404802 -38.629254) (xy 158.426815 -38.571508)
			(xy 158.455654 -38.51685) (xy 158.490897 -38.466085) (xy 158.532024 -38.419958) (xy 158.554928 -38.399212)
			(xy 158.563318 -38.391056) (xy 158.572302 -38.369481) (xy 158.570872 -38.346154) (xy 158.565596 -38.335712)
			(xy 158.553403 -38.313898) (xy 158.534225 -38.267749) (xy 158.521247 -38.219489) (xy 158.514691 -38.169945)
			(xy 158.514288 -38.144958) (xy 158.514774 -38.117707) (xy 158.52253 -38.063759) (xy 158.537885 -38.011464)
			(xy 158.560527 -37.961887) (xy 158.589993 -37.916037) (xy 158.625684 -37.874846) (xy 158.666875 -37.839155)
			(xy 158.712725 -37.809689) (xy 158.762302 -37.787047) (xy 158.814597 -37.771692) (xy 158.868545 -37.763936)
			(xy 158.923047 -37.763936) (xy 158.976995 -37.771692) (xy 159.02929 -37.787047) (xy 159.078867 -37.809689)
			(xy 159.124717 -37.839155) (xy 159.165908 -37.874846) (xy 159.201599 -37.916037) (xy 159.231065 -37.961887)
			(xy 159.253707 -38.011464) (xy 159.269062 -38.063759) (xy 159.271059 -38.077648) (xy 167.863266 -38.077648)
			(xy 167.863266 -38.077394) (xy 167.863703 -38.047186) (xy 167.870843 -37.987194) (xy 167.885045 -37.928472)
			(xy 167.906109 -37.871848) (xy 167.933737 -37.81812) (xy 167.967541 -37.768047) (xy 167.986964 -37.744908)
			(xy 167.992638 -37.737858) (xy 167.999008 -37.72093) (xy 167.99941 -37.711888) (xy 167.99941 -37.681408)
			(xy 167.998996 -37.672371) (xy 167.992613 -37.655455) (xy 167.986964 -37.648388) (xy 167.967573 -37.625224)
			(xy 167.933781 -37.575148) (xy 167.906155 -37.521424) (xy 167.885086 -37.464806) (xy 167.870869 -37.406092)
			(xy 167.863704 -37.346107) (xy 167.863266 -37.315902) (xy 167.863266 -37.315648) (xy 167.863783 -37.284918)
			(xy 167.871185 -37.223905) (xy 167.885888 -37.16423) (xy 167.907678 -37.106762) (xy 167.936235 -37.052339)
			(xy 167.971145 -37.001756) (xy 168.011897 -36.955749) (xy 168.057897 -36.91499) (xy 168.108476 -36.880074)
			(xy 168.162894 -36.851508) (xy 168.220359 -36.829711) (xy 168.280032 -36.814999) (xy 168.341044 -36.807587)
			(xy 168.371774 -36.80714) (xy 168.402046 -36.807571) (xy 168.462162 -36.814758) (xy 168.520999 -36.829033)
			(xy 168.577725 -36.850193) (xy 168.631536 -36.877941) (xy 168.681671 -36.911882) (xy 168.727421 -36.951537)
			(xy 168.768138 -36.996344) (xy 168.786048 -37.020754) (xy 168.791313 -37.02765) (xy 168.805476 -37.037651)
			(xy 168.813734 -37.040312) (xy 168.842182 -37.048186) (xy 168.850589 -37.050263) (xy 168.867864 -37.049218)
			(xy 168.875964 -37.046154) (xy 168.907609 -37.033258) (xy 168.973478 -37.015072) (xy 169.041188 -37.005853)
			(xy 169.075354 -37.00526) (xy 169.107316 -37.005802) (xy 169.170737 -37.013809) (xy 169.232654 -37.029701)
			(xy 169.292091 -37.053229) (xy 169.348111 -37.084022) (xy 169.369595 -37.099629) (xy 170.60087 -37.099629)
			(xy 170.60087 -37.000299) (xy 170.608862 -36.901292) (xy 170.624796 -36.803249) (xy 170.648567 -36.706806)
			(xy 170.680022 -36.612588) (xy 170.718955 -36.521208) (xy 170.765116 -36.433256) (xy 170.818204 -36.349304)
			(xy 170.877875 -36.269895) (xy 170.943743 -36.195546) (xy 171.01538 -36.126738) (xy 171.092321 -36.063918)
			(xy 171.174067 -36.007493) (xy 171.260089 -35.957828) (xy 171.349828 -35.915246) (xy 171.442702 -35.880024)
			(xy 171.53811 -35.852388) (xy 171.635432 -35.83252) (xy 171.734037 -35.820547) (xy 171.833286 -35.816548)
			(xy 171.932535 -35.820547) (xy 172.03114 -35.83252) (xy 172.128462 -35.852388) (xy 172.22387 -35.880024)
			(xy 172.316744 -35.915246) (xy 172.406483 -35.957828) (xy 172.492505 -36.007493) (xy 172.574251 -36.063918)
			(xy 172.651192 -36.126738) (xy 172.722829 -36.195546) (xy 172.788697 -36.269895) (xy 172.848368 -36.349304)
			(xy 172.901456 -36.433256) (xy 172.947617 -36.521208) (xy 172.98655 -36.612588) (xy 173.018005 -36.706806)
			(xy 173.041776 -36.803249) (xy 173.05771 -36.901292) (xy 173.065702 -37.000299) (xy 173.066202 -37.049964)
			(xy 173.065702 -37.099629) (xy 173.05771 -37.198636) (xy 173.041776 -37.296679) (xy 173.018005 -37.393122)
			(xy 172.98655 -37.48734) (xy 172.947617 -37.57872) (xy 172.901456 -37.666672) (xy 172.848368 -37.750624)
			(xy 172.788697 -37.830033) (xy 172.722829 -37.904382) (xy 172.651192 -37.97319) (xy 172.574251 -38.03601)
			(xy 172.492505 -38.092435) (xy 172.406483 -38.1421) (xy 172.316744 -38.184682) (xy 172.22387 -38.219904)
			(xy 172.128462 -38.24754) (xy 172.03114 -38.267408) (xy 171.932535 -38.279381) (xy 171.833286 -38.283381)
			(xy 171.734037 -38.279381) (xy 171.635432 -38.267408) (xy 171.53811 -38.24754) (xy 171.442702 -38.219904)
			(xy 171.349828 -38.184682) (xy 171.260089 -38.1421) (xy 171.174067 -38.092435) (xy 171.092321 -38.03601)
			(xy 171.01538 -37.97319) (xy 170.943743 -37.904382) (xy 170.877875 -37.830033) (xy 170.818204 -37.750624)
			(xy 170.765116 -37.666672) (xy 170.718955 -37.57872) (xy 170.680022 -37.48734) (xy 170.648567 -37.393122)
			(xy 170.624796 -37.296679) (xy 170.608862 -37.198636) (xy 170.60087 -37.099629) (xy 169.369595 -37.099629)
			(xy 169.399829 -37.121593) (xy 169.44643 -37.16535) (xy 169.487178 -37.214603) (xy 169.521433 -37.268575)
			(xy 169.548652 -37.326415) (xy 169.568407 -37.38721) (xy 169.580385 -37.450002) (xy 169.5844 -37.5138)
			(xy 169.580385 -37.577598) (xy 169.568407 -37.64039) (xy 169.548652 -37.701185) (xy 169.521433 -37.759025)
			(xy 169.487178 -37.812997) (xy 169.44643 -37.86225) (xy 169.399829 -37.906007) (xy 169.348111 -37.943578)
			(xy 169.292091 -37.974371) (xy 169.232654 -37.997899) (xy 169.170737 -38.013791) (xy 169.107316 -38.021798)
			(xy 169.075354 -38.022276) (xy 169.074338 -38.022276) (xy 169.054762 -38.022069) (xy 169.01573 -38.019018)
			(xy 168.99636 -38.01618) (xy 168.985692 -38.014402) (xy 168.965118 -38.01999) (xy 168.88968 -38.080442)
			(xy 168.880028 -38.098984) (xy 168.879266 -38.109906) (xy 168.876799 -38.141763) (xy 168.864783 -38.204522)
			(xy 168.844999 -38.265281) (xy 168.817759 -38.323083) (xy 168.783493 -38.377017) (xy 168.742739 -38.426233)
			(xy 168.696142 -38.469956) (xy 168.644434 -38.507498) (xy 168.58843 -38.538265) (xy 168.529013 -38.561775)
			(xy 168.467119 -38.577655) (xy 168.403723 -38.585657) (xy 168.371774 -38.586156) (xy 168.341044 -38.585668)
			(xy 168.280033 -38.578258) (xy 168.22036 -38.563548) (xy 168.162895 -38.541753) (xy 168.108475 -38.513191)
			(xy 168.057895 -38.478278) (xy 168.011891 -38.437524) (xy 167.971135 -38.391522) (xy 167.93622 -38.340943)
			(xy 167.907656 -38.286525) (xy 167.885859 -38.229061) (xy 167.871146 -38.169388) (xy 167.863733 -38.108378)
			(xy 167.863266 -38.077648) (xy 159.271059 -38.077648) (xy 159.276818 -38.117707) (xy 159.277304 -38.144958)
			(xy 159.276872 -38.170747) (xy 159.269932 -38.221854) (xy 159.256173 -38.271562) (xy 159.235846 -38.318965)
			(xy 159.222948 -38.3413) (xy 159.217448 -38.351651) (xy 159.215493 -38.374976) (xy 159.224073 -38.396755)
			(xy 159.232346 -38.405054) (xy 159.254471 -38.425735) (xy 159.294148 -38.471493) (xy 159.328109 -38.52164)
			(xy 159.355875 -38.575466) (xy 159.37705 -38.632208) (xy 159.391337 -38.691064) (xy 159.396047 -38.730428)
			(xy 173.486316 -38.730428) (xy 173.490387 -38.674806) (xy 173.502513 -38.620369) (xy 173.522436 -38.568278)
			(xy 173.549732 -38.519643) (xy 173.583818 -38.4755) (xy 173.623967 -38.436791) (xy 173.669325 -38.40434)
			(xy 173.718925 -38.378839) (xy 173.771709 -38.360832) (xy 173.826552 -38.350702) (xy 173.882286 -38.348665)
			(xy 173.937723 -38.354765) (xy 173.99168 -38.368871) (xy 174.043009 -38.390683) (xy 174.090615 -38.419737)
			(xy 174.133483 -38.455412) (xy 174.1707 -38.496949) (xy 174.201473 -38.543462) (xy 174.225145 -38.593959)
			(xy 174.241213 -38.647366) (xy 174.249333 -38.702542) (xy 174.249842 -38.730428) (xy 174.502316 -38.730428)
			(xy 174.506387 -38.674806) (xy 174.518513 -38.620369) (xy 174.538436 -38.568278) (xy 174.565732 -38.519643)
			(xy 174.599818 -38.4755) (xy 174.639967 -38.436791) (xy 174.685325 -38.40434) (xy 174.734925 -38.378839)
			(xy 174.787709 -38.360832) (xy 174.842552 -38.350702) (xy 174.898286 -38.348665) (xy 174.953723 -38.354765)
			(xy 175.00768 -38.368871) (xy 175.059009 -38.390683) (xy 175.106615 -38.419737) (xy 175.149483 -38.455412)
			(xy 175.1867 -38.496949) (xy 175.217473 -38.543462) (xy 175.241145 -38.593959) (xy 175.257213 -38.647366)
			(xy 175.265333 -38.702542) (xy 175.265842 -38.730428) (xy 175.518316 -38.730428) (xy 175.522387 -38.674806)
			(xy 175.534513 -38.620369) (xy 175.554436 -38.568278) (xy 175.581732 -38.519643) (xy 175.615818 -38.4755)
			(xy 175.655967 -38.436791) (xy 175.701325 -38.40434) (xy 175.750925 -38.378839) (xy 175.803709 -38.360832)
			(xy 175.858552 -38.350702) (xy 175.914286 -38.348665) (xy 175.969723 -38.354765) (xy 176.02368 -38.368871)
			(xy 176.075009 -38.390683) (xy 176.122615 -38.419737) (xy 176.165483 -38.455412) (xy 176.2027 -38.496949)
			(xy 176.233473 -38.543462) (xy 176.257145 -38.593959) (xy 176.273213 -38.647366) (xy 176.281333 -38.702542)
			(xy 176.281842 -38.730428) (xy 176.281333 -38.758314) (xy 176.273213 -38.81349) (xy 176.257145 -38.866897)
			(xy 176.233473 -38.917394) (xy 176.2027 -38.963907) (xy 176.165483 -39.005444) (xy 176.122615 -39.041119)
			(xy 176.075009 -39.070173) (xy 176.02368 -39.091985) (xy 175.969723 -39.106091) (xy 175.914286 -39.112191)
			(xy 175.858552 -39.110154) (xy 175.803709 -39.100024) (xy 175.750925 -39.082017) (xy 175.701325 -39.056516)
			(xy 175.655967 -39.024065) (xy 175.615818 -38.985356) (xy 175.581732 -38.941213) (xy 175.554436 -38.892578)
			(xy 175.534513 -38.840487) (xy 175.522387 -38.78605) (xy 175.518316 -38.730428) (xy 175.265842 -38.730428)
			(xy 175.265333 -38.758314) (xy 175.257213 -38.81349) (xy 175.241145 -38.866897) (xy 175.217473 -38.917394)
			(xy 175.1867 -38.963907) (xy 175.149483 -39.005444) (xy 175.106615 -39.041119) (xy 175.059009 -39.070173)
			(xy 175.00768 -39.091985) (xy 174.953723 -39.106091) (xy 174.898286 -39.112191) (xy 174.842552 -39.110154)
			(xy 174.787709 -39.100024) (xy 174.734925 -39.082017) (xy 174.685325 -39.056516) (xy 174.639967 -39.024065)
			(xy 174.599818 -38.985356) (xy 174.565732 -38.941213) (xy 174.538436 -38.892578) (xy 174.518513 -38.840487)
			(xy 174.506387 -38.78605) (xy 174.502316 -38.730428) (xy 174.249842 -38.730428) (xy 174.249333 -38.758314)
			(xy 174.241213 -38.81349) (xy 174.225145 -38.866897) (xy 174.201473 -38.917394) (xy 174.1707 -38.963907)
			(xy 174.133483 -39.005444) (xy 174.090615 -39.041119) (xy 174.043009 -39.070173) (xy 173.99168 -39.091985)
			(xy 173.937723 -39.106091) (xy 173.882286 -39.112191) (xy 173.826552 -39.110154) (xy 173.771709 -39.100024)
			(xy 173.718925 -39.082017) (xy 173.669325 -39.056516) (xy 173.623967 -39.024065) (xy 173.583818 -38.985356)
			(xy 173.549732 -38.941213) (xy 173.522436 -38.892578) (xy 173.502513 -38.840487) (xy 173.490387 -38.78605)
			(xy 173.486316 -38.730428) (xy 159.396047 -38.730428) (xy 159.398532 -38.7512) (xy 159.39897 -38.781482)
			(xy 159.398468 -38.813443) (xy 159.390457 -38.876861) (xy 159.37456 -38.938775) (xy 159.351028 -38.998208)
			(xy 159.320234 -39.054223) (xy 159.282661 -39.105938) (xy 159.238904 -39.152535) (xy 159.189651 -39.19328)
			(xy 159.13568 -39.227531) (xy 159.077841 -39.254748) (xy 159.017048 -39.274501) (xy 158.954258 -39.286479)
			(xy 158.890462 -39.290493) (xy 158.826666 -39.286479) (xy 158.763876 -39.274501) (xy 158.703083 -39.254748)
			(xy 158.645244 -39.227531) (xy 158.591273 -39.19328) (xy 158.54202 -39.152535) (xy 158.498263 -39.105938)
			(xy 158.46069 -39.054223) (xy 158.429896 -38.998208) (xy 158.406364 -38.938775) (xy 158.390467 -38.876861)
			(xy 158.382456 -38.813443) (xy 158.381954 -38.781482) (xy 154.376026 -38.781482) (xy 154.373461 -38.792093)
			(xy 154.35248 -38.848579) (xy 154.324967 -38.902188) (xy 154.291308 -38.952168) (xy 154.27198 -38.975284)
			(xy 154.266392 -38.982369) (xy 154.260147 -38.999287) (xy 154.259788 -39.008304) (xy 154.259788 -39.03853)
			(xy 154.260134 -39.047548) (xy 154.266389 -39.064465) (xy 154.27198 -39.07155) (xy 154.291286 -39.094683)
			(xy 154.324945 -39.144659) (xy 154.352459 -39.198265) (xy 154.37344 -39.254748) (xy 154.387594 -39.313316)
			(xy 154.394722 -39.373147) (xy 154.39517 -39.403274) (xy 154.394668 -39.435235) (xy 154.386657 -39.498653)
			(xy 154.37076 -39.560567) (xy 154.347228 -39.62) (xy 154.316434 -39.676015) (xy 154.278861 -39.72773)
			(xy 154.235104 -39.774327) (xy 154.185851 -39.815072) (xy 154.13188 -39.849323) (xy 154.074041 -39.87654)
			(xy 154.013248 -39.896293) (xy 153.950458 -39.908271) (xy 153.886662 -39.912285) (xy 153.822866 -39.908271)
			(xy 153.760076 -39.896293) (xy 153.699283 -39.87654) (xy 153.641444 -39.849323) (xy 153.587473 -39.815072)
			(xy 153.53822 -39.774327) (xy 153.494463 -39.72773) (xy 153.45689 -39.676015) (xy 153.426096 -39.62)
			(xy 153.402564 -39.560567) (xy 153.386667 -39.498653) (xy 153.378656 -39.435235) (xy 153.378154 -39.403274)
			(xy 152.172507 -39.403274) (xy 152.132515 -39.436358) (xy 152.078544 -39.470609) (xy 152.020705 -39.497826)
			(xy 151.959912 -39.517579) (xy 151.897122 -39.529557) (xy 151.833326 -39.533571) (xy 151.76953 -39.529557)
			(xy 151.70674 -39.517579) (xy 151.645947 -39.497826) (xy 151.588108 -39.470609) (xy 151.534137 -39.436358)
			(xy 151.484884 -39.395613) (xy 151.441127 -39.349016) (xy 151.403554 -39.297301) (xy 151.37276 -39.241286)
			(xy 151.349228 -39.181853) (xy 151.333331 -39.119939) (xy 151.32532 -39.056521) (xy 143.75156 -39.056521)
			(xy 143.743549 -39.119939) (xy 143.727652 -39.181853) (xy 143.70412 -39.241286) (xy 143.673326 -39.297301)
			(xy 143.635753 -39.349016) (xy 143.591996 -39.395613) (xy 143.542743 -39.436358) (xy 143.488772 -39.470609)
			(xy 143.430933 -39.497826) (xy 143.37014 -39.517579) (xy 143.30735 -39.529557) (xy 143.243554 -39.533571)
			(xy 143.179758 -39.529557) (xy 143.116968 -39.517579) (xy 143.056175 -39.497826) (xy 142.998336 -39.470609)
			(xy 142.944365 -39.436358) (xy 142.895112 -39.395613) (xy 142.851355 -39.349016) (xy 142.813782 -39.297301)
			(xy 142.782988 -39.241286) (xy 142.759456 -39.181853) (xy 142.743559 -39.119939) (xy 142.735548 -39.056521)
			(xy 141.70855 -39.056521) (xy 141.695143 -39.071484) (xy 141.652275 -39.107159) (xy 141.604669 -39.136213)
			(xy 141.55334 -39.158025) (xy 141.499383 -39.172131) (xy 141.443946 -39.178231) (xy 141.388212 -39.176194)
			(xy 141.333369 -39.166064) (xy 141.280585 -39.148057) (xy 141.230985 -39.122556) (xy 141.185627 -39.090105)
			(xy 141.145478 -39.051396) (xy 141.111392 -39.007253) (xy 141.084096 -38.958618) (xy 141.064173 -38.906527)
			(xy 141.052047 -38.85209) (xy 141.047976 -38.796468) (xy 137.977545 -38.796468) (xy 137.956537 -38.82186)
			(xy 137.909935 -38.865618) (xy 137.858215 -38.90319) (xy 137.802194 -38.933983) (xy 137.742755 -38.957511)
			(xy 137.680836 -38.973404) (xy 137.617413 -38.98141) (xy 137.58545 -38.981888) (xy 137.552561 -38.981356)
			(xy 137.487334 -38.972869) (xy 137.423745 -38.956044) (xy 137.362856 -38.93116) (xy 137.305684 -38.898634)
			(xy 137.253182 -38.859008) (xy 137.229342 -38.836346) (xy 137.221944 -38.829673) (xy 137.2035 -38.82218)
			(xy 137.183592 -38.82228) (xy 137.174224 -38.825678) (xy 137.08761 -38.862) (xy 137.078522 -38.866163)
			(xy 137.06439 -38.880282) (xy 137.056765 -38.898746) (xy 137.056368 -38.908736) (xy 137.056368 -39.238174)
			(xy 137.056847 -39.248133) (xy 137.064531 -39.266517) (xy 137.078607 -39.280618) (xy 137.08761 -39.28491)
			(xy 137.174224 -39.321232) (xy 137.183595 -39.324588) (xy 137.203478 -39.324652) (xy 137.221904 -39.317178)
			(xy 137.229342 -39.310564) (xy 137.253166 -39.287883) (xy 137.305667 -39.24825) (xy 137.362841 -39.21572)
			(xy 137.423734 -39.190837) (xy 137.487328 -39.174015) (xy 137.55256 -39.165537) (xy 137.58545 -39.165022)
			(xy 137.617416 -39.16544) (xy 137.680845 -39.173447) (xy 137.742771 -39.189341) (xy 137.802215 -39.212872)
			(xy 137.858242 -39.243668) (xy 137.909966 -39.281244) (xy 137.956573 -39.325006) (xy 137.997328 -39.374265)
			(xy 138.031586 -39.428244) (xy 138.058809 -39.486091) (xy 138.078566 -39.546894) (xy 138.090547 -39.609694)
			(xy 138.094562 -39.6735) (xy 138.090547 -39.737306) (xy 138.078566 -39.800106) (xy 138.070354 -39.825379)
			(xy 141.60093 -39.825379) (xy 141.60093 -39.761457) (xy 141.608941 -39.698039) (xy 141.624838 -39.636125)
			(xy 141.64837 -39.576692) (xy 141.679164 -39.520677) (xy 141.716737 -39.468962) (xy 141.760494 -39.422365)
			(xy 141.809747 -39.38162) (xy 141.863718 -39.347369) (xy 141.921557 -39.320152) (xy 141.98235 -39.300399)
			(xy 142.04514 -39.288421) (xy 142.108936 -39.284408) (xy 142.172732 -39.288421) (xy 142.235522 -39.300399)
			(xy 142.296315 -39.320152) (xy 142.354154 -39.347369) (xy 142.408125 -39.38162) (xy 142.457378 -39.422365)
			(xy 142.501135 -39.468962) (xy 142.538708 -39.520677) (xy 142.569502 -39.576692) (xy 142.593034 -39.636125)
			(xy 142.608931 -39.698039) (xy 142.616942 -39.761457) (xy 142.617444 -39.793418) (xy 142.616942 -39.825379)
			(xy 142.608931 -39.888797) (xy 142.593034 -39.950711) (xy 142.569502 -40.010144) (xy 142.538708 -40.066159)
			(xy 142.501135 -40.117874) (xy 142.457378 -40.164471) (xy 142.408125 -40.205216) (xy 142.354154 -40.239467)
			(xy 142.296315 -40.266684) (xy 142.235522 -40.286437) (xy 142.172732 -40.298415) (xy 142.108936 -40.302429)
			(xy 142.04514 -40.298415) (xy 141.98235 -40.286437) (xy 141.921557 -40.266684) (xy 141.863718 -40.239467)
			(xy 141.809747 -40.205216) (xy 141.760494 -40.164471) (xy 141.716737 -40.117874) (xy 141.679164 -40.066159)
			(xy 141.64837 -40.010144) (xy 141.624838 -39.950711) (xy 141.608941 -39.888797) (xy 141.60093 -39.825379)
			(xy 138.070354 -39.825379) (xy 138.058809 -39.860909) (xy 138.031586 -39.918756) (xy 137.997328 -39.972735)
			(xy 137.956573 -40.021994) (xy 137.909966 -40.065756) (xy 137.858242 -40.103332) (xy 137.802215 -40.134128)
			(xy 137.742771 -40.157659) (xy 137.680845 -40.173553) (xy 137.617416 -40.18156) (xy 137.58545 -40.182038)
			(xy 137.552562 -40.181492) (xy 137.487336 -40.173006) (xy 137.423748 -40.156182) (xy 137.362859 -40.131301)
			(xy 137.305686 -40.098778) (xy 137.253183 -40.059156) (xy 137.229342 -40.036496) (xy 137.22194 -40.029826)
			(xy 137.203499 -40.022327) (xy 137.183592 -40.022428) (xy 137.174224 -40.025828) (xy 137.08761 -40.06215)
			(xy 137.078542 -40.066349) (xy 137.064409 -40.080453) (xy 137.056774 -40.098902) (xy 137.056368 -40.108886)
			(xy 137.056368 -40.206422) (xy 137.056764 -40.216495) (xy 137.064503 -40.235094) (xy 137.071354 -40.24249)
			(xy 137.519875 -40.691011) (xy 140.146272 -40.691011) (xy 140.146272 -40.627089) (xy 140.154283 -40.563671)
			(xy 140.17018 -40.501757) (xy 140.193712 -40.442324) (xy 140.224506 -40.386309) (xy 140.262079 -40.334594)
			(xy 140.305836 -40.287997) (xy 140.355089 -40.247252) (xy 140.40906 -40.213001) (xy 140.466899 -40.185784)
			(xy 140.527692 -40.166031) (xy 140.590482 -40.154053) (xy 140.654278 -40.15004) (xy 140.718074 -40.154053)
			(xy 140.780864 -40.166031) (xy 140.841657 -40.185784) (xy 140.899496 -40.213001) (xy 140.953467 -40.247252)
			(xy 141.00272 -40.287997) (xy 141.046477 -40.334594) (xy 141.08405 -40.386309) (xy 141.114844 -40.442324)
			(xy 141.138376 -40.501757) (xy 141.154273 -40.563671) (xy 141.162284 -40.627089) (xy 141.162786 -40.65905)
			(xy 141.162284 -40.691011) (xy 141.154273 -40.754429) (xy 141.141654 -40.803576) (xy 142.861536 -40.803576)
			(xy 142.865607 -40.747954) (xy 142.877733 -40.693517) (xy 142.897656 -40.641426) (xy 142.924952 -40.592791)
			(xy 142.959038 -40.548648) (xy 142.999187 -40.509939) (xy 143.044545 -40.477488) (xy 143.094145 -40.451987)
			(xy 143.146929 -40.43398) (xy 143.201772 -40.42385) (xy 143.257506 -40.421813) (xy 143.312943 -40.427913)
			(xy 143.339 -40.434725) (xy 151.524202 -40.434725) (xy 151.524202 -40.370803) (xy 151.532213 -40.307385)
			(xy 151.54811 -40.245471) (xy 151.571642 -40.186038) (xy 151.602436 -40.130023) (xy 151.640009 -40.078308)
			(xy 151.683766 -40.031711) (xy 151.733019 -39.990966) (xy 151.78699 -39.956715) (xy 151.844829 -39.929498)
			(xy 151.905622 -39.909745) (xy 151.968412 -39.897767) (xy 152.032208 -39.893754) (xy 152.096004 -39.897767)
			(xy 152.158794 -39.909745) (xy 152.219587 -39.929498) (xy 152.277426 -39.956715) (xy 152.331397 -39.990966)
			(xy 152.38065 -40.031711) (xy 152.424407 -40.078308) (xy 152.46198 -40.130023) (xy 152.492774 -40.186038)
			(xy 152.516306 -40.245471) (xy 152.532203 -40.307385) (xy 152.533594 -40.318393) (xy 189.716404 -40.318393)
			(xy 189.716404 -40.254471) (xy 189.724415 -40.191053) (xy 189.740312 -40.129139) (xy 189.763844 -40.069706)
			(xy 189.794638 -40.013691) (xy 189.832211 -39.961976) (xy 189.875968 -39.915379) (xy 189.925221 -39.874634)
			(xy 189.979192 -39.840383) (xy 190.037031 -39.813166) (xy 190.097824 -39.793413) (xy 190.160614 -39.781435)
			(xy 190.22441 -39.777422) (xy 190.288206 -39.781435) (xy 190.350996 -39.793413) (xy 190.411789 -39.813166)
			(xy 190.469628 -39.840383) (xy 190.523599 -39.874634) (xy 190.572852 -39.915379) (xy 190.616609 -39.961976)
			(xy 190.654182 -40.013691) (xy 190.684976 -40.069706) (xy 190.708508 -40.129139) (xy 190.724405 -40.191053)
			(xy 190.732416 -40.254471) (xy 190.732658 -40.269879) (xy 191.592956 -40.269879) (xy 191.592956 -40.205957)
			(xy 191.600967 -40.142539) (xy 191.616864 -40.080625) (xy 191.640396 -40.021192) (xy 191.67119 -39.965177)
			(xy 191.708763 -39.913462) (xy 191.75252 -39.866865) (xy 191.801773 -39.82612) (xy 191.855744 -39.791869)
			(xy 191.913583 -39.764652) (xy 191.974376 -39.744899) (xy 192.037166 -39.732921) (xy 192.100962 -39.728908)
			(xy 192.164758 -39.732921) (xy 192.227548 -39.744899) (xy 192.288341 -39.764652) (xy 192.34618 -39.791869)
			(xy 192.400151 -39.82612) (xy 192.449404 -39.866865) (xy 192.493161 -39.913462) (xy 192.530734 -39.965177)
			(xy 192.561528 -40.021192) (xy 192.58506 -40.080625) (xy 192.600957 -40.142539) (xy 192.604497 -40.170565)
			(xy 195.434452 -40.170565) (xy 195.434452 -40.106643) (xy 195.442463 -40.043225) (xy 195.45836 -39.981311)
			(xy 195.481892 -39.921878) (xy 195.512686 -39.865863) (xy 195.550259 -39.814148) (xy 195.594016 -39.767551)
			(xy 195.643269 -39.726806) (xy 195.69724 -39.692555) (xy 195.755079 -39.665338) (xy 195.815872 -39.645585)
			(xy 195.878662 -39.633607) (xy 195.942458 -39.629594) (xy 196.006254 -39.633607) (xy 196.069044 -39.645585)
			(xy 196.129837 -39.665338) (xy 196.187676 -39.692555) (xy 196.241647 -39.726806) (xy 196.2909 -39.767551)
			(xy 196.334657 -39.814148) (xy 196.37223 -39.865863) (xy 196.403024 -39.921878) (xy 196.426556 -39.981311)
			(xy 196.442453 -40.043225) (xy 196.450464 -40.106643) (xy 196.450966 -40.138604) (xy 196.450464 -40.170565)
			(xy 196.442453 -40.233983) (xy 196.426556 -40.295897) (xy 196.403024 -40.35533) (xy 196.37223 -40.411345)
			(xy 196.334657 -40.46306) (xy 196.2909 -40.509657) (xy 196.241647 -40.550402) (xy 196.187676 -40.584653)
			(xy 196.129837 -40.61187) (xy 196.069044 -40.631623) (xy 196.006254 -40.643601) (xy 195.942458 -40.647615)
			(xy 195.878662 -40.643601) (xy 195.815872 -40.631623) (xy 195.755079 -40.61187) (xy 195.69724 -40.584653)
			(xy 195.643269 -40.550402) (xy 195.594016 -40.509657) (xy 195.550259 -40.46306) (xy 195.512686 -40.411345)
			(xy 195.481892 -40.35533) (xy 195.45836 -40.295897) (xy 195.442463 -40.233983) (xy 195.434452 -40.170565)
			(xy 192.604497 -40.170565) (xy 192.608968 -40.205957) (xy 192.60947 -40.237918) (xy 192.608968 -40.269879)
			(xy 192.600957 -40.333297) (xy 192.58506 -40.395211) (xy 192.561528 -40.454644) (xy 192.530734 -40.510659)
			(xy 192.493161 -40.562374) (xy 192.449404 -40.608971) (xy 192.400151 -40.649716) (xy 192.359027 -40.675814)
			(xy 215.999312 -40.675814) (xy 216.003383 -40.620192) (xy 216.015509 -40.565755) (xy 216.035432 -40.513664)
			(xy 216.062728 -40.465029) (xy 216.096814 -40.420886) (xy 216.136963 -40.382177) (xy 216.182321 -40.349726)
			(xy 216.231921 -40.324225) (xy 216.284705 -40.306218) (xy 216.339548 -40.296088) (xy 216.395282 -40.294051)
			(xy 216.450719 -40.300151) (xy 216.504676 -40.314257) (xy 216.556005 -40.336069) (xy 216.603611 -40.365123)
			(xy 216.646479 -40.400798) (xy 216.683696 -40.442335) (xy 216.714469 -40.488848) (xy 216.738141 -40.539345)
			(xy 216.754209 -40.592752) (xy 216.762329 -40.647928) (xy 216.762838 -40.675814) (xy 216.762329 -40.7037)
			(xy 216.754209 -40.758876) (xy 216.738141 -40.812283) (xy 216.714469 -40.86278) (xy 216.683696 -40.909293)
			(xy 216.646479 -40.95083) (xy 216.603611 -40.986505) (xy 216.556005 -41.015559) (xy 216.504676 -41.037371)
			(xy 216.450719 -41.051477) (xy 216.395282 -41.057577) (xy 216.339548 -41.05554) (xy 216.284705 -41.04541)
			(xy 216.231921 -41.027403) (xy 216.182321 -41.001902) (xy 216.136963 -40.969451) (xy 216.096814 -40.930742)
			(xy 216.062728 -40.886599) (xy 216.035432 -40.837964) (xy 216.015509 -40.785873) (xy 216.003383 -40.731436)
			(xy 215.999312 -40.675814) (xy 192.359027 -40.675814) (xy 192.34618 -40.683967) (xy 192.288341 -40.711184)
			(xy 192.227548 -40.730937) (xy 192.164758 -40.742915) (xy 192.100962 -40.746929) (xy 192.037166 -40.742915)
			(xy 191.974376 -40.730937) (xy 191.913583 -40.711184) (xy 191.855744 -40.683967) (xy 191.801773 -40.649716)
			(xy 191.75252 -40.608971) (xy 191.708763 -40.562374) (xy 191.67119 -40.510659) (xy 191.640396 -40.454644)
			(xy 191.616864 -40.395211) (xy 191.600967 -40.333297) (xy 191.592956 -40.269879) (xy 190.732658 -40.269879)
			(xy 190.732918 -40.286432) (xy 190.732416 -40.318393) (xy 190.724405 -40.381811) (xy 190.708508 -40.443725)
			(xy 190.684976 -40.503158) (xy 190.654182 -40.559173) (xy 190.616609 -40.610888) (xy 190.572852 -40.657485)
			(xy 190.523599 -40.69823) (xy 190.469628 -40.732481) (xy 190.411789 -40.759698) (xy 190.350996 -40.779451)
			(xy 190.288206 -40.791429) (xy 190.22441 -40.795443) (xy 190.160614 -40.791429) (xy 190.097824 -40.779451)
			(xy 190.037031 -40.759698) (xy 189.979192 -40.732481) (xy 189.925221 -40.69823) (xy 189.875968 -40.657485)
			(xy 189.832211 -40.610888) (xy 189.794638 -40.559173) (xy 189.763844 -40.503158) (xy 189.740312 -40.443725)
			(xy 189.724415 -40.381811) (xy 189.716404 -40.318393) (xy 152.533594 -40.318393) (xy 152.540214 -40.370803)
			(xy 152.540716 -40.402764) (xy 152.540214 -40.434725) (xy 152.532203 -40.498143) (xy 152.516306 -40.560057)
			(xy 152.492774 -40.61949) (xy 152.46198 -40.675505) (xy 152.424407 -40.72722) (xy 152.38065 -40.773817)
			(xy 152.331397 -40.814562) (xy 152.306283 -40.8305) (xy 156.742382 -40.8305) (xy 156.746453 -40.774878)
			(xy 156.758579 -40.720441) (xy 156.778502 -40.66835) (xy 156.805798 -40.619715) (xy 156.839884 -40.575572)
			(xy 156.880033 -40.536863) (xy 156.925391 -40.504412) (xy 156.974991 -40.478911) (xy 157.027775 -40.460904)
			(xy 157.082618 -40.450774) (xy 157.138352 -40.448737) (xy 157.193789 -40.454837) (xy 157.247746 -40.468943)
			(xy 157.299075 -40.490755) (xy 157.346681 -40.519809) (xy 157.389549 -40.555484) (xy 157.426766 -40.597021)
			(xy 157.457539 -40.643534) (xy 157.481211 -40.694031) (xy 157.497279 -40.747438) (xy 157.505399 -40.802614)
			(xy 157.505908 -40.8305) (xy 157.505399 -40.858386) (xy 157.497279 -40.913562) (xy 157.481211 -40.966969)
			(xy 157.457539 -41.017466) (xy 157.426766 -41.063979) (xy 157.39037 -41.1046) (xy 162.306434 -41.1046)
			(xy 162.310449 -41.040795) (xy 162.322429 -40.977997) (xy 162.342185 -40.917195) (xy 162.369406 -40.859349)
			(xy 162.403663 -40.805371) (xy 162.444415 -40.756112) (xy 162.49102 -40.71235) (xy 162.542742 -40.674774)
			(xy 162.598766 -40.643976) (xy 162.658208 -40.620444) (xy 162.720131 -40.604547) (xy 162.783559 -40.596538)
			(xy 162.815524 -40.596058) (xy 162.845154 -40.596468) (xy 162.904008 -40.60339) (xy 162.961659 -40.617103)
			(xy 163.017326 -40.63742) (xy 163.070257 -40.664068) (xy 163.119733 -40.696684) (xy 163.142676 -40.715438)
			(xy 163.15203 -40.722518) (xy 163.174789 -40.728097) (xy 163.197674 -40.723057) (xy 163.207192 -40.7162)
			(xy 163.234358 -40.695134) (xy 163.293295 -40.65975) (xy 163.356464 -40.632631) (xy 163.422711 -40.614272)
			(xy 163.490828 -40.605008) (xy 163.5252 -40.60444) (xy 163.557164 -40.604846) (xy 163.620588 -40.612858)
			(xy 163.682508 -40.628756) (xy 163.741947 -40.65229) (xy 163.797967 -40.683087) (xy 163.849686 -40.720663)
			(xy 163.896288 -40.764425) (xy 163.937037 -40.813683) (xy 163.971292 -40.867659) (xy 163.998511 -40.925503)
			(xy 164.018266 -40.986302) (xy 164.029189 -41.043563) (xy 188.729868 -41.043563) (xy 188.729868 -40.979641)
			(xy 188.737879 -40.916223) (xy 188.753776 -40.854309) (xy 188.777308 -40.794876) (xy 188.808102 -40.738861)
			(xy 188.845675 -40.687146) (xy 188.889432 -40.640549) (xy 188.938685 -40.599804) (xy 188.992656 -40.565553)
			(xy 189.050495 -40.538336) (xy 189.111288 -40.518583) (xy 189.174078 -40.506605) (xy 189.237874 -40.502592)
			(xy 189.30167 -40.506605) (xy 189.36446 -40.518583) (xy 189.425253 -40.538336) (xy 189.483092 -40.565553)
			(xy 189.537063 -40.599804) (xy 189.586316 -40.640549) (xy 189.630073 -40.687146) (xy 189.667646 -40.738861)
			(xy 189.69844 -40.794876) (xy 189.721972 -40.854309) (xy 189.737869 -40.916223) (xy 189.74588 -40.979641)
			(xy 189.746382 -41.011602) (xy 189.74588 -41.043563) (xy 189.737869 -41.106981) (xy 189.721972 -41.168895)
			(xy 189.69844 -41.228328) (xy 189.667646 -41.284343) (xy 189.630073 -41.336058) (xy 189.586316 -41.382655)
			(xy 189.537063 -41.4234) (xy 189.483092 -41.457651) (xy 189.425253 -41.484868) (xy 189.36446 -41.504621)
			(xy 189.30167 -41.516599) (xy 189.237874 -41.520613) (xy 189.174078 -41.516599) (xy 189.111288 -41.504621)
			(xy 189.050495 -41.484868) (xy 188.992656 -41.457651) (xy 188.938685 -41.4234) (xy 188.889432 -41.382655)
			(xy 188.845675 -41.336058) (xy 188.808102 -41.284343) (xy 188.777308 -41.228328) (xy 188.753776 -41.168895)
			(xy 188.737879 -41.106981) (xy 188.729868 -41.043563) (xy 164.029189 -41.043563) (xy 164.030245 -41.049098)
			(xy 164.034259 -41.1129) (xy 164.030245 -41.176702) (xy 164.018266 -41.239498) (xy 163.998511 -41.300297)
			(xy 163.971292 -41.358141) (xy 163.937037 -41.412117) (xy 163.896288 -41.461375) (xy 163.849686 -41.505137)
			(xy 163.80886 -41.534799) (xy 191.217544 -41.534799) (xy 191.217544 -41.470877) (xy 191.225555 -41.407459)
			(xy 191.241452 -41.345545) (xy 191.264984 -41.286112) (xy 191.295778 -41.230097) (xy 191.333351 -41.178382)
			(xy 191.377108 -41.131785) (xy 191.426361 -41.09104) (xy 191.480332 -41.056789) (xy 191.538171 -41.029572)
			(xy 191.598964 -41.009819) (xy 191.661754 -40.997841) (xy 191.72555 -40.993828) (xy 191.789346 -40.997841)
			(xy 191.852136 -41.009819) (xy 191.912929 -41.029572) (xy 191.970768 -41.056789) (xy 192.024739 -41.09104)
			(xy 192.073992 -41.131785) (xy 192.117749 -41.178382) (xy 192.155322 -41.230097) (xy 192.186116 -41.286112)
			(xy 192.209648 -41.345545) (xy 192.225545 -41.407459) (xy 192.233556 -41.470877) (xy 192.234058 -41.502838)
			(xy 192.233556 -41.534799) (xy 192.225545 -41.598217) (xy 192.209648 -41.660131) (xy 192.186116 -41.719564)
			(xy 192.155322 -41.775579) (xy 192.117749 -41.827294) (xy 192.073992 -41.873891) (xy 192.024739 -41.914636)
			(xy 191.970768 -41.948887) (xy 191.912929 -41.976104) (xy 191.852136 -41.995857) (xy 191.789346 -42.007835)
			(xy 191.72555 -42.011849) (xy 191.661754 -42.007835) (xy 191.598964 -41.995857) (xy 191.538171 -41.976104)
			(xy 191.480332 -41.948887) (xy 191.426361 -41.914636) (xy 191.377108 -41.873891) (xy 191.333351 -41.827294)
			(xy 191.295778 -41.775579) (xy 191.264984 -41.719564) (xy 191.241452 -41.660131) (xy 191.225555 -41.598217)
			(xy 191.217544 -41.534799) (xy 163.80886 -41.534799) (xy 163.797967 -41.542713) (xy 163.741947 -41.57351)
			(xy 163.682508 -41.597044) (xy 163.620588 -41.612942) (xy 163.557164 -41.620954) (xy 163.5252 -41.621456)
			(xy 163.495571 -41.621029) (xy 163.436718 -41.61411) (xy 163.379067 -41.6004) (xy 163.323399 -41.580086)
			(xy 163.270469 -41.553441) (xy 163.220992 -41.520828) (xy 163.198048 -41.502076) (xy 163.18868 -41.495017)
			(xy 163.16593 -41.489429) (xy 163.143049 -41.494461) (xy 163.133532 -41.501314) (xy 163.10636 -41.522371)
			(xy 163.047424 -41.557756) (xy 162.984256 -41.584877) (xy 162.918011 -41.603238) (xy 162.849895 -41.612504)
			(xy 162.815524 -41.613074) (xy 162.783559 -41.612662) (xy 162.720131 -41.604653) (xy 162.658208 -41.588756)
			(xy 162.598766 -41.565224) (xy 162.542742 -41.534426) (xy 162.49102 -41.49685) (xy 162.444415 -41.453088)
			(xy 162.403663 -41.403829) (xy 162.369406 -41.349851) (xy 162.342185 -41.292005) (xy 162.322429 -41.231203)
			(xy 162.310449 -41.168405) (xy 162.306434 -41.1046) (xy 157.39037 -41.1046) (xy 157.389549 -41.105516)
			(xy 157.346681 -41.141191) (xy 157.299075 -41.170245) (xy 157.247746 -41.192057) (xy 157.193789 -41.206163)
			(xy 157.138352 -41.212263) (xy 157.082618 -41.210226) (xy 157.027775 -41.200096) (xy 156.974991 -41.182089)
			(xy 156.925391 -41.156588) (xy 156.880033 -41.124137) (xy 156.839884 -41.085428) (xy 156.805798 -41.041285)
			(xy 156.778502 -40.99265) (xy 156.758579 -40.940559) (xy 156.746453 -40.886122) (xy 156.742382 -40.8305)
			(xy 152.306283 -40.8305) (xy 152.277426 -40.848813) (xy 152.219587 -40.87603) (xy 152.158794 -40.895783)
			(xy 152.096004 -40.907761) (xy 152.032208 -40.911775) (xy 151.968412 -40.907761) (xy 151.905622 -40.895783)
			(xy 151.844829 -40.87603) (xy 151.78699 -40.848813) (xy 151.733019 -40.814562) (xy 151.683766 -40.773817)
			(xy 151.640009 -40.72722) (xy 151.602436 -40.675505) (xy 151.571642 -40.61949) (xy 151.54811 -40.560057)
			(xy 151.532213 -40.498143) (xy 151.524202 -40.434725) (xy 143.339 -40.434725) (xy 143.3669 -40.442019)
			(xy 143.418229 -40.463831) (xy 143.465835 -40.492885) (xy 143.508703 -40.52856) (xy 143.54592 -40.570097)
			(xy 143.576693 -40.61661) (xy 143.600365 -40.667107) (xy 143.616433 -40.720514) (xy 143.624553 -40.77569)
			(xy 143.625062 -40.803576) (xy 143.624553 -40.831462) (xy 143.616433 -40.886638) (xy 143.600365 -40.940045)
			(xy 143.576693 -40.990542) (xy 143.54592 -41.037055) (xy 143.508703 -41.078592) (xy 143.465835 -41.114267)
			(xy 143.418229 -41.143321) (xy 143.3669 -41.165133) (xy 143.312943 -41.179239) (xy 143.257506 -41.185339)
			(xy 143.201772 -41.183302) (xy 143.146929 -41.173172) (xy 143.094145 -41.155165) (xy 143.044545 -41.129664)
			(xy 142.999187 -41.097213) (xy 142.959038 -41.058504) (xy 142.924952 -41.014361) (xy 142.897656 -40.965726)
			(xy 142.877733 -40.913635) (xy 142.865607 -40.859198) (xy 142.861536 -40.803576) (xy 141.141654 -40.803576)
			(xy 141.138376 -40.816343) (xy 141.114844 -40.875776) (xy 141.08405 -40.931791) (xy 141.046477 -40.983506)
			(xy 141.00272 -41.030103) (xy 140.953467 -41.070848) (xy 140.899496 -41.105099) (xy 140.841657 -41.132316)
			(xy 140.780864 -41.152069) (xy 140.718074 -41.164047) (xy 140.654278 -41.168061) (xy 140.590482 -41.164047)
			(xy 140.527692 -41.152069) (xy 140.466899 -41.132316) (xy 140.40906 -41.105099) (xy 140.355089 -41.070848)
			(xy 140.305836 -41.030103) (xy 140.262079 -40.983506) (xy 140.224506 -40.931791) (xy 140.193712 -40.875776)
			(xy 140.17018 -40.816343) (xy 140.154283 -40.754429) (xy 140.146272 -40.691011) (xy 137.519875 -40.691011)
			(xy 137.544302 -40.715438) (xy 137.551151 -40.722831) (xy 137.558866 -40.741436) (xy 137.559288 -40.751506)
			(xy 137.559288 -41.783) (xy 140.156182 -41.783) (xy 140.160253 -41.727378) (xy 140.172379 -41.672941)
			(xy 140.192302 -41.62085) (xy 140.219598 -41.572215) (xy 140.253684 -41.528072) (xy 140.293833 -41.489363)
			(xy 140.339191 -41.456912) (xy 140.388791 -41.431411) (xy 140.441575 -41.413404) (xy 140.496418 -41.403274)
			(xy 140.552152 -41.401237) (xy 140.607589 -41.407337) (xy 140.661546 -41.421443) (xy 140.712875 -41.443255)
			(xy 140.760481 -41.472309) (xy 140.803349 -41.507984) (xy 140.840566 -41.549521) (xy 140.871339 -41.596034)
			(xy 140.895011 -41.646531) (xy 140.911079 -41.699938) (xy 140.919199 -41.755114) (xy 140.919624 -41.778385)
			(xy 144.780756 -41.778385) (xy 144.780756 -41.714463) (xy 144.788767 -41.651045) (xy 144.804664 -41.589131)
			(xy 144.828196 -41.529698) (xy 144.85899 -41.473683) (xy 144.896563 -41.421968) (xy 144.94032 -41.375371)
			(xy 144.989573 -41.334626) (xy 145.043544 -41.300375) (xy 145.101383 -41.273158) (xy 145.162176 -41.253405)
			(xy 145.224966 -41.241427) (xy 145.288762 -41.237414) (xy 145.352558 -41.241427) (xy 145.415348 -41.253405)
			(xy 145.476141 -41.273158) (xy 145.53398 -41.300375) (xy 145.587951 -41.334626) (xy 145.637204 -41.375371)
			(xy 145.680961 -41.421968) (xy 145.718534 -41.473683) (xy 145.749328 -41.529698) (xy 145.77286 -41.589131)
			(xy 145.788757 -41.651045) (xy 145.796768 -41.714463) (xy 145.79727 -41.746424) (xy 145.796768 -41.778385)
			(xy 147.117556 -41.778385) (xy 147.117556 -41.714463) (xy 147.125567 -41.651045) (xy 147.141464 -41.589131)
			(xy 147.164996 -41.529698) (xy 147.19579 -41.473683) (xy 147.233363 -41.421968) (xy 147.27712 -41.375371)
			(xy 147.326373 -41.334626) (xy 147.380344 -41.300375) (xy 147.438183 -41.273158) (xy 147.498976 -41.253405)
			(xy 147.561766 -41.241427) (xy 147.625562 -41.237414) (xy 147.689358 -41.241427) (xy 147.752148 -41.253405)
			(xy 147.812941 -41.273158) (xy 147.87078 -41.300375) (xy 147.924751 -41.334626) (xy 147.974004 -41.375371)
			(xy 148.017761 -41.421968) (xy 148.055334 -41.473683) (xy 148.086128 -41.529698) (xy 148.10966 -41.589131)
			(xy 148.125557 -41.651045) (xy 148.133568 -41.714463) (xy 148.13407 -41.746424) (xy 148.133568 -41.778385)
			(xy 149.149556 -41.778385) (xy 149.149556 -41.714463) (xy 149.157567 -41.651045) (xy 149.173464 -41.589131)
			(xy 149.196996 -41.529698) (xy 149.22779 -41.473683) (xy 149.265363 -41.421968) (xy 149.30912 -41.375371)
			(xy 149.358373 -41.334626) (xy 149.412344 -41.300375) (xy 149.470183 -41.273158) (xy 149.530976 -41.253405)
			(xy 149.593766 -41.241427) (xy 149.657562 -41.237414) (xy 149.721358 -41.241427) (xy 149.784148 -41.253405)
			(xy 149.844941 -41.273158) (xy 149.90278 -41.300375) (xy 149.956751 -41.334626) (xy 150.006004 -41.375371)
			(xy 150.049761 -41.421968) (xy 150.087334 -41.473683) (xy 150.118128 -41.529698) (xy 150.14166 -41.589131)
			(xy 150.157557 -41.651045) (xy 150.165568 -41.714463) (xy 150.16607 -41.746424) (xy 150.165735 -41.76776)
			(xy 150.487632 -41.76776) (xy 150.491703 -41.712138) (xy 150.503829 -41.657701) (xy 150.523752 -41.60561)
			(xy 150.551048 -41.556975) (xy 150.585134 -41.512832) (xy 150.625283 -41.474123) (xy 150.670641 -41.441672)
			(xy 150.720241 -41.416171) (xy 150.773025 -41.398164) (xy 150.827868 -41.388034) (xy 150.883602 -41.385997)
			(xy 150.939039 -41.392097) (xy 150.992996 -41.406203) (xy 151.044325 -41.428015) (xy 151.091931 -41.457069)
			(xy 151.134799 -41.492744) (xy 151.172016 -41.534281) (xy 151.202789 -41.580794) (xy 151.226461 -41.631291)
			(xy 151.242529 -41.684698) (xy 151.250649 -41.739874) (xy 151.251158 -41.76776) (xy 151.250649 -41.795646)
			(xy 151.242529 -41.850822) (xy 151.226461 -41.904229) (xy 151.202789 -41.954726) (xy 151.172016 -42.001239)
			(xy 151.144109 -42.032385) (xy 156.667448 -42.032385) (xy 156.667448 -41.968463) (xy 156.675459 -41.905045)
			(xy 156.691356 -41.843131) (xy 156.714888 -41.783698) (xy 156.745682 -41.727683) (xy 156.783255 -41.675968)
			(xy 156.827012 -41.629371) (xy 156.876265 -41.588626) (xy 156.930236 -41.554375) (xy 156.988075 -41.527158)
			(xy 157.048868 -41.507405) (xy 157.111658 -41.495427) (xy 157.175454 -41.491414) (xy 157.23925 -41.495427)
			(xy 157.30204 -41.507405) (xy 157.362833 -41.527158) (xy 157.420672 -41.554375) (xy 157.474643 -41.588626)
			(xy 157.523896 -41.629371) (xy 157.567653 -41.675968) (xy 157.605226 -41.727683) (xy 157.63602 -41.783698)
			(xy 157.659552 -41.843131) (xy 157.675449 -41.905045) (xy 157.68346 -41.968463) (xy 157.683962 -42.000424)
			(xy 157.68346 -42.032385) (xy 157.675449 -42.095803) (xy 157.659552 -42.157717) (xy 157.63602 -42.21715)
			(xy 157.605226 -42.273165) (xy 157.567653 -42.32488) (xy 157.565521 -42.32715) (xy 177.908468 -42.32715)
			(xy 177.908468 -42.27265) (xy 177.916223 -42.218704) (xy 177.931577 -42.166412) (xy 177.954215 -42.116836)
			(xy 177.983679 -42.070986) (xy 178.019366 -42.029796) (xy 178.060553 -41.994104) (xy 178.106399 -41.964636)
			(xy 178.155972 -41.941991) (xy 178.208263 -41.926632) (xy 178.262208 -41.918871) (xy 178.289458 -41.918382)
			(xy 178.315778 -41.918841) (xy 178.367921 -41.926061) (xy 178.418575 -41.940383) (xy 178.466778 -41.961535)
			(xy 178.511614 -41.989116) (xy 178.552231 -42.0226) (xy 178.587858 -42.061352) (xy 178.617816 -42.104635)
			(xy 178.630072 -42.127932) (xy 178.634898 -42.13733) (xy 178.650138 -42.150284) (xy 178.7398 -42.178224)
			(xy 178.759866 -42.176446) (xy 178.76901 -42.171366) (xy 178.797045 -42.156658) (xy 178.855996 -42.13357)
			(xy 178.917357 -42.117979) (xy 178.980179 -42.110124) (xy 179.011834 -42.109644) (xy 179.042564 -42.110124)
			(xy 179.103575 -42.117535) (xy 179.163249 -42.132246) (xy 179.220714 -42.154041) (xy 179.275133 -42.182604)
			(xy 179.325714 -42.217518) (xy 179.371717 -42.258273) (xy 179.412474 -42.304275) (xy 179.447389 -42.354855)
			(xy 179.465468 -42.389298) (xy 188.825886 -42.389298) (xy 188.826376 -42.362047) (xy 188.834133 -42.3081)
			(xy 188.849488 -42.255805) (xy 188.872129 -42.206229) (xy 188.901594 -42.160378) (xy 188.937286 -42.119188)
			(xy 188.978475 -42.083497) (xy 189.024325 -42.05403) (xy 189.073902 -42.031389) (xy 189.126196 -42.016033)
			(xy 189.180143 -42.008276) (xy 189.207394 -42.00779) (xy 189.234633 -42.008282) (xy 189.288559 -42.016032)
			(xy 189.340833 -42.031373) (xy 189.390393 -42.053995) (xy 189.401039 -42.060833) (xy 208.441284 -42.060833)
			(xy 208.441284 -41.996911) (xy 208.449295 -41.933493) (xy 208.465192 -41.871579) (xy 208.488724 -41.812146)
			(xy 208.519518 -41.756131) (xy 208.557091 -41.704416) (xy 208.600848 -41.657819) (xy 208.650101 -41.617074)
			(xy 208.704072 -41.582823) (xy 208.761911 -41.555606) (xy 208.822704 -41.535853) (xy 208.885494 -41.523875)
			(xy 208.94929 -41.519862) (xy 209.013086 -41.523875) (xy 209.075876 -41.535853) (xy 209.136669 -41.555606)
			(xy 209.194508 -41.582823) (xy 209.248479 -41.617074) (xy 209.253104 -41.6209) (xy 211.637116 -41.6209)
			(xy 211.64113 -41.557105) (xy 211.653109 -41.494316) (xy 211.672862 -41.433523) (xy 211.70008 -41.375686)
			(xy 211.734332 -41.321716) (xy 211.775078 -41.272465) (xy 211.821676 -41.228709) (xy 211.873391 -41.191139)
			(xy 211.929408 -41.160348) (xy 211.988841 -41.13682) (xy 212.050755 -41.120926) (xy 212.114173 -41.112919)
			(xy 212.146134 -41.11244) (xy 212.146388 -41.11244) (xy 212.176596 -41.11287) (xy 212.236589 -41.120009)
			(xy 212.295312 -41.134211) (xy 212.351936 -41.155276) (xy 212.405664 -41.182907) (xy 212.455736 -41.216713)
			(xy 212.478874 -41.236138) (xy 212.485932 -41.241801) (xy 212.502854 -41.248178) (xy 212.511894 -41.248584)
			(xy 212.542374 -41.248584) (xy 212.551411 -41.248167) (xy 212.568327 -41.241786) (xy 212.575394 -41.236138)
			(xy 212.598523 -41.216704) (xy 212.648607 -41.182918) (xy 212.702339 -41.155299) (xy 212.758964 -41.134237)
			(xy 212.817684 -41.120029) (xy 212.877673 -41.112873) (xy 212.90788 -41.11244) (xy 212.908134 -41.11244)
			(xy 212.940097 -41.112848) (xy 213.003518 -41.120863) (xy 213.065434 -41.136765) (xy 213.124869 -41.1603)
			(xy 213.180886 -41.191099) (xy 213.232601 -41.228675) (xy 213.279199 -41.272437) (xy 213.319945 -41.321694)
			(xy 213.354197 -41.375669) (xy 213.381414 -41.43351) (xy 213.401167 -41.494307) (xy 213.413145 -41.557101)
			(xy 213.417159 -41.6209) (xy 220.761816 -41.6209) (xy 220.76583 -41.557105) (xy 220.777808 -41.494316)
			(xy 220.797562 -41.433524) (xy 220.824779 -41.375687) (xy 220.859031 -41.321717) (xy 220.899777 -41.272466)
			(xy 220.946375 -41.228711) (xy 220.998089 -41.191141) (xy 221.054105 -41.160349) (xy 221.113538 -41.136821)
			(xy 221.175452 -41.120927) (xy 221.238869 -41.112919) (xy 221.27083 -41.11244) (xy 221.304387 -41.11299)
			(xy 221.370917 -41.121834) (xy 221.435706 -41.13935) (xy 221.497629 -41.165235) (xy 221.55561 -41.199038)
			(xy 221.608642 -41.240173) (xy 221.655803 -41.287925) (xy 221.676468 -41.31437) (xy 221.683126 -41.322373)
			(xy 221.70123 -41.332604) (xy 221.71152 -41.334182) (xy 221.784926 -41.342564) (xy 221.795349 -41.343152)
			(xy 221.815276 -41.33701) (xy 221.823534 -41.330626) (xy 221.844321 -41.313491) (xy 221.889819 -41.284648)
			(xy 221.938925 -41.262498) (xy 221.990661 -41.247483) (xy 222.043995 -41.239903) (xy 222.07093 -41.23944)
			(xy 222.098183 -41.239832) (xy 222.152135 -41.247593) (xy 222.204432 -41.262953) (xy 222.254012 -41.285598)
			(xy 222.299864 -41.315069) (xy 222.341056 -41.350765) (xy 222.376749 -41.39196) (xy 222.406216 -41.437814)
			(xy 222.428858 -41.487396) (xy 222.444213 -41.539695) (xy 222.45197 -41.593647) (xy 222.45197 -41.648153)
			(xy 222.444213 -41.702105) (xy 222.428858 -41.754404) (xy 222.406216 -41.803986) (xy 222.376749 -41.84984)
			(xy 222.341056 -41.891035) (xy 222.299864 -41.926731) (xy 222.254012 -41.956202) (xy 222.204432 -41.978847)
			(xy 222.152135 -41.994207) (xy 222.098183 -42.001968) (xy 222.07093 -42.002456) (xy 222.043996 -42.001994)
			(xy 221.990664 -41.994404) (xy 221.938932 -41.979384) (xy 221.889827 -41.957234) (xy 221.844329 -41.928395)
			(xy 221.823534 -41.91127) (xy 221.815282 -41.904864) (xy 221.795351 -41.89869) (xy 221.784926 -41.899332)
			(xy 221.71152 -41.907714) (xy 221.701242 -41.909315) (xy 221.683154 -41.919555) (xy 221.676468 -41.927526)
			(xy 221.655814 -41.953983) (xy 221.608663 -42.001751) (xy 221.555634 -42.042898) (xy 221.497652 -42.076707)
			(xy 221.435723 -42.10259) (xy 221.370927 -42.120096) (xy 221.30439 -42.128922) (xy 221.27083 -42.129456)
			(xy 221.238869 -42.128881) (xy 221.175452 -42.120873) (xy 221.113538 -42.104979) (xy 221.054105 -42.081451)
			(xy 220.998089 -42.050659) (xy 220.946375 -42.013089) (xy 220.899777 -41.969334) (xy 220.859031 -41.920083)
			(xy 220.824779 -41.866113) (xy 220.797562 -41.808276) (xy 220.777808 -41.747484) (xy 220.76583 -41.684695)
			(xy 220.761816 -41.6209) (xy 213.417159 -41.6209) (xy 213.413145 -41.684699) (xy 213.401167 -41.747493)
			(xy 213.381414 -41.80829) (xy 213.354197 -41.866132) (xy 213.319945 -41.920106) (xy 213.279199 -41.969363)
			(xy 213.232601 -42.013125) (xy 213.180886 -42.050701) (xy 213.124869 -42.0815) (xy 213.065434 -42.105035)
			(xy 213.003518 -42.120937) (xy 212.940097 -42.128952) (xy 212.908134 -42.129456) (xy 212.90788 -42.129456)
			(xy 212.877671 -42.129046) (xy 212.817678 -42.121903) (xy 212.758955 -42.107697) (xy 212.70233 -42.086629)
			(xy 212.648603 -42.058994) (xy 212.598532 -42.025184) (xy 212.575394 -42.005758) (xy 212.568346 -42.000081)
			(xy 212.551416 -41.993713) (xy 212.542374 -41.993312) (xy 212.511894 -41.993312) (xy 212.502855 -41.993715)
			(xy 212.485939 -42.000105) (xy 212.478874 -42.005758) (xy 212.455718 -42.025159) (xy 212.40564 -42.05895)
			(xy 212.351914 -42.086573) (xy 212.295295 -42.107641) (xy 212.236579 -42.121856) (xy 212.176594 -42.129019)
			(xy 212.146388 -42.129456) (xy 212.146134 -42.129456) (xy 212.114173 -42.128881) (xy 212.050755 -42.120874)
			(xy 211.988841 -42.10498) (xy 211.929408 -42.081452) (xy 211.873391 -42.050661) (xy 211.821676 -42.013091)
			(xy 211.775078 -41.969335) (xy 211.734332 -41.920084) (xy 211.70008 -41.866114) (xy 211.672862 -41.808277)
			(xy 211.653109 -41.747484) (xy 211.64113 -41.684695) (xy 211.637116 -41.6209) (xy 209.253104 -41.6209)
			(xy 209.297732 -41.657819) (xy 209.341489 -41.704416) (xy 209.379062 -41.756131) (xy 209.409856 -41.812146)
			(xy 209.433388 -41.871579) (xy 209.449285 -41.933493) (xy 209.457296 -41.996911) (xy 209.457798 -42.028872)
			(xy 209.457296 -42.060833) (xy 209.449285 -42.124251) (xy 209.433388 -42.186165) (xy 209.409856 -42.245598)
			(xy 209.379062 -42.301613) (xy 209.341489 -42.353328) (xy 209.297732 -42.399925) (xy 209.248479 -42.44067)
			(xy 209.194508 -42.474921) (xy 209.136669 -42.502138) (xy 209.075876 -42.521891) (xy 209.013086 -42.533869)
			(xy 208.94929 -42.537883) (xy 208.885494 -42.533869) (xy 208.822704 -42.521891) (xy 208.761911 -42.502138)
			(xy 208.704072 -42.474921) (xy 208.650101 -42.44067) (xy 208.600848 -42.399925) (xy 208.557091 -42.353328)
			(xy 208.519518 -42.301613) (xy 208.488724 -42.245598) (xy 208.465192 -42.186165) (xy 208.449295 -42.124251)
			(xy 208.441284 -42.060833) (xy 189.401039 -42.060833) (xy 189.436231 -42.083437) (xy 189.477415 -42.1191)
			(xy 189.513106 -42.160259) (xy 189.54258 -42.206077) (xy 189.565235 -42.255621) (xy 189.580613 -42.307885)
			(xy 189.588399 -42.361805) (xy 189.588902 -42.389044) (xy 189.588902 -42.389552) (xy 189.588648 -42.400728)
			(xy 189.588394 -42.413428) (xy 189.599062 -42.435526) (xy 189.677294 -42.492676) (xy 189.687795 -42.49951)
			(xy 189.712572 -42.502989) (xy 189.724538 -42.49928) (xy 189.760608 -42.486846) (xy 189.834398 -42.467433)
			(xy 189.909579 -42.454409) (xy 189.9856 -42.447871) (xy 190.02375 -42.447464) (xy 190.065673 -42.448028)
			(xy 190.149146 -42.455923) (xy 190.231505 -42.471639) (xy 190.31202 -42.495035) (xy 190.389976 -42.525905)
			(xy 190.436419 -42.549572) (xy 195.542406 -42.549572) (xy 195.546477 -42.49395) (xy 195.558603 -42.439513)
			(xy 195.578526 -42.387422) (xy 195.605822 -42.338787) (xy 195.639908 -42.294644) (xy 195.680057 -42.255935)
			(xy 195.725415 -42.223484) (xy 195.775015 -42.197983) (xy 195.827799 -42.179976) (xy 195.882642 -42.169846)
			(xy 195.938376 -42.167809) (xy 195.993813 -42.173909) (xy 196.04777 -42.188015) (xy 196.099099 -42.209827)
			(xy 196.146705 -42.238881) (xy 196.189573 -42.274556) (xy 196.22679 -42.316093) (xy 196.257563 -42.362606)
			(xy 196.281235 -42.413103) (xy 196.297303 -42.46651) (xy 196.305423 -42.521686) (xy 196.305932 -42.549572)
			(xy 196.305423 -42.577458) (xy 196.297303 -42.632634) (xy 196.281235 -42.686041) (xy 196.257563 -42.736538)
			(xy 196.22679 -42.783051) (xy 196.189573 -42.824588) (xy 196.146705 -42.860263) (xy 196.099099 -42.889317)
			(xy 196.04777 -42.911129) (xy 195.993813 -42.925235) (xy 195.938376 -42.931335) (xy 195.882642 -42.929298)
			(xy 195.827799 -42.919168) (xy 195.775015 -42.901161) (xy 195.725415 -42.87566) (xy 195.680057 -42.843209)
			(xy 195.639908 -42.8045) (xy 195.605822 -42.760357) (xy 195.578526 -42.711722) (xy 195.558603 -42.659631)
			(xy 195.546477 -42.605194) (xy 195.542406 -42.549572) (xy 190.436419 -42.549572) (xy 190.464681 -42.563974)
			(xy 190.535472 -42.608905) (xy 190.60172 -42.660298) (xy 190.662838 -42.717697) (xy 190.718282 -42.780593)
			(xy 190.767562 -42.848428) (xy 190.810239 -42.9206) (xy 190.845935 -42.996467) (xy 190.874333 -43.075357)
			(xy 190.89518 -43.15657) (xy 190.908293 -43.239384) (xy 190.913553 -43.323064) (xy 190.910916 -43.406868)
			(xy 190.900403 -43.490052) (xy 190.882109 -43.571877) (xy 190.856196 -43.651618) (xy 190.822893 -43.728566)
			(xy 190.782497 -43.802038) (xy 190.750209 -43.849544) (xy 192.178176 -43.849544) (xy 192.182247 -43.793922)
			(xy 192.194373 -43.739485) (xy 192.214296 -43.687394) (xy 192.241592 -43.638759) (xy 192.275678 -43.594616)
			(xy 192.315827 -43.555907) (xy 192.361185 -43.523456) (xy 192.410785 -43.497955) (xy 192.463569 -43.479948)
			(xy 192.518412 -43.469818) (xy 192.574146 -43.467781) (xy 192.629583 -43.473881) (xy 192.68354 -43.487987)
			(xy 192.734869 -43.509799) (xy 192.782475 -43.538853) (xy 192.805373 -43.557909) (xy 222.172778 -43.557909)
			(xy 222.172778 -43.493987) (xy 222.180789 -43.430569) (xy 222.196686 -43.368655) (xy 222.220218 -43.309222)
			(xy 222.251012 -43.253207) (xy 222.288585 -43.201492) (xy 222.332342 -43.154895) (xy 222.381595 -43.11415)
			(xy 222.435566 -43.079899) (xy 222.493405 -43.052682) (xy 222.554198 -43.032929) (xy 222.616988 -43.020951)
			(xy 222.680784 -43.016938) (xy 222.74458 -43.020951) (xy 222.80737 -43.032929) (xy 222.868163 -43.052682)
			(xy 222.926002 -43.079899) (xy 222.979973 -43.11415) (xy 223.029226 -43.154895) (xy 223.072983 -43.201492)
			(xy 223.110556 -43.253207) (xy 223.14135 -43.309222) (xy 223.164882 -43.368655) (xy 223.180779 -43.430569)
			(xy 223.18879 -43.493987) (xy 223.189292 -43.525948) (xy 223.18879 -43.557909) (xy 223.180779 -43.621327)
			(xy 223.164882 -43.683241) (xy 223.14135 -43.742674) (xy 223.110556 -43.798689) (xy 223.072983 -43.850404)
			(xy 223.029226 -43.897001) (xy 222.979973 -43.937746) (xy 222.926002 -43.971997) (xy 222.868163 -43.999214)
			(xy 222.80737 -44.018967) (xy 222.74458 -44.030945) (xy 222.680784 -44.034959) (xy 222.616988 -44.030945)
			(xy 222.554198 -44.018967) (xy 222.493405 -43.999214) (xy 222.435566 -43.971997) (xy 222.381595 -43.937746)
			(xy 222.332342 -43.897001) (xy 222.288585 -43.850404) (xy 222.251012 -43.798689) (xy 222.220218 -43.742674)
			(xy 222.196686 -43.683241) (xy 222.180789 -43.621327) (xy 222.172778 -43.557909) (xy 192.805373 -43.557909)
			(xy 192.825343 -43.574528) (xy 192.86256 -43.616065) (xy 192.893333 -43.662578) (xy 192.917005 -43.713075)
			(xy 192.933073 -43.766482) (xy 192.941193 -43.821658) (xy 192.941702 -43.849544) (xy 192.941193 -43.87743)
			(xy 192.933073 -43.932606) (xy 192.917005 -43.986013) (xy 192.893333 -44.03651) (xy 192.86256 -44.083023)
			(xy 192.825343 -44.12456) (xy 192.782475 -44.160235) (xy 192.734869 -44.189289) (xy 192.68354 -44.211101)
			(xy 192.629583 -44.225207) (xy 192.574146 -44.231307) (xy 192.518412 -44.22927) (xy 192.463569 -44.21914)
			(xy 192.410785 -44.201133) (xy 192.361185 -44.175632) (xy 192.315827 -44.143181) (xy 192.275678 -44.104472)
			(xy 192.241592 -44.060329) (xy 192.214296 -44.011694) (xy 192.194373 -43.959603) (xy 192.182247 -43.905166)
			(xy 192.178176 -43.849544) (xy 190.750209 -43.849544) (xy 190.735366 -43.871383) (xy 190.681918 -43.935985)
			(xy 190.622627 -43.99527) (xy 190.558021 -44.048712) (xy 190.488672 -44.095838) (xy 190.415196 -44.136227)
			(xy 190.338245 -44.169523) (xy 190.258502 -44.19543) (xy 190.176675 -44.213717) (xy 190.09349 -44.224222)
			(xy 190.009686 -44.226852) (xy 189.926006 -44.221584) (xy 189.843193 -44.208465) (xy 189.761983 -44.18761)
			(xy 189.683095 -44.159205) (xy 189.607231 -44.123503) (xy 189.535063 -44.080819) (xy 189.467232 -44.031534)
			(xy 189.404341 -43.976083) (xy 189.346947 -43.914961) (xy 189.29556 -43.848708) (xy 189.250635 -43.777913)
			(xy 189.212573 -43.703205) (xy 189.18171 -43.625246) (xy 189.15832 -43.544729) (xy 189.142612 -43.462368)
			(xy 189.134724 -43.378895) (xy 189.134242 -43.336972) (xy 189.134242 -43.336718) (xy 189.134757 -43.292979)
			(xy 189.14335 -43.205925) (xy 189.160454 -43.120136) (xy 189.185903 -43.036442) (xy 189.219451 -42.955654)
			(xy 189.239652 -42.916856) (xy 189.245494 -42.90568) (xy 189.245748 -42.880534) (xy 189.201298 -42.794936)
			(xy 189.195022 -42.784232) (xy 189.174665 -42.770102) (xy 189.162436 -42.768012) (xy 189.162182 -42.768012)
			(xy 189.134721 -42.764282) (xy 189.081216 -42.749841) (xy 189.030365 -42.727806) (xy 188.983239 -42.698643)
			(xy 188.940832 -42.662965) (xy 188.904036 -42.621524) (xy 188.873627 -42.575192) (xy 188.850245 -42.524947)
			(xy 188.834383 -42.471846) (xy 188.826375 -42.417008) (xy 188.825886 -42.389298) (xy 179.465468 -42.389298)
			(xy 179.475953 -42.409273) (xy 179.49775 -42.466738) (xy 179.512462 -42.526411) (xy 179.519876 -42.587422)
			(xy 179.520342 -42.618152) (xy 179.519781 -42.653108) (xy 179.510213 -42.722362) (xy 179.49125 -42.789652)
			(xy 179.463251 -42.853712) (xy 179.426742 -42.913334) (xy 179.405026 -42.940732) (xy 179.399766 -42.947662)
			(xy 179.393936 -42.964042) (xy 179.393596 -42.972736) (xy 179.393596 -43.127168) (xy 179.393988 -43.13585)
			(xy 179.399826 -43.152208) (xy 179.405026 -43.159172) (xy 179.42673 -43.186578) (xy 179.463228 -43.246202)
			(xy 179.491222 -43.310261) (xy 179.510185 -43.377548) (xy 179.51976 -43.446798) (xy 179.520342 -43.481752)
			(xy 179.519817 -43.512482) (xy 179.512415 -43.573494) (xy 179.497712 -43.633169) (xy 179.475923 -43.690636)
			(xy 179.447366 -43.745058) (xy 179.412457 -43.795642) (xy 179.371706 -43.841648) (xy 179.325706 -43.882407)
			(xy 179.275129 -43.917324) (xy 179.220711 -43.94589) (xy 179.163247 -43.967688) (xy 179.103575 -43.9824)
			(xy 179.042564 -43.989812) (xy 179.011834 -43.99026) (xy 178.980179 -43.98977) (xy 178.91736 -43.981914)
			(xy 178.856001 -43.96632) (xy 178.797053 -43.943229) (xy 178.76901 -43.928538) (xy 178.759866 -43.923458)
			(xy 178.7398 -43.92168) (xy 178.650138 -43.94962) (xy 178.634898 -43.962574) (xy 178.630072 -43.971972)
			(xy 178.61782 -43.995269) (xy 178.587847 -44.03854) (xy 178.552214 -44.077283) (xy 178.511595 -44.110762)
			(xy 178.466761 -44.138342) (xy 178.418563 -44.159501) (xy 178.367914 -44.173836) (xy 178.315777 -44.181077)
			(xy 178.289458 -44.181522) (xy 178.26221 -44.181005) (xy 178.208269 -44.173244) (xy 178.155981 -44.157886)
			(xy 178.106411 -44.135243) (xy 178.060567 -44.105777) (xy 178.019384 -44.070086) (xy 177.983698 -44.028899)
			(xy 177.954237 -43.983052) (xy 177.9316 -43.93348) (xy 177.916247 -43.88119) (xy 177.908492 -43.827248)
			(xy 177.908492 -43.772752) (xy 177.916247 -43.71881) (xy 177.9316 -43.66652) (xy 177.954237 -43.616948)
			(xy 177.983698 -43.571101) (xy 178.019384 -43.529914) (xy 178.060567 -43.494223) (xy 178.106411 -43.464757)
			(xy 178.155981 -43.442114) (xy 178.208269 -43.426756) (xy 178.26221 -43.418995) (xy 178.289458 -43.418506)
			(xy 178.31551 -43.418984) (xy 178.367125 -43.426117) (xy 178.392328 -43.43273) (xy 178.402196 -43.43488)
			(xy 178.422203 -43.432259) (xy 178.43119 -43.42765) (xy 178.50358 -43.38574) (xy 178.515772 -43.36923)
			(xy 178.518312 -43.359324) (xy 178.525456 -43.332015) (xy 178.54501 -43.279058) (xy 178.570309 -43.228594)
			(xy 178.601043 -43.181242) (xy 178.618642 -43.159172) (xy 178.623897 -43.152239) (xy 178.629731 -43.135862)
			(xy 178.630072 -43.127168) (xy 178.630072 -42.972736) (xy 178.629685 -42.964053) (xy 178.623844 -42.947695)
			(xy 178.618642 -42.940732) (xy 178.60104 -42.918664) (xy 178.570311 -42.87131) (xy 178.545016 -42.820844)
			(xy 178.525466 -42.767886) (xy 178.518312 -42.74058) (xy 178.515772 -42.730674) (xy 178.50358 -42.714164)
			(xy 178.4223 -42.667174) (xy 178.402488 -42.66438) (xy 178.392582 -42.667174) (xy 178.392074 -42.667174)
			(xy 178.366939 -42.673803) (xy 178.315449 -42.680943) (xy 178.289458 -42.681398) (xy 178.262208 -42.680929)
			(xy 178.208263 -42.673168) (xy 178.155972 -42.657809) (xy 178.106399 -42.635164) (xy 178.060553 -42.605696)
			(xy 178.019366 -42.570004) (xy 177.983679 -42.528814) (xy 177.954215 -42.482964) (xy 177.931577 -42.433388)
			(xy 177.916223 -42.381096) (xy 177.908468 -42.32715) (xy 157.565521 -42.32715) (xy 157.523896 -42.371477)
			(xy 157.474643 -42.412222) (xy 157.420672 -42.446473) (xy 157.362833 -42.47369) (xy 157.30204 -42.493443)
			(xy 157.23925 -42.505421) (xy 157.175454 -42.509435) (xy 157.111658 -42.505421) (xy 157.048868 -42.493443)
			(xy 156.988075 -42.47369) (xy 156.930236 -42.446473) (xy 156.876265 -42.412222) (xy 156.827012 -42.371477)
			(xy 156.783255 -42.32488) (xy 156.745682 -42.273165) (xy 156.714888 -42.21715) (xy 156.691356 -42.157717)
			(xy 156.675459 -42.095803) (xy 156.667448 -42.032385) (xy 151.144109 -42.032385) (xy 151.134799 -42.042776)
			(xy 151.091931 -42.078451) (xy 151.044325 -42.107505) (xy 150.992996 -42.129317) (xy 150.939039 -42.143423)
			(xy 150.883602 -42.149523) (xy 150.827868 -42.147486) (xy 150.773025 -42.137356) (xy 150.720241 -42.119349)
			(xy 150.670641 -42.093848) (xy 150.625283 -42.061397) (xy 150.585134 -42.022688) (xy 150.551048 -41.978545)
			(xy 150.523752 -41.92991) (xy 150.503829 -41.877819) (xy 150.491703 -41.823382) (xy 150.487632 -41.76776)
			(xy 150.165735 -41.76776) (xy 150.165568 -41.778385) (xy 150.157557 -41.841803) (xy 150.14166 -41.903717)
			(xy 150.118128 -41.96315) (xy 150.087334 -42.019165) (xy 150.049761 -42.07088) (xy 150.006004 -42.117477)
			(xy 149.956751 -42.158222) (xy 149.90278 -42.192473) (xy 149.844941 -42.21969) (xy 149.784148 -42.239443)
			(xy 149.721358 -42.251421) (xy 149.657562 -42.255435) (xy 149.593766 -42.251421) (xy 149.530976 -42.239443)
			(xy 149.470183 -42.21969) (xy 149.412344 -42.192473) (xy 149.358373 -42.158222) (xy 149.30912 -42.117477)
			(xy 149.265363 -42.07088) (xy 149.22779 -42.019165) (xy 149.196996 -41.96315) (xy 149.173464 -41.903717)
			(xy 149.157567 -41.841803) (xy 149.149556 -41.778385) (xy 148.133568 -41.778385) (xy 148.125557 -41.841803)
			(xy 148.10966 -41.903717) (xy 148.086128 -41.96315) (xy 148.055334 -42.019165) (xy 148.017761 -42.07088)
			(xy 147.974004 -42.117477) (xy 147.924751 -42.158222) (xy 147.87078 -42.192473) (xy 147.812941 -42.21969)
			(xy 147.752148 -42.239443) (xy 147.689358 -42.251421) (xy 147.625562 -42.255435) (xy 147.561766 -42.251421)
			(xy 147.498976 -42.239443) (xy 147.438183 -42.21969) (xy 147.380344 -42.192473) (xy 147.326373 -42.158222)
			(xy 147.27712 -42.117477) (xy 147.233363 -42.07088) (xy 147.19579 -42.019165) (xy 147.164996 -41.96315)
			(xy 147.141464 -41.903717) (xy 147.125567 -41.841803) (xy 147.117556 -41.778385) (xy 145.796768 -41.778385)
			(xy 145.788757 -41.841803) (xy 145.77286 -41.903717) (xy 145.749328 -41.96315) (xy 145.718534 -42.019165)
			(xy 145.680961 -42.07088) (xy 145.637204 -42.117477) (xy 145.587951 -42.158222) (xy 145.53398 -42.192473)
			(xy 145.476141 -42.21969) (xy 145.415348 -42.239443) (xy 145.352558 -42.251421) (xy 145.288762 -42.255435)
			(xy 145.224966 -42.251421) (xy 145.162176 -42.239443) (xy 145.101383 -42.21969) (xy 145.043544 -42.192473)
			(xy 144.989573 -42.158222) (xy 144.94032 -42.117477) (xy 144.896563 -42.07088) (xy 144.85899 -42.019165)
			(xy 144.828196 -41.96315) (xy 144.804664 -41.903717) (xy 144.788767 -41.841803) (xy 144.780756 -41.778385)
			(xy 140.919624 -41.778385) (xy 140.919708 -41.783) (xy 140.919199 -41.810886) (xy 140.911079 -41.866062)
			(xy 140.895011 -41.919469) (xy 140.871339 -41.969966) (xy 140.840566 -42.016479) (xy 140.803349 -42.058016)
			(xy 140.760481 -42.093691) (xy 140.712875 -42.122745) (xy 140.661546 -42.144557) (xy 140.607589 -42.158663)
			(xy 140.552152 -42.164763) (xy 140.496418 -42.162726) (xy 140.441575 -42.152596) (xy 140.388791 -42.134589)
			(xy 140.339191 -42.109088) (xy 140.293833 -42.076637) (xy 140.253684 -42.037928) (xy 140.219598 -41.993785)
			(xy 140.192302 -41.94515) (xy 140.172379 -41.893059) (xy 140.160253 -41.838622) (xy 140.156182 -41.783)
			(xy 137.559288 -41.783) (xy 137.559288 -43.063371) (xy 144.780756 -43.063371) (xy 144.780756 -42.999449)
			(xy 144.788767 -42.936031) (xy 144.804664 -42.874117) (xy 144.828196 -42.814684) (xy 144.85899 -42.758669)
			(xy 144.896563 -42.706954) (xy 144.94032 -42.660357) (xy 144.989573 -42.619612) (xy 145.043544 -42.585361)
			(xy 145.101383 -42.558144) (xy 145.162176 -42.538391) (xy 145.224966 -42.526413) (xy 145.288762 -42.5224)
			(xy 145.352558 -42.526413) (xy 145.415348 -42.538391) (xy 145.476141 -42.558144) (xy 145.53398 -42.585361)
			(xy 145.587951 -42.619612) (xy 145.637204 -42.660357) (xy 145.680961 -42.706954) (xy 145.718534 -42.758669)
			(xy 145.749328 -42.814684) (xy 145.77286 -42.874117) (xy 145.788757 -42.936031) (xy 145.796768 -42.999449)
			(xy 145.79727 -43.03141) (xy 145.796768 -43.063371) (xy 147.117556 -43.063371) (xy 147.117556 -42.999449)
			(xy 147.125567 -42.936031) (xy 147.141464 -42.874117) (xy 147.164996 -42.814684) (xy 147.19579 -42.758669)
			(xy 147.233363 -42.706954) (xy 147.27712 -42.660357) (xy 147.326373 -42.619612) (xy 147.380344 -42.585361)
			(xy 147.438183 -42.558144) (xy 147.498976 -42.538391) (xy 147.561766 -42.526413) (xy 147.625562 -42.5224)
			(xy 147.689358 -42.526413) (xy 147.752148 -42.538391) (xy 147.812941 -42.558144) (xy 147.87078 -42.585361)
			(xy 147.924751 -42.619612) (xy 147.974004 -42.660357) (xy 148.017761 -42.706954) (xy 148.055334 -42.758669)
			(xy 148.086128 -42.814684) (xy 148.10966 -42.874117) (xy 148.125557 -42.936031) (xy 148.133568 -42.999449)
			(xy 148.13407 -43.03141) (xy 148.133568 -43.063371) (xy 149.149556 -43.063371) (xy 149.149556 -42.999449)
			(xy 149.157567 -42.936031) (xy 149.173464 -42.874117) (xy 149.196996 -42.814684) (xy 149.22779 -42.758669)
			(xy 149.265363 -42.706954) (xy 149.30912 -42.660357) (xy 149.358373 -42.619612) (xy 149.412344 -42.585361)
			(xy 149.470183 -42.558144) (xy 149.530976 -42.538391) (xy 149.593766 -42.526413) (xy 149.657562 -42.5224)
			(xy 149.721358 -42.526413) (xy 149.784148 -42.538391) (xy 149.844941 -42.558144) (xy 149.90278 -42.585361)
			(xy 149.956751 -42.619612) (xy 150.006004 -42.660357) (xy 150.049761 -42.706954) (xy 150.087334 -42.758669)
			(xy 150.118128 -42.814684) (xy 150.14166 -42.874117) (xy 150.157557 -42.936031) (xy 150.165568 -42.999449)
			(xy 150.16607 -43.03141) (xy 150.165568 -43.063371) (xy 150.157557 -43.126789) (xy 150.14166 -43.188703)
			(xy 150.118128 -43.248136) (xy 150.087334 -43.304151) (xy 150.077729 -43.317371) (xy 156.667448 -43.317371)
			(xy 156.667448 -43.253449) (xy 156.675459 -43.190031) (xy 156.691356 -43.128117) (xy 156.714888 -43.068684)
			(xy 156.745682 -43.012669) (xy 156.783255 -42.960954) (xy 156.827012 -42.914357) (xy 156.876265 -42.873612)
			(xy 156.930236 -42.839361) (xy 156.988075 -42.812144) (xy 157.048868 -42.792391) (xy 157.111658 -42.780413)
			(xy 157.175454 -42.7764) (xy 157.23925 -42.780413) (xy 157.30204 -42.792391) (xy 157.362833 -42.812144)
			(xy 157.420672 -42.839361) (xy 157.474643 -42.873612) (xy 157.523896 -42.914357) (xy 157.545045 -42.936879)
			(xy 158.433764 -42.936879) (xy 158.433764 -42.872957) (xy 158.441775 -42.809539) (xy 158.457672 -42.747625)
			(xy 158.481204 -42.688192) (xy 158.511998 -42.632177) (xy 158.549571 -42.580462) (xy 158.593328 -42.533865)
			(xy 158.642581 -42.49312) (xy 158.696552 -42.458869) (xy 158.754391 -42.431652) (xy 158.815184 -42.411899)
			(xy 158.877974 -42.399921) (xy 158.94177 -42.395908) (xy 159.005566 -42.399921) (xy 159.068356 -42.411899)
			(xy 159.129149 -42.431652) (xy 159.186988 -42.458869) (xy 159.240959 -42.49312) (xy 159.290212 -42.533865)
			(xy 159.333969 -42.580462) (xy 159.371542 -42.632177) (xy 159.402336 -42.688192) (xy 159.425868 -42.747625)
			(xy 159.441765 -42.809539) (xy 159.449776 -42.872957) (xy 159.450278 -42.904918) (xy 159.449776 -42.936879)
			(xy 159.441765 -43.000297) (xy 159.427331 -43.056513) (xy 162.286436 -43.056513) (xy 162.286436 -42.992591)
			(xy 162.294447 -42.929173) (xy 162.310344 -42.867259) (xy 162.333876 -42.807826) (xy 162.36467 -42.751811)
			(xy 162.402243 -42.700096) (xy 162.446 -42.653499) (xy 162.495253 -42.612754) (xy 162.549224 -42.578503)
			(xy 162.607063 -42.551286) (xy 162.667856 -42.531533) (xy 162.730646 -42.519555) (xy 162.794442 -42.515542)
			(xy 162.858238 -42.519555) (xy 162.921028 -42.531533) (xy 162.981821 -42.551286) (xy 163.03966 -42.578503)
			(xy 163.093631 -42.612754) (xy 163.142884 -42.653499) (xy 163.186641 -42.700096) (xy 163.224214 -42.751811)
			(xy 163.255008 -42.807826) (xy 163.27854 -42.867259) (xy 163.294437 -42.929173) (xy 163.298747 -42.963295)
			(xy 170.436788 -42.963295) (xy 170.436788 -42.899373) (xy 170.444799 -42.835955) (xy 170.460696 -42.774041)
			(xy 170.484228 -42.714608) (xy 170.515022 -42.658593) (xy 170.552595 -42.606878) (xy 170.596352 -42.560281)
			(xy 170.645605 -42.519536) (xy 170.699576 -42.485285) (xy 170.757415 -42.458068) (xy 170.818208 -42.438315)
			(xy 170.880998 -42.426337) (xy 170.944794 -42.422324) (xy 171.00859 -42.426337) (xy 171.07138 -42.438315)
			(xy 171.132173 -42.458068) (xy 171.190012 -42.485285) (xy 171.243983 -42.519536) (xy 171.293236 -42.560281)
			(xy 171.336993 -42.606878) (xy 171.374566 -42.658593) (xy 171.40536 -42.714608) (xy 171.428892 -42.774041)
			(xy 171.444789 -42.835955) (xy 171.4528 -42.899373) (xy 171.453302 -42.931334) (xy 171.4528 -42.963295)
			(xy 171.444789 -43.026713) (xy 171.428892 -43.088627) (xy 171.40536 -43.14806) (xy 171.374566 -43.204075)
			(xy 171.336993 -43.25579) (xy 171.293236 -43.302387) (xy 171.243983 -43.343132) (xy 171.190012 -43.377383)
			(xy 171.132173 -43.4046) (xy 171.07138 -43.424353) (xy 171.00859 -43.436331) (xy 170.944794 -43.440345)
			(xy 170.880998 -43.436331) (xy 170.818208 -43.424353) (xy 170.757415 -43.4046) (xy 170.699576 -43.377383)
			(xy 170.645605 -43.343132) (xy 170.596352 -43.302387) (xy 170.552595 -43.25579) (xy 170.515022 -43.204075)
			(xy 170.484228 -43.14806) (xy 170.460696 -43.088627) (xy 170.444799 -43.026713) (xy 170.436788 -42.963295)
			(xy 163.298747 -42.963295) (xy 163.302448 -42.992591) (xy 163.30295 -43.024552) (xy 163.302448 -43.056513)
			(xy 163.294437 -43.119931) (xy 163.27854 -43.181845) (xy 163.255008 -43.241278) (xy 163.224214 -43.297293)
			(xy 163.186641 -43.349008) (xy 163.142884 -43.395605) (xy 163.093631 -43.43635) (xy 163.03966 -43.470601)
			(xy 162.981821 -43.497818) (xy 162.921028 -43.517571) (xy 162.858238 -43.529549) (xy 162.794442 -43.533563)
			(xy 162.730646 -43.529549) (xy 162.667856 -43.517571) (xy 162.607063 -43.497818) (xy 162.549224 -43.470601)
			(xy 162.495253 -43.43635) (xy 162.446 -43.395605) (xy 162.402243 -43.349008) (xy 162.36467 -43.297293)
			(xy 162.333876 -43.241278) (xy 162.310344 -43.181845) (xy 162.294447 -43.119931) (xy 162.286436 -43.056513)
			(xy 159.427331 -43.056513) (xy 159.425868 -43.062211) (xy 159.402336 -43.121644) (xy 159.371542 -43.177659)
			(xy 159.333969 -43.229374) (xy 159.290212 -43.275971) (xy 159.240959 -43.316716) (xy 159.186988 -43.350967)
			(xy 159.129149 -43.378184) (xy 159.068356 -43.397937) (xy 159.005566 -43.409915) (xy 158.94177 -43.413929)
			(xy 158.877974 -43.409915) (xy 158.815184 -43.397937) (xy 158.754391 -43.378184) (xy 158.696552 -43.350967)
			(xy 158.642581 -43.316716) (xy 158.593328 -43.275971) (xy 158.549571 -43.229374) (xy 158.511998 -43.177659)
			(xy 158.481204 -43.121644) (xy 158.457672 -43.062211) (xy 158.441775 -43.000297) (xy 158.433764 -42.936879)
			(xy 157.545045 -42.936879) (xy 157.567653 -42.960954) (xy 157.605226 -43.012669) (xy 157.63602 -43.068684)
			(xy 157.659552 -43.128117) (xy 157.675449 -43.190031) (xy 157.68346 -43.253449) (xy 157.683962 -43.28541)
			(xy 157.68346 -43.317371) (xy 157.675449 -43.380789) (xy 157.659552 -43.442703) (xy 157.63602 -43.502136)
			(xy 157.605226 -43.558151) (xy 157.567653 -43.609866) (xy 157.523896 -43.656463) (xy 157.474643 -43.697208)
			(xy 157.420672 -43.731459) (xy 157.362833 -43.758676) (xy 157.30204 -43.778429) (xy 157.23925 -43.790407)
			(xy 157.175454 -43.794421) (xy 157.111658 -43.790407) (xy 157.048868 -43.778429) (xy 156.988075 -43.758676)
			(xy 156.930236 -43.731459) (xy 156.876265 -43.697208) (xy 156.827012 -43.656463) (xy 156.783255 -43.609866)
			(xy 156.745682 -43.558151) (xy 156.714888 -43.502136) (xy 156.691356 -43.442703) (xy 156.675459 -43.380789)
			(xy 156.667448 -43.317371) (xy 150.077729 -43.317371) (xy 150.049761 -43.355866) (xy 150.006004 -43.402463)
			(xy 149.956751 -43.443208) (xy 149.90278 -43.477459) (xy 149.844941 -43.504676) (xy 149.784148 -43.524429)
			(xy 149.721358 -43.536407) (xy 149.657562 -43.540421) (xy 149.593766 -43.536407) (xy 149.530976 -43.524429)
			(xy 149.470183 -43.504676) (xy 149.412344 -43.477459) (xy 149.358373 -43.443208) (xy 149.30912 -43.402463)
			(xy 149.265363 -43.355866) (xy 149.22779 -43.304151) (xy 149.196996 -43.248136) (xy 149.173464 -43.188703)
			(xy 149.157567 -43.126789) (xy 149.149556 -43.063371) (xy 148.133568 -43.063371) (xy 148.125557 -43.126789)
			(xy 148.10966 -43.188703) (xy 148.086128 -43.248136) (xy 148.055334 -43.304151) (xy 148.017761 -43.355866)
			(xy 147.974004 -43.402463) (xy 147.924751 -43.443208) (xy 147.87078 -43.477459) (xy 147.812941 -43.504676)
			(xy 147.752148 -43.524429) (xy 147.689358 -43.536407) (xy 147.625562 -43.540421) (xy 147.561766 -43.536407)
			(xy 147.498976 -43.524429) (xy 147.438183 -43.504676) (xy 147.380344 -43.477459) (xy 147.326373 -43.443208)
			(xy 147.27712 -43.402463) (xy 147.233363 -43.355866) (xy 147.19579 -43.304151) (xy 147.164996 -43.248136)
			(xy 147.141464 -43.188703) (xy 147.125567 -43.126789) (xy 147.117556 -43.063371) (xy 145.796768 -43.063371)
			(xy 145.788757 -43.126789) (xy 145.77286 -43.188703) (xy 145.749328 -43.248136) (xy 145.718534 -43.304151)
			(xy 145.680961 -43.355866) (xy 145.637204 -43.402463) (xy 145.587951 -43.443208) (xy 145.53398 -43.477459)
			(xy 145.476141 -43.504676) (xy 145.415348 -43.524429) (xy 145.352558 -43.536407) (xy 145.288762 -43.540421)
			(xy 145.224966 -43.536407) (xy 145.162176 -43.524429) (xy 145.101383 -43.504676) (xy 145.043544 -43.477459)
			(xy 144.989573 -43.443208) (xy 144.94032 -43.402463) (xy 144.896563 -43.355866) (xy 144.85899 -43.304151)
			(xy 144.828196 -43.248136) (xy 144.804664 -43.188703) (xy 144.788767 -43.126789) (xy 144.780756 -43.063371)
			(xy 137.559288 -43.063371) (xy 137.559288 -44.163488) (xy 137.558942 -44.173536) (xy 137.551337 -44.192132)
			(xy 137.544556 -44.199556) (xy 137.36193 -44.382182) (xy 137.354512 -44.388999) (xy 137.335927 -44.396733)
			(xy 137.325862 -44.397168) (xy 134.164832 -44.397168) (xy 134.154764 -44.396734) (xy 134.136165 -44.38902)
			(xy 134.128764 -44.382182) (xy 131.956302 -42.209466) (xy 131.949455 -42.202071) (xy 131.941739 -42.183468)
			(xy 131.941316 -42.173398) (xy 118.733367 -42.173398) (xy 118.736117 -42.182538) (xy 118.744237 -42.237714)
			(xy 118.744746 -42.2656) (xy 118.744237 -42.293486) (xy 118.736117 -42.348662) (xy 118.720049 -42.402069)
			(xy 118.696377 -42.452566) (xy 118.665604 -42.499079) (xy 118.628387 -42.540616) (xy 118.585519 -42.576291)
			(xy 118.537913 -42.605345) (xy 118.486584 -42.627157) (xy 118.432627 -42.641263) (xy 118.37719 -42.647363)
			(xy 118.321456 -42.645326) (xy 118.266613 -42.635196) (xy 118.213829 -42.617189) (xy 118.164229 -42.591688)
			(xy 118.118871 -42.559237) (xy 118.078722 -42.520528) (xy 118.044636 -42.476385) (xy 118.01734 -42.42775)
			(xy 117.997417 -42.375659) (xy 117.985291 -42.321222) (xy 117.98122 -42.2656) (xy 116.712746 -42.2656)
			(xy 116.712237 -42.293486) (xy 116.704117 -42.348662) (xy 116.688049 -42.402069) (xy 116.664377 -42.452566)
			(xy 116.633604 -42.499079) (xy 116.596387 -42.540616) (xy 116.553519 -42.576291) (xy 116.505913 -42.605345)
			(xy 116.454584 -42.627157) (xy 116.400627 -42.641263) (xy 116.34519 -42.647363) (xy 116.289456 -42.645326)
			(xy 116.234613 -42.635196) (xy 116.181829 -42.617189) (xy 116.132229 -42.591688) (xy 116.086871 -42.559237)
			(xy 116.046722 -42.520528) (xy 116.012636 -42.476385) (xy 115.98534 -42.42775) (xy 115.965417 -42.375659)
			(xy 115.953291 -42.321222) (xy 115.94922 -42.2656) (xy 112.648746 -42.2656) (xy 112.648237 -42.293486)
			(xy 112.640117 -42.348662) (xy 112.624049 -42.402069) (xy 112.600377 -42.452566) (xy 112.569604 -42.499079)
			(xy 112.532387 -42.540616) (xy 112.489519 -42.576291) (xy 112.441913 -42.605345) (xy 112.390584 -42.627157)
			(xy 112.336627 -42.641263) (xy 112.28119 -42.647363) (xy 112.225456 -42.645326) (xy 112.170613 -42.635196)
			(xy 112.117829 -42.617189) (xy 112.068229 -42.591688) (xy 112.022871 -42.559237) (xy 111.982722 -42.520528)
			(xy 111.948636 -42.476385) (xy 111.92134 -42.42775) (xy 111.901417 -42.375659) (xy 111.889291 -42.321222)
			(xy 111.88522 -42.2656) (xy 109.600746 -42.2656) (xy 109.600237 -42.293486) (xy 109.592117 -42.348662)
			(xy 109.576049 -42.402069) (xy 109.552377 -42.452566) (xy 109.521604 -42.499079) (xy 109.484387 -42.540616)
			(xy 109.441519 -42.576291) (xy 109.393913 -42.605345) (xy 109.342584 -42.627157) (xy 109.288627 -42.641263)
			(xy 109.23319 -42.647363) (xy 109.177456 -42.645326) (xy 109.122613 -42.635196) (xy 109.069829 -42.617189)
			(xy 109.020229 -42.591688) (xy 108.974871 -42.559237) (xy 108.934722 -42.520528) (xy 108.900636 -42.476385)
			(xy 108.87334 -42.42775) (xy 108.853417 -42.375659) (xy 108.841291 -42.321222) (xy 108.83722 -42.2656)
			(xy 86.557604 -42.2656) (xy 86.512831 -42.292925) (xy 86.461502 -42.314737) (xy 86.407545 -42.328843)
			(xy 86.352108 -42.334943) (xy 86.296374 -42.332906) (xy 86.241531 -42.322776) (xy 86.188747 -42.304769)
			(xy 86.139147 -42.279268) (xy 86.093789 -42.246817) (xy 86.05364 -42.208108) (xy 86.019554 -42.163965)
			(xy 85.992258 -42.11533) (xy 85.972335 -42.063239) (xy 85.960209 -42.008802) (xy 85.956138 -41.95318)
			(xy 63.57082 -41.95318) (xy 63.580895 -41.992421) (xy 63.588906 -42.055839) (xy 63.589408 -42.0878)
			(xy 63.588906 -42.119761) (xy 63.580895 -42.183179) (xy 63.564998 -42.245093) (xy 63.541466 -42.304526)
			(xy 63.510672 -42.360541) (xy 63.473099 -42.412256) (xy 63.429342 -42.458853) (xy 63.380089 -42.499598)
			(xy 63.326118 -42.533849) (xy 63.268279 -42.561066) (xy 63.207486 -42.580819) (xy 63.144696 -42.592797)
			(xy 63.0809 -42.596811) (xy 63.017104 -42.592797) (xy 62.954314 -42.580819) (xy 62.893521 -42.561066)
			(xy 62.835682 -42.533849) (xy 62.781711 -42.499598) (xy 62.732458 -42.458853) (xy 62.688701 -42.412256)
			(xy 62.651128 -42.360541) (xy 62.620334 -42.304526) (xy 62.596802 -42.245093) (xy 62.580905 -42.183179)
			(xy 62.572894 -42.119761) (xy 60.04827 -42.119761) (xy 60.056078 -42.133964) (xy 60.07961 -42.193397)
			(xy 60.095507 -42.255311) (xy 60.103518 -42.318729) (xy 60.10402 -42.35069) (xy 60.103518 -42.382651)
			(xy 60.095507 -42.446069) (xy 60.07961 -42.507983) (xy 60.056078 -42.567416) (xy 60.025284 -42.623431)
			(xy 59.987711 -42.675146) (xy 59.943954 -42.721743) (xy 59.894701 -42.762488) (xy 59.84073 -42.796739)
			(xy 59.782891 -42.823956) (xy 59.722098 -42.843709) (xy 59.659308 -42.855687) (xy 59.595512 -42.859701)
			(xy 59.531716 -42.855687) (xy 59.468926 -42.843709) (xy 59.408133 -42.823956) (xy 59.350294 -42.796739)
			(xy 59.296323 -42.762488) (xy 59.24707 -42.721743) (xy 59.203313 -42.675146) (xy 59.16574 -42.623431)
			(xy 59.134946 -42.567416) (xy 59.111414 -42.507983) (xy 59.095517 -42.446069) (xy 59.087506 -42.382651)
			(xy 46.293532 -42.382651) (xy 46.293532 -43.365166) (xy 46.294548 -43.374564) (xy 46.294548 -43.375072)
			(xy 46.295736 -43.380304) (xy 46.299892 -43.390015) (xy 109.727232 -43.390015) (xy 109.727232 -43.326093)
			(xy 109.735243 -43.262675) (xy 109.75114 -43.200761) (xy 109.774672 -43.141328) (xy 109.805466 -43.085313)
			(xy 109.843039 -43.033598) (xy 109.886796 -42.987001) (xy 109.936049 -42.946256) (xy 109.99002 -42.912005)
			(xy 110.047859 -42.884788) (xy 110.108652 -42.865035) (xy 110.171442 -42.853057) (xy 110.235238 -42.849044)
			(xy 110.299034 -42.853057) (xy 110.361824 -42.865035) (xy 110.422617 -42.884788) (xy 110.480456 -42.912005)
			(xy 110.534427 -42.946256) (xy 110.58368 -42.987001) (xy 110.627437 -43.033598) (xy 110.66501 -43.085313)
			(xy 110.695804 -43.141328) (xy 110.719336 -43.200761) (xy 110.735233 -43.262675) (xy 110.743244 -43.326093)
			(xy 110.743746 -43.358054) (xy 110.743244 -43.390015) (xy 111.759232 -43.390015) (xy 111.759232 -43.326093)
			(xy 111.767243 -43.262675) (xy 111.78314 -43.200761) (xy 111.806672 -43.141328) (xy 111.837466 -43.085313)
			(xy 111.875039 -43.033598) (xy 111.918796 -42.987001) (xy 111.968049 -42.946256) (xy 112.02202 -42.912005)
			(xy 112.079859 -42.884788) (xy 112.140652 -42.865035) (xy 112.203442 -42.853057) (xy 112.267238 -42.849044)
			(xy 112.331034 -42.853057) (xy 112.393824 -42.865035) (xy 112.454617 -42.884788) (xy 112.512456 -42.912005)
			(xy 112.566427 -42.946256) (xy 112.61568 -42.987001) (xy 112.659437 -43.033598) (xy 112.69701 -43.085313)
			(xy 112.727804 -43.141328) (xy 112.751336 -43.200761) (xy 112.767233 -43.262675) (xy 112.775244 -43.326093)
			(xy 112.775746 -43.358054) (xy 112.90122 -43.358054) (xy 112.905291 -43.302432) (xy 112.917417 -43.247995)
			(xy 112.93734 -43.195904) (xy 112.964636 -43.147269) (xy 112.998722 -43.103126) (xy 113.038871 -43.064417)
			(xy 113.084229 -43.031966) (xy 113.133829 -43.006465) (xy 113.186613 -42.988458) (xy 113.241456 -42.978328)
			(xy 113.29719 -42.976291) (xy 113.352627 -42.982391) (xy 113.406584 -42.996497) (xy 113.457913 -43.018309)
			(xy 113.505519 -43.047363) (xy 113.548387 -43.083038) (xy 113.585604 -43.124575) (xy 113.616377 -43.171088)
			(xy 113.640049 -43.221585) (xy 113.656117 -43.274992) (xy 113.664237 -43.330168) (xy 113.664746 -43.358054)
			(xy 113.664237 -43.38594) (xy 113.663637 -43.390015) (xy 113.791232 -43.390015) (xy 113.791232 -43.326093)
			(xy 113.799243 -43.262675) (xy 113.81514 -43.200761) (xy 113.838672 -43.141328) (xy 113.869466 -43.085313)
			(xy 113.907039 -43.033598) (xy 113.950796 -42.987001) (xy 114.000049 -42.946256) (xy 114.05402 -42.912005)
			(xy 114.111859 -42.884788) (xy 114.172652 -42.865035) (xy 114.235442 -42.853057) (xy 114.299238 -42.849044)
			(xy 114.363034 -42.853057) (xy 114.425824 -42.865035) (xy 114.486617 -42.884788) (xy 114.544456 -42.912005)
			(xy 114.598427 -42.946256) (xy 114.632279 -42.97426) (xy 130.011422 -42.97426) (xy 130.015493 -42.918638)
			(xy 130.027619 -42.864201) (xy 130.047542 -42.81211) (xy 130.074838 -42.763475) (xy 130.108924 -42.719332)
			(xy 130.149073 -42.680623) (xy 130.194431 -42.648172) (xy 130.244031 -42.622671) (xy 130.296815 -42.604664)
			(xy 130.351658 -42.594534) (xy 130.407392 -42.592497) (xy 130.462829 -42.598597) (xy 130.516786 -42.612703)
			(xy 130.568115 -42.634515) (xy 130.615721 -42.663569) (xy 130.658589 -42.699244) (xy 130.695806 -42.740781)
			(xy 130.726579 -42.787294) (xy 130.750251 -42.837791) (xy 130.766319 -42.891198) (xy 130.774439 -42.946374)
			(xy 130.774948 -42.97426) (xy 130.774439 -43.002146) (xy 130.766319 -43.057322) (xy 130.750251 -43.110729)
			(xy 130.726579 -43.161226) (xy 130.695806 -43.207739) (xy 130.658589 -43.249276) (xy 130.615721 -43.284951)
			(xy 130.568115 -43.314005) (xy 130.516786 -43.335817) (xy 130.462829 -43.349923) (xy 130.407392 -43.356023)
			(xy 130.351658 -43.353986) (xy 130.296815 -43.343856) (xy 130.244031 -43.325849) (xy 130.194431 -43.300348)
			(xy 130.149073 -43.267897) (xy 130.108924 -43.229188) (xy 130.074838 -43.185045) (xy 130.047542 -43.13641)
			(xy 130.027619 -43.084319) (xy 130.015493 -43.029882) (xy 130.011422 -42.97426) (xy 114.632279 -42.97426)
			(xy 114.64768 -42.987001) (xy 114.691437 -43.033598) (xy 114.72901 -43.085313) (xy 114.759804 -43.141328)
			(xy 114.783336 -43.200761) (xy 114.799233 -43.262675) (xy 114.807244 -43.326093) (xy 114.807746 -43.358054)
			(xy 114.807244 -43.390015) (xy 114.799233 -43.453433) (xy 114.783336 -43.515347) (xy 114.759804 -43.57478)
			(xy 114.72901 -43.630795) (xy 114.691437 -43.68251) (xy 114.64768 -43.729107) (xy 114.598427 -43.769852)
			(xy 114.544456 -43.804103) (xy 114.486617 -43.83132) (xy 114.425824 -43.851073) (xy 114.363034 -43.863051)
			(xy 114.299238 -43.867065) (xy 114.235442 -43.863051) (xy 114.172652 -43.851073) (xy 114.111859 -43.83132)
			(xy 114.05402 -43.804103) (xy 114.000049 -43.769852) (xy 113.950796 -43.729107) (xy 113.907039 -43.68251)
			(xy 113.869466 -43.630795) (xy 113.838672 -43.57478) (xy 113.81514 -43.515347) (xy 113.799243 -43.453433)
			(xy 113.791232 -43.390015) (xy 113.663637 -43.390015) (xy 113.656117 -43.441116) (xy 113.640049 -43.494523)
			(xy 113.616377 -43.54502) (xy 113.585604 -43.591533) (xy 113.548387 -43.63307) (xy 113.505519 -43.668745)
			(xy 113.457913 -43.697799) (xy 113.406584 -43.719611) (xy 113.352627 -43.733717) (xy 113.29719 -43.739817)
			(xy 113.241456 -43.73778) (xy 113.186613 -43.72765) (xy 113.133829 -43.709643) (xy 113.084229 -43.684142)
			(xy 113.038871 -43.651691) (xy 112.998722 -43.612982) (xy 112.964636 -43.568839) (xy 112.93734 -43.520204)
			(xy 112.917417 -43.468113) (xy 112.905291 -43.413676) (xy 112.90122 -43.358054) (xy 112.775746 -43.358054)
			(xy 112.775244 -43.390015) (xy 112.767233 -43.453433) (xy 112.751336 -43.515347) (xy 112.727804 -43.57478)
			(xy 112.69701 -43.630795) (xy 112.659437 -43.68251) (xy 112.61568 -43.729107) (xy 112.566427 -43.769852)
			(xy 112.512456 -43.804103) (xy 112.454617 -43.83132) (xy 112.393824 -43.851073) (xy 112.331034 -43.863051)
			(xy 112.267238 -43.867065) (xy 112.203442 -43.863051) (xy 112.140652 -43.851073) (xy 112.079859 -43.83132)
			(xy 112.02202 -43.804103) (xy 111.968049 -43.769852) (xy 111.918796 -43.729107) (xy 111.875039 -43.68251)
			(xy 111.837466 -43.630795) (xy 111.806672 -43.57478) (xy 111.78314 -43.515347) (xy 111.767243 -43.453433)
			(xy 111.759232 -43.390015) (xy 110.743244 -43.390015) (xy 110.735233 -43.453433) (xy 110.719336 -43.515347)
			(xy 110.695804 -43.57478) (xy 110.66501 -43.630795) (xy 110.627437 -43.68251) (xy 110.58368 -43.729107)
			(xy 110.534427 -43.769852) (xy 110.480456 -43.804103) (xy 110.422617 -43.83132) (xy 110.361824 -43.851073)
			(xy 110.299034 -43.863051) (xy 110.235238 -43.867065) (xy 110.171442 -43.863051) (xy 110.108652 -43.851073)
			(xy 110.047859 -43.83132) (xy 109.99002 -43.804103) (xy 109.936049 -43.769852) (xy 109.886796 -43.729107)
			(xy 109.843039 -43.68251) (xy 109.805466 -43.630795) (xy 109.774672 -43.57478) (xy 109.75114 -43.515347)
			(xy 109.735243 -43.453433) (xy 109.727232 -43.390015) (xy 46.299892 -43.390015) (xy 46.299956 -43.390165)
			(xy 46.30293 -43.39463) (xy 46.308264 -43.40098) (xy 48.855884 -45.9486) (xy 48.862234 -45.953934)
			(xy 48.866682 -45.95694) (xy 48.876547 -45.961169) (xy 48.881792 -45.962316) (xy 48.8823 -45.962316)
			(xy 48.891698 -45.963332) (xy 59.722004 -45.963332) (xy 59.723528 -45.963332) (xy 59.730552 -45.962902)
			(xy 59.743963 -45.958657) (xy 59.749944 -45.95495) (xy 59.77001 -45.941742) (xy 59.770264 -45.941488)
			(xy 59.776108 -45.937309) (xy 59.785392 -45.926351) (xy 59.788552 -45.919898) (xy 59.789568 -45.917358)
			(xy 59.818573 -45.842135) (xy 59.883167 -45.694399) (xy 59.955117 -45.550103) (xy 60.034241 -45.409612)
			(xy 60.120339 -45.273284) (xy 60.213192 -45.141464) (xy 60.312565 -45.014486) (xy 60.418205 -44.892673)
			(xy 60.529844 -44.776334) (xy 60.6472 -44.665764) (xy 60.769975 -44.561242) (xy 60.897856 -44.463036)
			(xy 61.03052 -44.371392) (xy 61.16763 -44.286545) (xy 61.308839 -44.20871) (xy 61.453787 -44.138083)
			(xy 61.602108 -44.074844) (xy 61.753425 -44.019153) (xy 61.907354 -43.971152) (xy 62.063505 -43.930963)
			(xy 62.221481 -43.898687) (xy 62.380882 -43.874406) (xy 62.541303 -43.858182) (xy 62.702338 -43.850056)
			(xy 62.782958 -43.849544) (xy 64.382904 -43.849544) (xy 64.462979 -43.85004) (xy 64.622928 -43.858051)
			(xy 64.782277 -43.874051) (xy 64.940626 -43.898001) (xy 65.097579 -43.929842) (xy 65.252743 -43.969492)
			(xy 65.405729 -44.016854) (xy 65.556155 -44.071808) (xy 65.703644 -44.134217) (xy 65.847828 -44.203925)
			(xy 65.988344 -44.280757) (xy 66.124841 -44.364521) (xy 66.256978 -44.455008) (xy 66.384424 -44.55199)
			(xy 66.50686 -44.655225) (xy 66.623979 -44.764454) (xy 66.735489 -44.879405) (xy 66.841109 -44.999789)
			(xy 66.940576 -45.125305) (xy 67.03364 -45.25564) (xy 67.12007 -45.390465) (xy 67.199648 -45.529445)
			(xy 67.23634 -45.60062) (xy 67.236594 -45.600874) (xy 67.239416 -45.606134) (xy 67.247117 -45.615251)
			(xy 67.251834 -45.618908) (xy 67.259708 -45.623734) (xy 67.261486 -45.62475) (xy 67.267328 -45.626274)
			(xy 67.278758 -45.628306) (xy 67.304666 -45.628052) (xy 67.306444 -45.628052) (xy 67.372992 -45.627544)
			(xy 67.380174 -45.627299) (xy 67.393971 -45.623305) (xy 67.40017 -45.61967) (xy 67.405504 -45.616114)
			(xy 67.414902 -45.605954) (xy 67.418204 -45.599096) (xy 67.454225 -45.52663) (xy 67.532416 -45.384924)
			(xy 67.617455 -45.247218) (xy 67.709139 -45.113845) (xy 67.757802 -45.049186) (xy 67.806598 -44.985957)
			(xy 67.909463 -44.863754) (xy 68.018119 -44.746671) (xy 68.132312 -44.63498) (xy 68.251773 -44.528944)
			(xy 68.376224 -44.428811) (xy 68.505374 -44.334815) (xy 68.638918 -44.247176) (xy 68.776546 -44.166101)
			(xy 68.917935 -44.091777) (xy 69.062754 -44.02438) (xy 69.210663 -43.964067) (xy 69.361316 -43.91098)
			(xy 69.514361 -43.865243) (xy 69.66944 -43.826962) (xy 69.826188 -43.796227) (xy 69.98424 -43.773112)
			(xy 70.143225 -43.757668) (xy 70.302771 -43.749934) (xy 70.382638 -43.749468) (xy 70.382892 -43.749468)
			(xy 70.463727 -43.749963) (xy 70.625202 -43.757883) (xy 70.786097 -43.773699) (xy 70.946024 -43.797373)
			(xy 71.1046 -43.828849) (xy 71.261445 -43.868051) (xy 71.416182 -43.914885) (xy 71.568441 -43.969238)
			(xy 71.717856 -44.030981) (xy 71.864069 -44.099965) (xy 72.00673 -44.176025) (xy 72.145495 -44.258979)
			(xy 72.280033 -44.348626) (xy 72.41002 -44.444753) (xy 72.535145 -44.547129) (xy 72.655108 -44.655508)
			(xy 72.769621 -44.769631) (xy 72.878409 -44.889223) (xy 72.981211 -45.013998) (xy 73.077781 -45.143656)
			(xy 73.167888 -45.277887) (xy 73.251314 -45.416368) (xy 73.327861 -45.558768) (xy 73.397344 -45.704745)
			(xy 73.459596 -45.853949) (xy 73.487534 -45.929804) (xy 73.489058 -45.934122) (xy 73.491799 -45.939488)
			(xy 73.499376 -45.948853) (xy 73.504044 -45.952664) (xy 73.507092 -45.95495) (xy 73.51776 -45.962316)
			(xy 73.52919 -45.963332) (xy 73.538593 -45.964177) (xy 73.555817 -45.971876) (xy 73.562718 -45.978318)
			(xy 73.843134 -46.258734) (xy 73.849982 -46.266131) (xy 73.857715 -46.28473) (xy 73.85812 -46.294802)
			(xy 73.85812 -46.44517) (xy 82.542632 -46.44517) (xy 82.546703 -46.389548) (xy 82.558829 -46.335111)
			(xy 82.578752 -46.28302) (xy 82.606048 -46.234385) (xy 82.640134 -46.190242) (xy 82.680283 -46.151533)
			(xy 82.725641 -46.119082) (xy 82.775241 -46.093581) (xy 82.828025 -46.075574) (xy 82.882868 -46.065444)
			(xy 82.938602 -46.063407) (xy 82.994039 -46.069507) (xy 83.047996 -46.083613) (xy 83.099325 -46.105425)
			(xy 83.146931 -46.134479) (xy 83.189799 -46.170154) (xy 83.227016 -46.211691) (xy 83.257789 -46.258204)
			(xy 83.281461 -46.308701) (xy 83.297529 -46.362108) (xy 83.305649 -46.417284) (xy 83.306158 -46.44517)
			(xy 83.305649 -46.473056) (xy 83.303367 -46.488561) (xy 83.764114 -46.488561) (xy 83.764114 -46.424639)
			(xy 83.772125 -46.361221) (xy 83.788022 -46.299307) (xy 83.811554 -46.239874) (xy 83.842348 -46.183859)
			(xy 83.879921 -46.132144) (xy 83.923678 -46.085547) (xy 83.972931 -46.044802) (xy 84.026902 -46.010551)
			(xy 84.084741 -45.983334) (xy 84.145534 -45.963581) (xy 84.208324 -45.951603) (xy 84.27212 -45.94759)
			(xy 84.335916 -45.951603) (xy 84.398706 -45.963581) (xy 84.459499 -45.983334) (xy 84.517338 -46.010551)
			(xy 84.571309 -46.044802) (xy 84.620562 -46.085547) (xy 84.664319 -46.132144) (xy 84.701892 -46.183859)
			(xy 84.732686 -46.239874) (xy 84.756218 -46.299307) (xy 84.772115 -46.361221) (xy 84.780126 -46.424639)
			(xy 84.780628 -46.4566) (xy 84.780126 -46.488561) (xy 84.772115 -46.551979) (xy 84.756218 -46.613893)
			(xy 84.732686 -46.673326) (xy 84.701892 -46.729341) (xy 84.664319 -46.781056) (xy 84.620562 -46.827653)
			(xy 84.571309 -46.868398) (xy 84.517338 -46.902649) (xy 84.459499 -46.929866) (xy 84.398706 -46.949619)
			(xy 84.335916 -46.961597) (xy 84.27212 -46.965611) (xy 84.208324 -46.961597) (xy 84.145534 -46.949619)
			(xy 84.084741 -46.929866) (xy 84.026902 -46.902649) (xy 83.972931 -46.868398) (xy 83.923678 -46.827653)
			(xy 83.879921 -46.781056) (xy 83.842348 -46.729341) (xy 83.811554 -46.673326) (xy 83.788022 -46.613893)
			(xy 83.772125 -46.551979) (xy 83.764114 -46.488561) (xy 83.303367 -46.488561) (xy 83.297529 -46.528232)
			(xy 83.281461 -46.581639) (xy 83.257789 -46.632136) (xy 83.227016 -46.678649) (xy 83.189799 -46.720186)
			(xy 83.146931 -46.755861) (xy 83.099325 -46.784915) (xy 83.047996 -46.806727) (xy 82.994039 -46.820833)
			(xy 82.938602 -46.826933) (xy 82.882868 -46.824896) (xy 82.828025 -46.814766) (xy 82.775241 -46.796759)
			(xy 82.725641 -46.771258) (xy 82.680283 -46.738807) (xy 82.640134 -46.700098) (xy 82.606048 -46.655955)
			(xy 82.578752 -46.60732) (xy 82.558829 -46.555229) (xy 82.546703 -46.500792) (xy 82.542632 -46.44517)
			(xy 73.85812 -46.44517) (xy 73.85812 -47.04994) (xy 89.78165 -47.04994) (xy 89.78563 -46.895439)
			(xy 89.797557 -46.741349) (xy 89.817402 -46.588076) (xy 89.84511 -46.436028) (xy 89.880608 -46.285609)
			(xy 89.923803 -46.137216) (xy 89.97458 -45.991243) (xy 90.032804 -45.848078) (xy 90.098321 -45.708101)
			(xy 90.170957 -45.571681) (xy 90.250519 -45.439181) (xy 90.336796 -45.310953) (xy 90.42956 -45.187337)
			(xy 90.528565 -45.068659) (xy 90.633548 -44.955236) (xy 90.74423 -44.847368) (xy 90.860319 -44.74534)
			(xy 90.981506 -44.649424) (xy 91.10747 -44.559873) (xy 91.237877 -44.476926) (xy 91.372381 -44.400801)
			(xy 91.510626 -44.331702) (xy 91.652244 -44.269811) (xy 91.796861 -44.215293) (xy 91.944092 -44.168291)
			(xy 92.093548 -44.128931) (xy 92.244832 -44.097317) (xy 92.397543 -44.073533) (xy 92.551275 -44.057642)
			(xy 92.705622 -44.049686) (xy 92.782898 -44.049188) (xy 94.383098 -44.049188) (xy 94.461836 -44.04972)
			(xy 94.619096 -44.057969) (xy 94.775706 -44.074457) (xy 94.931236 -44.099136) (xy 95.085258 -44.13194)
			(xy 95.237346 -44.172778) (xy 95.387083 -44.221537) (xy 95.534056 -44.278084) (xy 95.677861 -44.342262)
			(xy 95.818102 -44.413895) (xy 95.954392 -44.492786) (xy 96.086356 -44.578717) (xy 96.213631 -44.671452)
			(xy 96.335866 -44.770735) (xy 96.452725 -44.876294) (xy 96.563886 -44.987837) (xy 96.669044 -45.105057)
			(xy 96.767908 -45.227632) (xy 96.860206 -45.355224) (xy 96.945684 -45.487482) (xy 97.024107 -45.624041)
			(xy 97.095259 -45.764526) (xy 97.127568 -45.836332) (xy 97.132018 -45.845207) (xy 97.146387 -45.858883)
			(xy 97.164886 -45.866044) (xy 97.174812 -45.866304) (xy 97.268792 -45.86478) (xy 97.278774 -45.864116)
			(xy 97.297071 -45.856066) (xy 97.310919 -45.841649) (xy 97.31502 -45.832522) (xy 97.345783 -45.75647)
			(xy 97.41381 -45.607165) (xy 97.489171 -45.461424) (xy 97.571681 -45.319608) (xy 97.661135 -45.182066)
			(xy 97.757312 -45.049139) (xy 97.859975 -44.921154) (xy 97.968871 -44.798429) (xy 98.08373 -44.681266)
			(xy 98.204268 -44.569954) (xy 98.330188 -44.46477) (xy 98.461179 -44.365971) (xy 98.596917 -44.273803)
			(xy 98.737067 -44.188493) (xy 98.881283 -44.110252) (xy 99.029207 -44.039274) (xy 99.180476 -43.975733)
			(xy 99.334715 -43.919786) (xy 99.491544 -43.871572) (xy 99.650574 -43.831209) (xy 99.811413 -43.798799)
			(xy 99.973664 -43.774419) (xy 100.136926 -43.758132) (xy 100.300796 -43.749976) (xy 100.382832 -43.749468)
			(xy 100.463842 -43.749957) (xy 100.625667 -43.757907) (xy 100.786907 -43.773788) (xy 100.947173 -43.797561)
			(xy 101.10608 -43.82917) (xy 101.263244 -43.868538) (xy 101.418288 -43.91557) (xy 101.570837 -43.970153)
			(xy 101.720524 -44.032155) (xy 101.866988 -44.101428) (xy 102.009877 -44.177804) (xy 102.148846 -44.261098)
			(xy 102.283561 -44.351112) (xy 102.408334 -44.44365) (xy 148.255482 -44.44365) (xy 148.255984 -44.411689)
			(xy 148.263995 -44.348271) (xy 148.279892 -44.286357) (xy 148.303424 -44.226924) (xy 148.334218 -44.170909)
			(xy 148.371791 -44.119194) (xy 148.415548 -44.072597) (xy 148.464801 -44.031852) (xy 148.518772 -43.997601)
			(xy 148.576611 -43.970384) (xy 148.637404 -43.950631) (xy 148.700194 -43.938653) (xy 148.76399 -43.93464)
			(xy 148.827786 -43.938653) (xy 148.890576 -43.950631) (xy 148.951369 -43.970384) (xy 149.009208 -43.997601)
			(xy 149.063179 -44.031852) (xy 149.112432 -44.072597) (xy 149.156189 -44.119194) (xy 149.193762 -44.170909)
			(xy 149.224556 -44.226924) (xy 149.248088 -44.286357) (xy 149.263985 -44.348271) (xy 149.271996 -44.411689)
			(xy 149.272498 -44.44365) (xy 149.271948 -44.477207) (xy 149.263102 -44.543737) (xy 149.251774 -44.585636)
			(xy 151.936194 -44.585636) (xy 151.940265 -44.530014) (xy 151.952391 -44.475577) (xy 151.972314 -44.423486)
			(xy 151.99961 -44.374851) (xy 152.033696 -44.330708) (xy 152.073845 -44.291999) (xy 152.119203 -44.259548)
			(xy 152.168803 -44.234047) (xy 152.221587 -44.21604) (xy 152.27643 -44.20591) (xy 152.332164 -44.203873)
			(xy 152.387601 -44.209973) (xy 152.441558 -44.224079) (xy 152.492887 -44.245891) (xy 152.540493 -44.274945)
			(xy 152.583361 -44.31062) (xy 152.620578 -44.352157) (xy 152.651351 -44.39867) (xy 152.675023 -44.449167)
			(xy 152.691091 -44.502574) (xy 152.699211 -44.55775) (xy 152.69972 -44.585636) (xy 152.699211 -44.613522)
			(xy 152.698611 -44.617597) (xy 156.667448 -44.617597) (xy 156.667448 -44.553675) (xy 156.675459 -44.490257)
			(xy 156.691356 -44.428343) (xy 156.714888 -44.36891) (xy 156.745682 -44.312895) (xy 156.783255 -44.26118)
			(xy 156.827012 -44.214583) (xy 156.876265 -44.173838) (xy 156.930236 -44.139587) (xy 156.988075 -44.11237)
			(xy 157.048868 -44.092617) (xy 157.111658 -44.080639) (xy 157.175454 -44.076626) (xy 157.23925 -44.080639)
			(xy 157.30204 -44.092617) (xy 157.362833 -44.11237) (xy 157.420672 -44.139587) (xy 157.474643 -44.173838)
			(xy 157.523896 -44.214583) (xy 157.567653 -44.26118) (xy 157.605226 -44.312895) (xy 157.619555 -44.338959)
			(xy 165.690798 -44.338959) (xy 165.690798 -44.275037) (xy 165.698809 -44.211619) (xy 165.714706 -44.149705)
			(xy 165.738238 -44.090272) (xy 165.769032 -44.034257) (xy 165.806605 -43.982542) (xy 165.850362 -43.935945)
			(xy 165.899615 -43.8952) (xy 165.953586 -43.860949) (xy 166.011425 -43.833732) (xy 166.072218 -43.813979)
			(xy 166.135008 -43.802001) (xy 166.198804 -43.797988) (xy 166.2626 -43.802001) (xy 166.32539 -43.813979)
			(xy 166.386183 -43.833732) (xy 166.444022 -43.860949) (xy 166.497993 -43.8952) (xy 166.547246 -43.935945)
			(xy 166.591003 -43.982542) (xy 166.628576 -44.034257) (xy 166.65937 -44.090272) (xy 166.682902 -44.149705)
			(xy 166.698799 -44.211619) (xy 166.70681 -44.275037) (xy 166.707312 -44.306998) (xy 166.70681 -44.338959)
			(xy 166.698799 -44.402377) (xy 166.682902 -44.464291) (xy 166.65937 -44.523724) (xy 166.628576 -44.579739)
			(xy 166.591003 -44.631454) (xy 166.547246 -44.678051) (xy 166.497993 -44.718796) (xy 166.444022 -44.753047)
			(xy 166.386183 -44.780264) (xy 166.32539 -44.800017) (xy 166.2626 -44.811995) (xy 166.198804 -44.816009)
			(xy 166.135008 -44.811995) (xy 166.072218 -44.800017) (xy 166.011425 -44.780264) (xy 165.953586 -44.753047)
			(xy 165.899615 -44.718796) (xy 165.850362 -44.678051) (xy 165.806605 -44.631454) (xy 165.769032 -44.579739)
			(xy 165.738238 -44.523724) (xy 165.714706 -44.464291) (xy 165.698809 -44.402377) (xy 165.690798 -44.338959)
			(xy 157.619555 -44.338959) (xy 157.63602 -44.36891) (xy 157.659552 -44.428343) (xy 157.675449 -44.490257)
			(xy 157.68346 -44.553675) (xy 157.683962 -44.585636) (xy 157.68346 -44.617597) (xy 157.675449 -44.681015)
			(xy 157.659552 -44.742929) (xy 157.63602 -44.802362) (xy 157.605226 -44.858377) (xy 157.567653 -44.910092)
			(xy 157.523896 -44.956689) (xy 157.52139 -44.958762) (xy 164.575996 -44.958762) (xy 164.580067 -44.90314)
			(xy 164.592193 -44.848703) (xy 164.612116 -44.796612) (xy 164.639412 -44.747977) (xy 164.673498 -44.703834)
			(xy 164.713647 -44.665125) (xy 164.759005 -44.632674) (xy 164.808605 -44.607173) (xy 164.861389 -44.589166)
			(xy 164.916232 -44.579036) (xy 164.971966 -44.576999) (xy 165.027403 -44.583099) (xy 165.08136 -44.597205)
			(xy 165.132689 -44.619017) (xy 165.180295 -44.648071) (xy 165.223163 -44.683746) (xy 165.26038 -44.725283)
			(xy 165.291153 -44.771796) (xy 165.314825 -44.822293) (xy 165.330893 -44.8757) (xy 165.339013 -44.930876)
			(xy 165.339522 -44.958762) (xy 165.339013 -44.986648) (xy 165.330893 -45.041824) (xy 165.314825 -45.095231)
			(xy 165.291153 -45.145728) (xy 165.26038 -45.192241) (xy 165.223163 -45.233778) (xy 165.180295 -45.269453)
			(xy 165.132689 -45.298507) (xy 165.08136 -45.320319) (xy 165.027403 -45.334425) (xy 164.971966 -45.340525)
			(xy 164.916232 -45.338488) (xy 164.861389 -45.328358) (xy 164.808605 -45.310351) (xy 164.759005 -45.28485)
			(xy 164.713647 -45.252399) (xy 164.673498 -45.21369) (xy 164.639412 -45.169547) (xy 164.612116 -45.120912)
			(xy 164.592193 -45.068821) (xy 164.580067 -45.014384) (xy 164.575996 -44.958762) (xy 157.52139 -44.958762)
			(xy 157.474643 -44.997434) (xy 157.420672 -45.031685) (xy 157.362833 -45.058902) (xy 157.30204 -45.078655)
			(xy 157.23925 -45.090633) (xy 157.175454 -45.094647) (xy 157.111658 -45.090633) (xy 157.048868 -45.078655)
			(xy 156.988075 -45.058902) (xy 156.930236 -45.031685) (xy 156.876265 -44.997434) (xy 156.827012 -44.956689)
			(xy 156.783255 -44.910092) (xy 156.745682 -44.858377) (xy 156.714888 -44.802362) (xy 156.691356 -44.742929)
			(xy 156.675459 -44.681015) (xy 156.667448 -44.617597) (xy 152.698611 -44.617597) (xy 152.691091 -44.668698)
			(xy 152.675023 -44.722105) (xy 152.651351 -44.772602) (xy 152.620578 -44.819115) (xy 152.583361 -44.860652)
			(xy 152.540493 -44.896327) (xy 152.492887 -44.925381) (xy 152.441558 -44.947193) (xy 152.387601 -44.961299)
			(xy 152.332164 -44.967399) (xy 152.27643 -44.965362) (xy 152.221587 -44.955232) (xy 152.168803 -44.937225)
			(xy 152.119203 -44.911724) (xy 152.073845 -44.879273) (xy 152.033696 -44.840564) (xy 151.99961 -44.796421)
			(xy 151.972314 -44.747786) (xy 151.952391 -44.695695) (xy 151.940265 -44.641258) (xy 151.936194 -44.585636)
			(xy 149.251774 -44.585636) (xy 149.245585 -44.608525) (xy 149.2197 -44.670447) (xy 149.185897 -44.728428)
			(xy 149.144763 -44.78146) (xy 149.097013 -44.828623) (xy 149.070568 -44.849288) (xy 149.062547 -44.855927)
			(xy 149.052328 -44.874046) (xy 149.050756 -44.88434) (xy 149.042374 -44.957746) (xy 149.041766 -44.968169)
			(xy 149.047921 -44.988098) (xy 149.054312 -44.996354) (xy 149.071447 -45.017141) (xy 149.100292 -45.062638)
			(xy 149.122442 -45.111744) (xy 149.137457 -45.16348) (xy 149.145036 -45.216815) (xy 149.145498 -45.24375)
			(xy 149.145012 -45.271001) (xy 149.137256 -45.324949) (xy 149.121901 -45.377244) (xy 149.099259 -45.426821)
			(xy 149.069793 -45.472671) (xy 149.034102 -45.513862) (xy 148.992911 -45.549553) (xy 148.947061 -45.579019)
			(xy 148.897484 -45.601661) (xy 148.845189 -45.617016) (xy 148.791241 -45.624772) (xy 148.736739 -45.624772)
			(xy 148.682791 -45.617016) (xy 148.630496 -45.601661) (xy 148.580919 -45.579019) (xy 148.535069 -45.549553)
			(xy 148.493878 -45.513862) (xy 148.458187 -45.472671) (xy 148.428721 -45.426821) (xy 148.406079 -45.377244)
			(xy 148.390724 -45.324949) (xy 148.382968 -45.271001) (xy 148.382482 -45.24375) (xy 148.382946 -45.216816)
			(xy 148.390535 -45.163484) (xy 148.405553 -45.111751) (xy 148.427703 -45.062647) (xy 148.456543 -45.017149)
			(xy 148.473668 -44.996354) (xy 148.480107 -44.988124) (xy 148.486264 -44.968176) (xy 148.485606 -44.957746)
			(xy 148.477224 -44.88434) (xy 148.475601 -44.874067) (xy 148.465376 -44.855978) (xy 148.457412 -44.849288)
			(xy 148.430952 -44.828639) (xy 148.383186 -44.781485) (xy 148.342041 -44.728455) (xy 148.308234 -44.670472)
			(xy 148.282351 -44.608543) (xy 148.264844 -44.543747) (xy 148.256017 -44.47721) (xy 148.255482 -44.44365)
			(xy 102.408334 -44.44365) (xy 102.413696 -44.447627) (xy 102.538939 -44.550412) (xy 102.658988 -44.659218)
			(xy 102.773554 -44.773783) (xy 102.88236 -44.893832) (xy 102.985144 -45.019075) (xy 103.081659 -45.149211)
			(xy 103.171673 -45.283926) (xy 103.254967 -45.422895) (xy 103.331343 -45.565784) (xy 103.400616 -45.712248)
			(xy 103.462618 -45.861935) (xy 103.517201 -46.014484) (xy 103.564233 -46.169528) (xy 103.593449 -46.286166)
			(xy 155.37256 -46.286166) (xy 155.376631 -46.230544) (xy 155.388757 -46.176107) (xy 155.40868 -46.124016)
			(xy 155.435976 -46.075381) (xy 155.470062 -46.031238) (xy 155.510211 -45.992529) (xy 155.555569 -45.960078)
			(xy 155.605169 -45.934577) (xy 155.657953 -45.91657) (xy 155.712796 -45.90644) (xy 155.76853 -45.904403)
			(xy 155.823967 -45.910503) (xy 155.877924 -45.924609) (xy 155.929253 -45.946421) (xy 155.976859 -45.975475)
			(xy 156.019727 -46.01115) (xy 156.056944 -46.052687) (xy 156.087717 -46.0992) (xy 156.111389 -46.149697)
			(xy 156.127457 -46.203104) (xy 156.135577 -46.25828) (xy 156.135979 -46.280281) (xy 158.70529 -46.280281)
			(xy 158.70529 -46.216359) (xy 158.713301 -46.152941) (xy 158.729198 -46.091027) (xy 158.75273 -46.031594)
			(xy 158.783524 -45.975579) (xy 158.821097 -45.923864) (xy 158.864854 -45.877267) (xy 158.914107 -45.836522)
			(xy 158.968078 -45.802271) (xy 159.025917 -45.775054) (xy 159.08671 -45.755301) (xy 159.1495 -45.743323)
			(xy 159.213296 -45.73931) (xy 159.277092 -45.743323) (xy 159.339882 -45.755301) (xy 159.400675 -45.775054)
			(xy 159.458514 -45.802271) (xy 159.512485 -45.836522) (xy 159.561738 -45.877267) (xy 159.605495 -45.923864)
			(xy 159.643068 -45.975579) (xy 159.673862 -46.031594) (xy 159.697394 -46.091027) (xy 159.713291 -46.152941)
			(xy 159.719585 -46.202767) (xy 164.558266 -46.202767) (xy 164.563478 -46.139895) (xy 164.576426 -46.078151)
			(xy 164.596913 -46.018482) (xy 164.624623 -45.961805) (xy 164.659131 -45.908992) (xy 164.699906 -45.860852)
			(xy 164.746323 -45.818126) (xy 164.797669 -45.78147) (xy 164.853155 -45.751446) (xy 164.911928 -45.728517)
			(xy 164.973086 -45.713033) (xy 165.03569 -45.705234) (xy 165.067234 -45.70476) (xy 165.099613 -45.705277)
			(xy 165.163847 -45.713491) (xy 165.226518 -45.729796) (xy 165.286611 -45.753926) (xy 165.343154 -45.785491)
			(xy 165.369494 -45.804328) (xy 165.381194 -45.812315) (xy 165.40772 -45.822218) (xy 165.435946 -45.82445)
			(xy 165.463698 -45.81884) (xy 165.488841 -45.805819) (xy 165.509437 -45.786391) (xy 165.523901 -45.76205)
			(xy 165.531119 -45.734672) (xy 165.531292 -45.720508) (xy 165.531292 -45.710348) (xy 165.531716 -45.678803)
			(xy 165.539514 -45.616198) (xy 165.554996 -45.555038) (xy 165.577925 -45.496262) (xy 165.607947 -45.440774)
			(xy 165.644603 -45.389426) (xy 165.687328 -45.343006) (xy 165.735468 -45.302228) (xy 165.788281 -45.267717)
			(xy 165.844958 -45.240005) (xy 165.904628 -45.219515) (xy 165.966374 -45.206564) (xy 166.029247 -45.20135)
			(xy 166.092283 -45.203954) (xy 166.154512 -45.214334) (xy 166.21498 -45.232332) (xy 166.272757 -45.257672)
			(xy 166.326956 -45.289964) (xy 166.374738 -45.32715) (xy 177.908462 -45.32715) (xy 177.908462 -45.27265)
			(xy 177.916217 -45.218703) (xy 177.931571 -45.16641) (xy 177.95421 -45.116833) (xy 177.983674 -45.070983)
			(xy 178.019362 -45.029792) (xy 178.060549 -44.994099) (xy 178.106396 -44.96463) (xy 178.15597 -44.941986)
			(xy 178.208262 -44.926626) (xy 178.262208 -44.918865) (xy 178.289458 -44.918376) (xy 178.315778 -44.918838)
			(xy 178.36792 -44.926058) (xy 178.418574 -44.94038) (xy 178.466777 -44.961532) (xy 178.511613 -44.989112)
			(xy 178.55223 -45.022595) (xy 178.587857 -45.061347) (xy 178.617816 -45.10463) (xy 178.630072 -45.127926)
			(xy 178.634898 -45.137324) (xy 178.650138 -45.150278) (xy 178.7398 -45.178218) (xy 178.759866 -45.17644)
			(xy 178.76901 -45.17136) (xy 178.797044 -45.156651) (xy 178.855996 -45.133564) (xy 178.917357 -45.117972)
			(xy 178.980179 -45.110118) (xy 179.011834 -45.109638) (xy 179.042569 -45.110006) (xy 179.103589 -45.117419)
			(xy 179.163271 -45.132134) (xy 179.220744 -45.153935) (xy 179.275171 -45.182506) (xy 179.30768 -45.204949)
			(xy 181.026588 -45.204949) (xy 181.026588 -45.150451) (xy 181.034343 -45.096508) (xy 181.049696 -45.044218)
			(xy 181.072334 -44.994645) (xy 181.101796 -44.948797) (xy 181.137482 -44.907609) (xy 181.178667 -44.871919)
			(xy 181.224511 -44.842452) (xy 181.274082 -44.81981) (xy 181.326371 -44.804452) (xy 181.380313 -44.796691)
			(xy 181.407562 -44.796202) (xy 181.429807 -44.796531) (xy 181.473991 -44.80175) (xy 181.4957 -44.806616)
			(xy 181.504162 -44.808279) (xy 181.521301 -44.806458) (xy 181.529228 -44.80306) (xy 181.556152 -44.790106)
			(xy 181.563963 -44.785997) (xy 181.576443 -44.77354) (xy 181.580536 -44.765722) (xy 181.594441 -44.736873)
			(xy 181.628447 -44.682604) (xy 181.648354 -44.657518) (xy 181.653591 -44.650573) (xy 181.659436 -44.634205)
			(xy 181.659784 -44.625514) (xy 181.659784 -44.471082) (xy 181.659419 -44.462397) (xy 181.653563 -44.446039)
			(xy 181.648354 -44.439078) (xy 181.627266 -44.412422) (xy 181.591586 -44.354572) (xy 181.577234 -44.323762)
			(xy 181.573299 -44.315861) (xy 181.561088 -44.303132) (xy 181.553358 -44.29887) (xy 181.52618 -44.285662)
			(xy 181.518238 -44.282094) (xy 181.500962 -44.280023) (xy 181.492398 -44.281598) (xy 181.471476 -44.286087)
			(xy 181.428958 -44.290922) (xy 181.407562 -44.29125) (xy 181.380316 -44.290677) (xy 181.326378 -44.282917)
			(xy 181.274094 -44.26756) (xy 181.224527 -44.24492) (xy 181.178686 -44.215456) (xy 181.137505 -44.179768)
			(xy 181.101822 -44.138583) (xy 181.072362 -44.09274) (xy 181.049726 -44.043171) (xy 181.034375 -43.990885)
			(xy 181.02662 -43.936946) (xy 181.02662 -43.882454) (xy 181.034375 -43.828515) (xy 181.049726 -43.776229)
			(xy 181.072362 -43.72666) (xy 181.101822 -43.680817) (xy 181.137505 -43.639632) (xy 181.178686 -43.603944)
			(xy 181.224527 -43.57448) (xy 181.274094 -43.55184) (xy 181.326378 -43.536483) (xy 181.380316 -43.528723)
			(xy 181.407562 -43.528234) (xy 181.434776 -43.528714) (xy 181.488652 -43.536445) (xy 181.540882 -43.551755)
			(xy 181.590406 -43.574334) (xy 181.636218 -43.603722) (xy 181.677387 -43.639323) (xy 181.695598 -43.659552)
			(xy 181.70157 -43.665923) (xy 181.716776 -43.674487) (xy 181.725316 -43.676316) (xy 181.75478 -43.681142)
			(xy 181.763478 -43.682327) (xy 181.780762 -43.67933) (xy 181.788562 -43.6753) (xy 181.817552 -43.659299)
			(xy 181.87879 -43.634106) (xy 181.942779 -43.617071) (xy 182.008437 -43.60848) (xy 182.074655 -43.60848)
			(xy 182.140313 -43.617071) (xy 182.204302 -43.634106) (xy 182.26554 -43.659299) (xy 182.29453 -43.6753)
			(xy 182.302349 -43.679271) (xy 182.319615 -43.682265) (xy 182.328312 -43.681142) (xy 182.357776 -43.676316)
			(xy 182.366318 -43.674501) (xy 182.381511 -43.665914) (xy 182.387494 -43.659552) (xy 182.405688 -43.639308)
			(xy 182.446863 -43.603712) (xy 182.492679 -43.574328) (xy 182.542206 -43.551753) (xy 182.594438 -43.536445)
			(xy 182.648315 -43.528715) (xy 182.67553 -43.528234) (xy 182.702783 -43.528638) (xy 182.756733 -43.536399)
			(xy 182.80903 -43.551758) (xy 182.858609 -43.574404) (xy 182.904461 -43.603874) (xy 182.945652 -43.639569)
			(xy 182.981344 -43.680763) (xy 183.010811 -43.726617) (xy 183.033452 -43.776198) (xy 183.048808 -43.828496)
			(xy 183.056564 -43.882447) (xy 183.056564 -43.936953) (xy 183.048808 -43.990904) (xy 183.033452 -44.043202)
			(xy 183.010811 -44.092783) (xy 182.981344 -44.138637) (xy 182.945652 -44.179831) (xy 182.904461 -44.215526)
			(xy 182.858609 -44.244996) (xy 182.80903 -44.267642) (xy 182.756733 -44.283001) (xy 182.702783 -44.290762)
			(xy 182.67553 -44.29125) (xy 182.654133 -44.290938) (xy 182.611613 -44.286103) (xy 182.590694 -44.281598)
			(xy 182.58213 -44.280033) (xy 182.564858 -44.282107) (xy 182.556912 -44.285662) (xy 182.529734 -44.29887)
			(xy 182.52197 -44.303091) (xy 182.509734 -44.315822) (xy 182.505858 -44.323762) (xy 182.491545 -44.354592)
			(xy 182.45586 -44.412446) (xy 182.434738 -44.439078) (xy 182.429502 -44.446023) (xy 182.423656 -44.462391)
			(xy 182.423308 -44.471082) (xy 182.423308 -44.625514) (xy 182.423676 -44.634199) (xy 182.42953 -44.650557)
			(xy 182.434738 -44.657518) (xy 182.454618 -44.682624) (xy 182.488627 -44.736886) (xy 182.502556 -44.765722)
			(xy 182.506624 -44.773558) (xy 182.51911 -44.786024) (xy 182.523529 -44.788328) (xy 218.943934 -44.788328)
			(xy 218.948005 -44.732706) (xy 218.960131 -44.678269) (xy 218.980054 -44.626178) (xy 219.00735 -44.577543)
			(xy 219.041436 -44.5334) (xy 219.081585 -44.494691) (xy 219.126943 -44.46224) (xy 219.176543 -44.436739)
			(xy 219.229327 -44.418732) (xy 219.28417 -44.408602) (xy 219.339904 -44.406565) (xy 219.395341 -44.412665)
			(xy 219.449298 -44.426771) (xy 219.500627 -44.448583) (xy 219.548233 -44.477637) (xy 219.591101 -44.513312)
			(xy 219.628318 -44.554849) (xy 219.659091 -44.601362) (xy 219.682763 -44.651859) (xy 219.698831 -44.705266)
			(xy 219.706951 -44.760442) (xy 219.70746 -44.788328) (xy 219.706951 -44.816214) (xy 219.698831 -44.87139)
			(xy 219.682763 -44.924797) (xy 219.668647 -44.954909) (xy 222.172778 -44.954909) (xy 222.172778 -44.890987)
			(xy 222.180789 -44.827569) (xy 222.196686 -44.765655) (xy 222.220218 -44.706222) (xy 222.251012 -44.650207)
			(xy 222.288585 -44.598492) (xy 222.332342 -44.551895) (xy 222.381595 -44.51115) (xy 222.435566 -44.476899)
			(xy 222.493405 -44.449682) (xy 222.554198 -44.429929) (xy 222.616988 -44.417951) (xy 222.680784 -44.413938)
			(xy 222.74458 -44.417951) (xy 222.80737 -44.429929) (xy 222.868163 -44.449682) (xy 222.926002 -44.476899)
			(xy 222.979973 -44.51115) (xy 223.029226 -44.551895) (xy 223.072983 -44.598492) (xy 223.110556 -44.650207)
			(xy 223.14135 -44.706222) (xy 223.164882 -44.765655) (xy 223.180779 -44.827569) (xy 223.18879 -44.890987)
			(xy 223.189292 -44.922948) (xy 223.18879 -44.954909) (xy 223.180779 -45.018327) (xy 223.164882 -45.080241)
			(xy 223.14135 -45.139674) (xy 223.110556 -45.195689) (xy 223.072983 -45.247404) (xy 223.029226 -45.294001)
			(xy 222.979973 -45.334746) (xy 222.926002 -45.368997) (xy 222.868163 -45.396214) (xy 222.80737 -45.415967)
			(xy 222.74458 -45.427945) (xy 222.680784 -45.431959) (xy 222.616988 -45.427945) (xy 222.554198 -45.415967)
			(xy 222.493405 -45.396214) (xy 222.435566 -45.368997) (xy 222.381595 -45.334746) (xy 222.332342 -45.294001)
			(xy 222.288585 -45.247404) (xy 222.251012 -45.195689) (xy 222.220218 -45.139674) (xy 222.196686 -45.080241)
			(xy 222.180789 -45.018327) (xy 222.172778 -44.954909) (xy 219.668647 -44.954909) (xy 219.659091 -44.975294)
			(xy 219.628318 -45.021807) (xy 219.591101 -45.063344) (xy 219.548233 -45.099019) (xy 219.500627 -45.128073)
			(xy 219.449298 -45.149885) (xy 219.395341 -45.163991) (xy 219.339904 -45.170091) (xy 219.28417 -45.168054)
			(xy 219.229327 -45.157924) (xy 219.176543 -45.139917) (xy 219.126943 -45.114416) (xy 219.081585 -45.081965)
			(xy 219.041436 -45.043256) (xy 219.00735 -44.999113) (xy 218.980054 -44.950478) (xy 218.960131 -44.898387)
			(xy 218.948005 -44.84395) (xy 218.943934 -44.788328) (xy 182.523529 -44.788328) (xy 182.52694 -44.790106)
			(xy 182.553864 -44.80306) (xy 182.561792 -44.806449) (xy 182.578929 -44.808266) (xy 182.587392 -44.806616)
			(xy 182.609104 -44.80177) (xy 182.653286 -44.796555) (xy 182.67553 -44.796202) (xy 182.702781 -44.79667)
			(xy 182.756726 -44.80443) (xy 182.809019 -44.819788) (xy 182.858594 -44.842432) (xy 182.904442 -44.871899)
			(xy 182.945629 -44.907592) (xy 182.981319 -44.948782) (xy 183.010783 -44.994633) (xy 183.033422 -45.044209)
			(xy 183.048776 -45.096503) (xy 183.056532 -45.150449) (xy 183.056532 -45.204951) (xy 183.048776 -45.258897)
			(xy 183.033422 -45.311191) (xy 183.010783 -45.360767) (xy 182.981319 -45.406618) (xy 182.945629 -45.447808)
			(xy 182.904442 -45.483501) (xy 182.858594 -45.512968) (xy 182.809019 -45.535612) (xy 182.756726 -45.55097)
			(xy 182.702781 -45.55873) (xy 182.67553 -45.559218) (xy 182.675276 -45.559218) (xy 182.648667 -45.558742)
			(xy 182.595968 -45.551321) (xy 182.544811 -45.536652) (xy 182.496187 -45.515022) (xy 182.451037 -45.486848)
			(xy 182.410238 -45.452678) (xy 182.392066 -45.433234) (xy 182.386023 -45.427023) (xy 182.370839 -45.418702)
			(xy 182.362348 -45.416978) (xy 182.332884 -45.412406) (xy 182.324145 -45.411405) (xy 182.306872 -45.414636)
			(xy 182.299102 -45.418756) (xy 182.269687 -45.435341) (xy 182.207422 -45.461481) (xy 182.142249 -45.479159)
			(xy 182.07531 -45.488066) (xy 182.041546 -45.488606) (xy 182.00778 -45.488067) (xy 181.940834 -45.479189)
			(xy 181.875655 -45.461518) (xy 181.813394 -45.435365) (xy 181.78399 -45.418756) (xy 181.77622 -45.414627)
			(xy 181.758945 -45.411368) (xy 181.750208 -45.412406) (xy 181.720744 -45.416978) (xy 181.712262 -45.418734)
			(xy 181.697073 -45.427033) (xy 181.691026 -45.433234) (xy 181.672864 -45.452691) (xy 181.632079 -45.486888)
			(xy 181.586933 -45.515077) (xy 181.538303 -45.53671) (xy 181.487136 -45.551366) (xy 181.434428 -45.55876)
			(xy 181.407816 -45.559218) (xy 181.407562 -45.559218) (xy 181.380313 -45.558709) (xy 181.326371 -45.550948)
			(xy 181.274082 -45.53559) (xy 181.224511 -45.512948) (xy 181.178667 -45.483481) (xy 181.137482 -45.447791)
			(xy 181.101796 -45.406603) (xy 181.072334 -45.360755) (xy 181.049696 -45.311182) (xy 181.034343 -45.258892)
			(xy 181.026588 -45.204949) (xy 179.30768 -45.204949) (xy 179.325756 -45.217428) (xy 179.371763 -45.258193)
			(xy 179.412521 -45.304207) (xy 179.447436 -45.354798) (xy 179.475997 -45.409229) (xy 179.49779 -45.466705)
			(xy 179.512495 -45.52639) (xy 179.519899 -45.587411) (xy 179.520342 -45.618146) (xy 179.519777 -45.653102)
			(xy 179.51021 -45.722355) (xy 179.491248 -45.789646) (xy 179.46325 -45.853706) (xy 179.426742 -45.913328)
			(xy 179.405026 -45.940726) (xy 179.399769 -45.947657) (xy 179.393936 -45.964036) (xy 179.393596 -45.97273)
			(xy 179.393596 -46.0659) (xy 213.542116 -46.0659) (xy 213.54613 -46.002105) (xy 213.558109 -45.939316)
			(xy 213.577862 -45.878523) (xy 213.60508 -45.820686) (xy 213.639332 -45.766716) (xy 213.680078 -45.717465)
			(xy 213.726676 -45.673709) (xy 213.778391 -45.636139) (xy 213.834408 -45.605348) (xy 213.893841 -45.58182)
			(xy 213.955755 -45.565926) (xy 214.019173 -45.557919) (xy 214.051134 -45.55744) (xy 214.051388 -45.55744)
			(xy 214.081596 -45.55787) (xy 214.141589 -45.565009) (xy 214.200312 -45.579211) (xy 214.256936 -45.600276)
			(xy 214.310664 -45.627907) (xy 214.360736 -45.661713) (xy 214.383874 -45.681138) (xy 214.390932 -45.686801)
			(xy 214.407854 -45.693178) (xy 214.416894 -45.693584) (xy 214.447374 -45.693584) (xy 214.456411 -45.693167)
			(xy 214.473327 -45.686786) (xy 214.480394 -45.681138) (xy 214.503523 -45.661704) (xy 214.553607 -45.627918)
			(xy 214.607339 -45.600299) (xy 214.663964 -45.579237) (xy 214.722684 -45.565029) (xy 214.782673 -45.557873)
			(xy 214.81288 -45.55744) (xy 214.813134 -45.55744) (xy 214.845097 -45.557848) (xy 214.908518 -45.565863)
			(xy 214.970434 -45.581765) (xy 215.029869 -45.6053) (xy 215.085886 -45.636099) (xy 215.137601 -45.673675)
			(xy 215.184199 -45.717437) (xy 215.224945 -45.766694) (xy 215.259197 -45.820669) (xy 215.286414 -45.87851)
			(xy 215.306167 -45.939307) (xy 215.318145 -46.002101) (xy 215.322159 -46.0659) (xy 215.318145 -46.129699)
			(xy 215.306167 -46.192493) (xy 215.286414 -46.25329) (xy 215.259197 -46.311132) (xy 215.224945 -46.365106)
			(xy 215.184199 -46.414363) (xy 215.137601 -46.458125) (xy 215.085886 -46.495701) (xy 215.029869 -46.5265)
			(xy 214.970434 -46.550035) (xy 214.908518 -46.565937) (xy 214.845097 -46.573952) (xy 214.813134 -46.574456)
			(xy 214.81288 -46.574456) (xy 214.782671 -46.574046) (xy 214.722678 -46.566903) (xy 214.663955 -46.552697)
			(xy 214.60733 -46.531629) (xy 214.553603 -46.503994) (xy 214.503532 -46.470184) (xy 214.480394 -46.450758)
			(xy 214.473346 -46.445081) (xy 214.456416 -46.438713) (xy 214.447374 -46.438312) (xy 214.416894 -46.438312)
			(xy 214.407855 -46.438715) (xy 214.390939 -46.445105) (xy 214.383874 -46.450758) (xy 214.360718 -46.470159)
			(xy 214.31064 -46.50395) (xy 214.256914 -46.531573) (xy 214.200295 -46.552641) (xy 214.141579 -46.566856)
			(xy 214.081594 -46.574019) (xy 214.051388 -46.574456) (xy 214.051134 -46.574456) (xy 214.019173 -46.573881)
			(xy 213.955755 -46.565874) (xy 213.893841 -46.54998) (xy 213.834408 -46.526452) (xy 213.778391 -46.495661)
			(xy 213.726676 -46.458091) (xy 213.680078 -46.414335) (xy 213.639332 -46.365084) (xy 213.60508 -46.311114)
			(xy 213.577862 -46.253277) (xy 213.558109 -46.192484) (xy 213.54613 -46.129695) (xy 213.542116 -46.0659)
			(xy 179.393596 -46.0659) (xy 179.393596 -46.127162) (xy 179.393991 -46.135844) (xy 179.399827 -46.152202)
			(xy 179.405026 -46.159166) (xy 179.426727 -46.186574) (xy 179.463226 -46.246198) (xy 179.49122 -46.310256)
			(xy 179.510184 -46.377543) (xy 179.51976 -46.446792) (xy 179.520342 -46.481746) (xy 179.519888 -46.512477)
			(xy 179.512475 -46.573489) (xy 179.497762 -46.633164) (xy 179.475964 -46.69063) (xy 179.447399 -46.74505)
			(xy 179.412484 -46.795631) (xy 179.371727 -46.841635) (xy 179.325722 -46.882391) (xy 179.27514 -46.917306)
			(xy 179.220719 -46.945869) (xy 179.163252 -46.967666) (xy 179.103578 -46.982377) (xy 179.042565 -46.989788)
			(xy 179.011834 -46.990254) (xy 178.980179 -46.989764) (xy 178.917359 -46.981909) (xy 178.856001 -46.966315)
			(xy 178.797053 -46.943223) (xy 178.76901 -46.928532) (xy 178.759866 -46.923452) (xy 178.7398 -46.921674)
			(xy 178.650138 -46.949614) (xy 178.634898 -46.962568) (xy 178.630072 -46.971966) (xy 178.617817 -46.995262)
			(xy 178.587845 -47.038533) (xy 178.552212 -47.077276) (xy 178.511594 -47.110755) (xy 178.46676 -47.138336)
			(xy 178.418562 -47.159495) (xy 178.367914 -47.17383) (xy 178.315777 -47.181071) (xy 178.289458 -47.181516)
			(xy 178.262209 -47.181011) (xy 178.208267 -47.17325) (xy 178.155979 -47.157892) (xy 178.106408 -47.135249)
			(xy 178.060564 -47.105782) (xy 178.019379 -47.070091) (xy 177.983693 -47.028903) (xy 177.954231 -46.983055)
			(xy 177.931594 -46.933482) (xy 177.916241 -46.881192) (xy 177.908486 -46.827249) (xy 177.908486 -46.772751)
			(xy 177.916241 -46.718808) (xy 177.931594 -46.666518) (xy 177.954231 -46.616945) (xy 177.983693 -46.571097)
			(xy 178.019379 -46.529909) (xy 178.060564 -46.494218) (xy 178.106408 -46.464751) (xy 178.155979 -46.442108)
			(xy 178.208267 -46.42675) (xy 178.262209 -46.418989) (xy 178.289458 -46.4185) (xy 178.31551 -46.418978)
			(xy 178.367125 -46.426112) (xy 178.392328 -46.432724) (xy 178.402196 -46.434875) (xy 178.422203 -46.432254)
			(xy 178.43119 -46.427644) (xy 178.50358 -46.385734) (xy 178.515772 -46.369224) (xy 178.518312 -46.359318)
			(xy 178.525454 -46.332008) (xy 178.545008 -46.279052) (xy 178.570308 -46.228587) (xy 178.601043 -46.181236)
			(xy 178.618642 -46.159166) (xy 178.623899 -46.152235) (xy 178.629732 -46.135856) (xy 178.630072 -46.127162)
			(xy 178.630072 -45.97273) (xy 178.629688 -45.964047) (xy 178.623845 -45.947689) (xy 178.618642 -45.940726)
			(xy 178.601038 -45.91866) (xy 178.57031 -45.871305) (xy 178.545015 -45.820838) (xy 178.525465 -45.767881)
			(xy 178.518312 -45.740574) (xy 178.515772 -45.730668) (xy 178.50358 -45.714158) (xy 178.4223 -45.667168)
			(xy 178.402488 -45.664374) (xy 178.392582 -45.667168) (xy 178.392074 -45.667168) (xy 178.366939 -45.673797)
			(xy 178.315449 -45.680937) (xy 178.289458 -45.681392) (xy 178.262208 -45.680935) (xy 178.208262 -45.673174)
			(xy 178.15597 -45.657814) (xy 178.106396 -45.63517) (xy 178.060549 -45.605701) (xy 178.019362 -45.570008)
			(xy 177.983674 -45.528817) (xy 177.95421 -45.482967) (xy 177.931571 -45.43339) (xy 177.916217 -45.381097)
			(xy 177.908462 -45.32715) (xy 166.374738 -45.32715) (xy 166.376744 -45.328711) (xy 166.421357 -45.37332)
			(xy 166.460109 -45.423105) (xy 166.492406 -45.477301) (xy 166.517751 -45.535075) (xy 166.535755 -45.595541)
			(xy 166.546141 -45.65777) (xy 166.548751 -45.720805) (xy 166.543543 -45.783679) (xy 166.530597 -45.845426)
			(xy 166.510114 -45.905097) (xy 166.482406 -45.961777) (xy 166.447901 -46.014594) (xy 166.407127 -46.062737)
			(xy 166.360711 -46.105467) (xy 166.309367 -46.142127) (xy 166.253882 -46.172155) (xy 166.195108 -46.195089)
			(xy 166.13395 -46.210577) (xy 166.071345 -46.218381) (xy 166.0398 -46.218856) (xy 166.007421 -46.218337)
			(xy 165.943187 -46.210126) (xy 165.880515 -46.193823) (xy 165.820422 -46.169693) (xy 165.763879 -46.138126)
			(xy 165.73754 -46.119288) (xy 165.7259 -46.111206) (xy 165.699357 -46.101309) (xy 165.671116 -46.099085)
			(xy 165.64335 -46.104707) (xy 165.618198 -46.117742) (xy 165.597596 -46.137186) (xy 165.58313 -46.161543)
			(xy 165.575913 -46.188937) (xy 165.575742 -46.203108) (xy 165.575742 -46.213268) (xy 165.575266 -46.244812)
			(xy 165.567466 -46.307416) (xy 165.551983 -46.368574) (xy 165.529053 -46.427347) (xy 165.499029 -46.482833)
			(xy 165.462373 -46.534178) (xy 165.419646 -46.580595) (xy 165.371507 -46.621371) (xy 165.318693 -46.655878)
			(xy 165.262016 -46.683588) (xy 165.202348 -46.704074) (xy 165.140603 -46.717022) (xy 165.077731 -46.722234)
			(xy 165.014697 -46.719628) (xy 164.952469 -46.709245) (xy 164.892004 -46.691244) (xy 164.83423 -46.665903)
			(xy 164.780034 -46.633609) (xy 164.730248 -46.59486) (xy 164.685639 -46.55025) (xy 164.64689 -46.500465)
			(xy 164.614597 -46.446269) (xy 164.589255 -46.388494) (xy 164.571255 -46.328029) (xy 164.560872 -46.265801)
			(xy 164.558266 -46.202767) (xy 159.719585 -46.202767) (xy 159.721302 -46.216359) (xy 159.721804 -46.24832)
			(xy 159.721302 -46.280281) (xy 159.713291 -46.343699) (xy 159.697394 -46.405613) (xy 159.673862 -46.465046)
			(xy 159.643068 -46.521061) (xy 159.605495 -46.572776) (xy 159.561738 -46.619373) (xy 159.512485 -46.660118)
			(xy 159.458514 -46.694369) (xy 159.400675 -46.721586) (xy 159.339882 -46.741339) (xy 159.277092 -46.753317)
			(xy 159.213296 -46.757331) (xy 159.1495 -46.753317) (xy 159.08671 -46.741339) (xy 159.025917 -46.721586)
			(xy 158.968078 -46.694369) (xy 158.914107 -46.660118) (xy 158.864854 -46.619373) (xy 158.821097 -46.572776)
			(xy 158.783524 -46.521061) (xy 158.75273 -46.465046) (xy 158.729198 -46.405613) (xy 158.713301 -46.343699)
			(xy 158.70529 -46.280281) (xy 156.135979 -46.280281) (xy 156.136086 -46.286166) (xy 156.135577 -46.314052)
			(xy 156.127457 -46.369228) (xy 156.111389 -46.422635) (xy 156.087717 -46.473132) (xy 156.056944 -46.519645)
			(xy 156.019727 -46.561182) (xy 155.976859 -46.596857) (xy 155.929253 -46.625911) (xy 155.877924 -46.647723)
			(xy 155.823967 -46.661829) (xy 155.76853 -46.667929) (xy 155.712796 -46.665892) (xy 155.657953 -46.655762)
			(xy 155.605169 -46.637755) (xy 155.555569 -46.612254) (xy 155.510211 -46.579803) (xy 155.470062 -46.541094)
			(xy 155.435976 -46.496951) (xy 155.40868 -46.448316) (xy 155.388757 -46.396225) (xy 155.376631 -46.341788)
			(xy 155.37256 -46.286166) (xy 103.593449 -46.286166) (xy 103.6036 -46.326692) (xy 103.635209 -46.485599)
			(xy 103.658982 -46.645865) (xy 103.674863 -46.807105) (xy 103.682813 -46.96893) (xy 103.682813 -47.13095)
			(xy 103.674863 -47.292775) (xy 103.658982 -47.454015) (xy 103.635209 -47.614281) (xy 103.6036 -47.773188)
			(xy 103.587541 -47.837301) (xy 104.233974 -47.837301) (xy 104.233974 -47.773379) (xy 104.241985 -47.709961)
			(xy 104.257882 -47.648047) (xy 104.281414 -47.588614) (xy 104.312208 -47.532599) (xy 104.349781 -47.480884)
			(xy 104.393538 -47.434287) (xy 104.442791 -47.393542) (xy 104.496762 -47.359291) (xy 104.554601 -47.332074)
			(xy 104.615394 -47.312321) (xy 104.678184 -47.300343) (xy 104.74198 -47.29633) (xy 104.805776 -47.300343)
			(xy 104.868566 -47.312321) (xy 104.929359 -47.332074) (xy 104.987198 -47.359291) (xy 105.041169 -47.393542)
			(xy 105.090422 -47.434287) (xy 105.134179 -47.480884) (xy 105.171752 -47.532599) (xy 105.202546 -47.588614)
			(xy 105.226078 -47.648047) (xy 105.241975 -47.709961) (xy 105.249986 -47.773379) (xy 105.250488 -47.80534)
			(xy 105.249986 -47.837301) (xy 105.241975 -47.900719) (xy 105.226078 -47.962633) (xy 105.202546 -48.022066)
			(xy 105.171752 -48.078081) (xy 105.134179 -48.129796) (xy 105.090422 -48.176393) (xy 105.041169 -48.217138)
			(xy 104.987198 -48.251389) (xy 104.929359 -48.278606) (xy 104.868566 -48.298359) (xy 104.805776 -48.310337)
			(xy 104.74198 -48.314351) (xy 104.678184 -48.310337) (xy 104.615394 -48.298359) (xy 104.554601 -48.278606)
			(xy 104.496762 -48.251389) (xy 104.442791 -48.217138) (xy 104.393538 -48.176393) (xy 104.349781 -48.129796)
			(xy 104.312208 -48.078081) (xy 104.281414 -48.022066) (xy 104.257882 -47.962633) (xy 104.241985 -47.900719)
			(xy 104.233974 -47.837301) (xy 103.587541 -47.837301) (xy 103.564233 -47.930352) (xy 103.517201 -48.085396)
			(xy 103.462618 -48.237945) (xy 103.400616 -48.387632) (xy 103.331343 -48.534096) (xy 103.254967 -48.676985)
			(xy 103.221945 -48.73208) (xy 121.461898 -48.73208) (xy 121.467107 -48.669214) (xy 121.480053 -48.607474)
			(xy 121.500536 -48.54781) (xy 121.528241 -48.491138) (xy 121.562744 -48.438328) (xy 121.603514 -48.390191)
			(xy 121.649925 -48.347466) (xy 121.701264 -48.310811) (xy 121.756743 -48.280787) (xy 121.81551 -48.257856)
			(xy 121.876661 -48.24237) (xy 121.939259 -48.234568) (xy 121.9708 -48.234092) (xy 122.005273 -48.234672)
			(xy 122.073588 -48.243992) (xy 122.140019 -48.262449) (xy 122.20335 -48.289704) (xy 122.233182 -48.30699)
			(xy 122.246136 -48.314864) (xy 122.275854 -48.313848) (xy 122.376946 -48.243744) (xy 122.388122 -48.216058)
			(xy 122.385328 -48.201326) (xy 122.381294 -48.178297) (xy 122.376969 -48.13174) (xy 122.376692 -48.108362)
			(xy 122.376692 -48.1076) (xy 122.377156 -48.076869) (xy 122.384565 -48.015855) (xy 122.399273 -47.956179)
			(xy 122.421068 -47.898711) (xy 122.449631 -47.844289) (xy 122.484545 -47.793707) (xy 122.525302 -47.747702)
			(xy 122.571307 -47.706945) (xy 122.621889 -47.672031) (xy 122.676311 -47.643468) (xy 122.733779 -47.621673)
			(xy 122.793455 -47.606965) (xy 122.854469 -47.599556) (xy 122.8852 -47.599092) (xy 122.91572 -47.599541)
			(xy 122.976322 -47.606843) (xy 123.035613 -47.621352) (xy 123.092738 -47.64286) (xy 123.146875 -47.671057)
			(xy 123.197244 -47.705537) (xy 123.22048 -47.72533) (xy 123.227158 -47.730757) (xy 123.243141 -47.737109)
			(xy 123.251722 -47.737776) (xy 123.28144 -47.739046) (xy 123.290137 -47.73911) (xy 123.30676 -47.734031)
			(xy 123.313952 -47.72914) (xy 123.340336 -47.710131) (xy 123.397022 -47.678262) (xy 123.457311 -47.653887)
			(xy 123.520218 -47.637405) (xy 123.584713 -47.629084) (xy 123.617228 -47.628556) (xy 123.649186 -47.629132)
			(xy 123.712597 -47.637145) (xy 123.774503 -47.653043) (xy 123.833929 -47.676575) (xy 123.889937 -47.707368)
			(xy 123.941645 -47.744938) (xy 123.988236 -47.788693) (xy 124.028976 -47.837941) (xy 124.063222 -47.891908)
			(xy 124.090435 -47.94974) (xy 124.110185 -48.010528) (xy 124.122161 -48.073311) (xy 124.126173 -48.137064)
			(xy 125.40691 -48.137064) (xy 125.410981 -48.081442) (xy 125.423107 -48.027005) (xy 125.44303 -47.974914)
			(xy 125.470326 -47.926279) (xy 125.504412 -47.882136) (xy 125.544561 -47.843427) (xy 125.589919 -47.810976)
			(xy 125.639519 -47.785475) (xy 125.692303 -47.767468) (xy 125.747146 -47.757338) (xy 125.80288 -47.755301)
			(xy 125.858317 -47.761401) (xy 125.912274 -47.775507) (xy 125.963603 -47.797319) (xy 126.011209 -47.826373)
			(xy 126.054077 -47.862048) (xy 126.091294 -47.903585) (xy 126.122067 -47.950098) (xy 126.145739 -48.000595)
			(xy 126.161807 -48.054002) (xy 126.169927 -48.109178) (xy 126.170436 -48.137064) (xy 126.169927 -48.16495)
			(xy 126.161807 -48.220126) (xy 126.145739 -48.273533) (xy 126.122067 -48.32403) (xy 126.091294 -48.370543)
			(xy 126.054077 -48.41208) (xy 126.011209 -48.447755) (xy 125.963603 -48.476809) (xy 125.912274 -48.498621)
			(xy 125.858317 -48.512727) (xy 125.80288 -48.518827) (xy 125.747146 -48.51679) (xy 125.692303 -48.50666)
			(xy 125.639519 -48.488653) (xy 125.589919 -48.463152) (xy 125.544561 -48.430701) (xy 125.504412 -48.391992)
			(xy 125.470326 -48.347849) (xy 125.44303 -48.299214) (xy 125.423107 -48.247123) (xy 125.410981 -48.192686)
			(xy 125.40691 -48.137064) (xy 124.126173 -48.137064) (xy 124.126175 -48.1371) (xy 124.122161 -48.200889)
			(xy 124.110185 -48.263672) (xy 124.090435 -48.32446) (xy 124.063222 -48.382292) (xy 124.028976 -48.436259)
			(xy 123.988236 -48.485507) (xy 123.941645 -48.529262) (xy 123.889937 -48.566832) (xy 123.833929 -48.597625)
			(xy 123.774503 -48.621157) (xy 123.712597 -48.637055) (xy 123.649186 -48.645068) (xy 123.617228 -48.645572)
			(xy 123.586708 -48.645115) (xy 123.526106 -48.637816) (xy 123.466815 -48.623309) (xy 123.40969 -48.601803)
			(xy 123.355552 -48.573607) (xy 123.305184 -48.539127) (xy 123.281948 -48.519334) (xy 123.275256 -48.513926)
			(xy 123.259284 -48.507561) (xy 123.250706 -48.506888) (xy 123.220988 -48.505618) (xy 123.212293 -48.505574)
			(xy 123.19567 -48.51064) (xy 123.188476 -48.515524) (xy 123.16208 -48.534516) (xy 123.105398 -48.566389)
			(xy 123.045112 -48.590768) (xy 122.982208 -48.607254) (xy 122.917714 -48.615578) (xy 122.8852 -48.616108)
			(xy 122.850727 -48.615528) (xy 122.782412 -48.606208) (xy 122.715981 -48.587751) (xy 122.65265 -48.560496)
			(xy 122.622818 -48.54321) (xy 122.609864 -48.535336) (xy 122.580146 -48.536352) (xy 122.479054 -48.606456)
			(xy 122.467878 -48.634142) (xy 122.470672 -48.648874) (xy 122.474706 -48.671903) (xy 122.479031 -48.71846)
			(xy 122.479155 -48.728884) (xy 131.239006 -48.728884) (xy 131.239508 -48.696923) (xy 131.247519 -48.633505)
			(xy 131.263416 -48.571591) (xy 131.286948 -48.512158) (xy 131.317742 -48.456143) (xy 131.355315 -48.404428)
			(xy 131.399072 -48.357831) (xy 131.448325 -48.317086) (xy 131.502296 -48.282835) (xy 131.560135 -48.255618)
			(xy 131.620928 -48.235865) (xy 131.683718 -48.223887) (xy 131.747514 -48.219874) (xy 131.81131 -48.223887)
			(xy 131.8741 -48.235865) (xy 131.934893 -48.255618) (xy 131.992732 -48.282835) (xy 132.046703 -48.317086)
			(xy 132.095956 -48.357831) (xy 132.139713 -48.404428) (xy 132.177286 -48.456143) (xy 132.20808 -48.512158)
			(xy 132.231612 -48.571591) (xy 132.247509 -48.633505) (xy 132.25552 -48.696923) (xy 132.256022 -48.728884)
			(xy 132.255469 -48.762713) (xy 132.246476 -48.829773) (xy 132.228674 -48.895048) (xy 132.202376 -48.957387)
			(xy 132.168047 -49.015691) (xy 132.126293 -49.06893) (xy 132.077851 -49.116164) (xy 132.051044 -49.136808)
			(xy 132.03971 -49.145874) (xy 132.029546 -49.159414) (xy 140.100304 -49.159414) (xy 140.100779 -49.12904)
			(xy 140.108011 -49.068725) (xy 140.122375 -49.0097) (xy 140.143664 -48.952805) (xy 140.171578 -48.898851)
			(xy 140.205717 -48.848604) (xy 140.245597 -48.80278) (xy 140.290651 -48.762031) (xy 140.315188 -48.744124)
			(xy 140.323041 -48.738108) (xy 140.33375 -48.721496) (xy 140.336016 -48.711866) (xy 140.34897 -48.642778)
			(xy 140.350345 -48.632996) (xy 140.346431 -48.613656) (xy 140.34135 -48.605186) (xy 140.325358 -48.580182)
			(xy 140.298666 -48.527166) (xy 140.278322 -48.471404) (xy 140.264603 -48.413655) (xy 140.257695 -48.354702)
			(xy 140.257276 -48.325024) (xy 140.257778 -48.293063) (xy 140.265789 -48.229645) (xy 140.281686 -48.167731)
			(xy 140.305218 -48.108298) (xy 140.336012 -48.052283) (xy 140.373585 -48.000568) (xy 140.417342 -47.953971)
			(xy 140.466595 -47.913226) (xy 140.520566 -47.878975) (xy 140.578405 -47.851758) (xy 140.639198 -47.832005)
			(xy 140.701988 -47.820027) (xy 140.765784 -47.816014) (xy 140.82958 -47.820027) (xy 140.89237 -47.832005)
			(xy 140.953163 -47.851758) (xy 141.011002 -47.878975) (xy 141.064973 -47.913226) (xy 141.114226 -47.953971)
			(xy 141.157983 -48.000568) (xy 141.195556 -48.052283) (xy 141.22635 -48.108298) (xy 141.249882 -48.167731)
			(xy 141.265779 -48.229645) (xy 141.268357 -48.250051) (xy 145.649944 -48.250051) (xy 145.649944 -48.186129)
			(xy 145.657955 -48.122711) (xy 145.673852 -48.060797) (xy 145.697384 -48.001364) (xy 145.728178 -47.945349)
			(xy 145.765751 -47.893634) (xy 145.809508 -47.847037) (xy 145.858761 -47.806292) (xy 145.912732 -47.772041)
			(xy 145.970571 -47.744824) (xy 146.031364 -47.725071) (xy 146.094154 -47.713093) (xy 146.15795 -47.70908)
			(xy 146.221746 -47.713093) (xy 146.284536 -47.725071) (xy 146.345329 -47.744824) (xy 146.403168 -47.772041)
			(xy 146.457139 -47.806292) (xy 146.506392 -47.847037) (xy 146.550149 -47.893634) (xy 146.587722 -47.945349)
			(xy 146.618516 -48.001364) (xy 146.642048 -48.060797) (xy 146.657945 -48.122711) (xy 146.665956 -48.186129)
			(xy 146.666458 -48.21809) (xy 146.665956 -48.250051) (xy 146.657945 -48.313469) (xy 146.642048 -48.375383)
			(xy 146.618516 -48.434816) (xy 146.607503 -48.454848) (xy 149.555218 -48.454848) (xy 149.555218 -48.400352)
			(xy 149.562974 -48.34641) (xy 149.578327 -48.29412) (xy 149.600966 -48.244548) (xy 149.630429 -48.198703)
			(xy 149.666117 -48.157517) (xy 149.707303 -48.121829) (xy 149.753148 -48.092366) (xy 149.80272 -48.069727)
			(xy 149.85501 -48.054374) (xy 149.908952 -48.046618) (xy 149.9362 -48.046132) (xy 149.961805 -48.046525)
			(xy 150.012554 -48.053372) (xy 150.061933 -48.066943) (xy 150.109053 -48.086995) (xy 150.131272 -48.099726)
			(xy 150.143718 -48.107092) (xy 150.17242 -48.106584) (xy 150.273258 -48.042068) (xy 150.285704 -48.01616)
			(xy 150.28418 -48.001936) (xy 150.282883 -47.988766) (xy 150.281486 -47.962337) (xy 150.281386 -47.949104)
			(xy 150.28186 -47.918373) (xy 150.289268 -47.85736) (xy 150.303976 -47.797685) (xy 150.32577 -47.740217)
			(xy 150.354332 -47.685795) (xy 150.389245 -47.635213) (xy 150.430001 -47.589208) (xy 150.476005 -47.548452)
			(xy 150.526587 -47.513537) (xy 150.581008 -47.484974) (xy 150.638475 -47.463179) (xy 150.69815 -47.448469)
			(xy 150.759163 -47.44106) (xy 150.789894 -47.440596) (xy 150.822032 -47.441123) (xy 150.885797 -47.449207)
			(xy 150.948036 -47.46526) (xy 151.007756 -47.489026) (xy 151.064007 -47.520126) (xy 151.115891 -47.558065)
			(xy 151.162582 -47.602238) (xy 151.18334 -47.626778) (xy 151.18969 -47.634398) (xy 151.206962 -47.64405)
			(xy 151.296116 -47.654718) (xy 151.314912 -47.649638) (xy 151.322786 -47.643796) (xy 151.347731 -47.625828)
			(xy 151.402169 -47.597274) (xy 151.460481 -47.577817) (xy 151.521158 -47.56796) (xy 151.551894 -47.567342)
			(xy 151.579274 -47.567787) (xy 151.63347 -47.575628) (xy 151.685988 -47.591135) (xy 151.73575 -47.613991)
			(xy 151.781735 -47.643725) (xy 151.822996 -47.679726) (xy 151.8412 -47.700184) (xy 151.8412 -47.700438)
			(xy 151.8496 -47.709175) (xy 151.87201 -47.71832) (xy 151.884126 -47.717964) (xy 151.97836 -47.709836)
			(xy 151.998934 -47.697136) (xy 152.005284 -47.686468) (xy 152.022586 -47.658721) (xy 152.063278 -47.607534)
			(xy 152.110192 -47.56198) (xy 152.162555 -47.522811) (xy 152.219504 -47.490672) (xy 152.2801 -47.466093)
			(xy 152.343345 -47.449478) (xy 152.408198 -47.441101) (xy 152.440894 -47.440596) (xy 152.472857 -47.441069)
			(xy 152.536279 -47.44908) (xy 152.598196 -47.464977) (xy 152.657633 -47.488509) (xy 152.713652 -47.519305)
			(xy 152.765369 -47.556879) (xy 152.811969 -47.600639) (xy 152.8441 -47.639478) (xy 162.375596 -47.639478)
			(xy 162.376179 -47.606577) (xy 162.384677 -47.541326) (xy 162.401515 -47.477715) (xy 162.426413 -47.416806)
			(xy 162.458955 -47.359614) (xy 162.498598 -47.307094) (xy 162.54468 -47.260123) (xy 162.596433 -47.219483)
			(xy 162.652992 -47.185855) (xy 162.713415 -47.159797) (xy 162.744912 -47.150274) (xy 162.754056 -47.147734)
			(xy 162.769296 -47.136304) (xy 162.81527 -47.060358) (xy 162.818572 -47.041816) (xy 162.81654 -47.032164)
			(xy 162.812877 -47.013134) (xy 162.808929 -46.97458) (xy 162.808666 -46.955202) (xy 162.808666 -46.954948)
			(xy 162.809152 -46.927697) (xy 162.816908 -46.873749) (xy 162.832263 -46.821454) (xy 162.854905 -46.771877)
			(xy 162.884371 -46.726027) (xy 162.920062 -46.684836) (xy 162.961253 -46.649145) (xy 163.007103 -46.619679)
			(xy 163.05668 -46.597037) (xy 163.108975 -46.581682) (xy 163.162923 -46.573926) (xy 163.217425 -46.573926)
			(xy 163.271373 -46.581682) (xy 163.323668 -46.597037) (xy 163.373245 -46.619679) (xy 163.419095 -46.649145)
			(xy 163.460286 -46.684836) (xy 163.495977 -46.726027) (xy 163.525443 -46.771877) (xy 163.548085 -46.821454)
			(xy 163.56344 -46.873749) (xy 163.571196 -46.927697) (xy 163.571682 -46.954948) (xy 163.571197 -46.983436)
			(xy 163.562717 -47.039779) (xy 163.545952 -47.094233) (xy 163.521275 -47.145589) (xy 163.489235 -47.192704)
			(xy 163.450545 -47.234531) (xy 163.406065 -47.270138) (xy 163.38169 -47.284894) (xy 163.373562 -47.28972)
			(xy 163.36137 -47.304706) (xy 163.33851 -47.380398) (xy 163.336229 -47.389535) (xy 163.33765 -47.408295)
			(xy 163.341304 -47.416974) (xy 163.341304 -47.417482) (xy 163.353531 -47.443488) (xy 163.372712 -47.497659)
			(xy 163.385653 -47.55365) (xy 163.39219 -47.610745) (xy 163.392612 -47.639478) (xy 163.39211 -47.671439)
			(xy 163.384099 -47.734857) (xy 163.368202 -47.796771) (xy 163.34467 -47.856204) (xy 163.313876 -47.912219)
			(xy 163.276303 -47.963934) (xy 163.232546 -48.010531) (xy 163.183293 -48.051276) (xy 163.129322 -48.085527)
			(xy 163.071483 -48.112744) (xy 163.01069 -48.132497) (xy 162.9479 -48.144475) (xy 162.884104 -48.148489)
			(xy 162.820308 -48.144475) (xy 162.757518 -48.132497) (xy 162.696725 -48.112744) (xy 162.638886 -48.085527)
			(xy 162.584915 -48.051276) (xy 162.535662 -48.010531) (xy 162.491905 -47.963934) (xy 162.454332 -47.912219)
			(xy 162.423538 -47.856204) (xy 162.400006 -47.796771) (xy 162.384109 -47.734857) (xy 162.376098 -47.671439)
			(xy 162.375596 -47.639478) (xy 152.8441 -47.639478) (xy 152.852717 -47.649894) (xy 152.88697 -47.703869)
			(xy 152.914189 -47.76171) (xy 152.933943 -47.822507) (xy 152.945922 -47.8853) (xy 152.949936 -47.9491)
			(xy 152.945922 -48.0129) (xy 152.933943 -48.075693) (xy 152.914189 -48.13649) (xy 152.88697 -48.194331)
			(xy 152.852717 -48.248306) (xy 152.811969 -48.297561) (xy 152.780459 -48.327151) (xy 177.908456 -48.327151)
			(xy 177.908456 -48.272649) (xy 177.916212 -48.218702) (xy 177.931565 -48.166408) (xy 177.954205 -48.11683)
			(xy 177.983669 -48.070979) (xy 178.019358 -48.029788) (xy 178.060546 -47.994094) (xy 178.106393 -47.964625)
			(xy 178.155968 -47.94198) (xy 178.208261 -47.926621) (xy 178.262207 -47.918859) (xy 178.289458 -47.91837)
			(xy 178.315778 -47.918836) (xy 178.36792 -47.926055) (xy 178.418573 -47.940377) (xy 178.466776 -47.961528)
			(xy 178.511612 -47.989108) (xy 178.55223 -48.022591) (xy 178.587856 -48.061342) (xy 178.617816 -48.104624)
			(xy 178.630072 -48.12792) (xy 178.634898 -48.137318) (xy 178.650138 -48.150272) (xy 178.7398 -48.178212)
			(xy 178.759866 -48.176434) (xy 178.76901 -48.171354) (xy 178.797049 -48.156654) (xy 178.855998 -48.133562)
			(xy 178.917358 -48.117968) (xy 178.980179 -48.110113) (xy 179.011834 -48.109632) (xy 179.042568 -48.110006)
			(xy 179.103588 -48.117419) (xy 179.16327 -48.132134) (xy 179.220743 -48.153935) (xy 179.275169 -48.182505)
			(xy 179.325754 -48.217426) (xy 179.365845 -48.252949) (xy 181.026588 -48.252949) (xy 181.026588 -48.198451)
			(xy 181.034343 -48.144508) (xy 181.049696 -48.092218) (xy 181.072334 -48.042645) (xy 181.101796 -47.996797)
			(xy 181.137482 -47.955609) (xy 181.178667 -47.919919) (xy 181.224511 -47.890452) (xy 181.274082 -47.86781)
			(xy 181.326371 -47.852452) (xy 181.380313 -47.844691) (xy 181.407562 -47.844202) (xy 181.429807 -47.844531)
			(xy 181.473991 -47.84975) (xy 181.4957 -47.854616) (xy 181.504162 -47.856279) (xy 181.521301 -47.854458)
			(xy 181.529228 -47.85106) (xy 181.556152 -47.838106) (xy 181.563963 -47.833997) (xy 181.576443 -47.82154)
			(xy 181.580536 -47.813722) (xy 181.594441 -47.784873) (xy 181.628447 -47.730604) (xy 181.648354 -47.705518)
			(xy 181.653591 -47.698573) (xy 181.659436 -47.682205) (xy 181.659784 -47.673514) (xy 181.659784 -47.519082)
			(xy 181.659419 -47.510397) (xy 181.653563 -47.494039) (xy 181.648354 -47.487078) (xy 181.627266 -47.460422)
			(xy 181.591586 -47.402572) (xy 181.577234 -47.371762) (xy 181.573299 -47.363861) (xy 181.561088 -47.351132)
			(xy 181.553358 -47.34687) (xy 181.52618 -47.333662) (xy 181.518238 -47.330094) (xy 181.500962 -47.328023)
			(xy 181.492398 -47.329598) (xy 181.471476 -47.334087) (xy 181.428958 -47.338922) (xy 181.407562 -47.33925)
			(xy 181.380316 -47.338677) (xy 181.326378 -47.330917) (xy 181.274094 -47.31556) (xy 181.224527 -47.29292)
			(xy 181.178686 -47.263456) (xy 181.137505 -47.227768) (xy 181.101822 -47.186583) (xy 181.072362 -47.14074)
			(xy 181.049726 -47.091171) (xy 181.034375 -47.038885) (xy 181.02662 -46.984946) (xy 181.02662 -46.930454)
			(xy 181.034375 -46.876515) (xy 181.049726 -46.824229) (xy 181.072362 -46.77466) (xy 181.101822 -46.728817)
			(xy 181.137505 -46.687632) (xy 181.178686 -46.651944) (xy 181.224527 -46.62248) (xy 181.274094 -46.59984)
			(xy 181.326378 -46.584483) (xy 181.380316 -46.576723) (xy 181.407562 -46.576234) (xy 181.434776 -46.576714)
			(xy 181.488652 -46.584445) (xy 181.540882 -46.599755) (xy 181.590406 -46.622334) (xy 181.636218 -46.651722)
			(xy 181.677387 -46.687323) (xy 181.695598 -46.707552) (xy 181.70157 -46.713923) (xy 181.716776 -46.722487)
			(xy 181.725316 -46.724316) (xy 181.75478 -46.729142) (xy 181.763478 -46.730327) (xy 181.780762 -46.72733)
			(xy 181.788562 -46.7233) (xy 181.817552 -46.707299) (xy 181.87879 -46.682106) (xy 181.942779 -46.665071)
			(xy 182.008437 -46.65648) (xy 182.074655 -46.65648) (xy 182.140313 -46.665071) (xy 182.204302 -46.682106)
			(xy 182.26554 -46.707299) (xy 182.29453 -46.7233) (xy 182.302349 -46.727271) (xy 182.319615 -46.730265)
			(xy 182.328312 -46.729142) (xy 182.357776 -46.724316) (xy 182.366318 -46.722501) (xy 182.381511 -46.713914)
			(xy 182.387494 -46.707552) (xy 182.405688 -46.687308) (xy 182.446863 -46.651712) (xy 182.492679 -46.622328)
			(xy 182.542206 -46.599753) (xy 182.594438 -46.584445) (xy 182.648315 -46.576715) (xy 182.67553 -46.576234)
			(xy 182.702783 -46.576638) (xy 182.756733 -46.584399) (xy 182.80903 -46.599758) (xy 182.858609 -46.622404)
			(xy 182.904461 -46.651874) (xy 182.945652 -46.687569) (xy 182.981344 -46.728763) (xy 183.010811 -46.774617)
			(xy 183.022402 -46.8) (xy 190.391097 -46.8) (xy 190.395111 -46.736209) (xy 190.407087 -46.673424)
			(xy 190.426837 -46.612635) (xy 190.45405 -46.5548) (xy 190.488297 -46.500832) (xy 190.529037 -46.451581)
			(xy 190.575628 -46.407825) (xy 190.627336 -46.370252) (xy 190.683345 -46.339456) (xy 190.742771 -46.315922)
			(xy 190.804679 -46.300022) (xy 190.868092 -46.292005) (xy 190.90005 -46.2915) (xy 190.932567 -46.292012)
			(xy 190.997071 -46.300286) (xy 191.059993 -46.316719) (xy 191.120306 -46.341042) (xy 191.177025 -46.372857)
			(xy 191.229224 -46.411646) (xy 191.27605 -46.456775) (xy 191.316738 -46.507507) (xy 191.350625 -46.563013)
			(xy 191.364362 -46.59249) (xy 191.368426 -46.601634) (xy 191.382904 -46.61535) (xy 191.468756 -46.648624)
			(xy 191.488822 -46.647862) (xy 191.497966 -46.643798) (xy 191.530401 -46.630163) (xy 191.598079 -46.610923)
			(xy 191.667764 -46.601214) (xy 191.702944 -46.600618) (xy 191.703198 -46.600618) (xy 191.735162 -46.601047)
			(xy 191.798586 -46.609059) (xy 191.860506 -46.624957) (xy 191.919945 -46.64849) (xy 191.975966 -46.679288)
			(xy 192.027685 -46.716864) (xy 192.074286 -46.760625) (xy 192.115036 -46.809883) (xy 192.14929 -46.863859)
			(xy 192.17651 -46.921703) (xy 192.196264 -46.982502) (xy 192.208243 -47.045298) (xy 192.212258 -47.1091)
			(xy 192.208243 -47.172902) (xy 192.196264 -47.235698) (xy 192.17651 -47.296497) (xy 192.14929 -47.354341)
			(xy 192.115036 -47.408317) (xy 192.074286 -47.457575) (xy 192.027685 -47.501336) (xy 191.975966 -47.538912)
			(xy 191.919945 -47.56971) (xy 191.860506 -47.593243) (xy 191.798586 -47.609141) (xy 191.735162 -47.617153)
			(xy 191.703198 -47.617634) (xy 191.670681 -47.61712) (xy 191.606175 -47.608851) (xy 191.543251 -47.592421)
			(xy 191.482936 -47.5681) (xy 191.426216 -47.536285) (xy 191.374017 -47.497496) (xy 191.327192 -47.452365)
			(xy 191.286505 -47.401631) (xy 191.252621 -47.346122) (xy 191.238886 -47.316644) (xy 191.234822 -47.3075)
			(xy 191.220344 -47.293784) (xy 191.134492 -47.26051) (xy 191.114426 -47.261272) (xy 191.105282 -47.265336)
			(xy 191.072854 -47.278989) (xy 191.005173 -47.298222) (xy 190.935484 -47.307924) (xy 190.900304 -47.308516)
			(xy 190.90005 -47.308516) (xy 190.868092 -47.307995) (xy 190.804679 -47.299978) (xy 190.742771 -47.284078)
			(xy 190.683345 -47.260544) (xy 190.627336 -47.229748) (xy 190.575628 -47.192175) (xy 190.529037 -47.148419)
			(xy 190.488297 -47.099168) (xy 190.45405 -47.0452) (xy 190.426837 -46.987365) (xy 190.407087 -46.926576)
			(xy 190.395111 -46.863791) (xy 190.391097 -46.8) (xy 183.022402 -46.8) (xy 183.033452 -46.824198)
			(xy 183.048808 -46.876496) (xy 183.056564 -46.930447) (xy 183.056564 -46.984953) (xy 183.048808 -47.038904)
			(xy 183.033452 -47.091202) (xy 183.010811 -47.140783) (xy 182.981344 -47.186637) (xy 182.945652 -47.227831)
			(xy 182.904461 -47.263526) (xy 182.858609 -47.292996) (xy 182.80903 -47.315642) (xy 182.756733 -47.331001)
			(xy 182.702783 -47.338762) (xy 182.67553 -47.33925) (xy 182.654133 -47.338938) (xy 182.611613 -47.334103)
			(xy 182.590694 -47.329598) (xy 182.58213 -47.328033) (xy 182.564858 -47.330107) (xy 182.556912 -47.333662)
			(xy 182.529734 -47.34687) (xy 182.52197 -47.351091) (xy 182.509734 -47.363822) (xy 182.505858 -47.371762)
			(xy 182.491545 -47.402592) (xy 182.45586 -47.460446) (xy 182.434738 -47.487078) (xy 182.429502 -47.494023)
			(xy 182.423656 -47.510391) (xy 182.423308 -47.519082) (xy 182.423308 -47.673514) (xy 182.423676 -47.682199)
			(xy 182.42953 -47.698557) (xy 182.434738 -47.705518) (xy 182.454618 -47.730624) (xy 182.488627 -47.784886)
			(xy 182.502556 -47.813722) (xy 182.506624 -47.821558) (xy 182.51911 -47.834024) (xy 182.52694 -47.838106)
			(xy 182.553864 -47.85106) (xy 182.561792 -47.854449) (xy 182.578929 -47.856266) (xy 182.587392 -47.854616)
			(xy 182.609104 -47.84977) (xy 182.653286 -47.844555) (xy 182.67553 -47.844202) (xy 182.702781 -47.84467)
			(xy 182.756726 -47.85243) (xy 182.809019 -47.867788) (xy 182.858594 -47.890432) (xy 182.904442 -47.919899)
			(xy 182.945629 -47.955592) (xy 182.981319 -47.996782) (xy 182.990028 -48.010334) (xy 193.243217 -48.010334)
			(xy 193.243219 -47.955839) (xy 193.250976 -47.901898) (xy 193.266331 -47.849611) (xy 193.28897 -47.80004)
			(xy 193.318434 -47.754197) (xy 193.354122 -47.713012) (xy 193.395307 -47.677326) (xy 193.441152 -47.647864)
			(xy 193.490723 -47.625226) (xy 193.543011 -47.609873) (xy 193.596952 -47.602118) (xy 193.6242 -47.601632)
			(xy 193.624454 -47.601632) (xy 193.642537 -47.601841) (xy 193.67854 -47.605273) (xy 193.696336 -47.60849)
			(xy 193.709036 -47.61103) (xy 193.733674 -47.603156) (xy 193.801746 -47.532544) (xy 193.810006 -47.522933)
			(xy 193.816813 -47.498556) (xy 193.8147 -47.486062) (xy 193.8147 -47.485554) (xy 193.808542 -47.457316)
			(xy 193.801924 -47.399898) (xy 193.801492 -47.371) (xy 193.801994 -47.339039) (xy 193.810005 -47.275621)
			(xy 193.825902 -47.213707) (xy 193.849434 -47.154274) (xy 193.880228 -47.098259) (xy 193.917801 -47.046544)
			(xy 193.961558 -46.999947) (xy 194.010811 -46.959202) (xy 194.064782 -46.924951) (xy 194.122621 -46.897734)
			(xy 194.183414 -46.877981) (xy 194.246204 -46.866003) (xy 194.31 -46.86199) (xy 194.373796 -46.866003)
			(xy 194.436586 -46.877981) (xy 194.497379 -46.897734) (xy 194.555218 -46.924951) (xy 194.609189 -46.959202)
			(xy 194.658442 -46.999947) (xy 194.702199 -47.046544) (xy 194.739772 -47.098259) (xy 194.770566 -47.154274)
			(xy 194.794098 -47.213707) (xy 194.809995 -47.275621) (xy 194.818006 -47.339039) (xy 194.818508 -47.371)
			(xy 194.818042 -47.40274) (xy 194.810155 -47.465728) (xy 194.794491 -47.527245) (xy 194.771293 -47.586335)
			(xy 194.740923 -47.642079) (xy 194.703851 -47.693609) (xy 194.660655 -47.740126) (xy 194.636644 -47.76089)
			(xy 194.625722 -47.770034) (xy 194.616578 -47.796958) (xy 194.639692 -47.899066) (xy 194.642099 -47.90812)
			(xy 194.652495 -47.923692) (xy 194.667799 -47.934477) (xy 194.676776 -47.937166) (xy 194.706267 -47.945166)
			(xy 194.763253 -47.967223) (xy 194.817184 -47.995953) (xy 194.867282 -48.030939) (xy 194.912826 -48.071679)
			(xy 194.953158 -48.117584) (xy 194.987697 -48.167992) (xy 195.015945 -48.222177) (xy 195.037495 -48.279357)
			(xy 195.052035 -48.338707) (xy 195.059356 -48.399373) (xy 195.059808 -48.429926) (xy 195.059306 -48.461887)
			(xy 195.051295 -48.525305) (xy 195.035398 -48.587219) (xy 195.011866 -48.646652) (xy 194.981072 -48.702667)
			(xy 194.943499 -48.754382) (xy 194.899742 -48.800979) (xy 194.850489 -48.841724) (xy 194.796518 -48.875975)
			(xy 194.738679 -48.903192) (xy 194.677886 -48.922945) (xy 194.615096 -48.934923) (xy 194.5513 -48.938937)
			(xy 194.487504 -48.934923) (xy 194.424714 -48.922945) (xy 194.363921 -48.903192) (xy 194.306082 -48.875975)
			(xy 194.252111 -48.841724) (xy 194.202858 -48.800979) (xy 194.159101 -48.754382) (xy 194.121528 -48.702667)
			(xy 194.090734 -48.646652) (xy 194.067202 -48.587219) (xy 194.051305 -48.525305) (xy 194.043294 -48.461887)
			(xy 194.042792 -48.429926) (xy 194.043276 -48.398186) (xy 194.05116 -48.335199) (xy 194.066821 -48.273682)
			(xy 194.090016 -48.214593) (xy 194.120384 -48.158849) (xy 194.157452 -48.107318) (xy 194.200646 -48.0608)
			(xy 194.224656 -48.040036) (xy 194.235578 -48.030892) (xy 194.244722 -48.003968) (xy 194.21856 -47.887636)
			(xy 194.198494 -47.867316) (xy 194.184524 -47.86376) (xy 194.173216 -47.860848) (xy 194.150856 -47.854114)
			(xy 194.13982 -47.850298) (xy 194.127882 -47.84598) (xy 194.102228 -47.84979) (xy 194.01409 -47.917354)
			(xy 194.003676 -47.940976) (xy 194.004692 -47.953676) (xy 194.005708 -47.98314) (xy 194.005179 -48.010388)
			(xy 193.997418 -48.064328) (xy 193.98206 -48.116614) (xy 193.959417 -48.166183) (xy 193.92995 -48.212025)
			(xy 193.894259 -48.253207) (xy 193.853071 -48.28889) (xy 193.807224 -48.318349) (xy 193.757652 -48.340983)
			(xy 193.705363 -48.356332) (xy 193.651421 -48.364084) (xy 193.596926 -48.36408) (xy 193.542985 -48.356321)
			(xy 193.490698 -48.340964) (xy 193.441129 -48.318323) (xy 193.395286 -48.288858) (xy 193.354103 -48.253169)
			(xy 193.318418 -48.211982) (xy 193.288958 -48.166136) (xy 193.266322 -48.116564) (xy 193.250971 -48.064276)
			(xy 193.243217 -48.010334) (xy 182.990028 -48.010334) (xy 183.010783 -48.042633) (xy 183.033422 -48.092209)
			(xy 183.048776 -48.144503) (xy 183.056532 -48.198449) (xy 183.056532 -48.252951) (xy 183.048776 -48.306897)
			(xy 183.033422 -48.359191) (xy 183.010783 -48.408767) (xy 182.981319 -48.454618) (xy 182.945629 -48.495808)
			(xy 182.904442 -48.531501) (xy 182.858594 -48.560968) (xy 182.809019 -48.583612) (xy 182.756726 -48.59897)
			(xy 182.702781 -48.60673) (xy 182.67553 -48.607218) (xy 182.675276 -48.607218) (xy 182.648667 -48.606742)
			(xy 182.595968 -48.599321) (xy 182.544811 -48.584652) (xy 182.496187 -48.563022) (xy 182.451037 -48.534848)
			(xy 182.410238 -48.500678) (xy 182.392066 -48.481234) (xy 182.386023 -48.475023) (xy 182.370839 -48.466702)
			(xy 182.362348 -48.464978) (xy 182.332884 -48.460406) (xy 182.324145 -48.459405) (xy 182.306872 -48.462636)
			(xy 182.299102 -48.466756) (xy 182.269687 -48.483341) (xy 182.207422 -48.509481) (xy 182.142249 -48.527159)
			(xy 182.07531 -48.536066) (xy 182.041546 -48.536606) (xy 182.00778 -48.536067) (xy 181.940834 -48.527189)
			(xy 181.875655 -48.509518) (xy 181.813394 -48.483365) (xy 181.78399 -48.466756) (xy 181.77622 -48.462627)
			(xy 181.758945 -48.459368) (xy 181.750208 -48.460406) (xy 181.720744 -48.464978) (xy 181.712262 -48.466734)
			(xy 181.697073 -48.475033) (xy 181.691026 -48.481234) (xy 181.672864 -48.500691) (xy 181.632079 -48.534888)
			(xy 181.586933 -48.563077) (xy 181.538303 -48.58471) (xy 181.487136 -48.599366) (xy 181.434428 -48.60676)
			(xy 181.407816 -48.607218) (xy 181.407562 -48.607218) (xy 181.380313 -48.606709) (xy 181.326371 -48.598948)
			(xy 181.274082 -48.58359) (xy 181.224511 -48.560948) (xy 181.178667 -48.531481) (xy 181.137482 -48.495791)
			(xy 181.101796 -48.454603) (xy 181.072334 -48.408755) (xy 181.049696 -48.359182) (xy 181.034343 -48.306892)
			(xy 181.026588 -48.252949) (xy 179.365845 -48.252949) (xy 179.371761 -48.258191) (xy 179.412519 -48.304204)
			(xy 179.447434 -48.354795) (xy 179.475996 -48.409225) (xy 179.497788 -48.466701) (xy 179.512494 -48.526384)
			(xy 179.519899 -48.587406) (xy 179.520342 -48.61814) (xy 179.519774 -48.653096) (xy 179.510207 -48.722349)
			(xy 179.491247 -48.78964) (xy 179.463249 -48.8537) (xy 179.426742 -48.913322) (xy 179.405026 -48.94072)
			(xy 179.399771 -48.947653) (xy 179.393937 -48.96403) (xy 179.393596 -48.972724) (xy 179.393596 -49.127156)
			(xy 179.393993 -49.135838) (xy 179.399828 -49.152196) (xy 179.405026 -49.15916) (xy 179.426724 -49.18657)
			(xy 179.463223 -49.246193) (xy 179.491219 -49.310251) (xy 179.510183 -49.377537) (xy 179.519759 -49.446786)
			(xy 179.520342 -49.48174) (xy 179.519882 -49.512471) (xy 179.51247 -49.573483) (xy 179.497758 -49.633158)
			(xy 179.475961 -49.690624) (xy 179.447396 -49.745044) (xy 179.412481 -49.795625) (xy 179.371724 -49.841629)
			(xy 179.32572 -49.882385) (xy 179.275139 -49.917299) (xy 179.220718 -49.945863) (xy 179.163252 -49.967659)
			(xy 179.103577 -49.982371) (xy 179.042565 -49.989782) (xy 179.011834 -49.990248) (xy 178.980179 -49.989759)
			(xy 178.917359 -49.981903) (xy 178.856001 -49.966309) (xy 178.797053 -49.943217) (xy 178.76901 -49.928526)
			(xy 178.759866 -49.923446) (xy 178.7398 -49.921668) (xy 178.650138 -49.949608) (xy 178.634898 -49.962562)
			(xy 178.630072 -49.97196) (xy 178.617815 -49.995254) (xy 178.587843 -50.038526) (xy 178.552211 -50.077269)
			(xy 178.511592 -50.110749) (xy 178.466759 -50.138329) (xy 178.418562 -50.159488) (xy 178.367914 -50.173824)
			(xy 178.315777 -50.181065) (xy 178.289458 -50.18151) (xy 178.262209 -50.181017) (xy 178.208266 -50.173256)
			(xy 178.155977 -50.157897) (xy 178.106405 -50.135254) (xy 178.06056 -50.105787) (xy 178.019375 -50.070095)
			(xy 177.983688 -50.028906) (xy 177.954226 -49.983058) (xy 177.931588 -49.933484) (xy 177.916235 -49.881193)
			(xy 177.90848 -49.827249) (xy 177.90848 -49.772751) (xy 177.916235 -49.718807) (xy 177.931588 -49.666516)
			(xy 177.954226 -49.616942) (xy 177.983688 -49.571094) (xy 178.019375 -49.529905) (xy 178.06056 -49.494213)
			(xy 178.106405 -49.464746) (xy 178.155977 -49.442103) (xy 178.208266 -49.426744) (xy 178.262209 -49.418983)
			(xy 178.289458 -49.418494) (xy 178.31551 -49.418972) (xy 178.367125 -49.426106) (xy 178.392328 -49.432718)
			(xy 178.402196 -49.43487) (xy 178.422203 -49.432248) (xy 178.43119 -49.427638) (xy 178.50358 -49.385728)
			(xy 178.515772 -49.369218) (xy 178.518312 -49.359312) (xy 178.525485 -49.332011) (xy 178.545029 -49.279053)
			(xy 178.57032 -49.228586) (xy 178.601047 -49.181232) (xy 178.618642 -49.15916) (xy 178.62386 -49.152203)
			(xy 178.629717 -49.135844) (xy 178.630072 -49.127156) (xy 178.630072 -48.972724) (xy 178.62969 -48.96404)
			(xy 178.623846 -48.947682) (xy 178.618642 -48.94072) (xy 178.601037 -48.918655) (xy 178.570308 -48.8713)
			(xy 178.545014 -48.820833) (xy 178.525465 -48.767875) (xy 178.518312 -48.740568) (xy 178.515772 -48.730662)
			(xy 178.50358 -48.714152) (xy 178.4223 -48.667162) (xy 178.402488 -48.664368) (xy 178.392582 -48.667162)
			(xy 178.392074 -48.667162) (xy 178.366939 -48.673791) (xy 178.315449 -48.680931) (xy 178.289458 -48.681386)
			(xy 178.262207 -48.680941) (xy 178.208261 -48.673179) (xy 178.155968 -48.65782) (xy 178.106393 -48.635175)
			(xy 178.060546 -48.605706) (xy 178.019358 -48.570012) (xy 177.983669 -48.528821) (xy 177.954205 -48.48297)
			(xy 177.931565 -48.433392) (xy 177.916212 -48.381098) (xy 177.908456 -48.327151) (xy 152.780459 -48.327151)
			(xy 152.765369 -48.341321) (xy 152.713652 -48.378895) (xy 152.657633 -48.409691) (xy 152.598196 -48.433223)
			(xy 152.536279 -48.44912) (xy 152.472857 -48.457131) (xy 152.440894 -48.457612) (xy 152.408188 -48.457097)
			(xy 152.343314 -48.448719) (xy 152.280051 -48.43209) (xy 152.219443 -48.407484) (xy 152.162492 -48.375308)
			(xy 152.110138 -48.336092) (xy 152.063246 -48.290486) (xy 152.022591 -48.239242) (xy 152.005284 -48.211486)
			(xy 151.998488 -48.201425) (xy 151.977933 -48.188568) (xy 151.965914 -48.186848) (xy 151.883872 -48.17999)
			(xy 151.871851 -48.179607) (xy 151.849589 -48.18864) (xy 151.8412 -48.197262) (xy 151.8412 -48.197516)
			(xy 151.82298 -48.217958) (xy 151.781726 -48.253964) (xy 151.735745 -48.2837) (xy 151.685985 -48.306553)
			(xy 151.633467 -48.322055) (xy 151.579273 -48.329886) (xy 151.551894 -48.330358) (xy 151.521201 -48.329749)
			(xy 151.460605 -48.319925) (xy 151.402363 -48.300531) (xy 151.347974 -48.272068) (xy 151.32304 -48.254158)
			(xy 151.315166 -48.248316) (xy 151.29637 -48.243236) (xy 151.206962 -48.253904) (xy 151.18969 -48.263556)
			(xy 151.183594 -48.271176) (xy 151.162843 -48.295736) (xy 151.116181 -48.339974) (xy 151.064312 -48.377972)
			(xy 151.008064 -48.409124) (xy 150.948337 -48.432933) (xy 150.886083 -48.449018) (xy 150.822297 -48.457121)
			(xy 150.790148 -48.457612) (xy 150.789894 -48.457612) (xy 150.756688 -48.457018) (xy 150.690843 -48.448343)
			(xy 150.626686 -48.431182) (xy 150.565304 -48.405824) (xy 150.50774 -48.372701) (xy 150.48103 -48.352964)
			(xy 150.469346 -48.344074) (xy 150.441152 -48.34128) (xy 150.332948 -48.393858) (xy 150.317708 -48.417988)
			(xy 150.317708 -48.432466) (xy 150.316902 -48.459491) (xy 150.308588 -48.512914) (xy 150.292815 -48.564629)
			(xy 150.2699 -48.613599) (xy 150.240301 -48.658844) (xy 150.204612 -48.699457) (xy 150.163547 -48.734626)
			(xy 150.117928 -48.763645) (xy 150.06867 -48.785934) (xy 150.016758 -48.801045) (xy 149.963233 -48.808678)
			(xy 149.9362 -48.809148) (xy 149.908952 -48.808582) (xy 149.85501 -48.800826) (xy 149.80272 -48.785473)
			(xy 149.753148 -48.762834) (xy 149.707303 -48.733371) (xy 149.666117 -48.697683) (xy 149.630429 -48.656497)
			(xy 149.600966 -48.610652) (xy 149.578327 -48.56108) (xy 149.562974 -48.50879) (xy 149.555218 -48.454848)
			(xy 146.607503 -48.454848) (xy 146.587722 -48.490831) (xy 146.550149 -48.542546) (xy 146.506392 -48.589143)
			(xy 146.457139 -48.629888) (xy 146.403168 -48.664139) (xy 146.345329 -48.691356) (xy 146.284536 -48.711109)
			(xy 146.221746 -48.723087) (xy 146.15795 -48.727101) (xy 146.094154 -48.723087) (xy 146.031364 -48.711109)
			(xy 145.970571 -48.691356) (xy 145.912732 -48.664139) (xy 145.858761 -48.629888) (xy 145.809508 -48.589143)
			(xy 145.765751 -48.542546) (xy 145.728178 -48.490831) (xy 145.697384 -48.434816) (xy 145.673852 -48.375383)
			(xy 145.657955 -48.313469) (xy 145.649944 -48.250051) (xy 141.268357 -48.250051) (xy 141.27379 -48.293063)
			(xy 141.274292 -48.325024) (xy 141.273847 -48.355399) (xy 141.266611 -48.415715) (xy 141.252243 -48.474741)
			(xy 141.230949 -48.531636) (xy 141.203031 -48.58559) (xy 141.168888 -48.635837) (xy 141.129004 -48.68166)
			(xy 141.083947 -48.722407) (xy 141.059408 -48.740314) (xy 141.051576 -48.746353) (xy 141.040856 -48.762948)
			(xy 141.03858 -48.772572) (xy 141.025626 -48.84166) (xy 141.02423 -48.85144) (xy 141.028158 -48.870783)
			(xy 141.033246 -48.879252) (xy 141.049254 -48.904247) (xy 141.075943 -48.957265) (xy 141.096284 -49.013029)
			(xy 141.109999 -49.07078) (xy 141.116903 -49.129735) (xy 141.11732 -49.159414) (xy 141.116818 -49.191375)
			(xy 141.108807 -49.254793) (xy 141.09291 -49.316707) (xy 141.069378 -49.37614) (xy 141.038584 -49.432155)
			(xy 141.001011 -49.48387) (xy 140.957254 -49.530467) (xy 140.908001 -49.571212) (xy 140.85403 -49.605463)
			(xy 140.796191 -49.63268) (xy 140.735398 -49.652433) (xy 140.672608 -49.664411) (xy 140.608812 -49.668425)
			(xy 140.545016 -49.664411) (xy 140.482226 -49.652433) (xy 140.421433 -49.63268) (xy 140.363594 -49.605463)
			(xy 140.309623 -49.571212) (xy 140.26037 -49.530467) (xy 140.216613 -49.48387) (xy 140.17904 -49.432155)
			(xy 140.148246 -49.37614) (xy 140.124714 -49.316707) (xy 140.108817 -49.254793) (xy 140.100806 -49.191375)
			(xy 140.100304 -49.159414) (xy 132.029546 -49.159414) (xy 132.022293 -49.169076) (xy 132.012099 -49.196238)
			(xy 132.009949 -49.225171) (xy 132.016017 -49.253541) (xy 132.029813 -49.279063) (xy 132.050226 -49.299679)
			(xy 132.07561 -49.313728) (xy 132.089652 -49.317402) (xy 132.120019 -49.324718) (xy 132.178843 -49.345727)
			(xy 132.234651 -49.373782) (xy 132.286604 -49.408459) (xy 132.33392 -49.449237) (xy 132.375886 -49.495502)
			(xy 132.411872 -49.546558) (xy 132.437797 -49.595024) (xy 138.605766 -49.595024) (xy 138.609837 -49.539402)
			(xy 138.621963 -49.484965) (xy 138.641886 -49.432874) (xy 138.669182 -49.384239) (xy 138.703268 -49.340096)
			(xy 138.743417 -49.301387) (xy 138.788775 -49.268936) (xy 138.838375 -49.243435) (xy 138.891159 -49.225428)
			(xy 138.946002 -49.215298) (xy 139.001736 -49.213261) (xy 139.057173 -49.219361) (xy 139.11113 -49.233467)
			(xy 139.162459 -49.255279) (xy 139.210065 -49.284333) (xy 139.252933 -49.320008) (xy 139.29015 -49.361545)
			(xy 139.320923 -49.408058) (xy 139.344595 -49.458555) (xy 139.360663 -49.511962) (xy 139.368783 -49.567138)
			(xy 139.369292 -49.595024) (xy 139.368783 -49.62291) (xy 139.360663 -49.678086) (xy 139.344595 -49.731493)
			(xy 139.320923 -49.78199) (xy 139.29015 -49.828503) (xy 139.252933 -49.87004) (xy 139.210065 -49.905715)
			(xy 139.162459 -49.934769) (xy 139.11113 -49.956581) (xy 139.057173 -49.970687) (xy 139.001736 -49.976787)
			(xy 138.946002 -49.97475) (xy 138.891159 -49.96462) (xy 138.838375 -49.946613) (xy 138.788775 -49.921112)
			(xy 138.743417 -49.888661) (xy 138.703268 -49.849952) (xy 138.669182 -49.805809) (xy 138.641886 -49.757174)
			(xy 138.621963 -49.705083) (xy 138.609837 -49.650646) (xy 138.605766 -49.595024) (xy 132.437797 -49.595024)
			(xy 132.441334 -49.601636) (xy 132.463831 -49.659907) (xy 132.479023 -49.720495) (xy 132.486682 -49.782487)
			(xy 132.487162 -49.813718) (xy 132.48666 -49.845679) (xy 132.478649 -49.909097) (xy 132.462752 -49.971011)
			(xy 132.43922 -50.030444) (xy 132.408426 -50.086459) (xy 132.370853 -50.138174) (xy 132.327096 -50.184771)
			(xy 132.277843 -50.225516) (xy 132.223872 -50.259767) (xy 132.166033 -50.286984) (xy 132.10524 -50.306737)
			(xy 132.04245 -50.318715) (xy 131.978654 -50.322729) (xy 131.914858 -50.318715) (xy 131.852068 -50.306737)
			(xy 131.791275 -50.286984) (xy 131.733436 -50.259767) (xy 131.679465 -50.225516) (xy 131.630212 -50.184771)
			(xy 131.586455 -50.138174) (xy 131.548882 -50.086459) (xy 131.518088 -50.030444) (xy 131.494556 -49.971011)
			(xy 131.478659 -49.909097) (xy 131.470648 -49.845679) (xy 131.470146 -49.813718) (xy 131.470674 -49.779887)
			(xy 131.479667 -49.712826) (xy 131.497472 -49.647549) (xy 131.523773 -49.585209) (xy 131.558106 -49.526905)
			(xy 131.599866 -49.473667) (xy 131.648314 -49.426436) (xy 131.675124 -49.405794) (xy 131.686467 -49.396737)
			(xy 131.703891 -49.373534) (xy 131.71409 -49.346368) (xy 131.716242 -49.317432) (xy 131.710173 -49.289057)
			(xy 131.696372 -49.263532) (xy 131.675953 -49.242916) (xy 131.650562 -49.228871) (xy 131.636516 -49.2252)
			(xy 131.606144 -49.217905) (xy 131.547321 -49.196892) (xy 131.491513 -49.168834) (xy 131.43956 -49.134154)
			(xy 131.392245 -49.093373) (xy 131.35028 -49.047106) (xy 131.314295 -48.996049) (xy 131.284833 -48.94097)
			(xy 131.262337 -48.882697) (xy 131.247145 -48.822109) (xy 131.239486 -48.760116) (xy 131.239006 -48.728884)
			(xy 122.479155 -48.728884) (xy 122.479308 -48.741838) (xy 122.479308 -48.7426) (xy 122.478832 -48.774141)
			(xy 122.47103 -48.836739) (xy 122.455544 -48.89789) (xy 122.432613 -48.956657) (xy 122.402589 -49.012136)
			(xy 122.365934 -49.063475) (xy 122.323209 -49.109886) (xy 122.275072 -49.150656) (xy 122.222262 -49.185159)
			(xy 122.16559 -49.212864) (xy 122.105926 -49.233347) (xy 122.044186 -49.246293) (xy 121.98132 -49.251502)
			(xy 121.918291 -49.248895) (xy 121.85607 -49.238512) (xy 121.79561 -49.220512) (xy 121.737841 -49.195173)
			(xy 121.68365 -49.162882) (xy 121.63387 -49.124136) (xy 121.589264 -49.07953) (xy 121.550518 -49.02975)
			(xy 121.518227 -48.975559) (xy 121.492888 -48.91779) (xy 121.474888 -48.85733) (xy 121.464505 -48.795109)
			(xy 121.461898 -48.73208) (xy 103.221945 -48.73208) (xy 103.171673 -48.815954) (xy 103.081659 -48.950669)
			(xy 102.985144 -49.080805) (xy 102.88236 -49.206048) (xy 102.773554 -49.326097) (xy 102.658988 -49.440662)
			(xy 102.538939 -49.549468) (xy 102.413696 -49.652253) (xy 102.283561 -49.748768) (xy 102.148846 -49.838782)
			(xy 102.009877 -49.922076) (xy 101.866988 -49.998452) (xy 101.720524 -50.067725) (xy 101.570837 -50.129727)
			(xy 101.418288 -50.18431) (xy 101.263244 -50.231342) (xy 101.10608 -50.27071) (xy 100.947173 -50.302319)
			(xy 100.786907 -50.326092) (xy 100.625667 -50.341973) (xy 100.463842 -50.349923) (xy 100.382832 -50.35042)
			(xy 100.300794 -50.34996) (xy 100.13692 -50.341813) (xy 99.973653 -50.325533) (xy 99.811397 -50.301161)
			(xy 99.650553 -50.268756) (xy 99.491517 -50.228398) (xy 99.334683 -50.180187) (xy 99.180439 -50.124243)
			(xy 99.029166 -50.060703) (xy 98.881236 -49.989724) (xy 98.737017 -49.911483) (xy 98.596863 -49.826171)
			(xy 98.461122 -49.734001) (xy 98.330129 -49.635199) (xy 98.204207 -49.53001) (xy 98.083668 -49.418693)
			(xy 97.968809 -49.301525) (xy 97.859914 -49.178793) (xy 97.757253 -49.050802) (xy 97.661078 -48.917868)
			(xy 97.571628 -48.780319) (xy 97.489124 -48.638495) (xy 97.413768 -48.492746) (xy 97.345749 -48.343433)
			(xy 97.31502 -48.267366) (xy 97.310956 -48.258211) (xy 97.297113 -48.243762) (xy 97.278787 -48.235727)
			(xy 97.268792 -48.235108) (xy 97.159572 -48.233076) (xy 97.133918 -48.249586) (xy 97.127568 -48.263556)
			(xy 97.095239 -48.335351) (xy 97.024078 -48.475829) (xy 96.945648 -48.612382) (xy 96.860164 -48.744633)
			(xy 96.767862 -48.872219) (xy 96.668995 -48.994788) (xy 96.563836 -49.112004) (xy 96.452674 -49.223542)
			(xy 96.335815 -49.329098) (xy 96.213581 -49.428379) (xy 96.086308 -49.521113) (xy 95.954347 -49.607044)
			(xy 95.818061 -49.685936) (xy 95.677825 -49.757572) (xy 95.534025 -49.821754) (xy 95.387056 -49.878306)
			(xy 95.237324 -49.927072) (xy 95.08524 -49.967918) (xy 94.931223 -50.000732) (xy 94.775698 -50.025423)
			(xy 94.619091 -50.041923) (xy 94.461835 -50.050188) (xy 94.383098 -50.0507) (xy 92.782898 -50.0507)
			(xy 92.705622 -50.050194) (xy 92.551275 -50.042238) (xy 92.397543 -50.026347) (xy 92.244832 -50.002563)
			(xy 92.093548 -49.970949) (xy 91.944092 -49.931589) (xy 91.796861 -49.884587) (xy 91.652244 -49.830069)
			(xy 91.510626 -49.768178) (xy 91.372381 -49.699079) (xy 91.237877 -49.622954) (xy 91.10747 -49.540007)
			(xy 90.981506 -49.450456) (xy 90.860319 -49.35454) (xy 90.74423 -49.252512) (xy 90.633548 -49.144644)
			(xy 90.528565 -49.031221) (xy 90.42956 -48.912543) (xy 90.336796 -48.788927) (xy 90.250519 -48.660699)
			(xy 90.170957 -48.528199) (xy 90.098321 -48.391779) (xy 90.032804 -48.251802) (xy 89.97458 -48.108637)
			(xy 89.923803 -47.962664) (xy 89.880608 -47.814271) (xy 89.84511 -47.663852) (xy 89.817402 -47.511804)
			(xy 89.797557 -47.358531) (xy 89.78563 -47.204441) (xy 89.78165 -47.04994) (xy 73.85812 -47.04994)
			(xy 73.85812 -48.867017) (xy 85.40597 -48.867017) (xy 85.40597 -48.803095) (xy 85.413981 -48.739677)
			(xy 85.429878 -48.677763) (xy 85.45341 -48.61833) (xy 85.484204 -48.562315) (xy 85.521777 -48.5106)
			(xy 85.565534 -48.464003) (xy 85.614787 -48.423258) (xy 85.668758 -48.389007) (xy 85.726597 -48.36179)
			(xy 85.78739 -48.342037) (xy 85.85018 -48.330059) (xy 85.913976 -48.326046) (xy 85.977772 -48.330059)
			(xy 86.040562 -48.342037) (xy 86.101355 -48.36179) (xy 86.159194 -48.389007) (xy 86.213165 -48.423258)
			(xy 86.262418 -48.464003) (xy 86.306175 -48.5106) (xy 86.343748 -48.562315) (xy 86.374542 -48.61833)
			(xy 86.398074 -48.677763) (xy 86.413971 -48.739677) (xy 86.421982 -48.803095) (xy 86.422484 -48.835056)
			(xy 86.421982 -48.867017) (xy 86.413971 -48.930435) (xy 86.398074 -48.992349) (xy 86.374542 -49.051782)
			(xy 86.343748 -49.107797) (xy 86.306175 -49.159512) (xy 86.262418 -49.206109) (xy 86.213165 -49.246854)
			(xy 86.159194 -49.281105) (xy 86.101355 -49.308322) (xy 86.040562 -49.328075) (xy 85.977772 -49.340053)
			(xy 85.913976 -49.344067) (xy 85.85018 -49.340053) (xy 85.78739 -49.328075) (xy 85.726597 -49.308322)
			(xy 85.668758 -49.281105) (xy 85.614787 -49.246854) (xy 85.565534 -49.206109) (xy 85.521777 -49.159512)
			(xy 85.484204 -49.107797) (xy 85.45341 -49.051782) (xy 85.429878 -48.992349) (xy 85.413981 -48.930435)
			(xy 85.40597 -48.867017) (xy 73.85812 -48.867017) (xy 73.85812 -50.653907) (xy 87.11793 -50.653907)
			(xy 87.11793 -50.589985) (xy 87.125941 -50.526567) (xy 87.141838 -50.464653) (xy 87.16537 -50.40522)
			(xy 87.196164 -50.349205) (xy 87.233737 -50.29749) (xy 87.277494 -50.250893) (xy 87.326747 -50.210148)
			(xy 87.380718 -50.175897) (xy 87.438557 -50.14868) (xy 87.49935 -50.128927) (xy 87.56214 -50.116949)
			(xy 87.625936 -50.112936) (xy 87.689732 -50.116949) (xy 87.752522 -50.128927) (xy 87.813315 -50.14868)
			(xy 87.871154 -50.175897) (xy 87.925125 -50.210148) (xy 87.974378 -50.250893) (xy 88.018135 -50.29749)
			(xy 88.055708 -50.349205) (xy 88.086502 -50.40522) (xy 88.110034 -50.464653) (xy 88.125931 -50.526567)
			(xy 88.133942 -50.589985) (xy 88.134444 -50.621946) (xy 88.133942 -50.653907) (xy 88.125931 -50.717325)
			(xy 88.110034 -50.779239) (xy 88.086502 -50.838672) (xy 88.055708 -50.894687) (xy 88.018135 -50.946402)
			(xy 87.974378 -50.992999) (xy 87.962047 -51.0032) (xy 123.214892 -51.0032) (xy 123.215469 -50.9741)
			(xy 123.224303 -50.916575) (xy 123.241765 -50.861057) (xy 123.267451 -50.808833) (xy 123.300766 -50.761112)
			(xy 123.340938 -50.719) (xy 123.387036 -50.683474) (xy 123.41225 -50.668936) (xy 123.425275 -50.661193)
			(xy 123.446361 -50.639448) (xy 123.460143 -50.612476) (xy 123.465409 -50.582648) (xy 123.461696 -50.552587)
			(xy 123.449331 -50.524937) (xy 123.429401 -50.502129) (xy 123.416822 -50.493676) (xy 123.393456 -50.478705)
			(xy 123.350959 -50.44302) (xy 123.31408 -50.401554) (xy 123.283599 -50.355182) (xy 123.260158 -50.304883)
			(xy 123.244252 -50.251719) (xy 123.236216 -50.196811) (xy 123.23572 -50.169064) (xy 123.236206 -50.141813)
			(xy 123.243962 -50.087865) (xy 123.259317 -50.03557) (xy 123.281959 -49.985993) (xy 123.311425 -49.940143)
			(xy 123.347116 -49.898952) (xy 123.388307 -49.863261) (xy 123.434157 -49.833795) (xy 123.483734 -49.811153)
			(xy 123.536029 -49.795798) (xy 123.589977 -49.788042) (xy 123.644479 -49.788042) (xy 123.698427 -49.795798)
			(xy 123.750722 -49.811153) (xy 123.800299 -49.833795) (xy 123.846149 -49.863261) (xy 123.88734 -49.898952)
			(xy 123.923031 -49.940143) (xy 123.952497 -49.985993) (xy 123.975139 -50.03557) (xy 123.990494 -50.087865)
			(xy 123.99825 -50.141813) (xy 123.998736 -50.169064) (xy 125.40691 -50.169064) (xy 125.410981 -50.113442)
			(xy 125.423107 -50.059005) (xy 125.44303 -50.006914) (xy 125.470326 -49.958279) (xy 125.504412 -49.914136)
			(xy 125.544561 -49.875427) (xy 125.589919 -49.842976) (xy 125.639519 -49.817475) (xy 125.692303 -49.799468)
			(xy 125.747146 -49.789338) (xy 125.80288 -49.787301) (xy 125.858317 -49.793401) (xy 125.912274 -49.807507)
			(xy 125.963603 -49.829319) (xy 126.011209 -49.858373) (xy 126.054077 -49.894048) (xy 126.091294 -49.935585)
			(xy 126.122067 -49.982098) (xy 126.145739 -50.032595) (xy 126.146262 -50.034334) (xy 127.841089 -50.034334)
			(xy 127.843694 -49.971305) (xy 127.854075 -49.909082) (xy 127.872073 -49.848621) (xy 127.897411 -49.790851)
			(xy 127.929701 -49.736658) (xy 127.968445 -49.686876) (xy 128.01305 -49.642268) (xy 128.06283 -49.60352)
			(xy 128.117021 -49.571227) (xy 128.17479 -49.545885) (xy 128.235249 -49.527883) (xy 128.297472 -49.517497)
			(xy 128.3605 -49.514888) (xy 128.423368 -49.520095) (xy 128.485109 -49.533038) (xy 128.544775 -49.553519)
			(xy 128.601449 -49.581222) (xy 128.654261 -49.615723) (xy 128.702401 -49.656491) (xy 128.745128 -49.702901)
			(xy 128.781786 -49.75424) (xy 128.811812 -49.809718) (xy 128.834746 -49.868484) (xy 128.850235 -49.929636)
			(xy 128.858041 -49.992235) (xy 128.858518 -50.023776) (xy 128.858479 -50.035412) (xy 128.857462 -50.058663)
			(xy 128.856486 -50.070258) (xy 128.855216 -50.082196) (xy 128.86436 -50.105056) (xy 128.944624 -50.175414)
			(xy 128.967992 -50.18151) (xy 128.979676 -50.178716) (xy 128.97993 -50.178716) (xy 129.007683 -50.172794)
			(xy 129.064077 -50.166434) (xy 129.092452 -50.166016) (xy 129.126148 -50.166534) (xy 129.19295 -50.175423)
			(xy 129.25799 -50.193065) (xy 129.320128 -50.21915) (xy 129.378272 -50.25322) (xy 129.431402 -50.294677)
			(xy 129.478586 -50.342794) (xy 129.518995 -50.396726) (xy 129.535936 -50.425858) (xy 129.542581 -50.436084)
			(xy 129.563007 -50.449344) (xy 129.575052 -50.451258) (xy 129.670302 -50.461164) (xy 129.692908 -50.45202)
			(xy 129.70129 -50.442622) (xy 129.7195 -50.422309) (xy 129.760715 -50.38657) (xy 129.8066 -50.357065)
			(xy 129.856219 -50.334395) (xy 129.90856 -50.319021) (xy 129.962558 -50.311258) (xy 129.989834 -50.310796)
			(xy 130.017084 -50.311276) (xy 130.071029 -50.319037) (xy 130.12332 -50.334395) (xy 130.172893 -50.357038)
			(xy 130.21874 -50.386506) (xy 130.259926 -50.422198) (xy 130.295615 -50.463387) (xy 130.325078 -50.509237)
			(xy 130.347717 -50.558812) (xy 130.363071 -50.611105) (xy 130.370826 -50.66505) (xy 130.370826 -50.71955)
			(xy 130.363071 -50.773495) (xy 130.347717 -50.825788) (xy 130.325078 -50.875363) (xy 130.295615 -50.921213)
			(xy 130.274132 -50.946007) (xy 130.88975 -50.946007) (xy 130.88975 -50.882085) (xy 130.897761 -50.818667)
			(xy 130.913658 -50.756753) (xy 130.93719 -50.69732) (xy 130.967984 -50.641305) (xy 131.005557 -50.58959)
			(xy 131.049314 -50.542993) (xy 131.098567 -50.502248) (xy 131.152538 -50.467997) (xy 131.210377 -50.44078)
			(xy 131.27117 -50.421027) (xy 131.33396 -50.409049) (xy 131.397756 -50.405036) (xy 131.461552 -50.409049)
			(xy 131.524342 -50.421027) (xy 131.585135 -50.44078) (xy 131.642974 -50.467997) (xy 131.696945 -50.502248)
			(xy 131.746198 -50.542993) (xy 131.789955 -50.58959) (xy 131.827528 -50.641305) (xy 131.858322 -50.69732)
			(xy 131.881854 -50.756753) (xy 131.897751 -50.818667) (xy 131.905147 -50.877216) (xy 139.331954 -50.877216)
			(xy 139.332446 -50.846151) (xy 139.340008 -50.784483) (xy 139.355032 -50.724198) (xy 139.377295 -50.666194)
			(xy 139.406464 -50.611337) (xy 139.423902 -50.585624) (xy 139.429458 -50.576804) (xy 139.433675 -50.556412)
			(xy 139.429468 -50.536017) (xy 139.423902 -50.527204) (xy 139.406455 -50.501496) (xy 139.377288 -50.446636)
			(xy 139.355024 -50.388631) (xy 139.339993 -50.328346) (xy 139.332421 -50.266678) (xy 139.331954 -50.235612)
			(xy 139.332456 -50.203651) (xy 139.340467 -50.140233) (xy 139.356364 -50.078319) (xy 139.379896 -50.018886)
			(xy 139.41069 -49.962871) (xy 139.448263 -49.911156) (xy 139.49202 -49.864559) (xy 139.541273 -49.823814)
			(xy 139.595244 -49.789563) (xy 139.653083 -49.762346) (xy 139.713876 -49.742593) (xy 139.776666 -49.730615)
			(xy 139.840462 -49.726602) (xy 139.904258 -49.730615) (xy 139.967048 -49.742593) (xy 140.027841 -49.762346)
			(xy 140.08568 -49.789563) (xy 140.139651 -49.823814) (xy 140.188904 -49.864559) (xy 140.232661 -49.911156)
			(xy 140.270234 -49.962871) (xy 140.301028 -50.018886) (xy 140.32456 -50.078319) (xy 140.340457 -50.140233)
			(xy 140.348468 -50.203651) (xy 140.34897 -50.235612) (xy 140.348505 -50.266678) (xy 140.340939 -50.328347)
			(xy 140.325909 -50.388633) (xy 140.30364 -50.446637) (xy 140.274463 -50.501492) (xy 140.257022 -50.527204)
			(xy 140.251439 -50.53601) (xy 140.247229 -50.556412) (xy 140.251449 -50.576811) (xy 140.257022 -50.585624)
			(xy 140.274472 -50.61133) (xy 140.30364 -50.66619) (xy 140.325905 -50.724195) (xy 140.340935 -50.784481)
			(xy 140.348505 -50.84615) (xy 140.34897 -50.877216) (xy 143.027654 -50.877216) (xy 143.028133 -50.849506)
			(xy 143.036167 -50.794671) (xy 143.052053 -50.741577) (xy 143.075457 -50.691341) (xy 143.105885 -50.645022)
			(xy 143.12392 -50.623978) (xy 143.129711 -50.616829) (xy 143.136228 -50.599641) (xy 143.13662 -50.59045)
			(xy 143.13662 -50.51298) (xy 143.13027 -50.495962) (xy 143.12392 -50.48885) (xy 143.105901 -50.467793)
			(xy 143.075468 -50.42148) (xy 143.052063 -50.371247) (xy 143.036179 -50.318154) (xy 143.028152 -50.263321)
			(xy 143.027654 -50.235612) (xy 143.02814 -50.208361) (xy 143.035896 -50.154413) (xy 143.051251 -50.102118)
			(xy 143.073893 -50.052541) (xy 143.103359 -50.006691) (xy 143.13905 -49.9655) (xy 143.180241 -49.929809)
			(xy 143.226091 -49.900343) (xy 143.275668 -49.877701) (xy 143.327963 -49.862346) (xy 143.381911 -49.85459)
			(xy 143.436413 -49.85459) (xy 143.490361 -49.862346) (xy 143.542656 -49.877701) (xy 143.592233 -49.900343)
			(xy 143.638083 -49.929809) (xy 143.679274 -49.9655) (xy 143.714965 -50.006691) (xy 143.744431 -50.052541)
			(xy 143.767073 -50.102118) (xy 143.782428 -50.154413) (xy 143.783256 -50.160174) (xy 147.32 -50.160174)
			(xy 147.320561 -50.126113) (xy 147.329636 -50.058599) (xy 147.347648 -49.992902) (xy 147.374274 -49.9302)
			(xy 147.409036 -49.871615) (xy 147.451312 -49.818199) (xy 147.475448 -49.79416) (xy 147.482814 -49.787048)
			(xy 147.490434 -49.769522) (xy 147.493736 -49.679098) (xy 147.487132 -49.660556) (xy 147.480528 -49.65319)
			(xy 147.460234 -49.629829) (xy 147.424877 -49.579041) (xy 147.395943 -49.524338) (xy 147.37386 -49.466529)
			(xy 147.358954 -49.406468) (xy 147.351446 -49.345042) (xy 147.350988 -49.3141) (xy 147.35149 -49.282139)
			(xy 147.359501 -49.218721) (xy 147.375398 -49.156807) (xy 147.39893 -49.097374) (xy 147.429724 -49.041359)
			(xy 147.467297 -48.989644) (xy 147.511054 -48.943047) (xy 147.560307 -48.902302) (xy 147.614278 -48.868051)
			(xy 147.672117 -48.840834) (xy 147.73291 -48.821081) (xy 147.7957 -48.809103) (xy 147.859496 -48.80509)
			(xy 147.923292 -48.809103) (xy 147.986082 -48.821081) (xy 148.046875 -48.840834) (xy 148.104714 -48.868051)
			(xy 148.158685 -48.902302) (xy 148.207938 -48.943047) (xy 148.251695 -48.989644) (xy 148.289268 -49.041359)
			(xy 148.304573 -49.0692) (xy 151.203412 -49.0692) (xy 151.207426 -49.005405) (xy 151.219404 -48.942617)
			(xy 151.239157 -48.881824) (xy 151.266374 -48.823987) (xy 151.300626 -48.770018) (xy 151.341371 -48.720766)
			(xy 151.387969 -48.677011) (xy 151.439683 -48.63944) (xy 151.495698 -48.608648) (xy 151.555131 -48.585119)
			(xy 151.617044 -48.569224) (xy 151.680462 -48.561216) (xy 151.712422 -48.560736) (xy 151.745118 -48.561228)
			(xy 151.809973 -48.569598) (xy 151.87322 -48.586211) (xy 151.933817 -48.610791) (xy 151.990764 -48.642935)
			(xy 152.043122 -48.682112) (xy 152.090028 -48.727675) (xy 152.130708 -48.778874) (xy 152.148032 -48.806608)
			(xy 152.154382 -48.817276) (xy 152.174956 -48.829976) (xy 152.26919 -48.838104) (xy 152.281301 -48.838415)
			(xy 152.303702 -48.829291) (xy 152.312116 -48.820578) (xy 152.312116 -48.820324) (xy 152.33032 -48.799869)
			(xy 152.371583 -48.763873) (xy 152.417568 -48.734147) (xy 152.467331 -48.7113) (xy 152.519849 -48.695803)
			(xy 152.574044 -48.687975) (xy 152.6288 -48.687975) (xy 152.682995 -48.695803) (xy 152.735513 -48.7113)
			(xy 152.785276 -48.734147) (xy 152.831261 -48.763873) (xy 152.872524 -48.799869) (xy 152.890728 -48.820324)
			(xy 152.899148 -48.829037) (xy 152.921543 -48.838192) (xy 152.933654 -48.83785) (xy 153.015696 -48.830992)
			(xy 153.027624 -48.829303) (xy 153.048037 -48.81657) (xy 153.054812 -48.806608) (xy 153.072082 -48.778828)
			(xy 153.11275 -48.727592) (xy 153.159651 -48.681992) (xy 153.212011 -48.642782) (xy 153.268966 -48.610609)
			(xy 153.329576 -48.586003) (xy 153.39284 -48.569371) (xy 153.457715 -48.560987) (xy 153.490422 -48.560482)
			(xy 153.522382 -48.561005) (xy 153.585796 -48.569019) (xy 153.647707 -48.584917) (xy 153.707136 -48.608449)
			(xy 153.763148 -48.639244) (xy 153.814859 -48.676816) (xy 153.861453 -48.720573) (xy 153.902195 -48.769824)
			(xy 153.936444 -48.823793) (xy 153.963659 -48.881629) (xy 153.98341 -48.94242) (xy 153.995387 -49.005207)
			(xy 153.999401 -49.069) (xy 153.995387 -49.132793) (xy 153.989542 -49.163435) (xy 158.590482 -49.163435)
			(xy 158.590482 -49.099513) (xy 158.598493 -49.036095) (xy 158.61439 -48.974181) (xy 158.637922 -48.914748)
			(xy 158.668716 -48.858733) (xy 158.706289 -48.807018) (xy 158.750046 -48.760421) (xy 158.799299 -48.719676)
			(xy 158.85327 -48.685425) (xy 158.911109 -48.658208) (xy 158.971902 -48.638455) (xy 159.034692 -48.626477)
			(xy 159.098488 -48.622464) (xy 159.162284 -48.626477) (xy 159.225074 -48.638455) (xy 159.285867 -48.658208)
			(xy 159.343706 -48.685425) (xy 159.397677 -48.719676) (xy 159.44693 -48.760421) (xy 159.490687 -48.807018)
			(xy 159.52826 -48.858733) (xy 159.559054 -48.914748) (xy 159.582586 -48.974181) (xy 159.598483 -49.036095)
			(xy 159.606494 -49.099513) (xy 159.606996 -49.131474) (xy 159.606494 -49.163435) (xy 159.598483 -49.226853)
			(xy 159.582586 -49.288767) (xy 159.559054 -49.3482) (xy 159.52826 -49.404215) (xy 159.490687 -49.45593)
			(xy 159.44693 -49.502527) (xy 159.397677 -49.543272) (xy 159.343706 -49.577523) (xy 159.285867 -49.60474)
			(xy 159.225074 -49.624493) (xy 159.162284 -49.636471) (xy 159.098488 -49.640485) (xy 159.034692 -49.636471)
			(xy 158.971902 -49.624493) (xy 158.911109 -49.60474) (xy 158.85327 -49.577523) (xy 158.799299 -49.543272)
			(xy 158.750046 -49.502527) (xy 158.706289 -49.45593) (xy 158.668716 -49.404215) (xy 158.637922 -49.3482)
			(xy 158.61439 -49.288767) (xy 158.598493 -49.226853) (xy 158.590482 -49.163435) (xy 153.989542 -49.163435)
			(xy 153.98341 -49.19558) (xy 153.963659 -49.256371) (xy 153.936444 -49.314207) (xy 153.902195 -49.368176)
			(xy 153.861453 -49.417427) (xy 153.814859 -49.461184) (xy 153.763148 -49.498756) (xy 153.707136 -49.529551)
			(xy 153.647707 -49.553083) (xy 153.585796 -49.568981) (xy 153.522382 -49.576995) (xy 153.490422 -49.577498)
			(xy 153.457716 -49.576999) (xy 153.392843 -49.568614) (xy 153.329581 -49.551979) (xy 153.268975 -49.527369)
			(xy 153.212025 -49.49519) (xy 153.159671 -49.455975) (xy 153.112778 -49.410369) (xy 153.072121 -49.359127)
			(xy 153.054812 -49.331372) (xy 153.048032 -49.321413) (xy 153.027623 -49.308678) (xy 153.015696 -49.306988)
			(xy 152.933654 -49.30013) (xy 152.921533 -49.299763) (xy 152.899115 -49.3089) (xy 152.890728 -49.317656)
			(xy 152.872524 -49.338111) (xy 152.831261 -49.374107) (xy 152.785276 -49.403833) (xy 152.735513 -49.42668)
			(xy 152.682995 -49.442177) (xy 152.6288 -49.450005) (xy 152.574044 -49.450005) (xy 152.519849 -49.442177)
			(xy 152.467331 -49.42668) (xy 152.417568 -49.403833) (xy 152.371583 -49.374107) (xy 152.33032 -49.338111)
			(xy 152.312116 -49.317656) (xy 152.312116 -49.317402) (xy 152.303734 -49.308773) (xy 152.281468 -49.299757)
			(xy 152.269444 -49.30013) (xy 152.187402 -49.306988) (xy 152.175368 -49.308666) (xy 152.154804 -49.321538)
			(xy 152.148032 -49.331626) (xy 152.130708 -49.359371) (xy 152.09005 -49.41061) (xy 152.043158 -49.456213)
			(xy 151.990807 -49.495428) (xy 151.933859 -49.527606) (xy 151.873256 -49.552217) (xy 151.809997 -49.568855)
			(xy 151.745127 -49.577244) (xy 151.712422 -49.577752) (xy 151.680462 -49.577184) (xy 151.617044 -49.569176)
			(xy 151.555131 -49.553281) (xy 151.495698 -49.529752) (xy 151.439683 -49.49896) (xy 151.387969 -49.461389)
			(xy 151.341371 -49.417634) (xy 151.300626 -49.368382) (xy 151.266374 -49.314413) (xy 151.239157 -49.256576)
			(xy 151.219404 -49.195783) (xy 151.207426 -49.132995) (xy 151.203412 -49.0692) (xy 148.304573 -49.0692)
			(xy 148.320062 -49.097374) (xy 148.343594 -49.156807) (xy 148.359491 -49.218721) (xy 148.367502 -49.282139)
			(xy 148.368004 -49.3141) (xy 148.367491 -49.348162) (xy 148.358405 -49.415678) (xy 148.340384 -49.481376)
			(xy 148.313749 -49.544078) (xy 148.278979 -49.602662) (xy 148.236695 -49.656076) (xy 148.212556 -49.680114)
			(xy 148.20519 -49.687226) (xy 148.19757 -49.704752) (xy 148.194268 -49.795176) (xy 148.200872 -49.813718)
			(xy 148.207476 -49.821084) (xy 148.227759 -49.844455) (xy 148.263117 -49.895241) (xy 148.292052 -49.949941)
			(xy 148.314137 -50.007748) (xy 148.329046 -50.067808) (xy 148.336557 -50.129233) (xy 148.337016 -50.160174)
			(xy 148.336514 -50.192135) (xy 148.328503 -50.255553) (xy 148.312606 -50.317467) (xy 148.289074 -50.3769)
			(xy 148.25828 -50.432915) (xy 148.220707 -50.48463) (xy 148.17695 -50.531227) (xy 148.127697 -50.571972)
			(xy 148.073726 -50.606223) (xy 148.015887 -50.63344) (xy 147.955094 -50.653193) (xy 147.892304 -50.665171)
			(xy 147.828508 -50.669185) (xy 147.764712 -50.665171) (xy 147.701922 -50.653193) (xy 147.641129 -50.63344)
			(xy 147.58329 -50.606223) (xy 147.529319 -50.571972) (xy 147.480066 -50.531227) (xy 147.436309 -50.48463)
			(xy 147.398736 -50.432915) (xy 147.367942 -50.3769) (xy 147.34441 -50.317467) (xy 147.328513 -50.255553)
			(xy 147.320502 -50.192135) (xy 147.32 -50.160174) (xy 143.783256 -50.160174) (xy 143.790184 -50.208361)
			(xy 143.79067 -50.235612) (xy 143.790167 -50.263321) (xy 143.782142 -50.318156) (xy 143.766263 -50.371251)
			(xy 143.742864 -50.421487) (xy 143.712438 -50.467807) (xy 143.694404 -50.48885) (xy 143.688604 -50.495993)
			(xy 143.682091 -50.513185) (xy 143.681704 -50.522378) (xy 143.681704 -50.599848) (xy 143.688054 -50.616866)
			(xy 143.694404 -50.623978) (xy 143.71244 -50.645021) (xy 143.742869 -50.691339) (xy 143.766271 -50.741575)
			(xy 143.782151 -50.794671) (xy 143.790174 -50.849506) (xy 143.79067 -50.877216) (xy 143.790184 -50.904467)
			(xy 143.782428 -50.958415) (xy 143.767073 -51.01071) (xy 143.757646 -51.031351) (xy 145.653754 -51.031351)
			(xy 145.653754 -50.967429) (xy 145.661765 -50.904011) (xy 145.677662 -50.842097) (xy 145.701194 -50.782664)
			(xy 145.731988 -50.726649) (xy 145.769561 -50.674934) (xy 145.813318 -50.628337) (xy 145.862571 -50.587592)
			(xy 145.916542 -50.553341) (xy 145.974381 -50.526124) (xy 146.035174 -50.506371) (xy 146.097964 -50.494393)
			(xy 146.16176 -50.49038) (xy 146.225556 -50.494393) (xy 146.288346 -50.506371) (xy 146.349139 -50.526124)
			(xy 146.406978 -50.553341) (xy 146.460949 -50.587592) (xy 146.510202 -50.628337) (xy 146.553959 -50.674934)
			(xy 146.591532 -50.726649) (xy 146.622326 -50.782664) (xy 146.645858 -50.842097) (xy 146.661755 -50.904011)
			(xy 146.669766 -50.967429) (xy 146.670268 -50.99939) (xy 146.669766 -51.031351) (xy 146.661755 -51.094769)
			(xy 146.645858 -51.156683) (xy 146.622326 -51.216116) (xy 146.591532 -51.272131) (xy 146.553959 -51.323846)
			(xy 146.510202 -51.370443) (xy 146.460949 -51.411188) (xy 146.406978 -51.445439) (xy 146.349139 -51.472656)
			(xy 146.288346 -51.492409) (xy 146.225556 -51.504387) (xy 146.16176 -51.508401) (xy 146.097964 -51.504387)
			(xy 146.035174 -51.492409) (xy 145.974381 -51.472656) (xy 145.916542 -51.445439) (xy 145.862571 -51.411188)
			(xy 145.813318 -51.370443) (xy 145.769561 -51.323846) (xy 145.731988 -51.272131) (xy 145.701194 -51.216116)
			(xy 145.677662 -51.156683) (xy 145.661765 -51.094769) (xy 145.653754 -51.031351) (xy 143.757646 -51.031351)
			(xy 143.744431 -51.060287) (xy 143.714965 -51.106137) (xy 143.679274 -51.147328) (xy 143.638083 -51.183019)
			(xy 143.592233 -51.212485) (xy 143.542656 -51.235127) (xy 143.490361 -51.250482) (xy 143.436413 -51.258238)
			(xy 143.381911 -51.258238) (xy 143.327963 -51.250482) (xy 143.275668 -51.235127) (xy 143.226091 -51.212485)
			(xy 143.180241 -51.183019) (xy 143.13905 -51.147328) (xy 143.103359 -51.106137) (xy 143.073893 -51.060287)
			(xy 143.051251 -51.01071) (xy 143.035896 -50.958415) (xy 143.02814 -50.904467) (xy 143.027654 -50.877216)
			(xy 140.34897 -50.877216) (xy 140.348468 -50.909177) (xy 140.340457 -50.972595) (xy 140.32456 -51.034509)
			(xy 140.301028 -51.093942) (xy 140.270234 -51.149957) (xy 140.232661 -51.201672) (xy 140.188904 -51.248269)
			(xy 140.139651 -51.289014) (xy 140.08568 -51.323265) (xy 140.027841 -51.350482) (xy 139.967048 -51.370235)
			(xy 139.904258 -51.382213) (xy 139.840462 -51.386227) (xy 139.776666 -51.382213) (xy 139.713876 -51.370235)
			(xy 139.653083 -51.350482) (xy 139.595244 -51.323265) (xy 139.541273 -51.289014) (xy 139.49202 -51.248269)
			(xy 139.448263 -51.201672) (xy 139.41069 -51.149957) (xy 139.379896 -51.093942) (xy 139.356364 -51.034509)
			(xy 139.340467 -50.972595) (xy 139.332456 -50.909177) (xy 139.331954 -50.877216) (xy 131.905147 -50.877216)
			(xy 131.905762 -50.882085) (xy 131.906264 -50.914046) (xy 131.905762 -50.946007) (xy 131.897751 -51.009425)
			(xy 131.881854 -51.071339) (xy 131.858322 -51.130772) (xy 131.827528 -51.186787) (xy 131.789955 -51.238502)
			(xy 131.746198 -51.285099) (xy 131.696945 -51.325844) (xy 131.642974 -51.360095) (xy 131.585135 -51.387312)
			(xy 131.524342 -51.407065) (xy 131.461552 -51.419043) (xy 131.397756 -51.423057) (xy 131.33396 -51.419043)
			(xy 131.27117 -51.407065) (xy 131.210377 -51.387312) (xy 131.152538 -51.360095) (xy 131.098567 -51.325844)
			(xy 131.049314 -51.285099) (xy 131.005557 -51.238502) (xy 130.967984 -51.186787) (xy 130.93719 -51.130772)
			(xy 130.913658 -51.071339) (xy 130.897761 -51.009425) (xy 130.88975 -50.946007) (xy 130.274132 -50.946007)
			(xy 130.259926 -50.962402) (xy 130.21874 -50.998094) (xy 130.172893 -51.027562) (xy 130.12332 -51.050205)
			(xy 130.071029 -51.065563) (xy 130.017084 -51.073324) (xy 129.989834 -51.073812) (xy 129.961294 -51.073312)
			(xy 129.904851 -51.064811) (xy 129.850305 -51.047995) (xy 129.798874 -51.023238) (xy 129.751706 -50.991093)
			(xy 129.709854 -50.952279) (xy 129.691638 -50.930302) (xy 129.684018 -50.92065) (xy 129.661412 -50.91049)
			(xy 129.553462 -50.917348) (xy 129.532126 -50.930048) (xy 129.525776 -50.940716) (xy 129.508373 -50.968082)
			(xy 129.467662 -51.018567) (xy 129.420865 -51.063468) (xy 129.368741 -51.102058) (xy 129.312134 -51.13371)
			(xy 129.251965 -51.157912) (xy 129.189207 -51.17427) (xy 129.124879 -51.182519) (xy 129.092452 -51.183032)
			(xy 129.061721 -51.18259) (xy 129.000707 -51.175176) (xy 128.941032 -51.160463) (xy 128.883565 -51.138664)
			(xy 128.829144 -51.110099) (xy 128.778563 -51.075182) (xy 128.732559 -51.034424) (xy 128.691803 -50.988418)
			(xy 128.656889 -50.937835) (xy 128.628326 -50.883413) (xy 128.60653 -50.825945) (xy 128.59182 -50.766269)
			(xy 128.584409 -50.705255) (xy 128.583944 -50.674524) (xy 128.583983 -50.662888) (xy 128.585 -50.639637)
			(xy 128.585976 -50.628042) (xy 128.587246 -50.616104) (xy 128.578102 -50.593244) (xy 128.497838 -50.522886)
			(xy 128.47447 -50.51679) (xy 128.462786 -50.519584) (xy 128.462532 -50.519584) (xy 128.434777 -50.525496)
			(xy 128.378385 -50.531863) (xy 128.35001 -50.532284) (xy 128.318469 -50.531843) (xy 128.25587 -50.524041)
			(xy 128.194717 -50.508557) (xy 128.135949 -50.485627) (xy 128.080468 -50.455604) (xy 128.029128 -50.418949)
			(xy 127.982715 -50.376225) (xy 127.941943 -50.328089) (xy 127.907439 -50.275279) (xy 127.879732 -50.218606)
			(xy 127.859247 -50.158942) (xy 127.8463 -50.097202) (xy 127.841089 -50.034334) (xy 126.146262 -50.034334)
			(xy 126.161807 -50.086002) (xy 126.169927 -50.141178) (xy 126.170436 -50.169064) (xy 126.169927 -50.19695)
			(xy 126.161807 -50.252126) (xy 126.145739 -50.305533) (xy 126.122067 -50.35603) (xy 126.091294 -50.402543)
			(xy 126.054077 -50.44408) (xy 126.011209 -50.479755) (xy 125.963603 -50.508809) (xy 125.912274 -50.530621)
			(xy 125.858317 -50.544727) (xy 125.80288 -50.550827) (xy 125.747146 -50.54879) (xy 125.692303 -50.53866)
			(xy 125.639519 -50.520653) (xy 125.589919 -50.495152) (xy 125.544561 -50.462701) (xy 125.504412 -50.423992)
			(xy 125.470326 -50.379849) (xy 125.44303 -50.331214) (xy 125.423107 -50.279123) (xy 125.410981 -50.224686)
			(xy 125.40691 -50.169064) (xy 123.998736 -50.169064) (xy 123.998247 -50.198167) (xy 123.989402 -50.255698)
			(xy 123.971927 -50.31122) (xy 123.946227 -50.363446) (xy 123.912898 -50.411166) (xy 123.872711 -50.453274)
			(xy 123.826599 -50.488794) (xy 123.801378 -50.503328) (xy 123.788383 -50.511119) (xy 123.767294 -50.532852)
			(xy 123.753508 -50.559814) (xy 123.748237 -50.589634) (xy 123.751944 -50.619689) (xy 123.764304 -50.647334)
			(xy 123.78423 -50.670138) (xy 123.796806 -50.678588) (xy 123.820139 -50.693608) (xy 123.86264 -50.729282)
			(xy 123.899523 -50.770739) (xy 123.93001 -50.817102) (xy 123.953457 -50.867394) (xy 123.969368 -50.920552)
			(xy 123.977409 -50.975456) (xy 123.977908 -51.0032) (xy 123.977422 -51.030451) (xy 123.969666 -51.084399)
			(xy 123.954311 -51.136694) (xy 123.931669 -51.186271) (xy 123.902203 -51.232121) (xy 123.866512 -51.273312)
			(xy 123.825321 -51.309003) (xy 123.779471 -51.338469) (xy 123.729894 -51.361111) (xy 123.677599 -51.376466)
			(xy 123.623651 -51.384222) (xy 123.569149 -51.384222) (xy 123.515201 -51.376466) (xy 123.462906 -51.361111)
			(xy 123.413329 -51.338469) (xy 123.367479 -51.309003) (xy 123.326288 -51.273312) (xy 123.290597 -51.232121)
			(xy 123.261131 -51.186271) (xy 123.238489 -51.136694) (xy 123.223134 -51.084399) (xy 123.215378 -51.030451)
			(xy 123.214892 -51.0032) (xy 87.962047 -51.0032) (xy 87.925125 -51.033744) (xy 87.871154 -51.067995)
			(xy 87.813315 -51.095212) (xy 87.752522 -51.114965) (xy 87.689732 -51.126943) (xy 87.625936 -51.130957)
			(xy 87.56214 -51.126943) (xy 87.49935 -51.114965) (xy 87.438557 -51.095212) (xy 87.380718 -51.067995)
			(xy 87.326747 -51.033744) (xy 87.277494 -50.992999) (xy 87.233737 -50.946402) (xy 87.196164 -50.894687)
			(xy 87.16537 -50.838672) (xy 87.141838 -50.779239) (xy 87.125941 -50.717325) (xy 87.11793 -50.653907)
			(xy 73.85812 -50.653907) (xy 73.85812 -51.85283) (xy 109.167928 -51.85283) (xy 109.171999 -51.797208)
			(xy 109.184125 -51.742771) (xy 109.204048 -51.69068) (xy 109.231344 -51.642045) (xy 109.26543 -51.597902)
			(xy 109.305579 -51.559193) (xy 109.350937 -51.526742) (xy 109.400537 -51.501241) (xy 109.453321 -51.483234)
			(xy 109.508164 -51.473104) (xy 109.563898 -51.471067) (xy 109.619335 -51.477167) (xy 109.673292 -51.491273)
			(xy 109.724621 -51.513085) (xy 109.763913 -51.537065) (xy 127.597148 -51.537065) (xy 127.597148 -51.473143)
			(xy 127.605159 -51.409725) (xy 127.621056 -51.347811) (xy 127.644588 -51.288378) (xy 127.675382 -51.232363)
			(xy 127.712955 -51.180648) (xy 127.756712 -51.134051) (xy 127.805965 -51.093306) (xy 127.859936 -51.059055)
			(xy 127.917775 -51.031838) (xy 127.978568 -51.012085) (xy 128.041358 -51.000107) (xy 128.105154 -50.996094)
			(xy 128.16895 -51.000107) (xy 128.23174 -51.012085) (xy 128.292533 -51.031838) (xy 128.350372 -51.059055)
			(xy 128.404343 -51.093306) (xy 128.453596 -51.134051) (xy 128.497353 -51.180648) (xy 128.534926 -51.232363)
			(xy 128.56572 -51.288378) (xy 128.589252 -51.347811) (xy 128.605149 -51.409725) (xy 128.61316 -51.473143)
			(xy 128.613662 -51.505104) (xy 128.61316 -51.537065) (xy 128.605149 -51.600483) (xy 128.589252 -51.662397)
			(xy 128.56572 -51.72183) (xy 128.534926 -51.777845) (xy 128.523476 -51.793605) (xy 152.47467 -51.793605)
			(xy 152.47467 -51.729683) (xy 152.482681 -51.666265) (xy 152.498578 -51.604351) (xy 152.52211 -51.544918)
			(xy 152.552904 -51.488903) (xy 152.590477 -51.437188) (xy 152.634234 -51.390591) (xy 152.683487 -51.349846)
			(xy 152.737458 -51.315595) (xy 152.795297 -51.288378) (xy 152.85609 -51.268625) (xy 152.91888 -51.256647)
			(xy 152.982676 -51.252634) (xy 153.046472 -51.256647) (xy 153.109262 -51.268625) (xy 153.170055 -51.288378)
			(xy 153.227894 -51.315595) (xy 153.281865 -51.349846) (xy 153.331118 -51.390591) (xy 153.374875 -51.437188)
			(xy 153.412448 -51.488903) (xy 153.443242 -51.544918) (xy 153.466774 -51.604351) (xy 153.482671 -51.666265)
			(xy 153.490682 -51.729683) (xy 153.491184 -51.761644) (xy 153.490682 -51.793605) (xy 154.12567 -51.793605)
			(xy 154.12567 -51.729683) (xy 154.133681 -51.666265) (xy 154.149578 -51.604351) (xy 154.17311 -51.544918)
			(xy 154.203904 -51.488903) (xy 154.241477 -51.437188) (xy 154.285234 -51.390591) (xy 154.334487 -51.349846)
			(xy 154.388458 -51.315595) (xy 154.446297 -51.288378) (xy 154.50709 -51.268625) (xy 154.56988 -51.256647)
			(xy 154.633676 -51.252634) (xy 154.697472 -51.256647) (xy 154.760262 -51.268625) (xy 154.813435 -51.285902)
			(xy 162.94354 -51.285902) (xy 162.944081 -51.257164) (xy 162.952702 -51.200338) (xy 162.969749 -51.145448)
			(xy 162.994836 -51.093736) (xy 163.027396 -51.046372) (xy 163.046664 -51.025044) (xy 163.053268 -51.018186)
			(xy 163.06038 -51.000152) (xy 163.06038 -50.911252) (xy 163.053268 -50.893218) (xy 163.046664 -50.88636)
			(xy 163.027399 -50.865028) (xy 162.994831 -50.817668) (xy 162.969737 -50.765958) (xy 162.952685 -50.711068)
			(xy 162.944061 -50.654241) (xy 162.94354 -50.625502) (xy 162.944026 -50.598251) (xy 162.951782 -50.544303)
			(xy 162.967137 -50.492008) (xy 162.989779 -50.442431) (xy 163.019245 -50.396581) (xy 163.054936 -50.35539)
			(xy 163.096127 -50.319699) (xy 163.141977 -50.290233) (xy 163.191554 -50.267591) (xy 163.243849 -50.252236)
			(xy 163.297797 -50.24448) (xy 163.352299 -50.24448) (xy 163.406247 -50.252236) (xy 163.458542 -50.267591)
			(xy 163.508119 -50.290233) (xy 163.553969 -50.319699) (xy 163.59516 -50.35539) (xy 163.630851 -50.396581)
			(xy 163.660317 -50.442431) (xy 163.682959 -50.492008) (xy 163.698314 -50.544303) (xy 163.70607 -50.598251)
			(xy 163.706556 -50.625502) (xy 163.706019 -50.65424) (xy 163.697397 -50.711066) (xy 163.680349 -50.765956)
			(xy 163.655261 -50.817668) (xy 163.6227 -50.865032) (xy 163.603432 -50.88636) (xy 163.596828 -50.893218)
			(xy 163.589716 -50.911252) (xy 163.589716 -50.970688) (xy 170.735496 -50.970688) (xy 170.739567 -50.915066)
			(xy 170.751693 -50.860629) (xy 170.771616 -50.808538) (xy 170.798912 -50.759903) (xy 170.832998 -50.71576)
			(xy 170.873147 -50.677051) (xy 170.918505 -50.6446) (xy 170.968105 -50.619099) (xy 171.020889 -50.601092)
			(xy 171.075732 -50.590962) (xy 171.131466 -50.588925) (xy 171.186903 -50.595025) (xy 171.24086 -50.609131)
			(xy 171.292189 -50.630943) (xy 171.339795 -50.659997) (xy 171.382663 -50.695672) (xy 171.41988 -50.737209)
			(xy 171.450653 -50.783722) (xy 171.474325 -50.834219) (xy 171.490393 -50.887626) (xy 171.498513 -50.942802)
			(xy 171.499022 -50.970688) (xy 171.498513 -50.998574) (xy 171.490393 -51.05375) (xy 171.474325 -51.107157)
			(xy 171.450653 -51.157654) (xy 171.41988 -51.204167) (xy 171.382663 -51.245704) (xy 171.339795 -51.281379)
			(xy 171.292189 -51.310433) (xy 171.252847 -51.327151) (xy 177.90845 -51.327151) (xy 177.90845 -51.272649)
			(xy 177.916206 -51.218701) (xy 177.93156 -51.166405) (xy 177.9542 -51.116827) (xy 177.983664 -51.070976)
			(xy 178.019354 -51.029783) (xy 178.060542 -50.994089) (xy 178.10639 -50.96462) (xy 178.155966 -50.941975)
			(xy 178.20826 -50.926615) (xy 178.262207 -50.918853) (xy 178.289458 -50.918364) (xy 178.315778 -50.918833)
			(xy 178.367919 -50.926052) (xy 178.418573 -50.940374) (xy 178.466775 -50.961525) (xy 178.511611 -50.989104)
			(xy 178.552229 -51.022586) (xy 178.587856 -51.061337) (xy 178.617815 -51.104618) (xy 178.630072 -51.127914)
			(xy 178.634898 -51.137312) (xy 178.650138 -51.150266) (xy 178.7398 -51.178206) (xy 178.759866 -51.176428)
			(xy 178.76901 -51.171348) (xy 178.797048 -51.156647) (xy 178.855998 -51.133556) (xy 178.917358 -51.117962)
			(xy 178.980179 -51.110107) (xy 179.011834 -51.109626) (xy 179.042567 -51.110024) (xy 179.103585 -51.117437)
			(xy 179.163264 -51.132151) (xy 179.220734 -51.153951) (xy 179.258832 -51.173949) (xy 181.026588 -51.173949)
			(xy 181.026588 -51.119451) (xy 181.034343 -51.065508) (xy 181.049696 -51.013218) (xy 181.072334 -50.963645)
			(xy 181.101796 -50.917797) (xy 181.137482 -50.876609) (xy 181.178667 -50.840919) (xy 181.224511 -50.811452)
			(xy 181.274082 -50.78881) (xy 181.326371 -50.773452) (xy 181.380313 -50.765691) (xy 181.407562 -50.765202)
			(xy 181.429807 -50.765531) (xy 181.473991 -50.77075) (xy 181.4957 -50.775616) (xy 181.504162 -50.777279)
			(xy 181.521301 -50.775458) (xy 181.529228 -50.77206) (xy 181.556152 -50.759106) (xy 181.563963 -50.754997)
			(xy 181.576443 -50.74254) (xy 181.580536 -50.734722) (xy 181.594441 -50.705873) (xy 181.628447 -50.651604)
			(xy 181.648354 -50.626518) (xy 181.653591 -50.619573) (xy 181.659436 -50.603205) (xy 181.659784 -50.594514)
			(xy 181.659784 -50.440082) (xy 181.659419 -50.431397) (xy 181.653563 -50.415039) (xy 181.648354 -50.408078)
			(xy 181.627266 -50.381422) (xy 181.591586 -50.323572) (xy 181.577234 -50.292762) (xy 181.573299 -50.284861)
			(xy 181.561088 -50.272132) (xy 181.553358 -50.26787) (xy 181.52618 -50.254662) (xy 181.518238 -50.251094)
			(xy 181.500962 -50.249023) (xy 181.492398 -50.250598) (xy 181.471476 -50.255087) (xy 181.428958 -50.259922)
			(xy 181.407562 -50.26025) (xy 181.380316 -50.259677) (xy 181.326378 -50.251917) (xy 181.274094 -50.23656)
			(xy 181.224527 -50.21392) (xy 181.178686 -50.184456) (xy 181.137505 -50.148768) (xy 181.101822 -50.107583)
			(xy 181.072362 -50.06174) (xy 181.049726 -50.012171) (xy 181.034375 -49.959885) (xy 181.02662 -49.905946)
			(xy 181.02662 -49.851454) (xy 181.034375 -49.797515) (xy 181.049726 -49.745229) (xy 181.072362 -49.69566)
			(xy 181.101822 -49.649817) (xy 181.137505 -49.608632) (xy 181.178686 -49.572944) (xy 181.224527 -49.54348)
			(xy 181.274094 -49.52084) (xy 181.326378 -49.505483) (xy 181.380316 -49.497723) (xy 181.407562 -49.497234)
			(xy 181.434776 -49.497714) (xy 181.488652 -49.505445) (xy 181.540882 -49.520755) (xy 181.590406 -49.543334)
			(xy 181.636218 -49.572722) (xy 181.677387 -49.608323) (xy 181.695598 -49.628552) (xy 181.70157 -49.634923)
			(xy 181.716776 -49.643487) (xy 181.725316 -49.645316) (xy 181.75478 -49.650142) (xy 181.763478 -49.651327)
			(xy 181.780762 -49.64833) (xy 181.788562 -49.6443) (xy 181.817552 -49.628299) (xy 181.87879 -49.603106)
			(xy 181.942779 -49.586071) (xy 182.008437 -49.57748) (xy 182.074655 -49.57748) (xy 182.140313 -49.586071)
			(xy 182.204302 -49.603106) (xy 182.26554 -49.628299) (xy 182.29453 -49.6443) (xy 182.302349 -49.648271)
			(xy 182.319615 -49.651265) (xy 182.328312 -49.650142) (xy 182.357776 -49.645316) (xy 182.366318 -49.643501)
			(xy 182.381511 -49.634914) (xy 182.387494 -49.628552) (xy 182.405688 -49.608308) (xy 182.446863 -49.572712)
			(xy 182.492679 -49.543328) (xy 182.542206 -49.520753) (xy 182.594438 -49.505445) (xy 182.648315 -49.497715)
			(xy 182.67553 -49.497234) (xy 182.702783 -49.497638) (xy 182.756733 -49.505399) (xy 182.80903 -49.520758)
			(xy 182.858609 -49.543404) (xy 182.904461 -49.572874) (xy 182.945652 -49.608569) (xy 182.981344 -49.649763)
			(xy 183.010811 -49.695617) (xy 183.033452 -49.745198) (xy 183.048808 -49.797496) (xy 183.056564 -49.851447)
			(xy 183.056564 -49.905953) (xy 183.048808 -49.959904) (xy 183.033452 -50.012202) (xy 183.010811 -50.061783)
			(xy 182.981344 -50.107637) (xy 182.945652 -50.148831) (xy 182.904461 -50.184526) (xy 182.858609 -50.213996)
			(xy 182.80903 -50.236642) (xy 182.756733 -50.252001) (xy 182.702783 -50.259762) (xy 182.67553 -50.26025)
			(xy 182.654133 -50.259938) (xy 182.611613 -50.255103) (xy 182.590694 -50.250598) (xy 182.58213 -50.249033)
			(xy 182.564858 -50.251107) (xy 182.556912 -50.254662) (xy 182.529734 -50.26787) (xy 182.52197 -50.272091)
			(xy 182.509734 -50.284822) (xy 182.505858 -50.292762) (xy 182.491545 -50.323592) (xy 182.45586 -50.381446)
			(xy 182.434738 -50.408078) (xy 182.429502 -50.415023) (xy 182.423656 -50.431391) (xy 182.423308 -50.440082)
			(xy 182.423308 -50.594514) (xy 182.423676 -50.603199) (xy 182.42953 -50.619557) (xy 182.434738 -50.626518)
			(xy 182.454618 -50.651624) (xy 182.488627 -50.705886) (xy 182.502556 -50.734722) (xy 182.506624 -50.742558)
			(xy 182.51911 -50.755024) (xy 182.52694 -50.759106) (xy 182.553864 -50.77206) (xy 182.561792 -50.775449)
			(xy 182.578929 -50.777266) (xy 182.587392 -50.775616) (xy 182.609104 -50.77077) (xy 182.653286 -50.765555)
			(xy 182.67553 -50.765202) (xy 182.702781 -50.76567) (xy 182.756726 -50.77343) (xy 182.809019 -50.788788)
			(xy 182.858594 -50.811432) (xy 182.904442 -50.840899) (xy 182.945629 -50.876592) (xy 182.981319 -50.917782)
			(xy 183.010783 -50.963633) (xy 183.033422 -51.013209) (xy 183.048776 -51.065503) (xy 183.056532 -51.119449)
			(xy 183.056532 -51.173951) (xy 183.048776 -51.227897) (xy 183.033422 -51.280191) (xy 183.010783 -51.329767)
			(xy 182.981319 -51.375618) (xy 182.945629 -51.416808) (xy 182.904442 -51.452501) (xy 182.858594 -51.481968)
			(xy 182.809019 -51.504612) (xy 182.756726 -51.51997) (xy 182.702781 -51.52773) (xy 182.67553 -51.528218)
			(xy 182.675276 -51.528218) (xy 182.648667 -51.527742) (xy 182.595968 -51.520321) (xy 182.544811 -51.505652)
			(xy 182.496187 -51.484022) (xy 182.451037 -51.455848) (xy 182.410238 -51.421678) (xy 182.392066 -51.402234)
			(xy 182.386023 -51.396023) (xy 182.370839 -51.387702) (xy 182.362348 -51.385978) (xy 182.332884 -51.381406)
			(xy 182.324145 -51.380405) (xy 182.306872 -51.383636) (xy 182.299102 -51.387756) (xy 182.269687 -51.404341)
			(xy 182.207422 -51.430481) (xy 182.142249 -51.448159) (xy 182.07531 -51.457066) (xy 182.041546 -51.457606)
			(xy 182.00778 -51.457067) (xy 181.940834 -51.448189) (xy 181.875655 -51.430518) (xy 181.813394 -51.404365)
			(xy 181.78399 -51.387756) (xy 181.77622 -51.383627) (xy 181.758945 -51.380368) (xy 181.750208 -51.381406)
			(xy 181.720744 -51.385978) (xy 181.712262 -51.387734) (xy 181.697073 -51.396033) (xy 181.691026 -51.402234)
			(xy 181.672864 -51.421691) (xy 181.632079 -51.455888) (xy 181.586933 -51.484077) (xy 181.538303 -51.50571)
			(xy 181.487136 -51.520366) (xy 181.434428 -51.52776) (xy 181.407816 -51.528218) (xy 181.407562 -51.528218)
			(xy 181.380313 -51.527709) (xy 181.326371 -51.519948) (xy 181.274082 -51.50459) (xy 181.224511 -51.481948)
			(xy 181.178667 -51.452481) (xy 181.137482 -51.416791) (xy 181.101796 -51.375603) (xy 181.072334 -51.329755)
			(xy 181.049696 -51.280182) (xy 181.034343 -51.227892) (xy 181.026588 -51.173949) (xy 179.258832 -51.173949)
			(xy 179.275158 -51.182519) (xy 179.325741 -51.217439) (xy 179.371746 -51.258202) (xy 179.412503 -51.304213)
			(xy 179.447416 -51.354801) (xy 179.475977 -51.409228) (xy 179.49777 -51.466701) (xy 179.512476 -51.526382)
			(xy 179.51988 -51.587401) (xy 179.520342 -51.618134) (xy 179.51977 -51.653089) (xy 179.510205 -51.722343)
			(xy 179.491245 -51.789634) (xy 179.463248 -51.853694) (xy 179.426741 -51.913316) (xy 179.405026 -51.940714)
			(xy 179.399774 -51.947648) (xy 179.393938 -51.964025) (xy 179.393596 -51.972718) (xy 179.393596 -51.999896)
			(xy 199.373496 -51.999896) (xy 199.37751 -51.794212) (xy 199.389546 -51.588842) (xy 199.409585 -51.384098)
			(xy 199.437598 -51.180291) (xy 199.473541 -50.977732) (xy 199.51736 -50.77673) (xy 199.568987 -50.577591)
			(xy 199.628345 -50.380618) (xy 199.695343 -50.18611) (xy 199.769879 -49.994365) (xy 199.851839 -49.805674)
			(xy 199.941099 -49.620324) (xy 200.037522 -49.438598) (xy 200.140963 -49.260772) (xy 200.251262 -49.087118)
			(xy 200.368253 -48.917899) (xy 200.491757 -48.753373) (xy 200.621586 -48.593792) (xy 200.757543 -48.439397)
			(xy 200.89942 -48.290425) (xy 201.047001 -48.147101) (xy 201.200062 -48.009645) (xy 201.358369 -47.878265)
			(xy 201.521682 -47.753162) (xy 201.689751 -47.634525) (xy 201.862321 -47.522537) (xy 202.039129 -47.417366)
			(xy 202.219906 -47.319175) (xy 202.404376 -47.228111) (xy 202.592258 -47.144314) (xy 202.783268 -47.067911)
			(xy 202.977112 -46.999018) (xy 203.173497 -46.937741) (xy 203.372123 -46.884173) (xy 203.572688 -46.838396)
			(xy 203.774886 -46.800478) (xy 203.97841 -46.770479) (xy 204.182949 -46.748442) (xy 204.388192 -46.734403)
			(xy 204.593827 -46.728383) (xy 204.79954 -46.73039) (xy 205.005018 -46.740422) (xy 205.209948 -46.758463)
			(xy 205.414018 -46.784486) (xy 205.616918 -46.818451) (xy 205.818338 -46.860306) (xy 206.017971 -46.909988)
			(xy 206.215514 -46.967422) (xy 206.369239 -47.0187) (xy 221.784191 -47.0187) (xy 221.788205 -46.954906)
			(xy 221.800182 -46.892118) (xy 221.819934 -46.831326) (xy 221.847149 -46.773489) (xy 221.881399 -46.719519)
			(xy 221.922142 -46.670267) (xy 221.968737 -46.626509) (xy 222.020449 -46.588937) (xy 222.076462 -46.558141)
			(xy 222.135892 -46.534609) (xy 222.197804 -46.518711) (xy 222.26122 -46.510697) (xy 222.29318 -46.510194)
			(xy 222.293434 -46.510194) (xy 222.321379 -46.510569) (xy 222.376929 -46.516713) (xy 222.431468 -46.528924)
			(xy 222.458026 -46.537626) (xy 222.468948 -46.541436) (xy 222.4913 -46.538896) (xy 222.568008 -46.491652)
			(xy 222.577225 -46.485287) (xy 222.589487 -46.466577) (xy 222.59163 -46.455584) (xy 222.59163 -46.45533)
			(xy 222.596744 -46.422578) (xy 222.614259 -46.358646) (xy 222.639935 -46.297533) (xy 222.673336 -46.240276)
			(xy 222.713896 -46.187846) (xy 222.760926 -46.141132) (xy 222.813629 -46.100927) (xy 222.87111 -46.067913)
			(xy 222.932395 -46.04265) (xy 222.996443 -46.025566) (xy 223.062168 -46.016952) (xy 223.095312 -46.016418)
			(xy 223.126045 -46.016826) (xy 223.187064 -46.024237) (xy 223.246744 -46.038949) (xy 223.304216 -46.060747)
			(xy 223.358641 -46.089313) (xy 223.409226 -46.124232) (xy 223.455233 -46.164994) (xy 223.495991 -46.211004)
			(xy 223.530906 -46.261592) (xy 223.559469 -46.316019) (xy 223.581263 -46.373492) (xy 223.59597 -46.433174)
			(xy 223.603376 -46.494193) (xy 223.60382 -46.524926) (xy 223.603385 -46.55672) (xy 223.595461 -46.619812)
			(xy 223.579727 -46.681423) (xy 223.55643 -46.740589) (xy 223.525932 -46.796386) (xy 223.488712 -46.847943)
			(xy 223.44535 -46.894453) (xy 223.396524 -46.935189) (xy 223.342998 -46.969516) (xy 223.314514 -46.98365)
			(xy 223.30156 -46.99) (xy 223.286066 -47.013622) (xy 223.283272 -47.133256) (xy 223.297496 -47.157894)
			(xy 223.309942 -47.164752) (xy 223.336458 -47.179594) (xy 223.386097 -47.214647) (xy 223.431203 -47.255369)
			(xy 223.471132 -47.301177) (xy 223.505315 -47.351419) (xy 223.533264 -47.405378) (xy 223.554581 -47.462285)
			(xy 223.568962 -47.521327) (xy 223.576201 -47.581662) (xy 223.576642 -47.612046) (xy 223.57614 -47.644007)
			(xy 223.568129 -47.707425) (xy 223.552232 -47.769339) (xy 223.5287 -47.828772) (xy 223.497906 -47.884787)
			(xy 223.460333 -47.936502) (xy 223.416576 -47.983099) (xy 223.367323 -48.023844) (xy 223.313352 -48.058095)
			(xy 223.255513 -48.085312) (xy 223.19472 -48.105065) (xy 223.13193 -48.117043) (xy 223.068134 -48.121057)
			(xy 223.004338 -48.117043) (xy 222.941548 -48.105065) (xy 222.880755 -48.085312) (xy 222.822916 -48.058095)
			(xy 222.768945 -48.023844) (xy 222.719692 -47.983099) (xy 222.675935 -47.936502) (xy 222.638362 -47.884787)
			(xy 222.607568 -47.828772) (xy 222.584036 -47.769339) (xy 222.568139 -47.707425) (xy 222.560128 -47.644007)
			(xy 222.559626 -47.612046) (xy 222.559626 -47.595028) (xy 222.549466 -47.573692) (xy 222.465646 -47.50943)
			(xy 222.442024 -47.505112) (xy 222.430594 -47.508414) (xy 222.397114 -47.517189) (xy 222.328548 -47.526613)
			(xy 222.293942 -47.52721) (xy 222.29318 -47.52721) (xy 222.26122 -47.526703) (xy 222.197804 -47.518689)
			(xy 222.135892 -47.502791) (xy 222.076462 -47.479259) (xy 222.020449 -47.448463) (xy 221.968737 -47.410891)
			(xy 221.922142 -47.367133) (xy 221.881399 -47.317881) (xy 221.847149 -47.263911) (xy 221.819934 -47.206074)
			(xy 221.800182 -47.145282) (xy 221.788205 -47.082494) (xy 221.784191 -47.0187) (xy 206.369239 -47.0187)
			(xy 206.410666 -47.032519) (xy 206.60313 -47.10518) (xy 206.792612 -47.185296) (xy 206.978823 -47.272743)
			(xy 207.161482 -47.367389) (xy 207.340308 -47.469089) (xy 207.51503 -47.577689) (xy 207.685383 -47.693024)
			(xy 207.851105 -47.814917) (xy 208.011946 -47.943183) (xy 208.167659 -48.077626) (xy 208.318009 -48.218043)
			(xy 208.462766 -48.364219) (xy 208.601709 -48.515931) (xy 208.734627 -48.672949) (xy 208.74357 -48.684391)
			(xy 216.970096 -48.684391) (xy 216.970096 -48.620469) (xy 216.978107 -48.557051) (xy 216.994004 -48.495137)
			(xy 217.017536 -48.435704) (xy 217.04833 -48.379689) (xy 217.085903 -48.327974) (xy 217.12966 -48.281377)
			(xy 217.178913 -48.240632) (xy 217.232884 -48.206381) (xy 217.290723 -48.179164) (xy 217.351516 -48.159411)
			(xy 217.414306 -48.147433) (xy 217.478102 -48.14342) (xy 217.541898 -48.147433) (xy 217.604688 -48.159411)
			(xy 217.665481 -48.179164) (xy 217.72332 -48.206381) (xy 217.777291 -48.240632) (xy 217.826544 -48.281377)
			(xy 217.870301 -48.327974) (xy 217.907874 -48.379689) (xy 217.938668 -48.435704) (xy 217.9622 -48.495137)
			(xy 217.978097 -48.557051) (xy 217.986108 -48.620469) (xy 217.98661 -48.65243) (xy 217.986108 -48.684391)
			(xy 217.978097 -48.747809) (xy 217.969326 -48.78197) (xy 222.686116 -48.78197) (xy 222.690187 -48.726348)
			(xy 222.702313 -48.671911) (xy 222.722236 -48.61982) (xy 222.749532 -48.571185) (xy 222.783618 -48.527042)
			(xy 222.823767 -48.488333) (xy 222.869125 -48.455882) (xy 222.918725 -48.430381) (xy 222.971509 -48.412374)
			(xy 223.026352 -48.402244) (xy 223.082086 -48.400207) (xy 223.137523 -48.406307) (xy 223.19148 -48.420413)
			(xy 223.242809 -48.442225) (xy 223.290415 -48.471279) (xy 223.333283 -48.506954) (xy 223.3705 -48.548491)
			(xy 223.401273 -48.595004) (xy 223.424945 -48.645501) (xy 223.441013 -48.698908) (xy 223.449133 -48.754084)
			(xy 223.449642 -48.78197) (xy 223.449133 -48.809856) (xy 223.441013 -48.865032) (xy 223.424945 -48.918439)
			(xy 223.401273 -48.968936) (xy 223.3705 -49.015449) (xy 223.333283 -49.056986) (xy 223.290415 -49.092661)
			(xy 223.242809 -49.121715) (xy 223.19148 -49.143527) (xy 223.137523 -49.157633) (xy 223.082086 -49.163733)
			(xy 223.026352 -49.161696) (xy 222.971509 -49.151566) (xy 222.918725 -49.133559) (xy 222.869125 -49.108058)
			(xy 222.823767 -49.075607) (xy 222.783618 -49.036898) (xy 222.749532 -48.992755) (xy 222.722236 -48.94412)
			(xy 222.702313 -48.892029) (xy 222.690187 -48.837592) (xy 222.686116 -48.78197) (xy 217.969326 -48.78197)
			(xy 217.9622 -48.809723) (xy 217.938668 -48.869156) (xy 217.907874 -48.925171) (xy 217.870301 -48.976886)
			(xy 217.826544 -49.023483) (xy 217.777291 -49.064228) (xy 217.72332 -49.098479) (xy 217.665481 -49.125696)
			(xy 217.604688 -49.145449) (xy 217.541898 -49.157427) (xy 217.478102 -49.161441) (xy 217.414306 -49.157427)
			(xy 217.351516 -49.145449) (xy 217.290723 -49.125696) (xy 217.232884 -49.098479) (xy 217.178913 -49.064228)
			(xy 217.12966 -49.023483) (xy 217.085903 -48.976886) (xy 217.04833 -48.925171) (xy 217.017536 -48.869156)
			(xy 216.994004 -48.809723) (xy 216.978107 -48.747809) (xy 216.970096 -48.684391) (xy 208.74357 -48.684391)
			(xy 208.861318 -48.835034) (xy 208.981588 -49.001937) (xy 209.095255 -49.173407) (xy 209.202145 -49.34918)
			(xy 209.302096 -49.52899) (xy 209.394955 -49.712563) (xy 209.480582 -49.899619) (xy 209.558844 -50.089874)
			(xy 209.629625 -50.283037) (xy 209.692815 -50.478815) (xy 209.748318 -50.676909) (xy 209.79605 -50.877018)
			(xy 209.835939 -51.078836) (xy 209.867923 -51.282058) (xy 209.891953 -51.486372) (xy 209.907994 -51.691468)
			(xy 209.91602 -51.897035) (xy 209.916522 -51.999896) (xy 209.91602 -52.102757) (xy 209.907994 -52.308324)
			(xy 209.891953 -52.51342) (xy 209.884422 -52.577449) (xy 212.552528 -52.577449) (xy 212.552528 -52.513527)
			(xy 212.560539 -52.450109) (xy 212.576436 -52.388195) (xy 212.599968 -52.328762) (xy 212.630762 -52.272747)
			(xy 212.668335 -52.221032) (xy 212.712092 -52.174435) (xy 212.761345 -52.13369) (xy 212.815316 -52.099439)
			(xy 212.873155 -52.072222) (xy 212.933948 -52.052469) (xy 212.996738 -52.040491) (xy 213.060534 -52.036478)
			(xy 213.12433 -52.040491) (xy 213.18712 -52.052469) (xy 213.247913 -52.072222) (xy 213.293839 -52.093833)
			(xy 214.001852 -52.093833) (xy 214.001852 -52.029911) (xy 214.009863 -51.966493) (xy 214.02576 -51.904579)
			(xy 214.049292 -51.845146) (xy 214.080086 -51.789131) (xy 214.117659 -51.737416) (xy 214.161416 -51.690819)
			(xy 214.210669 -51.650074) (xy 214.26464 -51.615823) (xy 214.322479 -51.588606) (xy 214.383272 -51.568853)
			(xy 214.446062 -51.556875) (xy 214.509858 -51.552862) (xy 214.573654 -51.556875) (xy 214.636444 -51.568853)
			(xy 214.697237 -51.588606) (xy 214.755076 -51.615823) (xy 214.809047 -51.650074) (xy 214.8583 -51.690819)
			(xy 214.902057 -51.737416) (xy 214.93963 -51.789131) (xy 214.970424 -51.845146) (xy 214.993956 -51.904579)
			(xy 215.009853 -51.966493) (xy 215.017864 -52.029911) (xy 215.018366 -52.061872) (xy 215.017864 -52.093833)
			(xy 215.009853 -52.157251) (xy 214.993956 -52.219165) (xy 214.970424 -52.278598) (xy 214.93963 -52.334613)
			(xy 214.902057 -52.386328) (xy 214.8583 -52.432925) (xy 214.809047 -52.47367) (xy 214.755076 -52.507921)
			(xy 214.697237 -52.535138) (xy 214.636444 -52.554891) (xy 214.573654 -52.566869) (xy 214.509858 -52.570883)
			(xy 214.446062 -52.566869) (xy 214.383272 -52.554891) (xy 214.322479 -52.535138) (xy 214.26464 -52.507921)
			(xy 214.210669 -52.47367) (xy 214.161416 -52.432925) (xy 214.117659 -52.386328) (xy 214.080086 -52.334613)
			(xy 214.049292 -52.278598) (xy 214.02576 -52.219165) (xy 214.009863 -52.157251) (xy 214.001852 -52.093833)
			(xy 213.293839 -52.093833) (xy 213.305752 -52.099439) (xy 213.359723 -52.13369) (xy 213.408976 -52.174435)
			(xy 213.452733 -52.221032) (xy 213.490306 -52.272747) (xy 213.5211 -52.328762) (xy 213.544632 -52.388195)
			(xy 213.560529 -52.450109) (xy 213.56854 -52.513527) (xy 213.569042 -52.545488) (xy 213.56854 -52.577449)
			(xy 213.560529 -52.640867) (xy 213.544632 -52.702781) (xy 213.5211 -52.762214) (xy 213.490306 -52.818229)
			(xy 213.452733 -52.869944) (xy 213.408976 -52.916541) (xy 213.359723 -52.957286) (xy 213.305752 -52.991537)
			(xy 213.247913 -53.018754) (xy 213.18712 -53.038507) (xy 213.12433 -53.050485) (xy 213.060534 -53.054499)
			(xy 212.996738 -53.050485) (xy 212.933948 -53.038507) (xy 212.873155 -53.018754) (xy 212.815316 -52.991537)
			(xy 212.761345 -52.957286) (xy 212.712092 -52.916541) (xy 212.668335 -52.869944) (xy 212.630762 -52.818229)
			(xy 212.599968 -52.762214) (xy 212.576436 -52.702781) (xy 212.560539 -52.640867) (xy 212.552528 -52.577449)
			(xy 209.884422 -52.577449) (xy 209.867923 -52.717734) (xy 209.835939 -52.920956) (xy 209.79605 -53.122774)
			(xy 209.748318 -53.322883) (xy 209.692815 -53.520977) (xy 209.629625 -53.716755) (xy 209.558844 -53.909918)
			(xy 209.480582 -54.100173) (xy 209.441047 -54.186539) (xy 212.130888 -54.186539) (xy 212.130888 -54.122617)
			(xy 212.138899 -54.059199) (xy 212.154796 -53.997285) (xy 212.178328 -53.937852) (xy 212.209122 -53.881837)
			(xy 212.246695 -53.830122) (xy 212.290452 -53.783525) (xy 212.339705 -53.74278) (xy 212.393676 -53.708529)
			(xy 212.451515 -53.681312) (xy 212.512308 -53.661559) (xy 212.575098 -53.649581) (xy 212.638894 -53.645568)
			(xy 212.70269 -53.649581) (xy 212.76548 -53.661559) (xy 212.826273 -53.681312) (xy 212.884112 -53.708529)
			(xy 212.938083 -53.74278) (xy 212.987336 -53.783525) (xy 213.031093 -53.830122) (xy 213.055524 -53.863748)
			(xy 215.444576 -53.863748) (xy 215.448647 -53.808126) (xy 215.460773 -53.753689) (xy 215.480696 -53.701598)
			(xy 215.507992 -53.652963) (xy 215.542078 -53.60882) (xy 215.582227 -53.570111) (xy 215.627585 -53.53766)
			(xy 215.677185 -53.512159) (xy 215.729969 -53.494152) (xy 215.784812 -53.484022) (xy 215.840546 -53.481985)
			(xy 215.895983 -53.488085) (xy 215.94994 -53.502191) (xy 216.001269 -53.524003) (xy 216.048875 -53.553057)
			(xy 216.091743 -53.588732) (xy 216.12896 -53.630269) (xy 216.159733 -53.676782) (xy 216.183405 -53.727279)
			(xy 216.199473 -53.780686) (xy 216.207593 -53.835862) (xy 216.208102 -53.863748) (xy 216.207593 -53.891634)
			(xy 216.199473 -53.94681) (xy 216.183405 -54.000217) (xy 216.159733 -54.050714) (xy 216.12896 -54.097227)
			(xy 216.091743 -54.138764) (xy 216.048875 -54.174439) (xy 216.001269 -54.203493) (xy 215.94994 -54.225305)
			(xy 215.895983 -54.239411) (xy 215.840546 -54.245511) (xy 215.784812 -54.243474) (xy 215.729969 -54.233344)
			(xy 215.677185 -54.215337) (xy 215.627585 -54.189836) (xy 215.582227 -54.157385) (xy 215.542078 -54.118676)
			(xy 215.507992 -54.074533) (xy 215.480696 -54.025898) (xy 215.460773 -53.973807) (xy 215.448647 -53.91937)
			(xy 215.444576 -53.863748) (xy 213.055524 -53.863748) (xy 213.068666 -53.881837) (xy 213.09946 -53.937852)
			(xy 213.122992 -53.997285) (xy 213.138889 -54.059199) (xy 213.1469 -54.122617) (xy 213.147402 -54.154578)
			(xy 213.1469 -54.186539) (xy 213.138889 -54.249957) (xy 213.122992 -54.311871) (xy 213.09946 -54.371304)
			(xy 213.068666 -54.427319) (xy 213.031093 -54.479034) (xy 212.987336 -54.525631) (xy 212.938083 -54.566376)
			(xy 212.884112 -54.600627) (xy 212.826273 -54.627844) (xy 212.76548 -54.647597) (xy 212.70269 -54.659575)
			(xy 212.638894 -54.663589) (xy 212.575098 -54.659575) (xy 212.512308 -54.647597) (xy 212.451515 -54.627844)
			(xy 212.393676 -54.600627) (xy 212.339705 -54.566376) (xy 212.290452 -54.525631) (xy 212.246695 -54.479034)
			(xy 212.209122 -54.427319) (xy 212.178328 -54.371304) (xy 212.154796 -54.311871) (xy 212.138899 -54.249957)
			(xy 212.130888 -54.186539) (xy 209.441047 -54.186539) (xy 209.394955 -54.287229) (xy 209.302096 -54.470802)
			(xy 209.202145 -54.650612) (xy 209.095255 -54.826385) (xy 208.981588 -54.997855) (xy 208.861318 -55.164758)
			(xy 208.734627 -55.326843) (xy 208.623762 -55.457809) (xy 212.130888 -55.457809) (xy 212.130888 -55.393887)
			(xy 212.138899 -55.330469) (xy 212.154796 -55.268555) (xy 212.178328 -55.209122) (xy 212.209122 -55.153107)
			(xy 212.246695 -55.101392) (xy 212.290452 -55.054795) (xy 212.339705 -55.01405) (xy 212.393676 -54.979799)
			(xy 212.451515 -54.952582) (xy 212.512308 -54.932829) (xy 212.575098 -54.920851) (xy 212.638894 -54.916838)
			(xy 212.70269 -54.920851) (xy 212.76548 -54.932829) (xy 212.826273 -54.952582) (xy 212.884112 -54.979799)
			(xy 212.91457 -54.999128) (xy 214.304116 -54.999128) (xy 214.308187 -54.943506) (xy 214.320313 -54.889069)
			(xy 214.340236 -54.836978) (xy 214.367532 -54.788343) (xy 214.401618 -54.7442) (xy 214.441767 -54.705491)
			(xy 214.487125 -54.67304) (xy 214.536725 -54.647539) (xy 214.589509 -54.629532) (xy 214.644352 -54.619402)
			(xy 214.700086 -54.617365) (xy 214.755523 -54.623465) (xy 214.80948 -54.637571) (xy 214.860809 -54.659383)
			(xy 214.908415 -54.688437) (xy 214.951283 -54.724112) (xy 214.96302 -54.737211) (xy 216.89923 -54.737211)
			(xy 216.89923 -54.673289) (xy 216.907241 -54.609871) (xy 216.923138 -54.547957) (xy 216.94667 -54.488524)
			(xy 216.977464 -54.432509) (xy 217.015037 -54.380794) (xy 217.058794 -54.334197) (xy 217.108047 -54.293452)
			(xy 217.162018 -54.259201) (xy 217.219857 -54.231984) (xy 217.28065 -54.212231) (xy 217.34344 -54.200253)
			(xy 217.407236 -54.19624) (xy 217.471032 -54.200253) (xy 217.533822 -54.212231) (xy 217.594615 -54.231984)
			(xy 217.652454 -54.259201) (xy 217.706425 -54.293452) (xy 217.755678 -54.334197) (xy 217.799435 -54.380794)
			(xy 217.837008 -54.432509) (xy 217.867802 -54.488524) (xy 217.891334 -54.547957) (xy 217.907231 -54.609871)
			(xy 217.915242 -54.673289) (xy 217.915744 -54.70525) (xy 217.915242 -54.737211) (xy 217.907231 -54.800629)
			(xy 217.891334 -54.862543) (xy 217.867802 -54.921976) (xy 217.837008 -54.977991) (xy 217.799435 -55.029706)
			(xy 217.755678 -55.076303) (xy 217.706425 -55.117048) (xy 217.652454 -55.151299) (xy 217.594615 -55.178516)
			(xy 217.533822 -55.198269) (xy 217.471032 -55.210247) (xy 217.407236 -55.214261) (xy 217.34344 -55.210247)
			(xy 217.28065 -55.198269) (xy 217.219857 -55.178516) (xy 217.162018 -55.151299) (xy 217.108047 -55.117048)
			(xy 217.058794 -55.076303) (xy 217.015037 -55.029706) (xy 216.977464 -54.977991) (xy 216.94667 -54.921976)
			(xy 216.923138 -54.862543) (xy 216.907241 -54.800629) (xy 216.89923 -54.737211) (xy 214.96302 -54.737211)
			(xy 214.9885 -54.765649) (xy 215.019273 -54.812162) (xy 215.042945 -54.862659) (xy 215.059013 -54.916066)
			(xy 215.067133 -54.971242) (xy 215.067642 -54.999128) (xy 215.067133 -55.027014) (xy 215.059013 -55.08219)
			(xy 215.042945 -55.135597) (xy 215.019273 -55.186094) (xy 214.9885 -55.232607) (xy 214.951283 -55.274144)
			(xy 214.908415 -55.309819) (xy 214.860809 -55.338873) (xy 214.80948 -55.360685) (xy 214.755523 -55.374791)
			(xy 214.700086 -55.380891) (xy 214.644352 -55.378854) (xy 214.589509 -55.368724) (xy 214.536725 -55.350717)
			(xy 214.487125 -55.325216) (xy 214.441767 -55.292765) (xy 214.401618 -55.254056) (xy 214.367532 -55.209913)
			(xy 214.340236 -55.161278) (xy 214.320313 -55.109187) (xy 214.308187 -55.05475) (xy 214.304116 -54.999128)
			(xy 212.91457 -54.999128) (xy 212.938083 -55.01405) (xy 212.987336 -55.054795) (xy 213.031093 -55.101392)
			(xy 213.068666 -55.153107) (xy 213.09946 -55.209122) (xy 213.122992 -55.268555) (xy 213.138889 -55.330469)
			(xy 213.1469 -55.393887) (xy 213.147402 -55.425848) (xy 213.1469 -55.457809) (xy 213.138889 -55.521227)
			(xy 213.122992 -55.583141) (xy 213.09946 -55.642574) (xy 213.068666 -55.698589) (xy 213.031093 -55.750304)
			(xy 212.987336 -55.796901) (xy 212.938083 -55.837646) (xy 212.884112 -55.871897) (xy 212.826273 -55.899114)
			(xy 212.76548 -55.918867) (xy 212.70269 -55.930845) (xy 212.638894 -55.934859) (xy 212.575098 -55.930845)
			(xy 212.512308 -55.918867) (xy 212.451515 -55.899114) (xy 212.393676 -55.871897) (xy 212.339705 -55.837646)
			(xy 212.290452 -55.796901) (xy 212.246695 -55.750304) (xy 212.209122 -55.698589) (xy 212.178328 -55.642574)
			(xy 212.154796 -55.583141) (xy 212.138899 -55.521227) (xy 212.130888 -55.457809) (xy 208.623762 -55.457809)
			(xy 208.601709 -55.483861) (xy 208.462766 -55.635573) (xy 208.318009 -55.781749) (xy 208.167659 -55.922166)
			(xy 208.011946 -56.056609) (xy 207.851105 -56.184875) (xy 207.685383 -56.306768) (xy 207.51503 -56.422103)
			(xy 207.340308 -56.530703) (xy 207.161482 -56.632403) (xy 206.978823 -56.727049) (xy 206.792612 -56.814496)
			(xy 206.60313 -56.894612) (xy 206.410666 -56.967273) (xy 206.215514 -57.03237) (xy 206.017971 -57.089804)
			(xy 205.818338 -57.139486) (xy 205.616918 -57.181341) (xy 205.414018 -57.215306) (xy 205.209948 -57.241329)
			(xy 205.005018 -57.25937) (xy 204.79954 -57.269402) (xy 204.593827 -57.271409) (xy 204.388192 -57.265389)
			(xy 204.182949 -57.25135) (xy 203.97841 -57.229313) (xy 203.774886 -57.199314) (xy 203.572688 -57.161396)
			(xy 203.372123 -57.115619) (xy 203.173497 -57.062051) (xy 202.977112 -57.000774) (xy 202.783268 -56.931881)
			(xy 202.592258 -56.855478) (xy 202.404376 -56.771681) (xy 202.219906 -56.680617) (xy 202.039129 -56.582426)
			(xy 201.862321 -56.477255) (xy 201.689751 -56.365267) (xy 201.521682 -56.24663) (xy 201.358369 -56.121527)
			(xy 201.200062 -55.990147) (xy 201.047001 -55.852691) (xy 200.89942 -55.709367) (xy 200.757543 -55.560395)
			(xy 200.621586 -55.406) (xy 200.491757 -55.246419) (xy 200.368253 -55.081893) (xy 200.251262 -54.912674)
			(xy 200.140963 -54.73902) (xy 200.037522 -54.561194) (xy 199.941099 -54.379468) (xy 199.851839 -54.194118)
			(xy 199.769879 -54.005427) (xy 199.695343 -53.813682) (xy 199.628345 -53.619174) (xy 199.568987 -53.422201)
			(xy 199.51736 -53.223062) (xy 199.473541 -53.02206) (xy 199.437598 -52.819501) (xy 199.409585 -52.615694)
			(xy 199.389546 -52.41095) (xy 199.37751 -52.20558) (xy 199.373496 -51.999896) (xy 179.393596 -51.999896)
			(xy 179.393596 -52.12715) (xy 179.393996 -52.135832) (xy 179.399829 -52.15219) (xy 179.405026 -52.159154)
			(xy 179.426722 -52.186566) (xy 179.463221 -52.246189) (xy 179.491217 -52.310246) (xy 179.510182 -52.377532)
			(xy 179.519759 -52.44678) (xy 179.520342 -52.481734) (xy 179.519876 -52.512464) (xy 179.512465 -52.573477)
			(xy 179.497753 -52.633151) (xy 179.475957 -52.690617) (xy 179.447393 -52.745038) (xy 179.412479 -52.795618)
			(xy 179.371722 -52.841622) (xy 179.325718 -52.882379) (xy 179.283022 -52.911851) (xy 181.026556 -52.911851)
			(xy 181.026556 -52.857349) (xy 181.034312 -52.803401) (xy 181.049666 -52.751107) (xy 181.072305 -52.701529)
			(xy 181.10177 -52.655678) (xy 181.137459 -52.614486) (xy 181.178647 -52.578793) (xy 181.224496 -52.549324)
			(xy 181.274071 -52.526679) (xy 181.326364 -52.51132) (xy 181.380311 -52.503558) (xy 181.407562 -52.50307)
			(xy 181.434777 -52.503538) (xy 181.488654 -52.51127) (xy 181.540885 -52.526581) (xy 181.590409 -52.549162)
			(xy 181.63622 -52.578553) (xy 181.677388 -52.614158) (xy 181.695598 -52.634388) (xy 181.701565 -52.640764)
			(xy 181.716775 -52.649324) (xy 181.725316 -52.651152) (xy 181.75478 -52.655978) (xy 181.763478 -52.657159)
			(xy 181.780762 -52.654164) (xy 181.788562 -52.650136) (xy 181.817552 -52.634135) (xy 181.87879 -52.608942)
			(xy 181.942779 -52.591907) (xy 182.008437 -52.583316) (xy 182.074655 -52.583316) (xy 182.140313 -52.591907)
			(xy 182.204302 -52.608942) (xy 182.26554 -52.634135) (xy 182.29453 -52.650136) (xy 182.302348 -52.654108)
			(xy 182.319615 -52.657101) (xy 182.328312 -52.655978) (xy 182.357776 -52.651152) (xy 182.366315 -52.649327)
			(xy 182.381509 -52.640746) (xy 182.387494 -52.634388) (xy 182.405674 -52.614131) (xy 182.446854 -52.578539)
			(xy 182.492674 -52.549158) (xy 182.542203 -52.526586) (xy 182.594436 -52.51128) (xy 182.648315 -52.503551)
			(xy 182.67553 -52.50307) (xy 182.702778 -52.503602) (xy 182.75672 -52.511362) (xy 182.809008 -52.526719)
			(xy 182.858578 -52.54936) (xy 182.904422 -52.578825) (xy 182.945606 -52.614515) (xy 182.981293 -52.655702)
			(xy 183.010754 -52.701548) (xy 183.033392 -52.751121) (xy 183.048745 -52.80341) (xy 183.0565 -52.857352)
			(xy 183.0565 -52.911848) (xy 183.048745 -52.96579) (xy 183.033392 -53.018079) (xy 183.010754 -53.067652)
			(xy 182.981293 -53.113498) (xy 182.945606 -53.154685) (xy 182.904422 -53.190375) (xy 182.858578 -53.21984)
			(xy 182.809008 -53.242481) (xy 182.75672 -53.257838) (xy 182.702778 -53.265598) (xy 182.67553 -53.266086)
			(xy 182.654133 -53.265775) (xy 182.611613 -53.26094) (xy 182.590694 -53.256434) (xy 182.58213 -53.254875)
			(xy 182.564859 -53.256946) (xy 182.556912 -53.260498) (xy 182.529734 -53.273706) (xy 182.521962 -53.277914)
			(xy 182.50973 -53.290654) (xy 182.505858 -53.298598) (xy 182.491535 -53.329424) (xy 182.455857 -53.38728)
			(xy 182.434738 -53.413914) (xy 182.429487 -53.420849) (xy 182.423651 -53.437225) (xy 182.423308 -53.445918)
			(xy 182.423308 -53.60035) (xy 182.423706 -53.609032) (xy 182.42954 -53.62539) (xy 182.434738 -53.632354)
			(xy 182.454623 -53.657456) (xy 182.488629 -53.711721) (xy 182.502556 -53.740558) (xy 182.506643 -53.748383)
			(xy 182.519115 -53.760856) (xy 182.52694 -53.764942) (xy 182.553864 -53.777896) (xy 182.561792 -53.781286)
			(xy 182.578929 -53.783102) (xy 182.587392 -53.781452) (xy 182.609104 -53.776607) (xy 182.653286 -53.771391)
			(xy 182.67553 -53.771038) (xy 182.702783 -53.771434) (xy 182.756734 -53.779195) (xy 182.809032 -53.794554)
			(xy 182.858611 -53.8172) (xy 182.904463 -53.846671) (xy 182.945655 -53.882366) (xy 182.981347 -53.923561)
			(xy 183.010814 -53.969415) (xy 183.033456 -54.018997) (xy 183.039928 -54.04104) (xy 189.02883 -54.04104)
			(xy 189.032901 -53.985418) (xy 189.045027 -53.930981) (xy 189.06495 -53.87889) (xy 189.092246 -53.830255)
			(xy 189.126332 -53.786112) (xy 189.166481 -53.747403) (xy 189.211839 -53.714952) (xy 189.261439 -53.689451)
			(xy 189.314223 -53.671444) (xy 189.369066 -53.661314) (xy 189.4248 -53.659277) (xy 189.480237 -53.665377)
			(xy 189.534194 -53.679483) (xy 189.585523 -53.701295) (xy 189.633129 -53.730349) (xy 189.675997 -53.766024)
			(xy 189.713214 -53.807561) (xy 189.743987 -53.854074) (xy 189.767659 -53.904571) (xy 189.783727 -53.957978)
			(xy 189.791847 -54.013154) (xy 189.792356 -54.04104) (xy 189.791847 -54.068926) (xy 189.783727 -54.124102)
			(xy 189.767659 -54.177509) (xy 189.743987 -54.228006) (xy 189.713214 -54.274519) (xy 189.675997 -54.316056)
			(xy 189.633129 -54.351731) (xy 189.585523 -54.380785) (xy 189.534194 -54.402597) (xy 189.480237 -54.416703)
			(xy 189.4248 -54.422803) (xy 189.369066 -54.420766) (xy 189.314223 -54.410636) (xy 189.261439 -54.392629)
			(xy 189.211839 -54.367128) (xy 189.166481 -54.334677) (xy 189.126332 -54.295968) (xy 189.092246 -54.251825)
			(xy 189.06495 -54.20319) (xy 189.045027 -54.151099) (xy 189.032901 -54.096662) (xy 189.02883 -54.04104)
			(xy 183.039928 -54.04104) (xy 183.048812 -54.071295) (xy 183.056568 -54.125247) (xy 183.056568 -54.179753)
			(xy 183.048812 -54.233705) (xy 183.033456 -54.286003) (xy 183.010814 -54.335585) (xy 182.981347 -54.381439)
			(xy 182.945655 -54.422634) (xy 182.904463 -54.458329) (xy 182.858611 -54.4878) (xy 182.809032 -54.510446)
			(xy 182.756734 -54.525805) (xy 182.702783 -54.533566) (xy 182.67553 -54.534054) (xy 182.675276 -54.534054)
			(xy 182.648668 -54.533566) (xy 182.59597 -54.526146) (xy 182.544813 -54.511479) (xy 182.496189 -54.489851)
			(xy 182.451039 -54.46168) (xy 182.410239 -54.427512) (xy 182.392066 -54.40807) (xy 182.386018 -54.401864)
			(xy 182.370838 -54.393539) (xy 182.362348 -54.391814) (xy 182.332884 -54.387242) (xy 182.324146 -54.386236)
			(xy 182.306871 -54.389469) (xy 182.299102 -54.393592) (xy 182.269689 -54.410181) (xy 182.207423 -54.436319)
			(xy 182.142249 -54.453996) (xy 182.075311 -54.462903) (xy 182.041546 -54.463442) (xy 182.00778 -54.462898)
			(xy 181.940835 -54.454021) (xy 181.875656 -54.436351) (xy 181.813394 -54.4102) (xy 181.78399 -54.393592)
			(xy 181.776219 -54.389465) (xy 181.758944 -54.386203) (xy 181.750208 -54.387242) (xy 181.720744 -54.391814)
			(xy 181.71226 -54.393561) (xy 181.697071 -54.401866) (xy 181.691026 -54.40807) (xy 181.672871 -54.427534)
			(xy 181.632084 -54.461728) (xy 181.586936 -54.489916) (xy 181.538305 -54.511547) (xy 181.487137 -54.526203)
			(xy 181.434429 -54.533596) (xy 181.407816 -54.534054) (xy 181.407562 -54.534054) (xy 181.380316 -54.533473)
			(xy 181.326379 -54.525713) (xy 181.274095 -54.510357) (xy 181.224529 -54.487716) (xy 181.178689 -54.458252)
			(xy 181.137508 -54.422565) (xy 181.101825 -54.381381) (xy 181.072366 -54.335538) (xy 181.04973 -54.285969)
			(xy 181.034379 -54.233684) (xy 181.026624 -54.179746) (xy 181.026624 -54.125254) (xy 181.034379 -54.071316)
			(xy 181.04973 -54.019031) (xy 181.072366 -53.969462) (xy 181.101825 -53.923619) (xy 181.137508 -53.882435)
			(xy 181.178688 -53.846748) (xy 181.224529 -53.817284) (xy 181.274095 -53.794643) (xy 181.326379 -53.779287)
			(xy 181.380316 -53.771527) (xy 181.407562 -53.771038) (xy 181.429807 -53.771366) (xy 181.473991 -53.776586)
			(xy 181.4957 -53.781452) (xy 181.504162 -53.783112) (xy 181.521301 -53.781292) (xy 181.529228 -53.777896)
			(xy 181.556152 -53.764942) (xy 181.563976 -53.760854) (xy 181.57645 -53.748383) (xy 181.580536 -53.740558)
			(xy 181.594431 -53.711704) (xy 181.628444 -53.657438) (xy 181.648354 -53.632354) (xy 181.653576 -53.625399)
			(xy 181.65943 -53.609039) (xy 181.659784 -53.60035) (xy 181.659784 -53.445918) (xy 181.659403 -53.437234)
			(xy 181.653557 -53.420877) (xy 181.648354 -53.413914) (xy 181.627257 -53.387265) (xy 181.591582 -53.32941)
			(xy 181.577234 -53.298598) (xy 181.573319 -53.290686) (xy 181.561093 -53.277964) (xy 181.553358 -53.273706)
			(xy 181.52618 -53.260498) (xy 181.518239 -53.256929) (xy 181.500962 -53.25486) (xy 181.492398 -53.256434)
			(xy 181.471476 -53.260923) (xy 181.428958 -53.265758) (xy 181.407562 -53.266086) (xy 181.380311 -53.265642)
			(xy 181.326364 -53.25788) (xy 181.274071 -53.242521) (xy 181.224496 -53.219876) (xy 181.178647 -53.190407)
			(xy 181.137459 -53.154714) (xy 181.10177 -53.113522) (xy 181.072305 -53.067671) (xy 181.049666 -53.018093)
			(xy 181.034312 -52.965799) (xy 181.026556 -52.911851) (xy 179.283022 -52.911851) (xy 179.275138 -52.917293)
			(xy 179.220717 -52.945857) (xy 179.163251 -52.967653) (xy 179.103577 -52.982365) (xy 179.042564 -52.989776)
			(xy 179.011834 -52.990242) (xy 178.980179 -52.989754) (xy 178.917359 -52.981898) (xy 178.856001 -52.966303)
			(xy 178.797053 -52.943212) (xy 178.76901 -52.92852) (xy 178.759866 -52.92344) (xy 178.7398 -52.921662)
			(xy 178.650138 -52.949602) (xy 178.634898 -52.962556) (xy 178.630072 -52.971954) (xy 178.617812 -52.995247)
			(xy 178.587841 -53.038519) (xy 178.552209 -53.077262) (xy 178.511591 -53.110742) (xy 178.466759 -53.138323)
			(xy 178.418561 -53.159482) (xy 178.367914 -53.173818) (xy 178.315777 -53.181059) (xy 178.289458 -53.181504)
			(xy 178.262208 -53.181023) (xy 178.208265 -53.173262) (xy 178.155974 -53.157903) (xy 178.106402 -53.135259)
			(xy 178.060556 -53.105791) (xy 178.019371 -53.0701) (xy 177.983683 -53.02891) (xy 177.954221 -52.983061)
			(xy 177.931582 -52.933486) (xy 177.916229 -52.881194) (xy 177.908474 -52.82725) (xy 177.908474 -52.77275)
			(xy 177.916229 -52.718806) (xy 177.931582 -52.666514) (xy 177.954221 -52.616939) (xy 177.983683 -52.57109)
			(xy 178.019371 -52.5299) (xy 178.060556 -52.494209) (xy 178.106402 -52.464741) (xy 178.155974 -52.442097)
			(xy 178.208265 -52.426738) (xy 178.262208 -52.418977) (xy 178.289458 -52.418488) (xy 178.31551 -52.418967)
			(xy 178.367125 -52.4261) (xy 178.392328 -52.432712) (xy 178.402196 -52.434865) (xy 178.422203 -52.432243)
			(xy 178.43119 -52.427632) (xy 178.50358 -52.385722) (xy 178.515772 -52.369212) (xy 178.518312 -52.359306)
			(xy 178.525483 -52.332004) (xy 178.545028 -52.279047) (xy 178.570319 -52.22858) (xy 178.601046 -52.181226)
			(xy 178.618642 -52.159154) (xy 178.623863 -52.152198) (xy 178.629718 -52.135839) (xy 178.630072 -52.12715)
			(xy 178.630072 -51.972718) (xy 178.629693 -51.964034) (xy 178.623847 -51.947676) (xy 178.618642 -51.940714)
			(xy 178.601035 -51.91865) (xy 178.570307 -51.871295) (xy 178.545013 -51.820827) (xy 178.525465 -51.767869)
			(xy 178.518312 -51.740562) (xy 178.515772 -51.730656) (xy 178.50358 -51.714146) (xy 178.4223 -51.667156)
			(xy 178.402488 -51.664362) (xy 178.392582 -51.667156) (xy 178.392074 -51.667156) (xy 178.366938 -51.673785)
			(xy 178.315449 -51.680925) (xy 178.289458 -51.68138) (xy 178.262207 -51.680947) (xy 178.20826 -51.673185)
			(xy 178.155966 -51.657825) (xy 178.10639 -51.63518) (xy 178.060542 -51.605711) (xy 178.019354 -51.570017)
			(xy 177.983664 -51.528824) (xy 177.9542 -51.482973) (xy 177.93156 -51.433395) (xy 177.916206 -51.381099)
			(xy 177.90845 -51.327151) (xy 171.252847 -51.327151) (xy 171.24086 -51.332245) (xy 171.186903 -51.346351)
			(xy 171.131466 -51.352451) (xy 171.075732 -51.350414) (xy 171.020889 -51.340284) (xy 170.968105 -51.322277)
			(xy 170.918505 -51.296776) (xy 170.873147 -51.264325) (xy 170.832998 -51.225616) (xy 170.798912 -51.181473)
			(xy 170.771616 -51.132838) (xy 170.751693 -51.080747) (xy 170.739567 -51.02631) (xy 170.735496 -50.970688)
			(xy 163.589716 -50.970688) (xy 163.589716 -51.000152) (xy 163.596828 -51.018186) (xy 163.603432 -51.025044)
			(xy 163.622699 -51.046375) (xy 163.655267 -51.093735) (xy 163.68036 -51.145446) (xy 163.697412 -51.200336)
			(xy 163.706035 -51.257163) (xy 163.706556 -51.285902) (xy 163.70607 -51.313153) (xy 163.698314 -51.367101)
			(xy 163.682959 -51.419396) (xy 163.660317 -51.468973) (xy 163.630851 -51.514823) (xy 163.59516 -51.556014)
			(xy 163.553969 -51.591705) (xy 163.508119 -51.621171) (xy 163.458542 -51.643813) (xy 163.406247 -51.659168)
			(xy 163.352299 -51.666924) (xy 163.297797 -51.666924) (xy 163.243849 -51.659168) (xy 163.191554 -51.643813)
			(xy 163.141977 -51.621171) (xy 163.096127 -51.591705) (xy 163.054936 -51.556014) (xy 163.019245 -51.514823)
			(xy 162.989779 -51.468973) (xy 162.967137 -51.419396) (xy 162.951782 -51.367101) (xy 162.944026 -51.313153)
			(xy 162.94354 -51.285902) (xy 154.813435 -51.285902) (xy 154.821055 -51.288378) (xy 154.878894 -51.315595)
			(xy 154.932865 -51.349846) (xy 154.982118 -51.390591) (xy 155.025875 -51.437188) (xy 155.063448 -51.488903)
			(xy 155.094242 -51.544918) (xy 155.117774 -51.604351) (xy 155.133671 -51.666265) (xy 155.141682 -51.729683)
			(xy 155.142184 -51.761644) (xy 155.141682 -51.793605) (xy 155.133671 -51.857023) (xy 155.117774 -51.918937)
			(xy 155.094242 -51.97837) (xy 155.063448 -52.034385) (xy 155.025875 -52.0861) (xy 154.982118 -52.132697)
			(xy 154.932865 -52.173442) (xy 154.878894 -52.207693) (xy 154.821055 -52.23491) (xy 154.760262 -52.254663)
			(xy 154.697472 -52.266641) (xy 154.633676 -52.270655) (xy 154.56988 -52.266641) (xy 154.50709 -52.254663)
			(xy 154.446297 -52.23491) (xy 154.388458 -52.207693) (xy 154.334487 -52.173442) (xy 154.285234 -52.132697)
			(xy 154.241477 -52.0861) (xy 154.203904 -52.034385) (xy 154.17311 -51.97837) (xy 154.149578 -51.918937)
			(xy 154.133681 -51.857023) (xy 154.12567 -51.793605) (xy 153.490682 -51.793605) (xy 153.482671 -51.857023)
			(xy 153.466774 -51.918937) (xy 153.443242 -51.97837) (xy 153.412448 -52.034385) (xy 153.374875 -52.0861)
			(xy 153.331118 -52.132697) (xy 153.281865 -52.173442) (xy 153.227894 -52.207693) (xy 153.170055 -52.23491)
			(xy 153.109262 -52.254663) (xy 153.046472 -52.266641) (xy 152.982676 -52.270655) (xy 152.91888 -52.266641)
			(xy 152.85609 -52.254663) (xy 152.795297 -52.23491) (xy 152.737458 -52.207693) (xy 152.683487 -52.173442)
			(xy 152.634234 -52.132697) (xy 152.590477 -52.0861) (xy 152.552904 -52.034385) (xy 152.52211 -51.97837)
			(xy 152.498578 -51.918937) (xy 152.482681 -51.857023) (xy 152.47467 -51.793605) (xy 128.523476 -51.793605)
			(xy 128.497353 -51.82956) (xy 128.453596 -51.876157) (xy 128.404343 -51.916902) (xy 128.350372 -51.951153)
			(xy 128.292533 -51.97837) (xy 128.23174 -51.998123) (xy 128.16895 -52.010101) (xy 128.105154 -52.014115)
			(xy 128.041358 -52.010101) (xy 127.978568 -51.998123) (xy 127.917775 -51.97837) (xy 127.859936 -51.951153)
			(xy 127.805965 -51.916902) (xy 127.756712 -51.876157) (xy 127.712955 -51.82956) (xy 127.675382 -51.777845)
			(xy 127.644588 -51.72183) (xy 127.621056 -51.662397) (xy 127.605159 -51.600483) (xy 127.597148 -51.537065)
			(xy 109.763913 -51.537065) (xy 109.772227 -51.542139) (xy 109.815095 -51.577814) (xy 109.852312 -51.619351)
			(xy 109.883085 -51.665864) (xy 109.906757 -51.716361) (xy 109.922825 -51.769768) (xy 109.930945 -51.824944)
			(xy 109.931454 -51.85283) (xy 109.930945 -51.880716) (xy 109.922825 -51.935892) (xy 109.906757 -51.989299)
			(xy 109.883085 -52.039796) (xy 109.852312 -52.086309) (xy 109.815095 -52.127846) (xy 109.772227 -52.163521)
			(xy 109.724621 -52.192575) (xy 109.673292 -52.214387) (xy 109.619335 -52.228493) (xy 109.563898 -52.234593)
			(xy 109.508164 -52.232556) (xy 109.453321 -52.222426) (xy 109.400537 -52.204419) (xy 109.350937 -52.178918)
			(xy 109.305579 -52.146467) (xy 109.26543 -52.107758) (xy 109.231344 -52.063615) (xy 109.204048 -52.01498)
			(xy 109.184125 -51.962889) (xy 109.171999 -51.908452) (xy 109.167928 -51.85283) (xy 73.85812 -51.85283)
			(xy 73.85812 -52.374038) (xy 73.859136 -52.383436) (xy 73.859136 -52.383944) (xy 73.86033 -52.389173)
			(xy 73.86456 -52.399027) (xy 73.867518 -52.403502) (xy 73.872852 -52.409852) (xy 74.568812 -53.105812)
			(xy 74.575162 -53.111146) (xy 74.579611 -53.114149) (xy 74.589478 -53.118371) (xy 74.59472 -53.119528)
			(xy 74.595228 -53.119528) (xy 74.604626 -53.120544) (xy 80.775302 -53.120544) (xy 80.785371 -53.120969)
			(xy 80.803971 -53.128689) (xy 80.81137 -53.13553) (xy 81.580185 -53.904345) (xy 103.96194 -53.904345)
			(xy 103.96194 -53.840423) (xy 103.969951 -53.777005) (xy 103.985848 -53.715091) (xy 104.00938 -53.655658)
			(xy 104.040174 -53.599643) (xy 104.077747 -53.547928) (xy 104.121504 -53.501331) (xy 104.170757 -53.460586)
			(xy 104.224728 -53.426335) (xy 104.282567 -53.399118) (xy 104.34336 -53.379365) (xy 104.40615 -53.367387)
			(xy 104.469946 -53.363374) (xy 104.533742 -53.367387) (xy 104.596532 -53.379365) (xy 104.657325 -53.399118)
			(xy 104.715164 -53.426335) (xy 104.769135 -53.460586) (xy 104.818388 -53.501331) (xy 104.862145 -53.547928)
			(xy 104.899718 -53.599643) (xy 104.930512 -53.655658) (xy 104.954044 -53.715091) (xy 104.969941 -53.777005)
			(xy 104.977952 -53.840423) (xy 104.978454 -53.872384) (xy 104.978454 -53.8724) (xy 105.992852 -53.8724)
			(xy 105.996867 -53.808596) (xy 106.008847 -53.745798) (xy 106.028604 -53.684997) (xy 106.055825 -53.627152)
			(xy 106.090083 -53.573174) (xy 106.130835 -53.523917) (xy 106.177441 -53.480156) (xy 106.229164 -53.442581)
			(xy 106.285188 -53.411786) (xy 106.344631 -53.388256) (xy 106.406554 -53.372362) (xy 106.469981 -53.364354)
			(xy 106.501946 -53.363876) (xy 106.533233 -53.364363) (xy 106.595335 -53.372039) (xy 106.656024 -53.387281)
			(xy 106.714383 -53.40986) (xy 106.769528 -53.439432) (xy 106.820625 -53.475552) (xy 106.866901 -53.517672)
			(xy 106.907656 -53.565154) (xy 106.925364 -53.590952) (xy 106.932877 -53.601112) (xy 106.955158 -53.612969)
			(xy 106.967782 -53.613558) (xy 107.05211 -53.613558) (xy 107.064718 -53.612931) (xy 107.086965 -53.601061)
			(xy 107.094528 -53.590952) (xy 107.112266 -53.565175) (xy 107.153019 -53.517696) (xy 107.199292 -53.475577)
			(xy 107.250385 -53.439457) (xy 107.305525 -53.409881) (xy 107.363879 -53.387297) (xy 107.424563 -53.372046)
			(xy 107.48666 -53.364359) (xy 107.517946 -53.363876) (xy 107.549904 -53.364413) (xy 107.613316 -53.372429)
			(xy 107.675223 -53.388329) (xy 107.734649 -53.411862) (xy 107.790658 -53.442658) (xy 107.842365 -53.480229)
			(xy 107.888956 -53.523985) (xy 107.929696 -53.573235) (xy 107.963942 -53.627203) (xy 107.991155 -53.685037)
			(xy 108.010905 -53.745825) (xy 108.022881 -53.80861) (xy 108.026895 -53.8724) (xy 108.024901 -53.904091)
			(xy 109.04194 -53.904091) (xy 109.04194 -53.840169) (xy 109.049951 -53.776751) (xy 109.065848 -53.714837)
			(xy 109.08938 -53.655404) (xy 109.120174 -53.599389) (xy 109.157747 -53.547674) (xy 109.201504 -53.501077)
			(xy 109.250757 -53.460332) (xy 109.304728 -53.426081) (xy 109.362567 -53.398864) (xy 109.42336 -53.379111)
			(xy 109.48615 -53.367133) (xy 109.549946 -53.36312) (xy 109.613742 -53.367133) (xy 109.676532 -53.379111)
			(xy 109.737325 -53.398864) (xy 109.795164 -53.426081) (xy 109.849135 -53.460332) (xy 109.898388 -53.501077)
			(xy 109.942145 -53.547674) (xy 109.979718 -53.599389) (xy 110.010512 -53.655404) (xy 110.034044 -53.714837)
			(xy 110.049941 -53.776751) (xy 110.057952 -53.840169) (xy 110.058454 -53.87213) (xy 110.057952 -53.904091)
			(xy 110.05792 -53.904345) (xy 110.794794 -53.904345) (xy 110.794794 -53.840423) (xy 110.802805 -53.777005)
			(xy 110.818702 -53.715091) (xy 110.842234 -53.655658) (xy 110.873028 -53.599643) (xy 110.910601 -53.547928)
			(xy 110.954358 -53.501331) (xy 111.003611 -53.460586) (xy 111.057582 -53.426335) (xy 111.115421 -53.399118)
			(xy 111.176214 -53.379365) (xy 111.239004 -53.367387) (xy 111.3028 -53.363374) (xy 111.366596 -53.367387)
			(xy 111.429386 -53.379365) (xy 111.490179 -53.399118) (xy 111.548018 -53.426335) (xy 111.601989 -53.460586)
			(xy 111.651242 -53.501331) (xy 111.694999 -53.547928) (xy 111.732572 -53.599643) (xy 111.763366 -53.655658)
			(xy 111.786898 -53.715091) (xy 111.802795 -53.777005) (xy 111.810806 -53.840423) (xy 111.811308 -53.872384)
			(xy 111.81081 -53.904091) (xy 112.08994 -53.904091) (xy 112.08994 -53.840169) (xy 112.097951 -53.776751)
			(xy 112.113848 -53.714837) (xy 112.13738 -53.655404) (xy 112.168174 -53.599389) (xy 112.205747 -53.547674)
			(xy 112.249504 -53.501077) (xy 112.298757 -53.460332) (xy 112.352728 -53.426081) (xy 112.410567 -53.398864)
			(xy 112.47136 -53.379111) (xy 112.53415 -53.367133) (xy 112.597946 -53.36312) (xy 112.661742 -53.367133)
			(xy 112.724532 -53.379111) (xy 112.785325 -53.398864) (xy 112.843164 -53.426081) (xy 112.897135 -53.460332)
			(xy 112.946388 -53.501077) (xy 112.990145 -53.547674) (xy 113.027718 -53.599389) (xy 113.058512 -53.655404)
			(xy 113.082044 -53.714837) (xy 113.097941 -53.776751) (xy 113.105952 -53.840169) (xy 113.106454 -53.87213)
			(xy 113.106187 -53.889105) (xy 113.41074 -53.889105) (xy 113.41074 -53.825183) (xy 113.418751 -53.761765)
			(xy 113.434648 -53.699851) (xy 113.45818 -53.640418) (xy 113.488974 -53.584403) (xy 113.526547 -53.532688)
			(xy 113.570304 -53.486091) (xy 113.619557 -53.445346) (xy 113.673528 -53.411095) (xy 113.731367 -53.383878)
			(xy 113.79216 -53.364125) (xy 113.85495 -53.352147) (xy 113.918746 -53.348134) (xy 113.982542 -53.352147)
			(xy 114.045332 -53.364125) (xy 114.106125 -53.383878) (xy 114.163964 -53.411095) (xy 114.217935 -53.445346)
			(xy 114.267188 -53.486091) (xy 114.310945 -53.532688) (xy 114.348518 -53.584403) (xy 114.379312 -53.640418)
			(xy 114.402844 -53.699851) (xy 114.418741 -53.761765) (xy 114.426752 -53.825183) (xy 114.427254 -53.857144)
			(xy 114.426752 -53.889105) (xy 114.418741 -53.952523) (xy 114.402844 -54.014437) (xy 114.398043 -54.026562)
			(xy 115.932456 -54.026562) (xy 115.936527 -53.97094) (xy 115.948653 -53.916503) (xy 115.968576 -53.864412)
			(xy 115.995872 -53.815777) (xy 116.029958 -53.771634) (xy 116.070107 -53.732925) (xy 116.115465 -53.700474)
			(xy 116.165065 -53.674973) (xy 116.217849 -53.656966) (xy 116.272692 -53.646836) (xy 116.328426 -53.644799)
			(xy 116.383863 -53.650899) (xy 116.43782 -53.665005) (xy 116.489149 -53.686817) (xy 116.536755 -53.715871)
			(xy 116.579623 -53.751546) (xy 116.61684 -53.793083) (xy 116.647613 -53.839596) (xy 116.671285 -53.890093)
			(xy 116.687353 -53.9435) (xy 116.695473 -53.998676) (xy 116.695982 -54.026562) (xy 116.695473 -54.054448)
			(xy 116.687353 -54.109624) (xy 116.671285 -54.163031) (xy 116.647613 -54.213528) (xy 116.61684 -54.260041)
			(xy 116.579623 -54.301578) (xy 116.536755 -54.337253) (xy 116.489149 -54.366307) (xy 116.43782 -54.388119)
			(xy 116.383863 -54.402225) (xy 116.328426 -54.408325) (xy 116.272692 -54.406288) (xy 116.217849 -54.396158)
			(xy 116.165065 -54.378151) (xy 116.115465 -54.35265) (xy 116.070107 -54.320199) (xy 116.029958 -54.28149)
			(xy 115.995872 -54.237347) (xy 115.968576 -54.188712) (xy 115.948653 -54.136621) (xy 115.936527 -54.082184)
			(xy 115.932456 -54.026562) (xy 114.398043 -54.026562) (xy 114.379312 -54.07387) (xy 114.348518 -54.129885)
			(xy 114.310945 -54.1816) (xy 114.267188 -54.228197) (xy 114.217935 -54.268942) (xy 114.163964 -54.303193)
			(xy 114.106125 -54.33041) (xy 114.045332 -54.350163) (xy 113.982542 -54.362141) (xy 113.918746 -54.366155)
			(xy 113.85495 -54.362141) (xy 113.79216 -54.350163) (xy 113.731367 -54.33041) (xy 113.673528 -54.303193)
			(xy 113.619557 -54.268942) (xy 113.570304 -54.228197) (xy 113.526547 -54.1816) (xy 113.488974 -54.129885)
			(xy 113.45818 -54.07387) (xy 113.434648 -54.014437) (xy 113.418751 -53.952523) (xy 113.41074 -53.889105)
			(xy 113.106187 -53.889105) (xy 113.105952 -53.904091) (xy 113.097941 -53.967509) (xy 113.082044 -54.029423)
			(xy 113.058512 -54.088856) (xy 113.027718 -54.144871) (xy 112.990145 -54.196586) (xy 112.946388 -54.243183)
			(xy 112.897135 -54.283928) (xy 112.843164 -54.318179) (xy 112.785325 -54.345396) (xy 112.724532 -54.365149)
			(xy 112.661742 -54.377127) (xy 112.597946 -54.381141) (xy 112.53415 -54.377127) (xy 112.47136 -54.365149)
			(xy 112.410567 -54.345396) (xy 112.352728 -54.318179) (xy 112.298757 -54.283928) (xy 112.249504 -54.243183)
			(xy 112.205747 -54.196586) (xy 112.168174 -54.144871) (xy 112.13738 -54.088856) (xy 112.113848 -54.029423)
			(xy 112.097951 -53.967509) (xy 112.08994 -53.904091) (xy 111.81081 -53.904091) (xy 111.810806 -53.904345)
			(xy 111.802795 -53.967763) (xy 111.786898 -54.029677) (xy 111.763366 -54.08911) (xy 111.732572 -54.145125)
			(xy 111.694999 -54.19684) (xy 111.651242 -54.243437) (xy 111.601989 -54.284182) (xy 111.548018 -54.318433)
			(xy 111.490179 -54.34565) (xy 111.429386 -54.365403) (xy 111.366596 -54.377381) (xy 111.3028 -54.381395)
			(xy 111.239004 -54.377381) (xy 111.176214 -54.365403) (xy 111.115421 -54.34565) (xy 111.057582 -54.318433)
			(xy 111.003611 -54.284182) (xy 110.954358 -54.243437) (xy 110.910601 -54.19684) (xy 110.873028 -54.145125)
			(xy 110.842234 -54.08911) (xy 110.818702 -54.029677) (xy 110.802805 -53.967763) (xy 110.794794 -53.904345)
			(xy 110.05792 -53.904345) (xy 110.049941 -53.967509) (xy 110.034044 -54.029423) (xy 110.010512 -54.088856)
			(xy 109.979718 -54.144871) (xy 109.942145 -54.196586) (xy 109.898388 -54.243183) (xy 109.849135 -54.283928)
			(xy 109.795164 -54.318179) (xy 109.737325 -54.345396) (xy 109.676532 -54.365149) (xy 109.613742 -54.377127)
			(xy 109.549946 -54.381141) (xy 109.48615 -54.377127) (xy 109.42336 -54.365149) (xy 109.362567 -54.345396)
			(xy 109.304728 -54.318179) (xy 109.250757 -54.283928) (xy 109.201504 -54.243183) (xy 109.157747 -54.196586)
			(xy 109.120174 -54.144871) (xy 109.08938 -54.088856) (xy 109.065848 -54.029423) (xy 109.049951 -53.967509)
			(xy 109.04194 -53.904091) (xy 108.024901 -53.904091) (xy 108.022881 -53.93619) (xy 108.010905 -53.998975)
			(xy 107.991155 -54.059763) (xy 107.963942 -54.117597) (xy 107.929696 -54.171565) (xy 107.888956 -54.220815)
			(xy 107.842365 -54.264571) (xy 107.790658 -54.302142) (xy 107.734649 -54.332938) (xy 107.675223 -54.356471)
			(xy 107.613316 -54.372371) (xy 107.549904 -54.380387) (xy 107.517946 -54.380892) (xy 107.486658 -54.380425)
			(xy 107.424555 -54.372748) (xy 107.363865 -54.357503) (xy 107.305505 -54.334923) (xy 107.25036 -54.305347)
			(xy 107.199263 -54.269225) (xy 107.152988 -54.227102) (xy 107.112235 -54.179616) (xy 107.094528 -54.153816)
			(xy 107.086975 -54.143692) (xy 107.064724 -54.131819) (xy 107.05211 -54.13121) (xy 106.967782 -54.13121)
			(xy 106.955176 -54.131845) (xy 106.932929 -54.143711) (xy 106.925364 -54.153816) (xy 106.907654 -54.179612)
			(xy 106.866894 -54.227089) (xy 106.820616 -54.269204) (xy 106.769518 -54.305321) (xy 106.714375 -54.334894)
			(xy 106.656018 -54.357476) (xy 106.595332 -54.372724) (xy 106.533232 -54.380409) (xy 106.501946 -54.380892)
			(xy 106.469981 -54.380446) (xy 106.406554 -54.372438) (xy 106.344631 -54.356544) (xy 106.285188 -54.333014)
			(xy 106.229164 -54.302219) (xy 106.177441 -54.264644) (xy 106.130835 -54.220883) (xy 106.090083 -54.171626)
			(xy 106.055825 -54.117648) (xy 106.028604 -54.059803) (xy 106.008847 -53.999002) (xy 105.996867 -53.936204)
			(xy 105.992852 -53.8724) (xy 104.978454 -53.8724) (xy 104.977952 -53.904345) (xy 104.969941 -53.967763)
			(xy 104.954044 -54.029677) (xy 104.930512 -54.08911) (xy 104.899718 -54.145125) (xy 104.862145 -54.19684)
			(xy 104.818388 -54.243437) (xy 104.769135 -54.284182) (xy 104.715164 -54.318433) (xy 104.657325 -54.34565)
			(xy 104.596532 -54.365403) (xy 104.533742 -54.377381) (xy 104.469946 -54.381395) (xy 104.40615 -54.377381)
			(xy 104.34336 -54.365403) (xy 104.282567 -54.34565) (xy 104.224728 -54.318433) (xy 104.170757 -54.284182)
			(xy 104.121504 -54.243437) (xy 104.077747 -54.19684) (xy 104.040174 -54.145125) (xy 104.00938 -54.08911)
			(xy 103.985848 -54.029677) (xy 103.969951 -53.967763) (xy 103.96194 -53.904345) (xy 81.580185 -53.904345)
			(xy 82.71383 -55.03799) (xy 100.45014 -55.03799) (xy 100.454211 -54.982368) (xy 100.466337 -54.927931)
			(xy 100.48626 -54.87584) (xy 100.513556 -54.827205) (xy 100.547642 -54.783062) (xy 100.587791 -54.744353)
			(xy 100.633149 -54.711902) (xy 100.682749 -54.686401) (xy 100.735533 -54.668394) (xy 100.790376 -54.658264)
			(xy 100.84611 -54.656227) (xy 100.901547 -54.662327) (xy 100.955504 -54.676433) (xy 101.006833 -54.698245)
			(xy 101.054439 -54.727299) (xy 101.097307 -54.762974) (xy 101.134524 -54.804511) (xy 101.165297 -54.851024)
			(xy 101.188969 -54.901521) (xy 101.205037 -54.954928) (xy 101.213157 -55.010104) (xy 101.213666 -55.03799)
			(xy 101.213157 -55.065876) (xy 101.205037 -55.121052) (xy 101.188969 -55.174459) (xy 101.165297 -55.224956)
			(xy 101.134524 -55.271469) (xy 101.125013 -55.282084) (xy 114.878864 -55.282084) (xy 114.882935 -55.226462)
			(xy 114.895061 -55.172025) (xy 114.914984 -55.119934) (xy 114.94228 -55.071299) (xy 114.976366 -55.027156)
			(xy 115.016515 -54.988447) (xy 115.061873 -54.955996) (xy 115.111473 -54.930495) (xy 115.164257 -54.912488)
			(xy 115.2191 -54.902358) (xy 115.274834 -54.900321) (xy 115.330271 -54.906421) (xy 115.384228 -54.920527)
			(xy 115.435557 -54.942339) (xy 115.483163 -54.971393) (xy 115.526031 -55.007068) (xy 115.563248 -55.048605)
			(xy 115.594021 -55.095118) (xy 115.617693 -55.145615) (xy 115.633761 -55.199022) (xy 115.641881 -55.254198)
			(xy 115.64239 -55.282084) (xy 115.641881 -55.30997) (xy 115.633761 -55.365146) (xy 115.617693 -55.418553)
			(xy 115.594409 -55.468223) (xy 117.459754 -55.468223) (xy 117.459754 -55.404301) (xy 117.467765 -55.340883)
			(xy 117.483662 -55.278969) (xy 117.507194 -55.219536) (xy 117.537988 -55.163521) (xy 117.575561 -55.111806)
			(xy 117.619318 -55.065209) (xy 117.668571 -55.024464) (xy 117.722542 -54.990213) (xy 117.780381 -54.962996)
			(xy 117.841174 -54.943243) (xy 117.903964 -54.931265) (xy 117.96776 -54.927252) (xy 118.031556 -54.931265)
			(xy 118.094346 -54.943243) (xy 118.155139 -54.962996) (xy 118.212978 -54.990213) (xy 118.266949 -55.024464)
			(xy 118.316202 -55.065209) (xy 118.359959 -55.111806) (xy 118.397532 -55.163521) (xy 118.428326 -55.219536)
			(xy 118.451858 -55.278969) (xy 118.467755 -55.340883) (xy 118.475766 -55.404301) (xy 118.476268 -55.436262)
			(xy 118.475766 -55.468223) (xy 118.467755 -55.531641) (xy 118.451858 -55.593555) (xy 118.428326 -55.652988)
			(xy 118.397532 -55.709003) (xy 118.359959 -55.760718) (xy 118.316202 -55.807315) (xy 118.266949 -55.84806)
			(xy 118.212978 -55.882311) (xy 118.155139 -55.909528) (xy 118.094346 -55.929281) (xy 118.031556 -55.941259)
			(xy 117.96776 -55.945273) (xy 117.903964 -55.941259) (xy 117.841174 -55.929281) (xy 117.780381 -55.909528)
			(xy 117.722542 -55.882311) (xy 117.668571 -55.84806) (xy 117.619318 -55.807315) (xy 117.575561 -55.760718)
			(xy 117.537988 -55.709003) (xy 117.507194 -55.652988) (xy 117.483662 -55.593555) (xy 117.467765 -55.531641)
			(xy 117.459754 -55.468223) (xy 115.594409 -55.468223) (xy 115.594021 -55.46905) (xy 115.563248 -55.515563)
			(xy 115.526031 -55.5571) (xy 115.483163 -55.592775) (xy 115.435557 -55.621829) (xy 115.384228 -55.643641)
			(xy 115.330271 -55.657747) (xy 115.274834 -55.663847) (xy 115.2191 -55.66181) (xy 115.164257 -55.65168)
			(xy 115.111473 -55.633673) (xy 115.061873 -55.608172) (xy 115.016515 -55.575721) (xy 114.976366 -55.537012)
			(xy 114.94228 -55.492869) (xy 114.914984 -55.444234) (xy 114.895061 -55.392143) (xy 114.882935 -55.337706)
			(xy 114.878864 -55.282084) (xy 101.125013 -55.282084) (xy 101.097307 -55.313006) (xy 101.054439 -55.348681)
			(xy 101.006833 -55.377735) (xy 100.955504 -55.399547) (xy 100.901547 -55.413653) (xy 100.84611 -55.419753)
			(xy 100.790376 -55.417716) (xy 100.735533 -55.407586) (xy 100.682749 -55.389579) (xy 100.633149 -55.364078)
			(xy 100.587791 -55.331627) (xy 100.547642 -55.292918) (xy 100.513556 -55.248775) (xy 100.48626 -55.20014)
			(xy 100.466337 -55.148049) (xy 100.454211 -55.093612) (xy 100.45014 -55.03799) (xy 82.71383 -55.03799)
			(xy 83.614514 -55.938674) (xy 83.621358 -55.946072) (xy 83.629079 -55.964672) (xy 83.6295 -55.974742)
			(xy 83.6295 -56.018641) (xy 87.911172 -56.018641) (xy 87.911172 -55.954719) (xy 87.919183 -55.891301)
			(xy 87.93508 -55.829387) (xy 87.958612 -55.769954) (xy 87.989406 -55.713939) (xy 88.026979 -55.662224)
			(xy 88.070736 -55.615627) (xy 88.119989 -55.574882) (xy 88.17396 -55.540631) (xy 88.231799 -55.513414)
			(xy 88.292592 -55.493661) (xy 88.355382 -55.481683) (xy 88.419178 -55.47767) (xy 88.482974 -55.481683)
			(xy 88.545764 -55.493661) (xy 88.606557 -55.513414) (xy 88.645557 -55.531766) (xy 93.932754 -55.531766)
			(xy 93.936825 -55.476144) (xy 93.948951 -55.421707) (xy 93.968874 -55.369616) (xy 93.99617 -55.320981)
			(xy 94.030256 -55.276838) (xy 94.070405 -55.238129) (xy 94.115763 -55.205678) (xy 94.165363 -55.180177)
			(xy 94.218147 -55.16217) (xy 94.27299 -55.15204) (xy 94.328724 -55.150003) (xy 94.384161 -55.156103)
			(xy 94.438118 -55.170209) (xy 94.489447 -55.192021) (xy 94.537053 -55.221075) (xy 94.579921 -55.25675)
			(xy 94.617138 -55.298287) (xy 94.647911 -55.3448) (xy 94.671583 -55.395297) (xy 94.687651 -55.448704)
			(xy 94.695771 -55.50388) (xy 94.69628 -55.531766) (xy 94.695771 -55.559652) (xy 94.687651 -55.614828)
			(xy 94.671583 -55.668235) (xy 94.647911 -55.718732) (xy 94.617138 -55.765245) (xy 94.579921 -55.806782)
			(xy 94.537053 -55.842457) (xy 94.489447 -55.871511) (xy 94.438118 -55.893323) (xy 94.384161 -55.907429)
			(xy 94.328724 -55.913529) (xy 94.27299 -55.911492) (xy 94.218147 -55.901362) (xy 94.165363 -55.883355)
			(xy 94.115763 -55.857854) (xy 94.070405 -55.825403) (xy 94.030256 -55.786694) (xy 93.99617 -55.742551)
			(xy 93.968874 -55.693916) (xy 93.948951 -55.641825) (xy 93.936825 -55.587388) (xy 93.932754 -55.531766)
			(xy 88.645557 -55.531766) (xy 88.664396 -55.540631) (xy 88.718367 -55.574882) (xy 88.76762 -55.615627)
			(xy 88.811377 -55.662224) (xy 88.84895 -55.713939) (xy 88.879744 -55.769954) (xy 88.903276 -55.829387)
			(xy 88.919173 -55.891301) (xy 88.927184 -55.954719) (xy 88.927686 -55.98668) (xy 88.927184 -56.018641)
			(xy 88.919173 -56.082059) (xy 88.903276 -56.143973) (xy 88.879744 -56.203406) (xy 88.84895 -56.259421)
			(xy 88.811377 -56.311136) (xy 88.76762 -56.357733) (xy 88.718367 -56.398478) (xy 88.664396 -56.432729)
			(xy 88.606557 -56.459946) (xy 88.545764 -56.479699) (xy 88.482974 -56.491677) (xy 88.419178 -56.495691)
			(xy 88.355382 -56.491677) (xy 88.292592 -56.479699) (xy 88.231799 -56.459946) (xy 88.17396 -56.432729)
			(xy 88.119989 -56.398478) (xy 88.070736 -56.357733) (xy 88.026979 -56.311136) (xy 87.989406 -56.259421)
			(xy 87.958612 -56.203406) (xy 87.93508 -56.143973) (xy 87.919183 -56.082059) (xy 87.911172 -56.018641)
			(xy 83.6295 -56.018641) (xy 83.6295 -57.233566) (xy 89.132664 -57.233566) (xy 89.133206 -57.20465)
			(xy 89.141926 -57.147478) (xy 89.159178 -57.092279) (xy 89.184565 -57.040317) (xy 89.217506 -56.992783)
			(xy 89.257245 -56.950766) (xy 89.27973 -56.932576) (xy 89.288543 -56.924975) (xy 89.298722 -56.904069)
			(xy 89.299288 -56.892444) (xy 89.299288 -56.812688) (xy 89.298746 -56.801056) (xy 89.28856 -56.780147)
			(xy 89.27973 -56.772556) (xy 89.257232 -56.754382) (xy 89.217496 -56.71236) (xy 89.184558 -56.664822)
			(xy 89.159172 -56.612857) (xy 89.141919 -56.557656) (xy 89.133196 -56.500483) (xy 89.132664 -56.471566)
			(xy 89.133146 -56.444315) (xy 89.140907 -56.390369) (xy 89.156265 -56.338076) (xy 89.178908 -56.2885)
			(xy 89.208375 -56.242651) (xy 89.244066 -56.201462) (xy 89.285256 -56.165771) (xy 89.331105 -56.136305)
			(xy 89.380681 -56.113662) (xy 89.432975 -56.098305) (xy 89.486921 -56.090546) (xy 89.514172 -56.090058)
			(xy 89.541469 -56.090549) (xy 89.595503 -56.098341) (xy 89.647876 -56.113755) (xy 89.697516 -56.136477)
			(xy 89.743411 -56.166043) (xy 89.784623 -56.201848) (xy 89.820311 -56.243162) (xy 89.849745 -56.289142)
			(xy 89.872325 -56.338847) (xy 89.88759 -56.391263) (xy 89.89187 -56.418226) (xy 89.893573 -56.427272)
			(xy 89.902414 -56.443398) (xy 89.916378 -56.455365) (xy 89.92489 -56.458866) (xy 90.022426 -56.494426)
			(xy 90.050112 -56.488838) (xy 90.060526 -56.47944) (xy 90.083959 -56.458976) (xy 90.134914 -56.423279)
			(xy 90.18984 -56.394059) (xy 90.247919 -56.371753) (xy 90.308283 -56.356692) (xy 90.370033 -56.349101)
			(xy 90.40114 -56.34863) (xy 90.433102 -56.349058) (xy 90.496521 -56.357075) (xy 90.558435 -56.372976)
			(xy 90.594342 -56.387195) (xy 92.3897 -56.387195) (xy 92.3897 -56.323273) (xy 92.397711 -56.259855)
			(xy 92.413608 -56.197941) (xy 92.43714 -56.138508) (xy 92.467934 -56.082493) (xy 92.505507 -56.030778)
			(xy 92.549264 -55.984181) (xy 92.598517 -55.943436) (xy 92.652488 -55.909185) (xy 92.710327 -55.881968)
			(xy 92.77112 -55.862215) (xy 92.83391 -55.850237) (xy 92.897706 -55.846224) (xy 92.961502 -55.850237)
			(xy 93.024292 -55.862215) (xy 93.085085 -55.881968) (xy 93.142924 -55.909185) (xy 93.196895 -55.943436)
			(xy 93.246148 -55.984181) (xy 93.289905 -56.030778) (xy 93.327478 -56.082493) (xy 93.358272 -56.138508)
			(xy 93.381804 -56.197941) (xy 93.397701 -56.259855) (xy 93.405712 -56.323273) (xy 93.406214 -56.355234)
			(xy 93.405712 -56.387195) (xy 93.397701 -56.450613) (xy 93.396135 -56.456711) (xy 95.279126 -56.456711)
			(xy 95.281734 -56.393688) (xy 95.292116 -56.331472) (xy 95.310115 -56.271017) (xy 95.335453 -56.213253)
			(xy 95.367741 -56.159067) (xy 95.406484 -56.10929) (xy 95.451085 -56.064688) (xy 95.500862 -56.025944)
			(xy 95.555048 -55.993656) (xy 95.612812 -55.968317) (xy 95.673266 -55.950318) (xy 95.735482 -55.939934)
			(xy 95.798505 -55.937326) (xy 95.861367 -55.942533) (xy 95.923102 -55.955475) (xy 95.982762 -55.975954)
			(xy 96.039431 -56.003655) (xy 96.092238 -56.038153) (xy 96.140373 -56.078918) (xy 96.183096 -56.125323)
			(xy 96.219751 -56.176656) (xy 96.249776 -56.232129) (xy 96.272708 -56.29089) (xy 96.284438 -56.3372)
			(xy 97.306382 -56.3372) (xy 97.310453 -56.281578) (xy 97.322579 -56.227141) (xy 97.342502 -56.17505)
			(xy 97.369798 -56.126415) (xy 97.403884 -56.082272) (xy 97.444033 -56.043563) (xy 97.489391 -56.011112)
			(xy 97.538991 -55.985611) (xy 97.591775 -55.967604) (xy 97.646618 -55.957474) (xy 97.702352 -55.955437)
			(xy 97.757789 -55.961537) (xy 97.811746 -55.975643) (xy 97.841204 -55.988161) (xy 101.091994 -55.988161)
			(xy 101.091994 -55.924239) (xy 101.100005 -55.860821) (xy 101.115902 -55.798907) (xy 101.139434 -55.739474)
			(xy 101.170228 -55.683459) (xy 101.207801 -55.631744) (xy 101.251558 -55.585147) (xy 101.300811 -55.544402)
			(xy 101.354782 -55.510151) (xy 101.412621 -55.482934) (xy 101.473414 -55.463181) (xy 101.536204 -55.451203)
			(xy 101.6 -55.44719) (xy 101.663796 -55.451203) (xy 101.726586 -55.463181) (xy 101.787379 -55.482934)
			(xy 101.845218 -55.510151) (xy 101.899189 -55.544402) (xy 101.948442 -55.585147) (xy 101.992199 -55.631744)
			(xy 102.029772 -55.683459) (xy 102.060566 -55.739474) (xy 102.084098 -55.798907) (xy 102.099995 -55.860821)
			(xy 102.108006 -55.924239) (xy 102.108109 -55.9308) (xy 104.215182 -55.9308) (xy 104.219253 -55.875178)
			(xy 104.231379 -55.820741) (xy 104.251302 -55.76865) (xy 104.278598 -55.720015) (xy 104.312684 -55.675872)
			(xy 104.352833 -55.637163) (xy 104.398191 -55.604712) (xy 104.447791 -55.579211) (xy 104.500575 -55.561204)
			(xy 104.555418 -55.551074) (xy 104.611152 -55.549037) (xy 104.666589 -55.555137) (xy 104.720546 -55.569243)
			(xy 104.771875 -55.591055) (xy 104.819481 -55.620109) (xy 104.862349 -55.655784) (xy 104.899566 -55.697321)
			(xy 104.930339 -55.743834) (xy 104.954011 -55.794331) (xy 104.970079 -55.847738) (xy 104.976546 -55.891684)
			(xy 111.199928 -55.891684) (xy 111.203999 -55.836062) (xy 111.216125 -55.781625) (xy 111.236048 -55.729534)
			(xy 111.263344 -55.680899) (xy 111.29743 -55.636756) (xy 111.337579 -55.598047) (xy 111.382937 -55.565596)
			(xy 111.432537 -55.540095) (xy 111.485321 -55.522088) (xy 111.540164 -55.511958) (xy 111.595898 -55.509921)
			(xy 111.651335 -55.516021) (xy 111.705292 -55.530127) (xy 111.756621 -55.551939) (xy 111.804227 -55.580993)
			(xy 111.847095 -55.616668) (xy 111.884312 -55.658205) (xy 111.915085 -55.704718) (xy 111.938757 -55.755215)
			(xy 111.954825 -55.808622) (xy 111.962945 -55.863798) (xy 111.963454 -55.891684) (xy 111.962945 -55.91957)
			(xy 111.954825 -55.974746) (xy 111.938757 -56.028153) (xy 111.915085 -56.07865) (xy 111.884312 -56.125163)
			(xy 111.847095 -56.1667) (xy 111.804227 -56.202375) (xy 111.756621 -56.231429) (xy 111.705292 -56.253241)
			(xy 111.651335 -56.267347) (xy 111.595898 -56.273447) (xy 111.540164 -56.27141) (xy 111.485321 -56.26128)
			(xy 111.432537 -56.243273) (xy 111.382937 -56.217772) (xy 111.337579 -56.185321) (xy 111.29743 -56.146612)
			(xy 111.263344 -56.102469) (xy 111.236048 -56.053834) (xy 111.216125 -56.001743) (xy 111.203999 -55.947306)
			(xy 111.199928 -55.891684) (xy 104.976546 -55.891684) (xy 104.978199 -55.902914) (xy 104.978708 -55.9308)
			(xy 104.978199 -55.958686) (xy 104.970079 -56.013862) (xy 104.954011 -56.067269) (xy 104.930339 -56.117766)
			(xy 104.899566 -56.164279) (xy 104.862349 -56.205816) (xy 104.819481 -56.241491) (xy 104.771875 -56.270545)
			(xy 104.720546 -56.292357) (xy 104.666589 -56.306463) (xy 104.611152 -56.312563) (xy 104.555418 -56.310526)
			(xy 104.500575 -56.300396) (xy 104.447791 -56.282389) (xy 104.398191 -56.256888) (xy 104.352833 -56.224437)
			(xy 104.312684 -56.185728) (xy 104.278598 -56.141585) (xy 104.251302 -56.09295) (xy 104.231379 -56.040859)
			(xy 104.219253 -55.986422) (xy 104.215182 -55.9308) (xy 102.108109 -55.9308) (xy 102.108508 -55.9562)
			(xy 102.108006 -55.988161) (xy 102.099995 -56.051579) (xy 102.084098 -56.113493) (xy 102.060566 -56.172926)
			(xy 102.029772 -56.228941) (xy 101.992199 -56.280656) (xy 101.948442 -56.327253) (xy 101.899189 -56.367998)
			(xy 101.845218 -56.402249) (xy 101.787379 -56.429466) (xy 101.726586 -56.449219) (xy 101.663796 -56.461197)
			(xy 101.6 -56.465211) (xy 101.536204 -56.461197) (xy 101.473414 -56.449219) (xy 101.412621 -56.429466)
			(xy 101.354782 -56.402249) (xy 101.300811 -56.367998) (xy 101.251558 -56.327253) (xy 101.207801 -56.280656)
			(xy 101.170228 -56.228941) (xy 101.139434 -56.172926) (xy 101.115902 -56.113493) (xy 101.100005 -56.051579)
			(xy 101.091994 -55.988161) (xy 97.841204 -55.988161) (xy 97.863075 -55.997455) (xy 97.910681 -56.026509)
			(xy 97.953549 -56.062184) (xy 97.990766 -56.103721) (xy 98.021539 -56.150234) (xy 98.045211 -56.200731)
			(xy 98.061279 -56.254138) (xy 98.069399 -56.309314) (xy 98.069908 -56.3372) (xy 98.069399 -56.365086)
			(xy 98.061279 -56.420262) (xy 98.045211 -56.473669) (xy 98.021539 -56.524166) (xy 97.990766 -56.570679)
			(xy 97.953549 -56.612216) (xy 97.910681 -56.647891) (xy 97.863075 -56.676945) (xy 97.811746 -56.698757)
			(xy 97.757789 -56.712863) (xy 97.702352 -56.718963) (xy 97.646618 -56.716926) (xy 97.591775 -56.706796)
			(xy 97.538991 -56.688789) (xy 97.489391 -56.663288) (xy 97.444033 -56.630837) (xy 97.403884 -56.592128)
			(xy 97.369798 -56.547985) (xy 97.342502 -56.49935) (xy 97.322579 -56.447259) (xy 97.310453 -56.392822)
			(xy 97.306382 -56.3372) (xy 96.284438 -56.3372) (xy 96.288196 -56.352035) (xy 96.296002 -56.414628)
			(xy 96.29648 -56.446166) (xy 96.296097 -56.474538) (xy 96.289782 -56.530928) (xy 96.277227 -56.586265)
			(xy 96.258588 -56.63986) (xy 96.246696 -56.665622) (xy 96.241362 -56.676544) (xy 96.24187 -56.700674)
			(xy 96.286574 -56.783732) (xy 96.292893 -56.793953) (xy 96.303385 -56.801215) (xy 106.917738 -56.801215)
			(xy 106.917738 -56.737293) (xy 106.925749 -56.673875) (xy 106.941646 -56.611961) (xy 106.965178 -56.552528)
			(xy 106.995972 -56.496513) (xy 107.033545 -56.444798) (xy 107.077302 -56.398201) (xy 107.126555 -56.357456)
			(xy 107.180526 -56.323205) (xy 107.238365 -56.295988) (xy 107.299158 -56.276235) (xy 107.361948 -56.264257)
			(xy 107.425744 -56.260244) (xy 107.48954 -56.264257) (xy 107.55233 -56.276235) (xy 107.613123 -56.295988)
			(xy 107.670962 -56.323205) (xy 107.724933 -56.357456) (xy 107.774186 -56.398201) (xy 107.817943 -56.444798)
			(xy 107.855516 -56.496513) (xy 107.88631 -56.552528) (xy 107.909842 -56.611961) (xy 107.925739 -56.673875)
			(xy 107.93375 -56.737293) (xy 107.934252 -56.769254) (xy 107.93375 -56.801215) (xy 107.925739 -56.864633)
			(xy 107.909842 -56.926547) (xy 107.88631 -56.98598) (xy 107.855516 -57.041995) (xy 107.817943 -57.09371)
			(xy 107.774186 -57.140307) (xy 107.724933 -57.181052) (xy 107.691814 -57.20207) (xy 109.631988 -57.20207)
			(xy 109.632484 -57.173801) (xy 109.640819 -57.117881) (xy 109.657318 -57.063804) (xy 109.681619 -57.012755)
			(xy 109.713189 -56.965853) (xy 109.751336 -56.924124) (xy 109.772958 -56.905906) (xy 109.781379 -56.898304)
			(xy 109.791146 -56.877864) (xy 109.791754 -56.866536) (xy 109.791754 -56.787796) (xy 109.791112 -56.776477)
			(xy 109.781356 -56.756043) (xy 109.772958 -56.748426) (xy 109.751347 -56.730199) (xy 109.713213 -56.688463)
			(xy 109.681652 -56.64156) (xy 109.657355 -56.590514) (xy 109.640852 -56.536443) (xy 109.632504 -56.480529)
			(xy 109.631988 -56.452262) (xy 109.632474 -56.425011) (xy 109.64023 -56.371063) (xy 109.655585 -56.318768)
			(xy 109.678227 -56.269191) (xy 109.707693 -56.223341) (xy 109.743384 -56.18215) (xy 109.784575 -56.146459)
			(xy 109.830425 -56.116993) (xy 109.880002 -56.094351) (xy 109.932297 -56.078996) (xy 109.986245 -56.07124)
			(xy 110.040747 -56.07124) (xy 110.094695 -56.078996) (xy 110.14699 -56.094351) (xy 110.196567 -56.116993)
			(xy 110.242417 -56.146459) (xy 110.283608 -56.18215) (xy 110.319299 -56.223341) (xy 110.348765 -56.269191)
			(xy 110.371407 -56.318768) (xy 110.386762 -56.371063) (xy 110.394518 -56.425011) (xy 110.395004 -56.452262)
			(xy 110.394463 -56.480529) (xy 110.386137 -56.536447) (xy 110.369647 -56.590523) (xy 110.358467 -56.614017)
			(xy 119.220228 -56.614017) (xy 119.220228 -56.550095) (xy 119.228239 -56.486677) (xy 119.244136 -56.424763)
			(xy 119.267668 -56.36533) (xy 119.298462 -56.309315) (xy 119.336035 -56.2576) (xy 119.379792 -56.211003)
			(xy 119.429045 -56.170258) (xy 119.483016 -56.136007) (xy 119.540855 -56.10879) (xy 119.601648 -56.089037)
			(xy 119.664438 -56.077059) (xy 119.728234 -56.073046) (xy 119.79203 -56.077059) (xy 119.85482 -56.089037)
			(xy 119.915613 -56.10879) (xy 119.973452 -56.136007) (xy 120.027423 -56.170258) (xy 120.076676 -56.211003)
			(xy 120.120433 -56.2576) (xy 120.158006 -56.309315) (xy 120.1888 -56.36533) (xy 120.212332 -56.424763)
			(xy 120.228229 -56.486677) (xy 120.23624 -56.550095) (xy 120.236742 -56.582056) (xy 120.23624 -56.614017)
			(xy 120.228229 -56.677435) (xy 120.22311 -56.697372) (xy 121.309892 -56.697372) (xy 121.309892 -52.981098)
			(xy 121.310016 -52.976207) (xy 121.311943 -52.966614) (xy 121.313702 -52.962048) (xy 121.352564 -52.86629)
			(xy 121.354644 -52.861459) (xy 121.360545 -52.852753) (xy 121.364248 -52.849018) (xy 121.400824 -52.813712)
			(xy 121.401332 -52.813204) (xy 121.928128 -52.286154) (xy 121.945403 -52.269482) (xy 121.984215 -52.241226)
			(xy 122.02697 -52.219391) (xy 122.072614 -52.204513) (xy 122.120024 -52.19696) (xy 122.144028 -52.196492)
			(xy 125.585474 -52.196492) (xy 125.595657 -52.195988) (xy 125.614396 -52.188009) (xy 125.621796 -52.180998)
			(xy 125.672342 -52.128928) (xy 125.679091 -52.121346) (xy 125.68657 -52.102498) (xy 125.68682 -52.092352)
			(xy 125.68682 -52.092098) (xy 125.686566 -52.07762) (xy 125.687068 -52.045659) (xy 125.695079 -51.982241)
			(xy 125.710976 -51.920327) (xy 125.734508 -51.860894) (xy 125.765302 -51.804879) (xy 125.802875 -51.753164)
			(xy 125.846632 -51.706567) (xy 125.895885 -51.665822) (xy 125.949856 -51.631571) (xy 126.007695 -51.604354)
			(xy 126.068488 -51.584601) (xy 126.131278 -51.572623) (xy 126.195074 -51.56861) (xy 126.25887 -51.572623)
			(xy 126.32166 -51.584601) (xy 126.382453 -51.604354) (xy 126.440292 -51.631571) (xy 126.494263 -51.665822)
			(xy 126.543516 -51.706567) (xy 126.587273 -51.753164) (xy 126.624846 -51.804879) (xy 126.65564 -51.860894)
			(xy 126.679172 -51.920327) (xy 126.695069 -51.982241) (xy 126.70308 -52.045659) (xy 126.703582 -52.07762)
			(xy 126.703328 -52.092098) (xy 126.703328 -52.092352) (xy 126.703531 -52.102507) (xy 126.711017 -52.121372)
			(xy 126.717806 -52.128928) (xy 126.768352 -52.180998) (xy 126.775775 -52.187981) (xy 126.794497 -52.195982)
			(xy 126.804674 -52.196492) (xy 129.583434 -52.196492) (xy 129.592301 -52.196155) (xy 129.60899 -52.190172)
			(xy 129.622621 -52.178835) (xy 129.627376 -52.171346) (xy 129.643495 -52.144545) (xy 129.6813 -52.094722)
			(xy 129.724927 -52.049909) (xy 129.773718 -52.010782) (xy 129.826938 -51.977931) (xy 129.883784 -51.951852)
			(xy 129.943397 -51.932938) (xy 130.00488 -51.921474) (xy 130.067304 -51.917633) (xy 130.129728 -51.921474)
			(xy 130.191211 -51.932938) (xy 130.250824 -51.951852) (xy 130.30767 -51.977931) (xy 130.36089 -52.010782)
			(xy 130.409681 -52.049909) (xy 130.453308 -52.094722) (xy 130.491113 -52.144545) (xy 130.507232 -52.171346)
			(xy 130.512082 -52.178758) (xy 130.525692 -52.190066) (xy 130.542327 -52.196098) (xy 130.551174 -52.196492)
			(xy 131.509516 -52.196492) (xy 131.533113 -52.196921) (xy 131.579741 -52.204205) (xy 131.624692 -52.218582)
			(xy 131.666893 -52.239708) (xy 131.705338 -52.267079) (xy 131.73911 -52.300044) (xy 131.75361 -52.318666)
			(xy 131.75742 -52.323746) (xy 131.764732 -52.332491) (xy 131.784942 -52.342979) (xy 131.8077 -52.34374)
			(xy 131.81838 -52.339748) (xy 131.818634 -52.339748) (xy 131.843053 -52.329407) (xy 131.894039 -52.31483)
			(xy 131.946552 -52.307454) (xy 131.973066 -52.306982) (xy 131.99958 -52.307451) (xy 132.052092 -52.314832)
			(xy 132.103077 -52.329413) (xy 132.127498 -52.339748) (xy 132.127752 -52.339748) (xy 132.138437 -52.34373)
			(xy 132.161192 -52.342995) (xy 132.181384 -52.33248) (xy 132.188712 -52.323746) (xy 132.192522 -52.318666)
			(xy 132.207027 -52.300053) (xy 132.240812 -52.267109) (xy 132.279261 -52.239752) (xy 132.321459 -52.218632)
			(xy 132.366402 -52.204251) (xy 132.413022 -52.196952) (xy 132.436616 -52.196492) (xy 145.316702 -52.196492)
			(xy 145.321593 -52.196616) (xy 145.331186 -52.198543) (xy 145.335752 -52.200302) (xy 145.43151 -52.239164)
			(xy 145.436341 -52.241244) (xy 145.445047 -52.247145) (xy 145.448782 -52.250848) (xy 145.484088 -52.287424)
			(xy 145.484596 -52.287932) (xy 145.910046 -52.713128) (xy 145.926718 -52.730403) (xy 145.954974 -52.769215)
			(xy 145.976809 -52.81197) (xy 145.991687 -52.857614) (xy 145.99924 -52.905024) (xy 145.999708 -52.929028)
			(xy 145.999708 -53.565806) (xy 146.000305 -53.576948) (xy 146.009787 -53.597113) (xy 146.017996 -53.604668)
			(xy 146.039051 -53.622906) (xy 146.076135 -53.664472) (xy 146.106787 -53.710984) (xy 146.130357 -53.761455)
			(xy 146.146345 -53.814815) (xy 146.154411 -53.869932) (xy 146.154902 -53.897784) (xy 146.394168 -53.897784)
			(xy 146.398239 -53.842162) (xy 146.410365 -53.787725) (xy 146.430288 -53.735634) (xy 146.457584 -53.686999)
			(xy 146.49167 -53.642856) (xy 146.531819 -53.604147) (xy 146.577177 -53.571696) (xy 146.626777 -53.546195)
			(xy 146.679561 -53.528188) (xy 146.734404 -53.518058) (xy 146.790138 -53.516021) (xy 146.845575 -53.522121)
			(xy 146.889285 -53.533548) (xy 167.101266 -53.533548) (xy 167.101717 -53.502827) (xy 167.109122 -53.441833)
			(xy 167.123818 -53.382174) (xy 167.145591 -53.324719) (xy 167.174124 -53.270304) (xy 167.191182 -53.24475)
			(xy 167.196536 -53.236044) (xy 167.200613 -53.21604) (xy 167.196567 -53.19603) (xy 167.191182 -53.187346)
			(xy 167.174167 -53.161764) (xy 167.145631 -53.107355) (xy 167.123857 -53.049904) (xy 167.10916 -52.990249)
			(xy 167.101756 -52.929259) (xy 167.101751 -52.86782) (xy 167.109146 -52.806828) (xy 167.123833 -52.747171)
			(xy 167.145599 -52.689718) (xy 167.174126 -52.635304) (xy 167.191182 -52.60975) (xy 167.196536 -52.601044)
			(xy 167.200613 -52.58104) (xy 167.196567 -52.56103) (xy 167.191182 -52.552346) (xy 167.174103 -52.526806)
			(xy 167.145574 -52.472387) (xy 167.123807 -52.414928) (xy 167.10912 -52.355266) (xy 167.101725 -52.29427)
			(xy 167.101266 -52.263548) (xy 167.101783 -52.232818) (xy 167.109185 -52.171805) (xy 167.123888 -52.11213)
			(xy 167.145678 -52.054662) (xy 167.174235 -52.000239) (xy 167.209145 -51.949656) (xy 167.249897 -51.903649)
			(xy 167.295897 -51.86289) (xy 167.346476 -51.827974) (xy 167.400894 -51.799408) (xy 167.458359 -51.777611)
			(xy 167.518032 -51.762899) (xy 167.579044 -51.755487) (xy 167.609774 -51.75504) (xy 167.645042 -51.755654)
			(xy 167.714893 -51.765461) (xy 167.782718 -51.784834) (xy 167.847211 -51.813401) (xy 167.87749 -51.831494)
			(xy 167.885254 -51.835845) (xy 167.902667 -51.83947) (xy 167.911526 -51.838606) (xy 167.94099 -51.834288)
			(xy 167.949656 -51.832705) (xy 167.965241 -51.824517) (xy 167.97147 -51.818286) (xy 167.992163 -51.796401)
			(xy 168.037833 -51.757133) (xy 168.087821 -51.723533) (xy 168.141426 -51.696069) (xy 168.197899 -51.675127)
			(xy 168.25645 -51.661) (xy 168.316259 -51.653885) (xy 168.346374 -51.65344) (xy 168.377107 -51.653862)
			(xy 168.438126 -51.661269) (xy 168.497807 -51.675977) (xy 168.55528 -51.697772) (xy 168.609707 -51.726337)
			(xy 168.660293 -51.761254) (xy 168.7063 -51.802015) (xy 168.747059 -51.848025) (xy 168.756687 -51.861974)
			(xy 171.966382 -51.861974) (xy 171.966884 -51.830013) (xy 171.974895 -51.766595) (xy 171.990792 -51.704681)
			(xy 172.014324 -51.645248) (xy 172.045118 -51.589233) (xy 172.082691 -51.537518) (xy 172.126448 -51.490921)
			(xy 172.175701 -51.450176) (xy 172.229672 -51.415925) (xy 172.287511 -51.388708) (xy 172.348304 -51.368955)
			(xy 172.411094 -51.356977) (xy 172.47489 -51.352964) (xy 172.538686 -51.356977) (xy 172.601476 -51.368955)
			(xy 172.662269 -51.388708) (xy 172.720108 -51.415925) (xy 172.774079 -51.450176) (xy 172.823332 -51.490921)
			(xy 172.867089 -51.537518) (xy 172.904662 -51.589233) (xy 172.935456 -51.645248) (xy 172.958988 -51.704681)
			(xy 172.974885 -51.766595) (xy 172.982896 -51.830013) (xy 172.983398 -51.861974) (xy 172.982794 -51.896779)
			(xy 172.973238 -51.965732) (xy 172.964348 -51.999388) (xy 172.964348 -51.999642) (xy 172.962228 -52.008997)
			(xy 172.964315 -52.028052) (xy 172.968412 -52.036726) (xy 173.00575 -52.107592) (xy 173.020228 -52.119784)
			(xy 173.029372 -52.123086) (xy 173.02988 -52.123086) (xy 173.059683 -52.133683) (xy 173.116586 -52.161311)
			(xy 173.169624 -52.195782) (xy 173.217978 -52.236564) (xy 173.260901 -52.283027) (xy 173.297732 -52.334454)
			(xy 173.3279 -52.390052) (xy 173.350942 -52.448962) (xy 173.366501 -52.510274) (xy 173.374336 -52.573042)
			(xy 173.374812 -52.60467) (xy 173.374258 -52.637193) (xy 173.365955 -52.701707) (xy 173.349494 -52.764636)
			(xy 173.325144 -52.824952) (xy 173.293302 -52.881672) (xy 173.254488 -52.933868) (xy 173.209335 -52.980689)
			(xy 173.158581 -53.021371) (xy 173.103054 -53.05525) (xy 173.073568 -53.068982) (xy 173.065333 -53.073122)
			(xy 173.052311 -53.086148) (xy 173.048168 -53.094382) (xy 173.035468 -53.122068) (xy 173.03207 -53.130553)
			(xy 173.030896 -53.148779) (xy 173.033182 -53.157628) (xy 173.043311 -53.193481) (xy 173.054143 -53.267189)
			(xy 173.054772 -53.30444) (xy 173.054772 -53.304694) (xy 173.054264 -53.324506) (xy 173.054264 -53.325014)
			(xy 173.054449 -53.334027) (xy 173.060296 -53.351068) (xy 173.065694 -53.358288) (xy 173.114208 -53.418232)
			(xy 173.130464 -53.427376) (xy 173.139608 -53.4289) (xy 173.171738 -53.434556) (xy 173.234292 -53.453085)
			(xy 173.293961 -53.479465) (xy 173.349764 -53.513263) (xy 173.400784 -53.553924) (xy 173.446182 -53.600778)
			(xy 173.485212 -53.653056) (xy 173.517232 -53.709898) (xy 173.541716 -53.77037) (xy 173.558261 -53.833478)
			(xy 173.566595 -53.898184) (xy 173.56709 -53.930804) (xy 173.566666 -53.961537) (xy 173.559257 -54.022554)
			(xy 173.544546 -54.082234) (xy 173.522749 -54.139705) (xy 173.494184 -54.19413) (xy 173.459266 -54.244715)
			(xy 173.418506 -54.290722) (xy 173.377383 -54.327152) (xy 177.908444 -54.327152) (xy 177.908444 -54.272648)
			(xy 177.9162 -54.218699) (xy 177.931554 -54.166403) (xy 177.954194 -54.116824) (xy 177.983659 -54.070972)
			(xy 178.019349 -54.029779) (xy 178.060538 -53.994085) (xy 178.106388 -53.964614) (xy 178.155964 -53.941969)
			(xy 178.208258 -53.926609) (xy 178.262206 -53.918847) (xy 178.289458 -53.918358) (xy 178.31578 -53.918775)
			(xy 178.367926 -53.925997) (xy 178.418583 -53.940322) (xy 178.466788 -53.961479) (xy 178.511625 -53.989066)
			(xy 178.552242 -54.022557) (xy 178.587865 -54.061317) (xy 178.617819 -54.104608) (xy 178.630072 -54.127908)
			(xy 178.634898 -54.137306) (xy 178.650138 -54.15026) (xy 178.7398 -54.1782) (xy 178.759866 -54.176422)
			(xy 178.76901 -54.171342) (xy 178.797048 -54.156641) (xy 178.855998 -54.13355) (xy 178.917358 -54.117956)
			(xy 178.980179 -54.110101) (xy 179.011834 -54.10962) (xy 179.042567 -54.110024) (xy 179.103584 -54.117437)
			(xy 179.163263 -54.13215) (xy 179.220733 -54.15395) (xy 179.275156 -54.182518) (xy 179.325739 -54.217438)
			(xy 179.371744 -54.2582) (xy 179.412501 -54.30421) (xy 179.447414 -54.354797) (xy 179.475976 -54.409224)
			(xy 179.497768 -54.466697) (xy 179.512475 -54.526377) (xy 179.51988 -54.587395) (xy 179.520342 -54.618128)
			(xy 179.519767 -54.653083) (xy 179.510202 -54.722337) (xy 179.491243 -54.789627) (xy 179.463247 -54.853687)
			(xy 179.426741 -54.91331) (xy 179.405026 -54.940708) (xy 179.399776 -54.947644) (xy 179.393939 -54.964019)
			(xy 179.393596 -54.972712) (xy 179.393596 -55.127144) (xy 179.393999 -55.135825) (xy 179.39983 -55.152183)
			(xy 179.405026 -55.159148) (xy 179.426719 -55.186562) (xy 179.463219 -55.246184) (xy 179.491215 -55.310241)
			(xy 179.51018 -55.377526) (xy 179.519758 -55.446774) (xy 179.520342 -55.481728) (xy 179.51987 -55.512458)
			(xy 179.512459 -55.57347) (xy 179.497749 -55.633145) (xy 179.475953 -55.690611) (xy 179.44739 -55.745031)
			(xy 179.412476 -55.795612) (xy 179.37172 -55.841616) (xy 179.325716 -55.882372) (xy 179.275136 -55.917287)
			(xy 179.230033 -55.94096) (xy 191.663064 -55.94096) (xy 191.667135 -55.885338) (xy 191.679261 -55.830901)
			(xy 191.699184 -55.77881) (xy 191.72648 -55.730175) (xy 191.760566 -55.686032) (xy 191.800715 -55.647323)
			(xy 191.846073 -55.614872) (xy 191.895673 -55.589371) (xy 191.948457 -55.571364) (xy 192.0033 -55.561234)
			(xy 192.059034 -55.559197) (xy 192.114471 -55.565297) (xy 192.168428 -55.579403) (xy 192.219757 -55.601215)
			(xy 192.267363 -55.630269) (xy 192.310231 -55.665944) (xy 192.347448 -55.707481) (xy 192.378221 -55.753994)
			(xy 192.401893 -55.804491) (xy 192.417961 -55.857898) (xy 192.426081 -55.913074) (xy 192.42659 -55.94096)
			(xy 192.426081 -55.968846) (xy 192.417961 -56.024022) (xy 192.401893 -56.077429) (xy 192.378221 -56.127926)
			(xy 192.347448 -56.174439) (xy 192.310231 -56.215976) (xy 192.267363 -56.251651) (xy 192.219757 -56.280705)
			(xy 192.168428 -56.302517) (xy 192.114471 -56.316623) (xy 192.059034 -56.322723) (xy 192.0033 -56.320686)
			(xy 191.948457 -56.310556) (xy 191.895673 -56.292549) (xy 191.846073 -56.267048) (xy 191.800715 -56.234597)
			(xy 191.760566 -56.195888) (xy 191.72648 -56.151745) (xy 191.699184 -56.10311) (xy 191.679261 -56.051019)
			(xy 191.667135 -55.996582) (xy 191.663064 -55.94096) (xy 179.230033 -55.94096) (xy 179.220716 -55.94585)
			(xy 179.16325 -55.967647) (xy 179.103576 -55.982358) (xy 179.042564 -55.98977) (xy 179.011834 -55.990236)
			(xy 178.980179 -55.989749) (xy 178.917359 -55.981893) (xy 178.856001 -55.966298) (xy 178.797053 -55.943206)
			(xy 178.76901 -55.928514) (xy 178.759866 -55.923434) (xy 178.7398 -55.921656) (xy 178.650138 -55.949596)
			(xy 178.634898 -55.96255) (xy 178.630072 -55.971948) (xy 178.617809 -55.995239) (xy 178.587839 -56.038512)
			(xy 178.552208 -56.077255) (xy 178.51159 -56.110735) (xy 178.466758 -56.138317) (xy 178.418561 -56.159476)
			(xy 178.367913 -56.173812) (xy 178.315777 -56.181053) (xy 178.289458 -56.181498) (xy 178.262208 -56.181029)
			(xy 178.208263 -56.173268) (xy 178.155972 -56.157909) (xy 178.106399 -56.135264) (xy 178.060553 -56.105796)
			(xy 178.019366 -56.070104) (xy 177.983679 -56.028914) (xy 177.954215 -55.983064) (xy 177.931577 -55.933488)
			(xy 177.916223 -55.881196) (xy 177.908468 -55.82725) (xy 177.908468 -55.77275) (xy 177.916223 -55.718804)
			(xy 177.931577 -55.666512) (xy 177.954215 -55.616936) (xy 177.983679 -55.571086) (xy 178.019366 -55.529896)
			(xy 178.060553 -55.494204) (xy 178.106399 -55.464736) (xy 178.155972 -55.442091) (xy 178.208263 -55.426732)
			(xy 178.262208 -55.418971) (xy 178.289458 -55.418482) (xy 178.31551 -55.418961) (xy 178.367125 -55.426094)
			(xy 178.392328 -55.432706) (xy 178.402196 -55.434859) (xy 178.422203 -55.432237) (xy 178.43119 -55.427626)
			(xy 178.50358 -55.385716) (xy 178.515772 -55.369206) (xy 178.518312 -55.3593) (xy 178.525481 -55.331998)
			(xy 178.545027 -55.27904) (xy 178.570319 -55.228574) (xy 178.601046 -55.18122) (xy 178.618642 -55.159148)
			(xy 178.623865 -55.152194) (xy 178.629719 -55.135833) (xy 178.630072 -55.127144) (xy 178.630072 -54.972712)
			(xy 178.629696 -54.964028) (xy 178.623847 -54.94767) (xy 178.618642 -54.940708) (xy 178.601033 -54.918645)
			(xy 178.570306 -54.87129) (xy 178.545012 -54.820822) (xy 178.525465 -54.767863) (xy 178.518312 -54.740556)
			(xy 178.515772 -54.73065) (xy 178.50358 -54.71414) (xy 178.4223 -54.66715) (xy 178.402488 -54.664356)
			(xy 178.392582 -54.66715) (xy 178.392074 -54.66715) (xy 178.366938 -54.673778) (xy 178.315449 -54.680919)
			(xy 178.289458 -54.681374) (xy 178.262206 -54.680953) (xy 178.208258 -54.673191) (xy 178.155964 -54.657831)
			(xy 178.106388 -54.635186) (xy 178.060538 -54.605715) (xy 178.019349 -54.570021) (xy 177.983659 -54.528828)
			(xy 177.954194 -54.482976) (xy 177.931554 -54.433397) (xy 177.9162 -54.381101) (xy 177.908444 -54.327152)
			(xy 173.377383 -54.327152) (xy 173.372497 -54.33148) (xy 173.321911 -54.366395) (xy 173.267485 -54.394958)
			(xy 173.210013 -54.416753) (xy 173.150333 -54.431461) (xy 173.089315 -54.438867) (xy 173.058582 -54.439312)
			(xy 173.027861 -54.438861) (xy 172.966866 -54.431456) (xy 172.907207 -54.416754) (xy 172.849755 -54.394972)
			(xy 172.795346 -54.366425) (xy 172.744774 -54.33153) (xy 172.698774 -54.290796) (xy 172.658018 -54.244815)
			(xy 172.6231 -54.194259) (xy 172.594527 -54.139864) (xy 172.572717 -54.082422) (xy 172.557988 -54.022771)
			(xy 172.550553 -53.961779) (xy 172.550074 -53.931058) (xy 172.550074 -53.93055) (xy 172.550582 -53.910992)
			(xy 172.550582 -53.910484) (xy 172.550389 -53.901472) (xy 172.544546 -53.884431) (xy 172.539152 -53.87721)
			(xy 172.490638 -53.817266) (xy 172.474382 -53.808122) (xy 172.465238 -53.806598) (xy 172.433115 -53.800908)
			(xy 172.370561 -53.782385) (xy 172.310891 -53.75601) (xy 172.255087 -53.722216) (xy 172.204066 -53.68156)
			(xy 172.158667 -53.634709) (xy 172.119636 -53.582433) (xy 172.087615 -53.525594) (xy 172.06313 -53.465124)
			(xy 172.046585 -53.402018) (xy 172.03825 -53.337314) (xy 172.037756 -53.304694) (xy 172.03824 -53.272168)
			(xy 172.046548 -53.20765) (xy 172.063016 -53.144718) (xy 172.087374 -53.084399) (xy 172.119224 -53.027678)
			(xy 172.158048 -52.975482) (xy 172.20321 -52.928663) (xy 172.253973 -52.887984) (xy 172.309509 -52.854111)
			(xy 172.339 -52.840382) (xy 172.347237 -52.836245) (xy 172.360259 -52.823218) (xy 172.3644 -52.814982)
			(xy 172.3771 -52.787296) (xy 172.380517 -52.778817) (xy 172.38168 -52.760586) (xy 172.379386 -52.751736)
			(xy 172.369272 -52.71588) (xy 172.35843 -52.642174) (xy 172.357796 -52.604924) (xy 172.357796 -52.60467)
			(xy 172.358389 -52.569864) (xy 172.367952 -52.500912) (xy 172.376846 -52.467256) (xy 172.376846 -52.467002)
			(xy 172.378943 -52.457643) (xy 172.376871 -52.438592) (xy 172.372782 -52.429918) (xy 172.335444 -52.359052)
			(xy 172.320966 -52.34686) (xy 172.311822 -52.343558) (xy 172.311314 -52.343558) (xy 172.281546 -52.332867)
			(xy 172.224643 -52.305253) (xy 172.171604 -52.270795) (xy 172.123247 -52.230025) (xy 172.080321 -52.183573)
			(xy 172.043486 -52.132155) (xy 172.013313 -52.076567) (xy 171.990266 -52.017665) (xy 171.974702 -51.956361)
			(xy 171.966861 -51.893599) (xy 171.966382 -51.861974) (xy 168.756687 -51.861974) (xy 168.781974 -51.898612)
			(xy 168.810537 -51.95304) (xy 168.83233 -52.010514) (xy 168.847035 -52.070195) (xy 168.854439 -52.131215)
			(xy 168.854882 -52.161948) (xy 168.854438 -52.192669) (xy 168.847033 -52.253664) (xy 168.832336 -52.313323)
			(xy 168.810561 -52.370778) (xy 168.782026 -52.425192) (xy 168.764966 -52.450746) (xy 168.759535 -52.45941)
			(xy 168.755489 -52.47944) (xy 168.759566 -52.499464) (xy 168.764966 -52.50815) (xy 168.782067 -52.533676)
			(xy 168.810595 -52.588096) (xy 168.83236 -52.645556) (xy 168.847048 -52.70522) (xy 168.854443 -52.766217)
			(xy 168.854438 -52.827662) (xy 168.847034 -52.888658) (xy 168.832337 -52.948319) (xy 168.810562 -53.005776)
			(xy 168.782026 -53.060192) (xy 168.764966 -53.085746) (xy 168.759535 -53.09441) (xy 168.755489 -53.11444)
			(xy 168.759566 -53.134464) (xy 168.764966 -53.14315) (xy 168.782037 -53.168696) (xy 168.810569 -53.223112)
			(xy 168.832338 -53.280569) (xy 168.847027 -53.34023) (xy 168.854422 -53.401227) (xy 168.854882 -53.431948)
			(xy 168.854489 -53.462681) (xy 168.847075 -53.523698) (xy 168.83236 -53.583377) (xy 168.810559 -53.640847)
			(xy 168.790884 -53.678328) (xy 170.636436 -53.678328) (xy 170.640507 -53.622706) (xy 170.652633 -53.568269)
			(xy 170.672556 -53.516178) (xy 170.699852 -53.467543) (xy 170.733938 -53.4234) (xy 170.774087 -53.384691)
			(xy 170.819445 -53.35224) (xy 170.869045 -53.326739) (xy 170.921829 -53.308732) (xy 170.976672 -53.298602)
			(xy 171.032406 -53.296565) (xy 171.087843 -53.302665) (xy 171.1418 -53.316771) (xy 171.193129 -53.338583)
			(xy 171.240735 -53.367637) (xy 171.283603 -53.403312) (xy 171.32082 -53.444849) (xy 171.351593 -53.491362)
			(xy 171.375265 -53.541859) (xy 171.391333 -53.595266) (xy 171.399453 -53.650442) (xy 171.399962 -53.678328)
			(xy 171.399453 -53.706214) (xy 171.391333 -53.76139) (xy 171.375265 -53.814797) (xy 171.351593 -53.865294)
			(xy 171.32082 -53.911807) (xy 171.283603 -53.953344) (xy 171.240735 -53.989019) (xy 171.193129 -54.018073)
			(xy 171.1418 -54.039885) (xy 171.087843 -54.053991) (xy 171.032406 -54.060091) (xy 170.976672 -54.058054)
			(xy 170.921829 -54.047924) (xy 170.869045 -54.029917) (xy 170.819445 -54.004416) (xy 170.774087 -53.971965)
			(xy 170.733938 -53.933256) (xy 170.699852 -53.889113) (xy 170.672556 -53.840478) (xy 170.652633 -53.788387)
			(xy 170.640507 -53.73395) (xy 170.636436 -53.678328) (xy 168.790884 -53.678328) (xy 168.78199 -53.69527)
			(xy 168.747069 -53.745853) (xy 168.706306 -53.791858) (xy 168.660295 -53.832615) (xy 168.609707 -53.867528)
			(xy 168.55528 -53.896089) (xy 168.497806 -53.917882) (xy 168.438126 -53.932588) (xy 168.377107 -53.939994)
			(xy 168.346374 -53.940456) (xy 168.311107 -53.939821) (xy 168.241256 -53.930021) (xy 168.173432 -53.910654)
			(xy 168.108938 -53.882093) (xy 168.078658 -53.864002) (xy 168.070884 -53.859673) (xy 168.053479 -53.856035)
			(xy 168.044622 -53.85689) (xy 168.015158 -53.861208) (xy 168.006487 -53.86277) (xy 167.990904 -53.870973)
			(xy 167.984678 -53.87721) (xy 167.96401 -53.899119) (xy 167.918335 -53.938386) (xy 167.868343 -53.971984)
			(xy 167.814734 -53.999444) (xy 167.758257 -54.020382) (xy 167.699703 -54.034504) (xy 167.639891 -54.041614)
			(xy 167.609774 -54.042056) (xy 167.579044 -54.041568) (xy 167.518033 -54.034158) (xy 167.45836 -54.019448)
			(xy 167.400895 -53.997653) (xy 167.346475 -53.969091) (xy 167.295895 -53.934178) (xy 167.249891 -53.893424)
			(xy 167.209135 -53.847422) (xy 167.17422 -53.796843) (xy 167.145656 -53.742425) (xy 167.123859 -53.684961)
			(xy 167.109146 -53.625288) (xy 167.101733 -53.564278) (xy 167.101266 -53.533548) (xy 146.889285 -53.533548)
			(xy 146.899532 -53.536227) (xy 146.950861 -53.558039) (xy 146.998467 -53.587093) (xy 147.041335 -53.622768)
			(xy 147.078552 -53.664305) (xy 147.109325 -53.710818) (xy 147.132997 -53.761315) (xy 147.149065 -53.814722)
			(xy 147.157185 -53.869898) (xy 147.157694 -53.897784) (xy 147.157185 -53.92567) (xy 147.149065 -53.980846)
			(xy 147.132997 -54.034253) (xy 147.109325 -54.08475) (xy 147.078552 -54.131263) (xy 147.041335 -54.1728)
			(xy 146.998467 -54.208475) (xy 146.950861 -54.237529) (xy 146.899532 -54.259341) (xy 146.845575 -54.273447)
			(xy 146.790138 -54.279547) (xy 146.734404 -54.27751) (xy 146.679561 -54.26738) (xy 146.626777 -54.249373)
			(xy 146.577177 -54.223872) (xy 146.531819 -54.191421) (xy 146.49167 -54.152712) (xy 146.457584 -54.108569)
			(xy 146.430288 -54.059934) (xy 146.410365 -54.007843) (xy 146.398239 -53.953406) (xy 146.394168 -53.897784)
			(xy 146.154902 -53.897784) (xy 146.154406 -53.925638) (xy 146.146372 -53.980763) (xy 146.130399 -54.034131)
			(xy 146.106828 -54.084606) (xy 146.076161 -54.131112) (xy 146.039052 -54.172659) (xy 146.017996 -54.1909)
			(xy 146.009828 -54.198488) (xy 146.000337 -54.218632) (xy 145.999708 -54.229762) (xy 145.999708 -54.408027)
			(xy 148.898604 -54.408027) (xy 148.898604 -54.344105) (xy 148.906615 -54.280687) (xy 148.922512 -54.218773)
			(xy 148.946044 -54.15934) (xy 148.976838 -54.103325) (xy 149.014411 -54.05161) (xy 149.058168 -54.005013)
			(xy 149.107421 -53.964268) (xy 149.161392 -53.930017) (xy 149.219231 -53.9028) (xy 149.280024 -53.883047)
			(xy 149.342814 -53.871069) (xy 149.40661 -53.867056) (xy 149.470406 -53.871069) (xy 149.533196 -53.883047)
			(xy 149.593989 -53.9028) (xy 149.651828 -53.930017) (xy 149.705799 -53.964268) (xy 149.755052 -54.005013)
			(xy 149.798809 -54.05161) (xy 149.836382 -54.103325) (xy 149.867176 -54.15934) (xy 149.890708 -54.218773)
			(xy 149.906605 -54.280687) (xy 149.914616 -54.344105) (xy 149.915118 -54.376066) (xy 149.914616 -54.408027)
			(xy 149.906605 -54.471445) (xy 149.890708 -54.533359) (xy 149.867176 -54.592792) (xy 149.836382 -54.648807)
			(xy 149.798809 -54.700522) (xy 149.755052 -54.747119) (xy 149.705799 -54.787864) (xy 149.677483 -54.805834)
			(xy 171.760896 -54.805834) (xy 171.76137 -54.775102) (xy 171.768774 -54.714087) (xy 171.78348 -54.654409)
			(xy 171.805272 -54.596939) (xy 171.833833 -54.542515) (xy 171.868746 -54.491931) (xy 171.909502 -54.445924)
			(xy 171.955507 -54.405165) (xy 172.006089 -54.370249) (xy 172.060512 -54.341685) (xy 172.117981 -54.319889)
			(xy 172.177658 -54.30518) (xy 172.238672 -54.297771) (xy 172.269404 -54.297326) (xy 172.300127 -54.297752)
			(xy 172.361124 -54.305157) (xy 172.420785 -54.319858) (xy 172.478239 -54.341641) (xy 172.53265 -54.370189)
			(xy 172.583224 -54.405086) (xy 172.629224 -54.445823) (xy 172.669981 -54.491806) (xy 172.704899 -54.542365)
			(xy 172.73347 -54.596764) (xy 172.755278 -54.654209) (xy 172.770004 -54.713863) (xy 172.777435 -54.774858)
			(xy 172.777912 -54.80558) (xy 172.777912 -54.806088) (xy 172.777658 -54.818788) (xy 172.807205 -54.826761)
			(xy 172.864319 -54.848745) (xy 172.918382 -54.877426) (xy 172.96861 -54.91239) (xy 173.014278 -54.95313)
			(xy 173.054725 -54.999059) (xy 173.089366 -55.04951) (xy 173.117699 -55.103756) (xy 173.139316 -55.16101)
			(xy 173.153903 -55.220446) (xy 173.16125 -55.281202) (xy 173.161706 -55.311802) (xy 173.161246 -55.342533)
			(xy 173.153837 -55.403547) (xy 173.139128 -55.463223) (xy 173.117333 -55.520691) (xy 173.08877 -55.575113)
			(xy 173.053855 -55.625696) (xy 173.013098 -55.671701) (xy 172.967093 -55.712458) (xy 172.91651 -55.747372)
			(xy 172.862088 -55.775935) (xy 172.80462 -55.797729) (xy 172.744943 -55.812438) (xy 172.683929 -55.819846)
			(xy 172.653198 -55.82031) (xy 172.622477 -55.819846) (xy 172.561482 -55.812443) (xy 172.501824 -55.797743)
			(xy 172.444372 -55.775962) (xy 172.389963 -55.747416) (xy 172.33939 -55.712523) (xy 172.293391 -55.671789)
			(xy 172.252634 -55.62581) (xy 172.217715 -55.575255) (xy 172.189143 -55.52086) (xy 172.167333 -55.463419)
			(xy 172.152603 -55.403768) (xy 172.145169 -55.342777) (xy 172.14469 -55.312056) (xy 172.14469 -55.311548)
			(xy 172.144944 -55.298848) (xy 172.11538 -55.290932) (xy 172.058263 -55.268945) (xy 172.004198 -55.240259)
			(xy 171.953968 -55.20529) (xy 171.908299 -55.164544) (xy 171.867853 -55.118609) (xy 171.833214 -55.068151)
			(xy 171.804883 -55.0139) (xy 171.78327 -54.956639) (xy 171.768689 -54.897198) (xy 171.761349 -54.836436)
			(xy 171.760896 -54.805834) (xy 149.677483 -54.805834) (xy 149.651828 -54.822115) (xy 149.593989 -54.849332)
			(xy 149.533196 -54.869085) (xy 149.470406 -54.881063) (xy 149.40661 -54.885077) (xy 149.342814 -54.881063)
			(xy 149.280024 -54.869085) (xy 149.219231 -54.849332) (xy 149.161392 -54.822115) (xy 149.107421 -54.787864)
			(xy 149.058168 -54.747119) (xy 149.014411 -54.700522) (xy 148.976838 -54.648807) (xy 148.946044 -54.592792)
			(xy 148.922512 -54.533359) (xy 148.906615 -54.471445) (xy 148.898604 -54.408027) (xy 145.999708 -54.408027)
			(xy 145.999708 -55.696358) (xy 158.013652 -55.696358) (xy 158.017723 -55.640736) (xy 158.029849 -55.586299)
			(xy 158.049772 -55.534208) (xy 158.077068 -55.485573) (xy 158.111154 -55.44143) (xy 158.151303 -55.402721)
			(xy 158.196661 -55.37027) (xy 158.246261 -55.344769) (xy 158.299045 -55.326762) (xy 158.353888 -55.316632)
			(xy 158.409622 -55.314595) (xy 158.465059 -55.320695) (xy 158.519016 -55.334801) (xy 158.570345 -55.356613)
			(xy 158.617951 -55.385667) (xy 158.660819 -55.421342) (xy 158.698036 -55.462879) (xy 158.728809 -55.509392)
			(xy 158.748446 -55.551281) (xy 170.776386 -55.551281) (xy 170.776386 -55.487359) (xy 170.784397 -55.423941)
			(xy 170.800294 -55.362027) (xy 170.823826 -55.302594) (xy 170.85462 -55.246579) (xy 170.892193 -55.194864)
			(xy 170.93595 -55.148267) (xy 170.985203 -55.107522) (xy 171.039174 -55.073271) (xy 171.097013 -55.046054)
			(xy 171.157806 -55.026301) (xy 171.220596 -55.014323) (xy 171.284392 -55.01031) (xy 171.348188 -55.014323)
			(xy 171.410978 -55.026301) (xy 171.471771 -55.046054) (xy 171.52961 -55.073271) (xy 171.583581 -55.107522)
			(xy 171.632834 -55.148267) (xy 171.676591 -55.194864) (xy 171.714164 -55.246579) (xy 171.744958 -55.302594)
			(xy 171.76849 -55.362027) (xy 171.784387 -55.423941) (xy 171.792398 -55.487359) (xy 171.7929 -55.51932)
			(xy 171.792398 -55.551281) (xy 171.784387 -55.614699) (xy 171.76849 -55.676613) (xy 171.744958 -55.736046)
			(xy 171.714164 -55.792061) (xy 171.676591 -55.843776) (xy 171.632834 -55.890373) (xy 171.583581 -55.931118)
			(xy 171.52961 -55.965369) (xy 171.471771 -55.992586) (xy 171.410978 -56.012339) (xy 171.348188 -56.024317)
			(xy 171.284392 -56.028331) (xy 171.220596 -56.024317) (xy 171.157806 -56.012339) (xy 171.097013 -55.992586)
			(xy 171.039174 -55.965369) (xy 170.985203 -55.931118) (xy 170.93595 -55.890373) (xy 170.892193 -55.843776)
			(xy 170.85462 -55.792061) (xy 170.823826 -55.736046) (xy 170.800294 -55.676613) (xy 170.784397 -55.614699)
			(xy 170.776386 -55.551281) (xy 158.748446 -55.551281) (xy 158.752481 -55.559889) (xy 158.768549 -55.613296)
			(xy 158.776669 -55.668472) (xy 158.777178 -55.696358) (xy 158.776669 -55.724244) (xy 158.768549 -55.77942)
			(xy 158.752481 -55.832827) (xy 158.728809 -55.883324) (xy 158.698036 -55.929837) (xy 158.660819 -55.971374)
			(xy 158.617951 -56.007049) (xy 158.570345 -56.036103) (xy 158.519016 -56.057915) (xy 158.465059 -56.072021)
			(xy 158.409622 -56.078121) (xy 158.353888 -56.076084) (xy 158.299045 -56.065954) (xy 158.246261 -56.047947)
			(xy 158.196661 -56.022446) (xy 158.151303 -55.989995) (xy 158.111154 -55.951286) (xy 158.077068 -55.907143)
			(xy 158.049772 -55.858508) (xy 158.029849 -55.806417) (xy 158.017723 -55.75198) (xy 158.013652 -55.696358)
			(xy 145.999708 -55.696358) (xy 145.999708 -55.909972) (xy 145.999239 -55.933976) (xy 145.991696 -55.981389)
			(xy 145.976823 -56.027037) (xy 145.954986 -56.069792) (xy 145.926725 -56.108602) (xy 145.910046 -56.125872)
			(xy 145.686272 -56.349646) (xy 145.668997 -56.366318) (xy 145.630185 -56.394574) (xy 145.58743 -56.416409)
			(xy 145.541786 -56.431287) (xy 145.494376 -56.43884) (xy 145.470372 -56.439308) (xy 144.983708 -56.439308)
			(xy 144.953482 -56.437784) (xy 144.92351 -56.433212) (xy 144.91462 -56.431434) (xy 144.897348 -56.434228)
			(xy 144.831562 -56.470296) (xy 144.824085 -56.47493) (xy 144.812521 -56.488164) (xy 144.808956 -56.496204)
			(xy 144.808702 -56.496204) (xy 144.808702 -56.496712) (xy 144.798642 -56.521583) (xy 144.772136 -56.568225)
			(xy 144.738934 -56.610364) (xy 144.699786 -56.647046) (xy 144.655579 -56.677441) (xy 144.607313 -56.70086)
			(xy 144.55608 -56.716775) (xy 144.50304 -56.724825) (xy 144.476216 -56.725312) (xy 144.448231 -56.724773)
			(xy 144.392951 -56.716019) (xy 144.33972 -56.698726) (xy 144.28985 -56.673318) (xy 144.244569 -56.640422)
			(xy 144.204991 -56.600846) (xy 144.172092 -56.555567) (xy 144.146682 -56.505699) (xy 144.129385 -56.452469)
			(xy 144.120629 -56.397189) (xy 144.120108 -56.369204) (xy 144.120501 -56.344241) (xy 144.12747 -56.294805)
			(xy 144.141271 -56.246825) (xy 144.161635 -56.201241) (xy 144.188163 -56.158947) (xy 144.203928 -56.139588)
			(xy 144.209894 -56.131916) (xy 144.216029 -56.113492) (xy 144.215866 -56.103774) (xy 144.21358 -56.07177)
			(xy 144.212584 -56.062145) (xy 144.204345 -56.044652) (xy 144.197578 -56.037734) (xy 144.18945 -56.030114)
			(xy 143.292576 -55.133494) (xy 143.285179 -55.12665) (xy 143.266577 -55.118933) (xy 143.256508 -55.118508)
			(xy 139.986512 -55.118508) (xy 139.977965 -55.118833) (xy 139.961823 -55.124457) (xy 139.948434 -55.135084)
			(xy 139.943586 -55.14213) (xy 139.897866 -55.214774) (xy 139.893531 -55.222226) (xy 139.889688 -55.239024)
			(xy 139.891625 -55.256146) (xy 139.895072 -55.26405) (xy 139.907025 -55.289861) (xy 139.925753 -55.343575)
			(xy 139.938369 -55.399042) (xy 139.944716 -55.455572) (xy 139.94511 -55.484014) (xy 139.944608 -55.515975)
			(xy 139.936597 -55.579393) (xy 139.9207 -55.641307) (xy 139.897168 -55.70074) (xy 139.866374 -55.756755)
			(xy 139.828801 -55.80847) (xy 139.785044 -55.855067) (xy 139.735791 -55.895812) (xy 139.68182 -55.930063)
			(xy 139.623981 -55.95728) (xy 139.563188 -55.977033) (xy 139.500398 -55.989011) (xy 139.436602 -55.993025)
			(xy 139.372806 -55.989011) (xy 139.310016 -55.977033) (xy 139.249223 -55.95728) (xy 139.191384 -55.930063)
			(xy 139.137413 -55.895812) (xy 139.08816 -55.855067) (xy 139.044403 -55.80847) (xy 139.00683 -55.756755)
			(xy 138.976036 -55.70074) (xy 138.952504 -55.641307) (xy 138.936607 -55.579393) (xy 138.928596 -55.515975)
			(xy 138.928094 -55.484014) (xy 138.928495 -55.455572) (xy 138.934842 -55.399044) (xy 138.947458 -55.343577)
			(xy 138.966186 -55.289864) (xy 138.978132 -55.26405) (xy 138.98157 -55.256143) (xy 138.983514 -55.239025)
			(xy 138.979659 -55.222234) (xy 138.975338 -55.214774) (xy 138.929618 -55.14213) (xy 138.924768 -55.135085)
			(xy 138.911379 -55.124459) (xy 138.895239 -55.118833) (xy 138.886692 -55.118508) (xy 137.480802 -55.118508)
			(xy 137.476329 -55.118415) (xy 137.467516 -55.116885) (xy 137.463276 -55.11546) (xy 137.422128 -55.10022)
			(xy 137.42162 -55.10022) (xy 137.401022 -55.093348) (xy 137.358239 -55.085947) (xy 137.33653 -55.085488)
			(xy 137.314821 -55.085937) (xy 137.272039 -55.093351) (xy 137.25144 -55.10022) (xy 137.250932 -55.10022)
			(xy 137.209784 -55.11546) (xy 137.205552 -55.116915) (xy 137.196733 -55.118441) (xy 137.192258 -55.118508)
			(xy 136.041892 -55.118508) (xy 136.031822 -55.118927) (xy 136.013224 -55.126652) (xy 136.005824 -55.133494)
			(xy 134.639304 -56.500014) (xy 137.035284 -56.500014) (xy 137.039355 -56.444392) (xy 137.051481 -56.389955)
			(xy 137.071404 -56.337864) (xy 137.0987 -56.289229) (xy 137.132786 -56.245086) (xy 137.172935 -56.206377)
			(xy 137.218293 -56.173926) (xy 137.267893 -56.148425) (xy 137.320677 -56.130418) (xy 137.37552 -56.120288)
			(xy 137.431254 -56.118251) (xy 137.486691 -56.124351) (xy 137.540648 -56.138457) (xy 137.591977 -56.160269)
			(xy 137.639583 -56.189323) (xy 137.682451 -56.224998) (xy 137.719668 -56.266535) (xy 137.750441 -56.313048)
			(xy 137.774113 -56.363545) (xy 137.790181 -56.416952) (xy 137.798301 -56.472128) (xy 137.79881 -56.500014)
			(xy 137.798301 -56.5279) (xy 137.790181 -56.583076) (xy 137.774113 -56.636483) (xy 137.750441 -56.68698)
			(xy 137.719668 -56.733493) (xy 137.682451 -56.77503) (xy 137.639583 -56.810705) (xy 137.591977 -56.839759)
			(xy 137.540648 -56.861571) (xy 137.486691 -56.875677) (xy 137.431254 -56.881777) (xy 137.37552 -56.87974)
			(xy 137.320677 -56.86961) (xy 137.267893 -56.851603) (xy 137.218293 -56.826102) (xy 137.172935 -56.793651)
			(xy 137.132786 -56.754942) (xy 137.0987 -56.710799) (xy 137.071404 -56.662164) (xy 137.051481 -56.610073)
			(xy 137.039355 -56.555636) (xy 137.035284 -56.500014) (xy 134.639304 -56.500014) (xy 133.975137 -57.164181)
			(xy 135.198352 -57.164181) (xy 135.198352 -57.100259) (xy 135.206363 -57.036841) (xy 135.22226 -56.974927)
			(xy 135.245792 -56.915494) (xy 135.276586 -56.859479) (xy 135.314159 -56.807764) (xy 135.357916 -56.761167)
			(xy 135.407169 -56.720422) (xy 135.46114 -56.686171) (xy 135.518979 -56.658954) (xy 135.579772 -56.639201)
			(xy 135.642562 -56.627223) (xy 135.706358 -56.62321) (xy 135.770154 -56.627223) (xy 135.832944 -56.639201)
			(xy 135.893737 -56.658954) (xy 135.951576 -56.686171) (xy 136.005547 -56.720422) (xy 136.0548 -56.761167)
			(xy 136.098557 -56.807764) (xy 136.13613 -56.859479) (xy 136.166924 -56.915494) (xy 136.190456 -56.974927)
			(xy 136.206353 -57.036841) (xy 136.214364 -57.100259) (xy 136.214866 -57.13222) (xy 136.214364 -57.164181)
			(xy 136.206353 -57.227599) (xy 136.190456 -57.289513) (xy 136.166924 -57.348946) (xy 136.13613 -57.404961)
			(xy 136.098557 -57.456676) (xy 136.0548 -57.503273) (xy 136.005547 -57.544018) (xy 135.951576 -57.578269)
			(xy 135.893737 -57.605486) (xy 135.832944 -57.625239) (xy 135.770154 -57.637217) (xy 135.706358 -57.641231)
			(xy 135.642562 -57.637217) (xy 135.579772 -57.625239) (xy 135.518979 -57.605486) (xy 135.46114 -57.578269)
			(xy 135.407169 -57.544018) (xy 135.357916 -57.503273) (xy 135.314159 -57.456676) (xy 135.276586 -57.404961)
			(xy 135.245792 -57.348946) (xy 135.22226 -57.289513) (xy 135.206363 -57.227599) (xy 135.198352 -57.164181)
			(xy 133.975137 -57.164181) (xy 133.722872 -57.416446) (xy 133.705597 -57.433118) (xy 133.666785 -57.461374)
			(xy 133.62403 -57.483209) (xy 133.578386 -57.498087) (xy 133.530976 -57.50564) (xy 133.506972 -57.506108)
			(xy 130.31978 -57.506108) (xy 130.295299 -57.505605) (xy 130.246979 -57.497693) (xy 130.200535 -57.482186)
			(xy 130.157155 -57.459479) (xy 130.117944 -57.430153) (xy 130.100578 -57.41289) (xy 130.098292 -57.41035)
			(xy 130.086808 -57.420923) (xy 130.062394 -57.440379) (xy 130.049524 -57.449212) (xy 130.039521 -57.456752)
			(xy 130.027808 -57.478865) (xy 130.027172 -57.491376) (xy 130.027172 -57.522872) (xy 130.027829 -57.535417)
			(xy 130.039706 -57.557524) (xy 130.049778 -57.565036) (xy 130.071697 -57.580329) (xy 130.111474 -57.616024)
			(xy 130.145885 -57.656917) (xy 130.174257 -57.702209) (xy 130.196035 -57.751016) (xy 130.210793 -57.802382)
			(xy 130.218242 -57.855306) (xy 130.218688 -57.882028) (xy 130.218202 -57.909279) (xy 130.217525 -57.913989)
			(xy 136.299696 -57.913989) (xy 136.299696 -57.850067) (xy 136.307707 -57.786649) (xy 136.323604 -57.724735)
			(xy 136.347136 -57.665302) (xy 136.37793 -57.609287) (xy 136.415503 -57.557572) (xy 136.45926 -57.510975)
			(xy 136.508513 -57.47023) (xy 136.562484 -57.435979) (xy 136.620323 -57.408762) (xy 136.681116 -57.389009)
			(xy 136.743906 -57.377031) (xy 136.807702 -57.373018) (xy 136.871498 -57.377031) (xy 136.934288 -57.389009)
			(xy 136.995081 -57.408762) (xy 137.05292 -57.435979) (xy 137.106891 -57.47023) (xy 137.156144 -57.510975)
			(xy 137.199901 -57.557572) (xy 137.237474 -57.609287) (xy 137.268268 -57.665302) (xy 137.2918 -57.724735)
			(xy 137.307697 -57.786649) (xy 137.313906 -57.8358) (xy 140.105382 -57.8358) (xy 140.109453 -57.780178)
			(xy 140.121579 -57.725741) (xy 140.141502 -57.67365) (xy 140.168798 -57.625015) (xy 140.202884 -57.580872)
			(xy 140.243033 -57.542163) (xy 140.288391 -57.509712) (xy 140.337991 -57.484211) (xy 140.390775 -57.466204)
			(xy 140.445618 -57.456074) (xy 140.501352 -57.454037) (xy 140.556789 -57.460137) (xy 140.610746 -57.474243)
			(xy 140.662075 -57.496055) (xy 140.709681 -57.525109) (xy 140.752549 -57.560784) (xy 140.789766 -57.602321)
			(xy 140.820539 -57.648834) (xy 140.844211 -57.699331) (xy 140.860279 -57.752738) (xy 140.868399 -57.807914)
			(xy 140.868908 -57.8358) (xy 140.868399 -57.863686) (xy 140.860279 -57.918862) (xy 140.844211 -57.972269)
			(xy 140.820539 -58.022766) (xy 140.797867 -58.057034) (xy 144.170908 -58.057034) (xy 144.171341 -58.03102)
			(xy 144.178901 -57.979544) (xy 144.193878 -57.929719) (xy 144.215955 -57.882606) (xy 144.244658 -57.839213)
			(xy 144.279377 -57.800464) (xy 144.319371 -57.767185) (xy 144.341342 -57.75325) (xy 144.353775 -57.745054)
			(xy 144.373652 -57.722898) (xy 144.386296 -57.695952) (xy 144.390635 -57.666505) (xy 144.386299 -57.637057)
			(xy 144.373657 -57.61011) (xy 144.353783 -57.587952) (xy 144.341342 -57.579768) (xy 144.31942 -57.565764)
			(xy 144.279445 -57.532484) (xy 144.244738 -57.49374) (xy 144.21604 -57.450357) (xy 144.19396 -57.403261)
			(xy 144.17897 -57.353452) (xy 144.171388 -57.301992) (xy 144.170908 -57.275984) (xy 144.171406 -57.249335)
			(xy 144.179349 -57.196631) (xy 144.195059 -57.145701) (xy 144.218185 -57.09768) (xy 144.248209 -57.053643)
			(xy 144.284461 -57.014572) (xy 144.326132 -56.981341) (xy 144.37229 -56.954692) (xy 144.421904 -56.93522)
			(xy 144.473866 -56.92336) (xy 144.527016 -56.919377) (xy 144.580166 -56.92336) (xy 144.632128 -56.93522)
			(xy 144.681742 -56.954692) (xy 144.7279 -56.981341) (xy 144.769571 -57.014572) (xy 144.805823 -57.053643)
			(xy 144.835847 -57.09768) (xy 144.858973 -57.145701) (xy 144.874683 -57.196631) (xy 144.882626 -57.249335)
			(xy 144.883124 -57.275984) (xy 147.514056 -57.275984) (xy 147.514524 -57.243786) (xy 147.522649 -57.179904)
			(xy 147.53878 -57.117561) (xy 147.562657 -57.057756) (xy 147.593899 -57.001446) (xy 147.632005 -56.949534)
			(xy 147.676364 -56.902853) (xy 147.726265 -56.86215) (xy 147.753324 -56.844692) (xy 147.760379 -56.839828)
			(xy 147.771085 -56.826462) (xy 147.776816 -56.810326) (xy 147.7772 -56.801766) (xy 147.7772 -56.715152)
			(xy 147.776907 -56.706574) (xy 147.771196 -56.690396) (xy 147.760439 -56.677031) (xy 147.753324 -56.672226)
			(xy 147.726264 -56.654774) (xy 147.676378 -56.614059) (xy 147.632032 -56.56737) (xy 147.593936 -56.515456)
			(xy 147.5627 -56.459147) (xy 147.538823 -56.399345) (xy 147.522689 -56.337007) (xy 147.514554 -56.27313)
			(xy 147.514056 -56.240934) (xy 147.514588 -56.210205) (xy 147.521992 -56.149195) (xy 147.536696 -56.089522)
			(xy 147.558485 -56.032057) (xy 147.587042 -55.977637) (xy 147.621951 -55.927055) (xy 147.662701 -55.881051)
			(xy 147.7087 -55.840294) (xy 147.759277 -55.805378) (xy 147.813693 -55.776814) (xy 147.871155 -55.755016)
			(xy 147.930826 -55.740304) (xy 147.991835 -55.732892) (xy 148.022564 -55.732426) (xy 148.055381 -55.732959)
			(xy 148.12047 -55.741411) (xy 148.183929 -55.758167) (xy 148.244706 -55.782948) (xy 148.30179 -55.815343)
			(xy 148.354231 -55.854812) (xy 148.401159 -55.9007) (xy 148.441793 -55.952244) (xy 148.475458 -56.008587)
			(xy 148.501595 -56.068794) (xy 148.519768 -56.131862) (xy 148.52523 -56.164226) (xy 148.527111 -56.173639)
			(xy 148.536758 -56.190216) (xy 148.544026 -56.196484) (xy 148.554074 -56.204358) (xy 149.110698 -56.204358)
			(xy 149.114769 -56.148736) (xy 149.126895 -56.094299) (xy 149.146818 -56.042208) (xy 149.174114 -55.993573)
			(xy 149.2082 -55.94943) (xy 149.248349 -55.910721) (xy 149.293707 -55.87827) (xy 149.343307 -55.852769)
			(xy 149.396091 -55.834762) (xy 149.450934 -55.824632) (xy 149.506668 -55.822595) (xy 149.562105 -55.828695)
			(xy 149.616062 -55.842801) (xy 149.667391 -55.864613) (xy 149.714997 -55.893667) (xy 149.757865 -55.929342)
			(xy 149.795082 -55.970879) (xy 149.825855 -56.017392) (xy 149.849527 -56.067889) (xy 149.865595 -56.121296)
			(xy 149.873715 -56.176472) (xy 149.874224 -56.204358) (xy 149.873715 -56.232244) (xy 149.865595 -56.28742)
			(xy 149.849527 -56.340827) (xy 149.825855 -56.391324) (xy 149.795082 -56.437837) (xy 149.757865 -56.479374)
			(xy 149.714997 -56.515049) (xy 149.66888 -56.543194) (xy 154.007818 -56.543194) (xy 154.011889 -56.487572)
			(xy 154.024015 -56.433135) (xy 154.043938 -56.381044) (xy 154.071234 -56.332409) (xy 154.10532 -56.288266)
			(xy 154.145469 -56.249557) (xy 154.190827 -56.217106) (xy 154.240427 -56.191605) (xy 154.293211 -56.173598)
			(xy 154.348054 -56.163468) (xy 154.403788 -56.161431) (xy 154.459225 -56.167531) (xy 154.513182 -56.181637)
			(xy 154.564511 -56.203449) (xy 154.612117 -56.232503) (xy 154.654985 -56.268178) (xy 154.692202 -56.309715)
			(xy 154.722975 -56.356228) (xy 154.746647 -56.406725) (xy 154.762715 -56.460132) (xy 154.770835 -56.515308)
			(xy 154.771344 -56.543194) (xy 154.770835 -56.57108) (xy 154.762715 -56.626256) (xy 154.746647 -56.679663)
			(xy 154.722975 -56.73016) (xy 154.692202 -56.776673) (xy 154.654985 -56.81821) (xy 154.612117 -56.853885)
			(xy 154.564511 -56.882939) (xy 154.513182 -56.904751) (xy 154.459225 -56.918857) (xy 154.403788 -56.924957)
			(xy 154.348054 -56.92292) (xy 154.293211 -56.91279) (xy 154.240427 -56.894783) (xy 154.190827 -56.869282)
			(xy 154.145469 -56.836831) (xy 154.10532 -56.798122) (xy 154.071234 -56.753979) (xy 154.043938 -56.705344)
			(xy 154.024015 -56.653253) (xy 154.011889 -56.598816) (xy 154.007818 -56.543194) (xy 149.66888 -56.543194)
			(xy 149.667391 -56.544103) (xy 149.616062 -56.565915) (xy 149.562105 -56.580021) (xy 149.506668 -56.586121)
			(xy 149.450934 -56.584084) (xy 149.396091 -56.573954) (xy 149.343307 -56.555947) (xy 149.293707 -56.530446)
			(xy 149.248349 -56.497995) (xy 149.2082 -56.459286) (xy 149.174114 -56.415143) (xy 149.146818 -56.366508)
			(xy 149.126895 -56.314417) (xy 149.114769 -56.25998) (xy 149.110698 -56.204358) (xy 148.554074 -56.204358)
			(xy 148.606256 -56.245252) (xy 148.62429 -56.25084) (xy 148.633942 -56.250078) (xy 148.66493 -56.248808)
			(xy 148.665184 -56.248808) (xy 148.692439 -56.249238) (xy 148.746394 -56.256993) (xy 148.798696 -56.272349)
			(xy 148.84828 -56.294991) (xy 148.894137 -56.32446) (xy 148.935334 -56.360155) (xy 148.97103 -56.40135)
			(xy 149.000501 -56.447206) (xy 149.023146 -56.496789) (xy 149.038503 -56.549091) (xy 149.046261 -56.603045)
			(xy 149.046261 -56.657555) (xy 149.038503 -56.711509) (xy 149.023146 -56.763811) (xy 149.000501 -56.813394)
			(xy 148.97103 -56.85925) (xy 148.935334 -56.900445) (xy 148.894137 -56.93614) (xy 148.84828 -56.965609)
			(xy 148.798696 -56.988251) (xy 148.746394 -57.003607) (xy 148.692439 -57.011362) (xy 148.665184 -57.011824)
			(xy 148.654237 -57.01174) (xy 148.632379 -57.010468) (xy 148.621496 -57.009284) (xy 148.608978 -57.008495)
			(xy 148.585674 -57.017704) (xy 148.577046 -57.02681) (xy 148.560624 -57.046045) (xy 170.841501 -57.046045)
			(xy 170.845807 -56.957689) (xy 170.857969 -56.870068) (xy 170.87789 -56.783879) (xy 170.905411 -56.699808)
			(xy 170.940314 -56.618523) (xy 170.982321 -56.540672) (xy 171.031097 -56.466873) (xy 171.086256 -56.397714)
			(xy 171.147357 -56.333745) (xy 171.213914 -56.275475) (xy 171.2854 -56.223367) (xy 171.361243 -56.177836)
			(xy 171.440843 -56.139243) (xy 171.523564 -56.107897) (xy 171.608749 -56.084047) (xy 171.695721 -56.067881)
			(xy 171.783787 -56.059529) (xy 171.872247 -56.059057) (xy 171.960397 -56.06647) (xy 172.047536 -56.081707)
			(xy 172.13297 -56.104648) (xy 172.216021 -56.13511) (xy 172.296027 -56.172851) (xy 172.372353 -56.217571)
			(xy 172.444389 -56.268914) (xy 172.511565 -56.326471) (xy 172.573345 -56.389785) (xy 172.629237 -56.458351)
			(xy 172.678798 -56.531626) (xy 172.721633 -56.609024) (xy 172.7574 -56.689932) (xy 172.77207 -56.731662)
			(xy 172.777354 -56.745495) (xy 172.794501 -56.769615) (xy 172.817842 -56.787808) (xy 172.84542 -56.798546)
			(xy 172.874918 -56.800927) (xy 172.903861 -56.794751) (xy 172.929818 -56.780538) (xy 172.950611 -56.759479)
			(xy 172.957998 -56.746648) (xy 172.972343 -56.72083) (xy 173.00774 -56.673554) (xy 173.049998 -56.632295)
			(xy 173.098107 -56.598039) (xy 173.150919 -56.571602) (xy 173.207173 -56.553617) (xy 173.265526 -56.544512)
			(xy 173.295056 -56.543956) (xy 173.322308 -56.544488) (xy 173.376259 -56.552239) (xy 173.428557 -56.56759)
			(xy 173.478138 -56.590228) (xy 173.523992 -56.619692) (xy 173.565186 -56.655382) (xy 173.600882 -56.696572)
			(xy 173.630351 -56.742423) (xy 173.652994 -56.792002) (xy 173.668351 -56.844298) (xy 173.676109 -56.898248)
			(xy 173.676109 -56.952752) (xy 173.668351 -57.006702) (xy 173.652994 -57.058998) (xy 173.630351 -57.108577)
			(xy 173.600882 -57.154428) (xy 173.565186 -57.195618) (xy 173.523992 -57.231308) (xy 173.478138 -57.260772)
			(xy 173.428557 -57.28341) (xy 173.376259 -57.298761) (xy 173.322308 -57.306512) (xy 173.295056 -57.306972)
			(xy 173.266004 -57.306405) (xy 173.208568 -57.297614) (xy 173.153131 -57.280211) (xy 173.100976 -57.2546)
			(xy 173.05331 -57.221373) (xy 173.011236 -57.181299) (xy 172.99305 -57.158636) (xy 172.983664 -57.147192)
			(xy 172.959599 -57.129972) (xy 172.93161 -57.120371) (xy 172.902043 -57.119192) (xy 172.873378 -57.126536)
			(xy 172.848019 -57.141785) (xy 172.828094 -57.163662) (xy 172.815273 -57.190331) (xy 172.812456 -57.204864)
			(xy 172.805066 -57.248476) (xy 172.783525 -57.334274) (xy 172.754425 -57.417812) (xy 172.717996 -57.498424)
			(xy 172.67453 -57.57547) (xy 172.624372 -57.648337) (xy 172.567921 -57.716444) (xy 172.505625 -57.779251)
			(xy 172.437982 -57.836257) (xy 172.365527 -57.887009) (xy 172.288839 -57.931103) (xy 172.25155 -57.948322)
			(xy 210.524342 -57.948322) (xy 210.528413 -57.8927) (xy 210.540539 -57.838263) (xy 210.560462 -57.786172)
			(xy 210.587758 -57.737537) (xy 210.621844 -57.693394) (xy 210.661993 -57.654685) (xy 210.707351 -57.622234)
			(xy 210.756951 -57.596733) (xy 210.809735 -57.578726) (xy 210.864578 -57.568596) (xy 210.920312 -57.566559)
			(xy 210.975749 -57.572659) (xy 211.029706 -57.586765) (xy 211.081035 -57.608577) (xy 211.128641 -57.637631)
			(xy 211.171509 -57.673306) (xy 211.208726 -57.714843) (xy 211.239499 -57.761356) (xy 211.263171 -57.811853)
			(xy 211.279239 -57.86526) (xy 211.287359 -57.920436) (xy 211.287868 -57.948322) (xy 211.287359 -57.976208)
			(xy 211.279239 -58.031384) (xy 211.263171 -58.084791) (xy 211.239499 -58.135288) (xy 211.208726 -58.181801)
			(xy 211.171509 -58.223338) (xy 211.128641 -58.259013) (xy 211.081035 -58.288067) (xy 211.029706 -58.309879)
			(xy 210.975749 -58.323985) (xy 210.920312 -58.330085) (xy 210.864578 -58.328048) (xy 210.809735 -58.317918)
			(xy 210.756951 -58.299911) (xy 210.707351 -58.27441) (xy 210.661993 -58.241959) (xy 210.621844 -58.20325)
			(xy 210.587758 -58.159107) (xy 210.560462 -58.110472) (xy 210.540539 -58.058381) (xy 210.528413 -58.003944)
			(xy 210.524342 -57.948322) (xy 172.25155 -57.948322) (xy 172.208527 -57.968189) (xy 172.12523 -57.997971)
			(xy 172.039611 -58.020213) (xy 171.95235 -58.034737) (xy 171.864142 -58.041428) (xy 171.775689 -58.040233)
			(xy 171.687694 -58.031161) (xy 171.600858 -58.014285) (xy 171.51587 -57.989739) (xy 171.433408 -57.957717)
			(xy 171.354127 -57.918475) (xy 171.278658 -57.872326) (xy 171.207601 -57.819635) (xy 171.141522 -57.760822)
			(xy 171.080946 -57.696356) (xy 171.026355 -57.626748) (xy 170.978184 -57.552553) (xy 170.936815 -57.474361)
			(xy 170.902578 -57.392794) (xy 170.875745 -57.3085) (xy 170.856529 -57.222151) (xy 170.845084 -57.134434)
			(xy 170.841501 -57.046045) (xy 148.560624 -57.046045) (xy 148.522182 -57.091072) (xy 148.514551 -57.101054)
			(xy 148.509202 -57.125566) (xy 148.512022 -57.137808) (xy 148.520914 -57.171529) (xy 148.530477 -57.240608)
			(xy 148.531072 -57.275476) (xy 148.531072 -57.275984) (xy 148.53057 -57.307945) (xy 148.522559 -57.371363)
			(xy 148.506662 -57.433277) (xy 148.48313 -57.49271) (xy 148.452336 -57.548725) (xy 148.414763 -57.60044)
			(xy 148.371006 -57.647037) (xy 148.345165 -57.668414) (xy 155.171138 -57.668414) (xy 155.175209 -57.612792)
			(xy 155.187335 -57.558355) (xy 155.207258 -57.506264) (xy 155.234554 -57.457629) (xy 155.26864 -57.413486)
			(xy 155.308789 -57.374777) (xy 155.354147 -57.342326) (xy 155.403747 -57.316825) (xy 155.456531 -57.298818)
			(xy 155.511374 -57.288688) (xy 155.567108 -57.286651) (xy 155.622545 -57.292751) (xy 155.676502 -57.306857)
			(xy 155.727831 -57.328669) (xy 155.775437 -57.357723) (xy 155.818305 -57.393398) (xy 155.855522 -57.434935)
			(xy 155.886295 -57.481448) (xy 155.909967 -57.531945) (xy 155.926035 -57.585352) (xy 155.934155 -57.640528)
			(xy 155.934664 -57.668414) (xy 155.934155 -57.6963) (xy 155.926035 -57.751476) (xy 155.909967 -57.804883)
			(xy 155.886295 -57.85538) (xy 155.855522 -57.901893) (xy 155.818305 -57.94343) (xy 155.775437 -57.979105)
			(xy 155.727831 -58.008159) (xy 155.676502 -58.029971) (xy 155.622545 -58.044077) (xy 155.567108 -58.050177)
			(xy 155.511374 -58.04814) (xy 155.456531 -58.03801) (xy 155.403747 -58.020003) (xy 155.354147 -57.994502)
			(xy 155.308789 -57.962051) (xy 155.26864 -57.923342) (xy 155.234554 -57.879199) (xy 155.207258 -57.830564)
			(xy 155.187335 -57.778473) (xy 155.175209 -57.724036) (xy 155.171138 -57.668414) (xy 148.345165 -57.668414)
			(xy 148.321753 -57.687782) (xy 148.267782 -57.722033) (xy 148.209943 -57.74925) (xy 148.14915 -57.769003)
			(xy 148.08636 -57.780981) (xy 148.022564 -57.784995) (xy 147.958768 -57.780981) (xy 147.895978 -57.769003)
			(xy 147.835185 -57.74925) (xy 147.777346 -57.722033) (xy 147.723375 -57.687782) (xy 147.674122 -57.647037)
			(xy 147.630365 -57.60044) (xy 147.592792 -57.548725) (xy 147.561998 -57.49271) (xy 147.538466 -57.433277)
			(xy 147.522569 -57.371363) (xy 147.514558 -57.307945) (xy 147.514056 -57.275984) (xy 144.883124 -57.275984)
			(xy 144.88269 -57.301998) (xy 144.875128 -57.353473) (xy 144.86015 -57.403298) (xy 144.838073 -57.450409)
			(xy 144.80937 -57.493803) (xy 144.774652 -57.532552) (xy 144.734661 -57.565832) (xy 144.71269 -57.579768)
			(xy 144.700286 -57.587972) (xy 144.680499 -57.610158) (xy 144.667918 -57.637092) (xy 144.663604 -57.666505)
			(xy 144.667921 -57.695917) (xy 144.680504 -57.72285) (xy 144.700293 -57.745034) (xy 144.71269 -57.75325)
			(xy 144.734628 -57.76723) (xy 144.774601 -57.800516) (xy 144.809305 -57.839264) (xy 144.838001 -57.882651)
			(xy 144.860078 -57.929751) (xy 144.875066 -57.979563) (xy 144.882645 -58.031025) (xy 144.883124 -58.057034)
			(xy 144.882626 -58.083683) (xy 144.874683 -58.136387) (xy 144.858973 -58.187317) (xy 144.835847 -58.235338)
			(xy 144.835152 -58.236358) (xy 149.110698 -58.236358) (xy 149.114769 -58.180736) (xy 149.126895 -58.126299)
			(xy 149.146818 -58.074208) (xy 149.174114 -58.025573) (xy 149.2082 -57.98143) (xy 149.248349 -57.942721)
			(xy 149.293707 -57.91027) (xy 149.343307 -57.884769) (xy 149.396091 -57.866762) (xy 149.450934 -57.856632)
			(xy 149.506668 -57.854595) (xy 149.562105 -57.860695) (xy 149.616062 -57.874801) (xy 149.667391 -57.896613)
			(xy 149.714997 -57.925667) (xy 149.757865 -57.961342) (xy 149.795082 -58.002879) (xy 149.825855 -58.049392)
			(xy 149.849527 -58.099889) (xy 149.865595 -58.153296) (xy 149.873715 -58.208472) (xy 149.874224 -58.236358)
			(xy 149.873715 -58.264244) (xy 149.865595 -58.31942) (xy 149.849527 -58.372827) (xy 149.825855 -58.423324)
			(xy 149.807749 -58.450691) (xy 152.787598 -58.450691) (xy 152.787598 -58.386769) (xy 152.795609 -58.323351)
			(xy 152.811506 -58.261437) (xy 152.835038 -58.202004) (xy 152.865832 -58.145989) (xy 152.903405 -58.094274)
			(xy 152.947162 -58.047677) (xy 152.996415 -58.006932) (xy 153.050386 -57.972681) (xy 153.108225 -57.945464)
			(xy 153.169018 -57.925711) (xy 153.231808 -57.913733) (xy 153.295604 -57.90972) (xy 153.3594 -57.913733)
			(xy 153.42219 -57.925711) (xy 153.482983 -57.945464) (xy 153.540822 -57.972681) (xy 153.594793 -58.006932)
			(xy 153.644046 -58.047677) (xy 153.687803 -58.094274) (xy 153.698793 -58.1094) (xy 157.086547 -58.1094)
			(xy 157.090561 -58.045601) (xy 157.102539 -57.982808) (xy 157.122292 -57.922012) (xy 157.149509 -57.864171)
			(xy 157.183761 -57.810196) (xy 157.224507 -57.76094) (xy 157.271105 -57.717179) (xy 157.32282 -57.679603)
			(xy 157.378836 -57.648805) (xy 157.438271 -57.62527) (xy 157.500187 -57.609369) (xy 157.563608 -57.601354)
			(xy 157.59557 -57.60085) (xy 157.629129 -57.601367) (xy 157.69566 -57.610216) (xy 157.76045 -57.627738)
			(xy 157.822373 -57.653627) (xy 157.880353 -57.687436) (xy 157.920606 -57.718663) (xy 162.07333 -57.718663)
			(xy 162.07333 -57.654741) (xy 162.081341 -57.591323) (xy 162.097238 -57.529409) (xy 162.12077 -57.469976)
			(xy 162.151564 -57.413961) (xy 162.189137 -57.362246) (xy 162.232894 -57.315649) (xy 162.282147 -57.274904)
			(xy 162.336118 -57.240653) (xy 162.393957 -57.213436) (xy 162.45475 -57.193683) (xy 162.51754 -57.181705)
			(xy 162.581336 -57.177692) (xy 162.645132 -57.181705) (xy 162.707922 -57.193683) (xy 162.768715 -57.213436)
			(xy 162.826554 -57.240653) (xy 162.880525 -57.274904) (xy 162.929778 -57.315649) (xy 162.973535 -57.362246)
			(xy 163.011108 -57.413961) (xy 163.041902 -57.469976) (xy 163.065434 -57.529409) (xy 163.081331 -57.591323)
			(xy 163.089342 -57.654741) (xy 163.089844 -57.686702) (xy 163.089342 -57.718663) (xy 163.081331 -57.782081)
			(xy 163.065434 -57.843995) (xy 163.041902 -57.903428) (xy 163.011108 -57.959443) (xy 162.973535 -58.011158)
			(xy 162.929778 -58.057755) (xy 162.880525 -58.0985) (xy 162.826554 -58.132751) (xy 162.768715 -58.159968)
			(xy 162.707922 -58.179721) (xy 162.645132 -58.191699) (xy 162.581336 -58.195713) (xy 162.51754 -58.191699)
			(xy 162.45475 -58.179721) (xy 162.393957 -58.159968) (xy 162.336118 -58.132751) (xy 162.282147 -58.0985)
			(xy 162.232894 -58.057755) (xy 162.189137 -58.011158) (xy 162.151564 -57.959443) (xy 162.12077 -57.903428)
			(xy 162.097238 -57.843995) (xy 162.081341 -57.782081) (xy 162.07333 -57.718663) (xy 157.920606 -57.718663)
			(xy 157.933384 -57.728576) (xy 157.980544 -57.776332) (xy 158.001208 -57.80278) (xy 158.007888 -57.810761)
			(xy 158.025976 -57.821004) (xy 158.03626 -57.822592) (xy 158.109666 -57.830974) (xy 158.12009 -57.831605)
			(xy 158.140021 -57.825436) (xy 158.148274 -57.819036) (xy 158.169047 -57.801883) (xy 158.214549 -57.773043)
			(xy 158.263658 -57.750896) (xy 158.315397 -57.735886) (xy 158.368734 -57.72831) (xy 158.39567 -57.72785)
			(xy 158.422921 -57.728395) (xy 158.476869 -57.736148) (xy 158.529165 -57.7515) (xy 158.578744 -57.774138)
			(xy 158.624595 -57.803602) (xy 158.665787 -57.839292) (xy 158.70148 -57.88048) (xy 158.730948 -57.92633)
			(xy 158.75359 -57.975907) (xy 158.768946 -58.028201) (xy 158.776703 -58.082149) (xy 158.776703 -58.136651)
			(xy 158.768946 -58.190599) (xy 158.75359 -58.242893) (xy 158.730948 -58.29247) (xy 158.70148 -58.33832)
			(xy 158.665787 -58.379508) (xy 158.624595 -58.415198) (xy 158.622959 -58.416249) (xy 216.07959 -58.416249)
			(xy 216.07959 -58.361751) (xy 216.087346 -58.307807) (xy 216.102699 -58.255515) (xy 216.125338 -58.205941)
			(xy 216.154801 -58.160093) (xy 216.190489 -58.118905) (xy 216.231676 -58.083215) (xy 216.277522 -58.053749)
			(xy 216.327095 -58.031107) (xy 216.379385 -58.015751) (xy 216.433329 -58.007992) (xy 216.460578 -58.007504)
			(xy 216.487948 -58.007982) (xy 216.542126 -58.015797) (xy 216.594629 -58.031283) (xy 216.644376 -58.054122)
			(xy 216.690344 -58.083844) (xy 216.711276 -58.101484) (xy 216.71153 -58.101738) (xy 216.718629 -58.107306)
			(xy 216.735536 -58.113563) (xy 216.74455 -58.11393) (xy 216.811606 -58.11393) (xy 216.820622 -58.113569)
			(xy 216.837539 -58.107323) (xy 216.844626 -58.101738) (xy 216.844626 -58.101484) (xy 216.84488 -58.101484)
			(xy 216.865807 -58.083838) (xy 216.911781 -58.054128) (xy 216.96153 -58.031294) (xy 217.014032 -58.015804)
			(xy 217.068209 -58.007977) (xy 217.095578 -58.007504) (xy 217.122833 -58.007941) (xy 217.176788 -58.015696)
			(xy 217.22909 -58.031051) (xy 217.278675 -58.053693) (xy 217.324532 -58.083161) (xy 217.365729 -58.118856)
			(xy 217.401426 -58.16005) (xy 217.430897 -58.205906) (xy 217.453542 -58.255489) (xy 217.468899 -58.307791)
			(xy 217.476657 -58.361745) (xy 217.476657 -58.416255) (xy 217.468899 -58.470209) (xy 217.453542 -58.522511)
			(xy 217.430897 -58.572094) (xy 217.401426 -58.61795) (xy 217.365729 -58.659144) (xy 217.324532 -58.694839)
			(xy 217.278675 -58.724307) (xy 217.22909 -58.746949) (xy 217.176788 -58.762304) (xy 217.122833 -58.770059)
			(xy 217.095578 -58.77052) (xy 217.068206 -58.770086) (xy 217.014025 -58.762264) (xy 216.961521 -58.746768)
			(xy 216.911774 -58.723919) (xy 216.86581 -58.694186) (xy 216.84488 -58.67654) (xy 216.844626 -58.676286)
			(xy 216.837537 -58.670703) (xy 216.820622 -58.664454) (xy 216.811606 -58.664094) (xy 216.74455 -58.664094)
			(xy 216.735536 -58.664477) (xy 216.718619 -58.670707) (xy 216.71153 -58.676286) (xy 216.71153 -58.67654)
			(xy 216.711276 -58.67654) (xy 216.690332 -58.694164) (xy 216.644362 -58.723876) (xy 216.594617 -58.746715)
			(xy 216.542119 -58.76221) (xy 216.487946 -58.770043) (xy 216.460578 -58.77052) (xy 216.433329 -58.770008)
			(xy 216.379385 -58.762249) (xy 216.327095 -58.746893) (xy 216.277522 -58.724251) (xy 216.231676 -58.694785)
			(xy 216.190489 -58.659095) (xy 216.154801 -58.617907) (xy 216.125338 -58.572059) (xy 216.102699 -58.522485)
			(xy 216.087346 -58.470193) (xy 216.07959 -58.416249) (xy 158.622959 -58.416249) (xy 158.578744 -58.444662)
			(xy 158.529165 -58.4673) (xy 158.476869 -58.482652) (xy 158.422921 -58.490405) (xy 158.39567 -58.490866)
			(xy 158.368737 -58.490379) (xy 158.315406 -58.482794) (xy 158.263674 -58.46778) (xy 158.21457 -58.445636)
			(xy 158.16907 -58.416802) (xy 158.148274 -58.39968) (xy 158.140041 -58.393246) (xy 158.120095 -58.387088)
			(xy 158.109666 -58.387742) (xy 158.03626 -58.396124) (xy 158.025985 -58.397741) (xy 158.007896 -58.407969)
			(xy 158.001208 -58.415936) (xy 157.980533 -58.442376) (xy 157.933385 -58.490145) (xy 157.880361 -58.531292)
			(xy 157.822381 -58.565103) (xy 157.760456 -58.590989) (xy 157.695663 -58.608499) (xy 157.629129 -58.617329)
			(xy 157.59557 -58.617866) (xy 157.563608 -58.617446) (xy 157.500187 -58.609431) (xy 157.438271 -58.59353)
			(xy 157.378836 -58.569995) (xy 157.32282 -58.539197) (xy 157.271105 -58.501621) (xy 157.224507 -58.45786)
			(xy 157.183761 -58.408604) (xy 157.149509 -58.354629) (xy 157.122292 -58.296788) (xy 157.102539 -58.235992)
			(xy 157.090561 -58.173199) (xy 157.086547 -58.1094) (xy 153.698793 -58.1094) (xy 153.725376 -58.145989)
			(xy 153.75617 -58.202004) (xy 153.779702 -58.261437) (xy 153.795599 -58.323351) (xy 153.80361 -58.386769)
			(xy 153.804112 -58.41873) (xy 153.80361 -58.450691) (xy 153.795599 -58.514109) (xy 153.779702 -58.576023)
			(xy 153.75617 -58.635456) (xy 153.725376 -58.691471) (xy 153.687803 -58.743186) (xy 153.644046 -58.789783)
			(xy 153.594793 -58.830528) (xy 153.540822 -58.864779) (xy 153.482983 -58.891996) (xy 153.42219 -58.911749)
			(xy 153.3594 -58.923727) (xy 153.295604 -58.927741) (xy 153.231808 -58.923727) (xy 153.169018 -58.911749)
			(xy 153.108225 -58.891996) (xy 153.050386 -58.864779) (xy 152.996415 -58.830528) (xy 152.947162 -58.789783)
			(xy 152.903405 -58.743186) (xy 152.865832 -58.691471) (xy 152.835038 -58.635456) (xy 152.811506 -58.576023)
			(xy 152.795609 -58.514109) (xy 152.787598 -58.450691) (xy 149.807749 -58.450691) (xy 149.795082 -58.469837)
			(xy 149.757865 -58.511374) (xy 149.714997 -58.547049) (xy 149.667391 -58.576103) (xy 149.616062 -58.597915)
			(xy 149.562105 -58.612021) (xy 149.506668 -58.618121) (xy 149.450934 -58.616084) (xy 149.396091 -58.605954)
			(xy 149.343307 -58.587947) (xy 149.293707 -58.562446) (xy 149.248349 -58.529995) (xy 149.2082 -58.491286)
			(xy 149.174114 -58.447143) (xy 149.146818 -58.398508) (xy 149.126895 -58.346417) (xy 149.114769 -58.29198)
			(xy 149.110698 -58.236358) (xy 144.835152 -58.236358) (xy 144.805823 -58.279375) (xy 144.769571 -58.318446)
			(xy 144.7279 -58.351677) (xy 144.681742 -58.378326) (xy 144.632128 -58.397798) (xy 144.580166 -58.409658)
			(xy 144.527016 -58.413642) (xy 144.473866 -58.409658) (xy 144.421904 -58.397798) (xy 144.37229 -58.378326)
			(xy 144.326132 -58.351677) (xy 144.284461 -58.318446) (xy 144.248209 -58.279375) (xy 144.218185 -58.235338)
			(xy 144.195059 -58.187317) (xy 144.179349 -58.136387) (xy 144.171406 -58.083683) (xy 144.170908 -58.057034)
			(xy 140.797867 -58.057034) (xy 140.789766 -58.069279) (xy 140.752549 -58.110816) (xy 140.709681 -58.146491)
			(xy 140.662075 -58.175545) (xy 140.610746 -58.197357) (xy 140.556789 -58.211463) (xy 140.501352 -58.217563)
			(xy 140.445618 -58.215526) (xy 140.390775 -58.205396) (xy 140.337991 -58.187389) (xy 140.288391 -58.161888)
			(xy 140.243033 -58.129437) (xy 140.202884 -58.090728) (xy 140.168798 -58.046585) (xy 140.141502 -57.99795)
			(xy 140.121579 -57.945859) (xy 140.109453 -57.891422) (xy 140.105382 -57.8358) (xy 137.313906 -57.8358)
			(xy 137.315708 -57.850067) (xy 137.31621 -57.882028) (xy 137.315708 -57.913989) (xy 137.307697 -57.977407)
			(xy 137.2918 -58.039321) (xy 137.268268 -58.098754) (xy 137.237474 -58.154769) (xy 137.199901 -58.206484)
			(xy 137.156144 -58.253081) (xy 137.106891 -58.293826) (xy 137.05292 -58.328077) (xy 136.995081 -58.355294)
			(xy 136.934288 -58.375047) (xy 136.871498 -58.387025) (xy 136.807702 -58.391039) (xy 136.743906 -58.387025)
			(xy 136.681116 -58.375047) (xy 136.620323 -58.355294) (xy 136.562484 -58.328077) (xy 136.508513 -58.293826)
			(xy 136.45926 -58.253081) (xy 136.415503 -58.206484) (xy 136.37793 -58.154769) (xy 136.347136 -58.098754)
			(xy 136.323604 -58.039321) (xy 136.307707 -57.977407) (xy 136.299696 -57.913989) (xy 130.217525 -57.913989)
			(xy 130.210446 -57.963227) (xy 130.195091 -58.015522) (xy 130.172449 -58.065099) (xy 130.142983 -58.110949)
			(xy 130.107292 -58.15214) (xy 130.066101 -58.187831) (xy 130.020251 -58.217297) (xy 129.970674 -58.239939)
			(xy 129.918379 -58.255294) (xy 129.864431 -58.26305) (xy 129.809929 -58.26305) (xy 129.755981 -58.255294)
			(xy 129.703686 -58.239939) (xy 129.654109 -58.217297) (xy 129.608259 -58.187831) (xy 129.567068 -58.15214)
			(xy 129.531377 -58.110949) (xy 129.501911 -58.065099) (xy 129.479269 -58.015522) (xy 129.463914 -57.963227)
			(xy 129.456158 -57.909279) (xy 129.455672 -57.882028) (xy 129.456131 -57.855307) (xy 129.463599 -57.80239)
			(xy 129.478365 -57.751029) (xy 129.500142 -57.702226) (xy 129.528505 -57.656932) (xy 129.562901 -57.61603)
			(xy 129.602659 -57.580319) (xy 129.624582 -57.565036) (xy 129.634703 -57.557576) (xy 129.646552 -57.535431)
			(xy 129.647188 -57.522872) (xy 129.647188 -57.491376) (xy 129.64659 -57.478856) (xy 129.63486 -57.456739)
			(xy 129.624836 -57.449212) (xy 129.611962 -57.440383) (xy 129.587546 -57.42093) (xy 129.576068 -57.41035)
			(xy 129.573782 -57.41289) (xy 129.556454 -57.430198) (xy 129.51726 -57.459565) (xy 129.473872 -57.482282)
			(xy 129.427409 -57.497764) (xy 129.379067 -57.505613) (xy 129.35458 -57.506108) (xy 127.550926 -57.506108)
			(xy 127.541373 -57.506003) (xy 127.522309 -57.50473) (xy 127.512826 -57.503568) (xy 127.502412 -57.503314)
			(xy 127.491612 -57.504601) (xy 127.472515 -57.514962) (xy 127.459411 -57.532293) (xy 127.454646 -57.553491)
			(xy 127.459073 -57.574762) (xy 127.465074 -57.583832) (xy 127.483371 -57.609905) (xy 127.513985 -57.665764)
			(xy 127.537371 -57.725014) (xy 127.553161 -57.786724) (xy 127.561108 -57.849925) (xy 127.561594 -57.881774)
			(xy 127.561092 -57.913735) (xy 127.553081 -57.977153) (xy 127.537184 -58.039067) (xy 127.513652 -58.0985)
			(xy 127.482858 -58.154515) (xy 127.445285 -58.20623) (xy 127.401528 -58.252827) (xy 127.352275 -58.293572)
			(xy 127.298304 -58.327823) (xy 127.240465 -58.35504) (xy 127.179672 -58.374793) (xy 127.116882 -58.386771)
			(xy 127.053086 -58.390785) (xy 126.98929 -58.386771) (xy 126.9265 -58.374793) (xy 126.865707 -58.35504)
			(xy 126.807868 -58.327823) (xy 126.753897 -58.293572) (xy 126.704644 -58.252827) (xy 126.660887 -58.20623)
			(xy 126.623314 -58.154515) (xy 126.59252 -58.0985) (xy 126.568988 -58.039067) (xy 126.553091 -57.977153)
			(xy 126.54508 -57.913735) (xy 126.544578 -57.881774) (xy 126.545083 -57.850215) (xy 126.552893 -57.787581)
			(xy 126.568388 -57.726394) (xy 126.591331 -57.667592) (xy 126.62137 -57.61208) (xy 126.63932 -57.586118)
			(xy 126.644425 -57.578151) (xy 126.649072 -57.559829) (xy 126.646765 -57.541068) (xy 126.637816 -57.524418)
			(xy 126.623443 -57.512141) (xy 126.605599 -57.505907) (xy 126.59614 -57.505854) (xy 126.585726 -57.506108)
			(xy 125.394212 -57.506108) (xy 125.367288 -57.52592) (xy 125.362462 -57.542176) (xy 125.352631 -57.573217)
			(xy 125.326152 -57.632704) (xy 125.292296 -57.688324) (xy 125.251618 -57.739167) (xy 125.204782 -57.784401)
			(xy 125.152554 -57.823287) (xy 125.095791 -57.855188) (xy 125.035419 -57.879582) (xy 124.972428 -57.896069)
			(xy 124.907847 -57.904381) (xy 124.842733 -57.904381) (xy 124.778152 -57.896069) (xy 124.715161 -57.879582)
			(xy 124.654789 -57.855188) (xy 124.598026 -57.823287) (xy 124.545798 -57.784401) (xy 124.498962 -57.739167)
			(xy 124.458284 -57.688324) (xy 124.424428 -57.632704) (xy 124.397949 -57.573217) (xy 124.388118 -57.542176)
			(xy 124.383292 -57.52592) (xy 124.356368 -57.506108) (xy 124.246894 -57.506108) (xy 124.21743 -57.534302)
			(xy 124.216668 -57.554622) (xy 124.21495 -57.582333) (xy 124.2045 -57.636859) (xy 124.186259 -57.689296)
			(xy 124.160612 -57.738536) (xy 124.128101 -57.78354) (xy 124.089412 -57.823358) (xy 124.045362 -57.85715)
			(xy 123.99688 -57.884202) (xy 123.944989 -57.903944) (xy 123.890786 -57.915958) (xy 123.835414 -57.919991)
			(xy 123.780042 -57.915958) (xy 123.725839 -57.903944) (xy 123.673948 -57.884202) (xy 123.625466 -57.85715)
			(xy 123.581416 -57.823358) (xy 123.542727 -57.78354) (xy 123.510216 -57.738536) (xy 123.484569 -57.689296)
			(xy 123.466328 -57.636859) (xy 123.455878 -57.582333) (xy 123.45416 -57.554622) (xy 123.453398 -57.534302)
			(xy 123.423934 -57.506108) (xy 122.118628 -57.506108) (xy 122.094624 -57.505639) (xy 122.047211 -57.498096)
			(xy 122.001563 -57.483223) (xy 121.958808 -57.461386) (xy 121.919998 -57.433125) (xy 121.902728 -57.416446)
			(xy 121.399554 -56.913272) (xy 121.382882 -56.895997) (xy 121.354626 -56.857185) (xy 121.332791 -56.81443)
			(xy 121.317913 -56.768786) (xy 121.31036 -56.721376) (xy 121.309892 -56.697372) (xy 120.22311 -56.697372)
			(xy 120.212332 -56.739349) (xy 120.1888 -56.798782) (xy 120.158006 -56.854797) (xy 120.120433 -56.906512)
			(xy 120.076676 -56.953109) (xy 120.027423 -56.993854) (xy 119.973452 -57.028105) (xy 119.915613 -57.055322)
			(xy 119.85482 -57.075075) (xy 119.79203 -57.087053) (xy 119.728234 -57.091067) (xy 119.664438 -57.087053)
			(xy 119.601648 -57.075075) (xy 119.540855 -57.055322) (xy 119.483016 -57.028105) (xy 119.429045 -56.993854)
			(xy 119.379792 -56.953109) (xy 119.336035 -56.906512) (xy 119.298462 -56.854797) (xy 119.267668 -56.798782)
			(xy 119.244136 -56.739349) (xy 119.228239 -56.677435) (xy 119.220228 -56.614017) (xy 110.358467 -56.614017)
			(xy 110.345355 -56.641573) (xy 110.313793 -56.688476) (xy 110.275652 -56.730207) (xy 110.254034 -56.748426)
			(xy 110.245597 -56.756013) (xy 110.235839 -56.776465) (xy 110.235238 -56.787796) (xy 110.235238 -56.866536)
			(xy 110.235865 -56.877857) (xy 110.245632 -56.898291) (xy 110.254034 -56.905906) (xy 110.275659 -56.924117)
			(xy 110.313792 -56.965856) (xy 110.345351 -57.012763) (xy 110.369647 -57.063812) (xy 110.386147 -57.117886)
			(xy 110.39449 -57.173802) (xy 110.395004 -57.20207) (xy 110.395003 -57.2021) (xy 116.474938 -57.2021)
			(xy 116.478953 -57.138296) (xy 116.490932 -57.075499) (xy 116.510688 -57.014698) (xy 116.537909 -56.956853)
			(xy 116.572165 -56.902875) (xy 116.612916 -56.853617) (xy 116.65952 -56.809855) (xy 116.711241 -56.772279)
			(xy 116.767264 -56.741482) (xy 116.826705 -56.717949) (xy 116.888627 -56.702052) (xy 116.952053 -56.694042)
			(xy 116.984018 -56.693562) (xy 117.017266 -56.694129) (xy 117.083194 -56.702793) (xy 117.147432 -56.719973)
			(xy 117.208885 -56.745374) (xy 117.266505 -56.778564) (xy 117.31931 -56.818977) (xy 117.366401 -56.865925)
			(xy 117.387116 -56.891936) (xy 117.395858 -56.902581) (xy 117.417883 -56.919106) (xy 117.443523 -56.929146)
			(xy 117.470913 -56.931971) (xy 117.498063 -56.927376) (xy 117.522997 -56.915694) (xy 117.543905 -56.897775)
			(xy 117.551962 -56.886602) (xy 117.567222 -56.864647) (xy 117.602898 -56.824822) (xy 117.643784 -56.790367)
			(xy 117.689078 -56.761956) (xy 117.737894 -56.740144) (xy 117.789277 -56.725359) (xy 117.84222 -56.71789)
			(xy 117.868954 -56.717438) (xy 117.896212 -56.717806) (xy 117.950175 -56.725558) (xy 118.002484 -56.740912)
			(xy 118.052076 -56.763555) (xy 118.097941 -56.793025) (xy 118.139144 -56.828723) (xy 118.174847 -56.869922)
			(xy 118.204323 -56.915783) (xy 118.226972 -56.965372) (xy 118.242332 -57.01768) (xy 118.250091 -57.071642)
			(xy 118.250091 -57.126158) (xy 118.242332 -57.18012) (xy 118.226972 -57.232428) (xy 118.204323 -57.282017)
			(xy 118.174847 -57.327878) (xy 118.139144 -57.369077) (xy 118.097941 -57.404775) (xy 118.052076 -57.434245)
			(xy 118.002485 -57.456888) (xy 117.950175 -57.472242) (xy 117.896212 -57.479994) (xy 117.868954 -57.480454)
			(xy 117.840382 -57.479912) (xy 117.783879 -57.471376) (xy 117.729283 -57.454502) (xy 117.677817 -57.429669)
			(xy 117.630634 -57.397432) (xy 117.609366 -57.378346) (xy 117.59895 -57.369298) (xy 117.574465 -57.35661)
			(xy 117.547476 -57.350943) (xy 117.519955 -57.352712) (xy 117.493914 -57.361788) (xy 117.471255 -57.377507)
			(xy 117.453634 -57.398721) (xy 117.447568 -57.411112) (xy 117.43375 -57.440442) (xy 117.399804 -57.495681)
			(xy 117.359111 -57.546156) (xy 117.312331 -57.591049) (xy 117.260225 -57.62963) (xy 117.203637 -57.661276)
			(xy 117.143485 -57.685471) (xy 117.080745 -57.701823) (xy 117.016436 -57.710067) (xy 116.984018 -57.710578)
			(xy 116.952053 -57.710158) (xy 116.888627 -57.702148) (xy 116.826705 -57.686251) (xy 116.767264 -57.662718)
			(xy 116.711241 -57.631921) (xy 116.65952 -57.594345) (xy 116.612916 -57.550583) (xy 116.572165 -57.501325)
			(xy 116.537909 -57.447347) (xy 116.510688 -57.389502) (xy 116.490932 -57.328701) (xy 116.478953 -57.265904)
			(xy 116.474938 -57.2021) (xy 110.395003 -57.2021) (xy 110.394518 -57.229321) (xy 110.386762 -57.283269)
			(xy 110.371407 -57.335564) (xy 110.348765 -57.385141) (xy 110.319299 -57.430991) (xy 110.283608 -57.472182)
			(xy 110.242417 -57.507873) (xy 110.196567 -57.537339) (xy 110.14699 -57.559981) (xy 110.094695 -57.575336)
			(xy 110.040747 -57.583092) (xy 109.986245 -57.583092) (xy 109.932297 -57.575336) (xy 109.880002 -57.559981)
			(xy 109.830425 -57.537339) (xy 109.784575 -57.507873) (xy 109.743384 -57.472182) (xy 109.707693 -57.430991)
			(xy 109.678227 -57.385141) (xy 109.655585 -57.335564) (xy 109.64023 -57.283269) (xy 109.632474 -57.229321)
			(xy 109.631988 -57.20207) (xy 107.691814 -57.20207) (xy 107.670962 -57.215303) (xy 107.613123 -57.24252)
			(xy 107.55233 -57.262273) (xy 107.48954 -57.274251) (xy 107.425744 -57.278265) (xy 107.361948 -57.274251)
			(xy 107.299158 -57.262273) (xy 107.238365 -57.24252) (xy 107.180526 -57.215303) (xy 107.126555 -57.181052)
			(xy 107.077302 -57.140307) (xy 107.033545 -57.09371) (xy 106.995972 -57.041995) (xy 106.965178 -56.98598)
			(xy 106.941646 -56.926547) (xy 106.925749 -56.864633) (xy 106.917738 -56.801215) (xy 96.303385 -56.801215)
			(xy 96.312624 -56.80761) (xy 96.32442 -56.809894) (xy 96.351432 -56.814149) (xy 96.403957 -56.829355)
			(xy 96.453774 -56.851901) (xy 96.499864 -56.881326) (xy 96.541282 -56.917027) (xy 96.577181 -56.958275)
			(xy 96.606826 -57.004223) (xy 96.62961 -57.053932) (xy 96.645066 -57.106384) (xy 96.652877 -57.160505)
			(xy 96.65335 -57.187846) (xy 96.652864 -57.215097) (xy 96.645108 -57.269045) (xy 96.629753 -57.32134)
			(xy 96.607111 -57.370917) (xy 96.577645 -57.416767) (xy 96.541954 -57.457958) (xy 96.500763 -57.493649)
			(xy 96.454913 -57.523115) (xy 96.405336 -57.545757) (xy 96.353041 -57.561112) (xy 96.299093 -57.568868)
			(xy 96.244591 -57.568868) (xy 96.190643 -57.561112) (xy 96.138348 -57.545757) (xy 96.088771 -57.523115)
			(xy 96.042921 -57.493649) (xy 96.00173 -57.457958) (xy 95.966039 -57.416767) (xy 95.936573 -57.370917)
			(xy 95.913931 -57.32134) (xy 95.898576 -57.269045) (xy 95.89082 -57.215097) (xy 95.890334 -57.187846)
			(xy 95.890785 -57.161466) (xy 95.898046 -57.109208) (xy 95.904812 -57.083706) (xy 95.907453 -57.071961)
			(xy 95.902808 -57.04837) (xy 95.895922 -57.038494) (xy 95.83801 -56.964326) (xy 95.816166 -56.954166)
			(xy 95.803974 -56.95442) (xy 95.787972 -56.954674) (xy 95.756434 -56.954203) (xy 95.693841 -56.946397)
			(xy 95.632695 -56.93091) (xy 95.573934 -56.907978) (xy 95.518461 -56.877955) (xy 95.467127 -56.8413)
			(xy 95.420722 -56.798577) (xy 95.379957 -56.750443) (xy 95.345458 -56.697636) (xy 95.317757 -56.640968)
			(xy 95.297277 -56.581308) (xy 95.284334 -56.519573) (xy 95.279126 -56.456711) (xy 93.396135 -56.456711)
			(xy 93.381804 -56.512527) (xy 93.358272 -56.57196) (xy 93.327478 -56.627975) (xy 93.289905 -56.67969)
			(xy 93.246148 -56.726287) (xy 93.196895 -56.767032) (xy 93.142924 -56.801283) (xy 93.085085 -56.8285)
			(xy 93.024292 -56.848253) (xy 92.961502 -56.860231) (xy 92.897706 -56.864245) (xy 92.83391 -56.860231)
			(xy 92.77112 -56.848253) (xy 92.710327 -56.8285) (xy 92.652488 -56.801283) (xy 92.598517 -56.767032)
			(xy 92.549264 -56.726287) (xy 92.505507 -56.67969) (xy 92.467934 -56.627975) (xy 92.43714 -56.57196)
			(xy 92.413608 -56.512527) (xy 92.397711 -56.450613) (xy 92.3897 -56.387195) (xy 90.594342 -56.387195)
			(xy 90.617868 -56.396511) (xy 90.673883 -56.42731) (xy 90.725597 -56.464886) (xy 90.772194 -56.508646)
			(xy 90.812938 -56.557902) (xy 90.847189 -56.611875) (xy 90.874405 -56.669716) (xy 90.894157 -56.730511)
			(xy 90.906135 -56.793302) (xy 90.910149 -56.8571) (xy 90.906135 -56.920898) (xy 90.894157 -56.983689)
			(xy 90.874405 -57.044484) (xy 90.847189 -57.102325) (xy 90.812938 -57.156298) (xy 90.772194 -57.205554)
			(xy 90.725597 -57.249314) (xy 90.673883 -57.28689) (xy 90.617868 -57.317689) (xy 90.558435 -57.341224)
			(xy 90.496521 -57.357125) (xy 90.433102 -57.365142) (xy 90.40114 -57.365646) (xy 90.369912 -57.365207)
			(xy 90.307927 -57.357561) (xy 90.247345 -57.342379) (xy 90.189079 -57.31989) (xy 90.134007 -57.290432)
			(xy 90.082958 -57.25445) (xy 90.05951 -57.23382) (xy 90.049096 -57.224422) (xy 90.021918 -57.218834)
			(xy 89.91092 -57.25795) (xy 89.89314 -57.279286) (xy 89.891108 -57.293256) (xy 89.886381 -57.319826)
			(xy 89.870506 -57.371403) (xy 89.847522 -57.420228) (xy 89.817888 -57.465328) (xy 89.782196 -57.505803)
			(xy 89.741157 -57.540846) (xy 89.69559 -57.569757) (xy 89.646404 -57.591959) (xy 89.594581 -57.60701)
			(xy 89.541154 -57.61461) (xy 89.514172 -57.615074) (xy 89.486917 -57.614671) (xy 89.432962 -57.606909)
			(xy 89.380661 -57.591548) (xy 89.331078 -57.5689) (xy 89.285224 -57.539426) (xy 89.24403 -57.503726)
			(xy 89.208337 -57.462527) (xy 89.17887 -57.416667) (xy 89.15623 -57.367081) (xy 89.140877 -57.314777)
			(xy 89.133125 -57.260821) (xy 89.132664 -57.233566) (xy 83.6295 -57.233566) (xy 83.6295 -57.850532)
			(xy 83.629071 -57.8606) (xy 83.621348 -57.879196) (xy 83.614514 -57.8866) (xy 83.053174 -58.44794)
			(xy 83.045777 -58.454789) (xy 83.027178 -58.462523) (xy 83.017106 -58.462926) (xy 81.826608 -58.462926)
			(xy 81.817621 -58.463269) (xy 81.800756 -58.469477) (xy 81.787099 -58.481159) (xy 81.782412 -58.488834)
			(xy 81.738724 -58.56605) (xy 81.735669 -58.571815) (xy 81.732326 -58.584421) (xy 81.73212 -58.590942)
			(xy 81.737708 -58.610754) (xy 81.739635 -58.615283) (xy 88.899994 -58.615283) (xy 88.899994 -58.551361)
			(xy 88.908005 -58.487943) (xy 88.923902 -58.426029) (xy 88.947434 -58.366596) (xy 88.978228 -58.310581)
			(xy 89.015801 -58.258866) (xy 89.059558 -58.212269) (xy 89.108811 -58.171524) (xy 89.162782 -58.137273)
			(xy 89.220621 -58.110056) (xy 89.281414 -58.090303) (xy 89.344204 -58.078325) (xy 89.408 -58.074312)
			(xy 89.471796 -58.078325) (xy 89.534586 -58.090303) (xy 89.595379 -58.110056) (xy 89.653218 -58.137273)
			(xy 89.707189 -58.171524) (xy 89.756442 -58.212269) (xy 89.800199 -58.258866) (xy 89.837772 -58.310581)
			(xy 89.868566 -58.366596) (xy 89.892098 -58.426029) (xy 89.907995 -58.487943) (xy 89.916006 -58.551361)
			(xy 89.916508 -58.583322) (xy 89.916006 -58.615283) (xy 89.907995 -58.678701) (xy 89.892098 -58.740615)
			(xy 89.868566 -58.800048) (xy 89.837772 -58.856063) (xy 89.829981 -58.866786) (xy 93.453204 -58.866786)
			(xy 93.453805 -58.837133) (xy 93.462996 -58.778542) (xy 93.48114 -58.722078) (xy 93.507799 -58.669101)
			(xy 93.542332 -58.620884) (xy 93.583908 -58.57859) (xy 93.607382 -58.560462) (xy 93.614785 -58.554451)
			(xy 93.624842 -58.538268) (xy 93.62694 -58.528966) (xy 93.639894 -58.461148) (xy 93.641139 -58.451725)
			(xy 93.637482 -58.433089) (xy 93.632782 -58.424826) (xy 93.632782 -58.424572) (xy 93.614259 -58.393995)
			(xy 93.585007 -58.328765) (xy 93.565178 -58.260082) (xy 93.55516 -58.189298) (xy 93.55455 -58.153554)
			(xy 93.555052 -58.121593) (xy 93.563063 -58.058175) (xy 93.57896 -57.996261) (xy 93.602492 -57.936828)
			(xy 93.633286 -57.880813) (xy 93.670859 -57.829098) (xy 93.714616 -57.782501) (xy 93.763869 -57.741756)
			(xy 93.81784 -57.707505) (xy 93.875679 -57.680288) (xy 93.936472 -57.660535) (xy 93.999262 -57.648557)
			(xy 94.063058 -57.644544) (xy 94.126854 -57.648557) (xy 94.189644 -57.660535) (xy 94.250437 -57.680288)
			(xy 94.308276 -57.707505) (xy 94.362247 -57.741756) (xy 94.4115 -57.782501) (xy 94.455257 -57.829098)
			(xy 94.49283 -57.880813) (xy 94.523624 -57.936828) (xy 94.547156 -57.996261) (xy 94.563053 -58.058175)
			(xy 94.565412 -58.076846) (xy 95.889824 -58.076846) (xy 95.893895 -58.021224) (xy 95.906021 -57.966787)
			(xy 95.925944 -57.914696) (xy 95.95324 -57.866061) (xy 95.987326 -57.821918) (xy 96.027475 -57.783209)
			(xy 96.072833 -57.750758) (xy 96.122433 -57.725257) (xy 96.175217 -57.70725) (xy 96.23006 -57.69712)
			(xy 96.285794 -57.695083) (xy 96.341231 -57.701183) (xy 96.395188 -57.715289) (xy 96.446517 -57.737101)
			(xy 96.494123 -57.766155) (xy 96.536991 -57.80183) (xy 96.574208 -57.843367) (xy 96.604981 -57.88988)
			(xy 96.614973 -57.911195) (xy 98.884734 -57.911195) (xy 98.884734 -57.847273) (xy 98.892745 -57.783855)
			(xy 98.908642 -57.721941) (xy 98.932174 -57.662508) (xy 98.962968 -57.606493) (xy 99.000541 -57.554778)
			(xy 99.044298 -57.508181) (xy 99.093551 -57.467436) (xy 99.147522 -57.433185) (xy 99.205361 -57.405968)
			(xy 99.266154 -57.386215) (xy 99.328944 -57.374237) (xy 99.39274 -57.370224) (xy 99.456536 -57.374237)
			(xy 99.519326 -57.386215) (xy 99.580119 -57.405968) (xy 99.637958 -57.433185) (xy 99.691929 -57.467436)
			(xy 99.741182 -57.508181) (xy 99.784939 -57.554778) (xy 99.822512 -57.606493) (xy 99.853306 -57.662508)
			(xy 99.876838 -57.721941) (xy 99.892735 -57.783855) (xy 99.900746 -57.847273) (xy 99.901248 -57.879234)
			(xy 99.900746 -57.911195) (xy 99.892735 -57.974613) (xy 99.876838 -58.036527) (xy 99.853306 -58.09596)
			(xy 99.822512 -58.151975) (xy 99.784939 -58.20369) (xy 99.741182 -58.250287) (xy 99.691929 -58.291032)
			(xy 99.637958 -58.325283) (xy 99.580119 -58.3525) (xy 99.519326 -58.372253) (xy 99.456536 -58.384231)
			(xy 99.39274 -58.388245) (xy 99.328944 -58.384231) (xy 99.266154 -58.372253) (xy 99.205361 -58.3525)
			(xy 99.147522 -58.325283) (xy 99.093551 -58.291032) (xy 99.044298 -58.250287) (xy 99.000541 -58.20369)
			(xy 98.962968 -58.151975) (xy 98.932174 -58.09596) (xy 98.908642 -58.036527) (xy 98.892745 -57.974613)
			(xy 98.884734 -57.911195) (xy 96.614973 -57.911195) (xy 96.628653 -57.940377) (xy 96.644721 -57.993784)
			(xy 96.652841 -58.04896) (xy 96.65335 -58.076846) (xy 96.652841 -58.104732) (xy 96.644721 -58.159908)
			(xy 96.628653 -58.213315) (xy 96.604981 -58.263812) (xy 96.574208 -58.310325) (xy 96.536991 -58.351862)
			(xy 96.494123 -58.387537) (xy 96.446517 -58.416591) (xy 96.395188 -58.438403) (xy 96.341231 -58.452509)
			(xy 96.285794 -58.458609) (xy 96.23006 -58.456572) (xy 96.175217 -58.446442) (xy 96.122433 -58.428435)
			(xy 96.072833 -58.402934) (xy 96.027475 -58.370483) (xy 95.987326 -58.331774) (xy 95.95324 -58.287631)
			(xy 95.925944 -58.238996) (xy 95.906021 -58.186905) (xy 95.893895 -58.132468) (xy 95.889824 -58.076846)
			(xy 94.565412 -58.076846) (xy 94.571064 -58.121593) (xy 94.571566 -58.153554) (xy 94.571566 -58.153808)
			(xy 94.570919 -58.190429) (xy 94.560385 -58.262909) (xy 94.539578 -58.333134) (xy 94.52483 -58.36666)
			(xy 94.521544 -58.37454) (xy 94.519927 -58.391529) (xy 94.524004 -58.408099) (xy 94.528386 -58.415428)
			(xy 94.574868 -58.487564) (xy 94.579802 -58.494541) (xy 94.589453 -58.502) (xy 106.20021 -58.502)
			(xy 106.204224 -58.438206) (xy 106.216202 -58.375418) (xy 106.235954 -58.314626) (xy 106.263171 -58.25679)
			(xy 106.297421 -58.20282) (xy 106.338166 -58.153569) (xy 106.384762 -58.109813) (xy 106.436475 -58.072243)
			(xy 106.492489 -58.041449) (xy 106.551921 -58.01792) (xy 106.613834 -58.002024) (xy 106.67725 -57.994014)
			(xy 106.70921 -57.993534) (xy 106.742505 -57.994075) (xy 106.80852 -58.00281) (xy 106.872827 -58.020103)
			(xy 106.903774 -58.032396) (xy 106.904028 -58.032396) (xy 106.91568 -58.036593) (xy 106.940317 -58.034316)
			(xy 106.951018 -58.028078) (xy 107.03179 -57.975246) (xy 107.043982 -57.953148) (xy 107.044236 -57.940702)
			(xy 107.045308 -57.913859) (xy 107.054065 -57.860856) (xy 107.070169 -57.809604) (xy 107.0933 -57.761118)
			(xy 107.123001 -57.716353) (xy 107.158687 -57.676197) (xy 107.19965 -57.641441) (xy 107.245083 -57.612772)
			(xy 107.294087 -57.590758) (xy 107.345694 -57.575833) (xy 107.398883 -57.568292) (xy 107.425744 -57.56783)
			(xy 107.452996 -57.568243) (xy 107.506944 -57.576005) (xy 107.559239 -57.591366) (xy 107.608816 -57.614012)
			(xy 107.654665 -57.643482) (xy 107.695854 -57.679177) (xy 107.731544 -57.72037) (xy 107.761009 -57.766223)
			(xy 107.78365 -57.815802) (xy 107.799004 -57.868099) (xy 107.801292 -57.884017) (xy 115.374668 -57.884017)
			(xy 115.374668 -57.820095) (xy 115.382679 -57.756677) (xy 115.398576 -57.694763) (xy 115.422108 -57.63533)
			(xy 115.452902 -57.579315) (xy 115.490475 -57.5276) (xy 115.534232 -57.481003) (xy 115.583485 -57.440258)
			(xy 115.637456 -57.406007) (xy 115.695295 -57.37879) (xy 115.756088 -57.359037) (xy 115.818878 -57.347059)
			(xy 115.882674 -57.343046) (xy 115.94647 -57.347059) (xy 116.00926 -57.359037) (xy 116.070053 -57.37879)
			(xy 116.127892 -57.406007) (xy 116.181863 -57.440258) (xy 116.231116 -57.481003) (xy 116.274873 -57.5276)
			(xy 116.312446 -57.579315) (xy 116.34324 -57.63533) (xy 116.366772 -57.694763) (xy 116.382669 -57.756677)
			(xy 116.39068 -57.820095) (xy 116.391182 -57.852056) (xy 116.39068 -57.884017) (xy 119.220228 -57.884017)
			(xy 119.220228 -57.820095) (xy 119.228239 -57.756677) (xy 119.244136 -57.694763) (xy 119.267668 -57.63533)
			(xy 119.298462 -57.579315) (xy 119.336035 -57.5276) (xy 119.379792 -57.481003) (xy 119.429045 -57.440258)
			(xy 119.483016 -57.406007) (xy 119.540855 -57.37879) (xy 119.601648 -57.359037) (xy 119.664438 -57.347059)
			(xy 119.728234 -57.343046) (xy 119.79203 -57.347059) (xy 119.85482 -57.359037) (xy 119.915613 -57.37879)
			(xy 119.973452 -57.406007) (xy 120.027423 -57.440258) (xy 120.076676 -57.481003) (xy 120.120433 -57.5276)
			(xy 120.158006 -57.579315) (xy 120.1888 -57.63533) (xy 120.212332 -57.694763) (xy 120.228229 -57.756677)
			(xy 120.23624 -57.820095) (xy 120.236742 -57.852056) (xy 120.23624 -57.884017) (xy 120.228229 -57.947435)
			(xy 120.212332 -58.009349) (xy 120.1888 -58.068782) (xy 120.158006 -58.124797) (xy 120.120433 -58.176512)
			(xy 120.076676 -58.223109) (xy 120.027423 -58.263854) (xy 119.973452 -58.298105) (xy 119.915613 -58.325322)
			(xy 119.85482 -58.345075) (xy 119.79203 -58.357053) (xy 119.728234 -58.361067) (xy 119.664438 -58.357053)
			(xy 119.601648 -58.345075) (xy 119.540855 -58.325322) (xy 119.483016 -58.298105) (xy 119.429045 -58.263854)
			(xy 119.379792 -58.223109) (xy 119.336035 -58.176512) (xy 119.298462 -58.124797) (xy 119.267668 -58.068782)
			(xy 119.244136 -58.009349) (xy 119.228239 -57.947435) (xy 119.220228 -57.884017) (xy 116.39068 -57.884017)
			(xy 116.382669 -57.947435) (xy 116.366772 -58.009349) (xy 116.34324 -58.068782) (xy 116.312446 -58.124797)
			(xy 116.274873 -58.176512) (xy 116.231116 -58.223109) (xy 116.181863 -58.263854) (xy 116.127892 -58.298105)
			(xy 116.070053 -58.325322) (xy 116.00926 -58.345075) (xy 115.94647 -58.357053) (xy 115.882674 -58.361067)
			(xy 115.818878 -58.357053) (xy 115.756088 -58.345075) (xy 115.695295 -58.325322) (xy 115.637456 -58.298105)
			(xy 115.583485 -58.263854) (xy 115.534232 -58.223109) (xy 115.490475 -58.176512) (xy 115.452902 -58.124797)
			(xy 115.422108 -58.068782) (xy 115.398576 -58.009349) (xy 115.382679 -57.947435) (xy 115.374668 -57.884017)
			(xy 107.801292 -57.884017) (xy 107.80676 -57.922048) (xy 107.80676 -57.976552) (xy 107.799004 -58.030501)
			(xy 107.78365 -58.082798) (xy 107.761009 -58.132377) (xy 107.731544 -58.17823) (xy 107.695854 -58.219423)
			(xy 107.654665 -58.255118) (xy 107.608816 -58.284588) (xy 107.559239 -58.307234) (xy 107.506944 -58.322595)
			(xy 107.452996 -58.330357) (xy 107.425744 -58.330846) (xy 107.403435 -58.330538) (xy 107.359123 -58.325312)
			(xy 107.337352 -58.320432) (xy 107.337098 -58.320432) (xy 107.32493 -58.318297) (xy 107.301034 -58.324409)
			(xy 107.291378 -58.332116) (xy 107.21975 -58.39714) (xy 107.211114 -58.420508) (xy 107.212892 -58.432954)
			(xy 107.215138 -58.450138) (xy 107.21755 -58.484713) (xy 107.217718 -58.502) (xy 116.641935 -58.502)
			(xy 116.645917 -58.448857) (xy 116.657776 -58.396901) (xy 116.677246 -58.347293) (xy 116.703891 -58.301141)
			(xy 116.737118 -58.259476) (xy 116.776184 -58.223228) (xy 116.820215 -58.193207) (xy 116.868229 -58.170084)
			(xy 116.919153 -58.154376) (xy 116.97185 -58.146432) (xy 116.998496 -58.145934) (xy 117.025688 -58.146434)
			(xy 117.079441 -58.154698) (xy 117.131309 -58.171048) (xy 117.180084 -58.195103) (xy 117.224628 -58.226304)
			(xy 117.244622 -58.24474) (xy 117.253188 -58.252309) (xy 117.274888 -58.259437) (xy 117.286278 -58.258456)
			(xy 117.37594 -58.247026) (xy 117.395244 -58.23458) (xy 117.40134 -58.224928) (xy 117.415365 -58.20319)
			(xy 117.448668 -58.163604) (xy 117.487349 -58.129256) (xy 117.530594 -58.100867) (xy 117.577492 -58.079035)
			(xy 117.627056 -58.06422) (xy 117.678243 -58.056735) (xy 117.704108 -58.056272) (xy 117.730755 -58.056811)
			(xy 117.783455 -58.064755) (xy 117.834382 -58.080465) (xy 117.882398 -58.103589) (xy 117.926432 -58.133612)
			(xy 117.965499 -58.169862) (xy 117.998728 -58.21153) (xy 118.025375 -58.257685) (xy 118.044845 -58.307296)
			(xy 118.056704 -58.359254) (xy 118.060687 -58.4124) (xy 118.056704 -58.465546) (xy 118.044845 -58.517504)
			(xy 118.025375 -58.567115) (xy 117.998728 -58.61327) (xy 117.965499 -58.654938) (xy 117.926432 -58.691188)
			(xy 117.882398 -58.721211) (xy 117.834382 -58.744335) (xy 117.783455 -58.760045) (xy 117.730755 -58.767989)
			(xy 117.704108 -58.768488) (xy 117.676916 -58.767979) (xy 117.623164 -58.759717) (xy 117.571296 -58.743369)
			(xy 117.522522 -58.719315) (xy 117.477977 -58.688117) (xy 117.457982 -58.669682) (xy 117.449412 -58.662118)
			(xy 117.427716 -58.654986) (xy 117.416326 -58.655966) (xy 117.326664 -58.667396) (xy 117.30736 -58.679842)
			(xy 117.301264 -58.689494) (xy 117.287244 -58.711236) (xy 117.253939 -58.75082) (xy 117.215257 -58.785167)
			(xy 117.172011 -58.813556) (xy 117.125112 -58.835387) (xy 117.075548 -58.850201) (xy 117.024362 -58.857687)
			(xy 116.998496 -58.85815) (xy 116.97185 -58.857568) (xy 116.919153 -58.849624) (xy 116.868229 -58.833916)
			(xy 116.820215 -58.810793) (xy 116.776184 -58.780772) (xy 116.737118 -58.744524) (xy 116.703891 -58.702859)
			(xy 116.677246 -58.656707) (xy 116.657776 -58.607099) (xy 116.645917 -58.555143) (xy 116.641935 -58.502)
			(xy 107.217718 -58.502) (xy 107.217718 -58.502042) (xy 107.217127 -58.536121) (xy 107.207956 -58.603661)
			(xy 107.19943 -58.636662) (xy 107.19943 -58.636916) (xy 107.197404 -58.645572) (xy 107.198895 -58.663277)
			(xy 107.206358 -58.679401) (xy 107.212384 -58.685938) (xy 107.284774 -58.758328) (xy 107.31119 -58.765186)
			(xy 107.324398 -58.76163) (xy 107.349244 -58.755224) (xy 107.400089 -58.748335) (xy 107.425744 -58.747914)
			(xy 107.452995 -58.748359) (xy 107.506941 -58.756121) (xy 107.559233 -58.771481) (xy 107.608808 -58.794126)
			(xy 107.654655 -58.823595) (xy 107.695843 -58.859288) (xy 107.731532 -58.90048) (xy 107.760995 -58.946331)
			(xy 107.783635 -58.995908) (xy 107.798988 -59.048202) (xy 107.806744 -59.102149) (xy 107.806744 -59.156651)
			(xy 107.802777 -59.184243) (xy 115.374668 -59.184243) (xy 115.374668 -59.120321) (xy 115.382679 -59.056903)
			(xy 115.398576 -58.994989) (xy 115.422108 -58.935556) (xy 115.452902 -58.879541) (xy 115.490475 -58.827826)
			(xy 115.534232 -58.781229) (xy 115.583485 -58.740484) (xy 115.637456 -58.706233) (xy 115.695295 -58.679016)
			(xy 115.756088 -58.659263) (xy 115.818878 -58.647285) (xy 115.882674 -58.643272) (xy 115.94647 -58.647285)
			(xy 116.00926 -58.659263) (xy 116.070053 -58.679016) (xy 116.127892 -58.706233) (xy 116.181863 -58.740484)
			(xy 116.231116 -58.781229) (xy 116.274873 -58.827826) (xy 116.304102 -58.868056) (xy 119.346216 -58.868056)
			(xy 119.350287 -58.812434) (xy 119.362413 -58.757997) (xy 119.382336 -58.705906) (xy 119.409632 -58.657271)
			(xy 119.443718 -58.613128) (xy 119.483867 -58.574419) (xy 119.529225 -58.541968) (xy 119.578825 -58.516467)
			(xy 119.631609 -58.49846) (xy 119.686452 -58.48833) (xy 119.742186 -58.486293) (xy 119.797623 -58.492393)
			(xy 119.85158 -58.506499) (xy 119.902909 -58.528311) (xy 119.950515 -58.557365) (xy 119.958458 -58.563975)
			(xy 135.198352 -58.563975) (xy 135.198352 -58.500053) (xy 135.206363 -58.436635) (xy 135.22226 -58.374721)
			(xy 135.245792 -58.315288) (xy 135.276586 -58.259273) (xy 135.314159 -58.207558) (xy 135.357916 -58.160961)
			(xy 135.407169 -58.120216) (xy 135.46114 -58.085965) (xy 135.518979 -58.058748) (xy 135.579772 -58.038995)
			(xy 135.642562 -58.027017) (xy 135.706358 -58.023004) (xy 135.770154 -58.027017) (xy 135.832944 -58.038995)
			(xy 135.893737 -58.058748) (xy 135.951576 -58.085965) (xy 136.005547 -58.120216) (xy 136.0548 -58.160961)
			(xy 136.098557 -58.207558) (xy 136.13613 -58.259273) (xy 136.166924 -58.315288) (xy 136.190456 -58.374721)
			(xy 136.206353 -58.436635) (xy 136.214364 -58.500053) (xy 136.214866 -58.532014) (xy 136.214364 -58.563975)
			(xy 139.000986 -58.563975) (xy 139.000986 -58.500053) (xy 139.008997 -58.436635) (xy 139.024894 -58.374721)
			(xy 139.048426 -58.315288) (xy 139.07922 -58.259273) (xy 139.116793 -58.207558) (xy 139.16055 -58.160961)
			(xy 139.209803 -58.120216) (xy 139.263774 -58.085965) (xy 139.321613 -58.058748) (xy 139.382406 -58.038995)
			(xy 139.445196 -58.027017) (xy 139.508992 -58.023004) (xy 139.572788 -58.027017) (xy 139.635578 -58.038995)
			(xy 139.696371 -58.058748) (xy 139.75421 -58.085965) (xy 139.808181 -58.120216) (xy 139.857434 -58.160961)
			(xy 139.901191 -58.207558) (xy 139.938764 -58.259273) (xy 139.969558 -58.315288) (xy 139.99309 -58.374721)
			(xy 140.008987 -58.436635) (xy 140.016998 -58.500053) (xy 140.0175 -58.532014) (xy 140.016998 -58.563975)
			(xy 140.008987 -58.627393) (xy 139.99309 -58.689307) (xy 139.969558 -58.74874) (xy 139.955769 -58.773822)
			(xy 146.47367 -58.773822) (xy 146.477741 -58.7182) (xy 146.489867 -58.663763) (xy 146.50979 -58.611672)
			(xy 146.537086 -58.563037) (xy 146.571172 -58.518894) (xy 146.611321 -58.480185) (xy 146.656679 -58.447734)
			(xy 146.706279 -58.422233) (xy 146.759063 -58.404226) (xy 146.813906 -58.394096) (xy 146.86964 -58.392059)
			(xy 146.925077 -58.398159) (xy 146.979034 -58.412265) (xy 147.030363 -58.434077) (xy 147.077969 -58.463131)
			(xy 147.120837 -58.498806) (xy 147.158054 -58.540343) (xy 147.188827 -58.586856) (xy 147.212499 -58.637353)
			(xy 147.228567 -58.69076) (xy 147.236687 -58.745936) (xy 147.237196 -58.773822) (xy 147.236687 -58.801708)
			(xy 147.228567 -58.856884) (xy 147.212499 -58.910291) (xy 147.188827 -58.960788) (xy 147.158054 -59.007301)
			(xy 147.149947 -59.016349) (xy 214.777568 -59.016349) (xy 214.777568 -58.952427) (xy 214.785579 -58.889009)
			(xy 214.801476 -58.827095) (xy 214.825008 -58.767662) (xy 214.855802 -58.711647) (xy 214.893375 -58.659932)
			(xy 214.937132 -58.613335) (xy 214.986385 -58.57259) (xy 215.040356 -58.538339) (xy 215.098195 -58.511122)
			(xy 215.158988 -58.491369) (xy 215.221778 -58.479391) (xy 215.285574 -58.475378) (xy 215.34937 -58.479391)
			(xy 215.41216 -58.491369) (xy 215.472953 -58.511122) (xy 215.530792 -58.538339) (xy 215.584763 -58.57259)
			(xy 215.634016 -58.613335) (xy 215.677773 -58.659932) (xy 215.715346 -58.711647) (xy 215.74614 -58.767662)
			(xy 215.769672 -58.827095) (xy 215.785569 -58.889009) (xy 215.78773 -58.906113) (xy 219.84436 -58.906113)
			(xy 219.84436 -58.842191) (xy 219.852371 -58.778773) (xy 219.868268 -58.716859) (xy 219.8918 -58.657426)
			(xy 219.922594 -58.601411) (xy 219.960167 -58.549696) (xy 220.003924 -58.503099) (xy 220.053177 -58.462354)
			(xy 220.107148 -58.428103) (xy 220.164987 -58.400886) (xy 220.22578 -58.381133) (xy 220.28857 -58.369155)
			(xy 220.352366 -58.365142) (xy 220.416162 -58.369155) (xy 220.478952 -58.381133) (xy 220.539745 -58.400886)
			(xy 220.597584 -58.428103) (xy 220.651555 -58.462354) (xy 220.700808 -58.503099) (xy 220.744565 -58.549696)
			(xy 220.782138 -58.601411) (xy 220.812932 -58.657426) (xy 220.836464 -58.716859) (xy 220.852361 -58.778773)
			(xy 220.860372 -58.842191) (xy 220.860874 -58.874152) (xy 220.860372 -58.906113) (xy 220.852361 -58.969531)
			(xy 220.836464 -59.031445) (xy 220.812932 -59.090878) (xy 220.782138 -59.146893) (xy 220.744565 -59.198608)
			(xy 220.700808 -59.245205) (xy 220.651555 -59.28595) (xy 220.597584 -59.320201) (xy 220.539745 -59.347418)
			(xy 220.478952 -59.367171) (xy 220.416162 -59.379149) (xy 220.352366 -59.383163) (xy 220.28857 -59.379149)
			(xy 220.22578 -59.367171) (xy 220.164987 -59.347418) (xy 220.107148 -59.320201) (xy 220.053177 -59.28595)
			(xy 220.003924 -59.245205) (xy 219.960167 -59.198608) (xy 219.922594 -59.146893) (xy 219.8918 -59.090878)
			(xy 219.868268 -59.031445) (xy 219.852371 -58.969531) (xy 219.84436 -58.906113) (xy 215.78773 -58.906113)
			(xy 215.79358 -58.952427) (xy 215.794082 -58.984388) (xy 215.79358 -59.016349) (xy 215.785569 -59.079767)
			(xy 215.769672 -59.141681) (xy 215.74614 -59.201114) (xy 215.715346 -59.257129) (xy 215.677773 -59.308844)
			(xy 215.634016 -59.355441) (xy 215.584763 -59.396186) (xy 215.530792 -59.430437) (xy 215.472953 -59.457654)
			(xy 215.41216 -59.477407) (xy 215.34937 -59.489385) (xy 215.285574 -59.493399) (xy 215.221778 -59.489385)
			(xy 215.158988 -59.477407) (xy 215.098195 -59.457654) (xy 215.040356 -59.430437) (xy 214.986385 -59.396186)
			(xy 214.937132 -59.355441) (xy 214.893375 -59.308844) (xy 214.855802 -59.257129) (xy 214.825008 -59.201114)
			(xy 214.801476 -59.141681) (xy 214.785579 -59.079767) (xy 214.777568 -59.016349) (xy 147.149947 -59.016349)
			(xy 147.120837 -59.048838) (xy 147.077969 -59.084513) (xy 147.030363 -59.113567) (xy 146.979034 -59.135379)
			(xy 146.925077 -59.149485) (xy 146.86964 -59.155585) (xy 146.813906 -59.153548) (xy 146.759063 -59.143418)
			(xy 146.706279 -59.125411) (xy 146.656679 -59.09991) (xy 146.611321 -59.067459) (xy 146.571172 -59.02875)
			(xy 146.537086 -58.984607) (xy 146.50979 -58.935972) (xy 146.489867 -58.883881) (xy 146.477741 -58.829444)
			(xy 146.47367 -58.773822) (xy 139.955769 -58.773822) (xy 139.938764 -58.804755) (xy 139.901191 -58.85647)
			(xy 139.857434 -58.903067) (xy 139.808181 -58.943812) (xy 139.75421 -58.978063) (xy 139.696371 -59.00528)
			(xy 139.635578 -59.025033) (xy 139.572788 -59.037011) (xy 139.508992 -59.041025) (xy 139.445196 -59.037011)
			(xy 139.382406 -59.025033) (xy 139.321613 -59.00528) (xy 139.263774 -58.978063) (xy 139.209803 -58.943812)
			(xy 139.16055 -58.903067) (xy 139.116793 -58.85647) (xy 139.07922 -58.804755) (xy 139.048426 -58.74874)
			(xy 139.024894 -58.689307) (xy 139.008997 -58.627393) (xy 139.000986 -58.563975) (xy 136.214364 -58.563975)
			(xy 136.206353 -58.627393) (xy 136.190456 -58.689307) (xy 136.166924 -58.74874) (xy 136.13613 -58.804755)
			(xy 136.098557 -58.85647) (xy 136.0548 -58.903067) (xy 136.005547 -58.943812) (xy 135.951576 -58.978063)
			(xy 135.893737 -59.00528) (xy 135.832944 -59.025033) (xy 135.770154 -59.037011) (xy 135.706358 -59.041025)
			(xy 135.642562 -59.037011) (xy 135.579772 -59.025033) (xy 135.518979 -59.00528) (xy 135.46114 -58.978063)
			(xy 135.407169 -58.943812) (xy 135.357916 -58.903067) (xy 135.314159 -58.85647) (xy 135.276586 -58.804755)
			(xy 135.245792 -58.74874) (xy 135.22226 -58.689307) (xy 135.206363 -58.627393) (xy 135.198352 -58.563975)
			(xy 119.958458 -58.563975) (xy 119.993383 -58.59304) (xy 120.0306 -58.634577) (xy 120.061373 -58.68109)
			(xy 120.085045 -58.731587) (xy 120.101113 -58.784994) (xy 120.109233 -58.84017) (xy 120.109742 -58.868056)
			(xy 120.109233 -58.895942) (xy 120.101113 -58.951118) (xy 120.085045 -59.004525) (xy 120.061373 -59.055022)
			(xy 120.0306 -59.101535) (xy 119.993383 -59.143072) (xy 119.950515 -59.178747) (xy 119.902909 -59.207801)
			(xy 119.888413 -59.213961) (xy 124.42418 -59.213961) (xy 124.42418 -59.150039) (xy 124.432191 -59.086621)
			(xy 124.448088 -59.024707) (xy 124.47162 -58.965274) (xy 124.502414 -58.909259) (xy 124.539987 -58.857544)
			(xy 124.583744 -58.810947) (xy 124.632997 -58.770202) (xy 124.686968 -58.735951) (xy 124.744807 -58.708734)
			(xy 124.8056 -58.688981) (xy 124.86839 -58.677003) (xy 124.932186 -58.67299) (xy 124.995982 -58.677003)
			(xy 125.058772 -58.688981) (xy 125.119565 -58.708734) (xy 125.177404 -58.735951) (xy 125.231375 -58.770202)
			(xy 125.280628 -58.810947) (xy 125.324385 -58.857544) (xy 125.361958 -58.909259) (xy 125.392752 -58.965274)
			(xy 125.416284 -59.024707) (xy 125.432181 -59.086621) (xy 125.440192 -59.150039) (xy 125.440694 -59.182)
			(xy 125.440192 -59.213961) (xy 126.54508 -59.213961) (xy 126.54508 -59.150039) (xy 126.553091 -59.086621)
			(xy 126.568988 -59.024707) (xy 126.59252 -58.965274) (xy 126.623314 -58.909259) (xy 126.660887 -58.857544)
			(xy 126.704644 -58.810947) (xy 126.753897 -58.770202) (xy 126.807868 -58.735951) (xy 126.865707 -58.708734)
			(xy 126.9265 -58.688981) (xy 126.98929 -58.677003) (xy 127.053086 -58.67299) (xy 127.116882 -58.677003)
			(xy 127.179672 -58.688981) (xy 127.240465 -58.708734) (xy 127.298304 -58.735951) (xy 127.352275 -58.770202)
			(xy 127.401528 -58.810947) (xy 127.445285 -58.857544) (xy 127.482858 -58.909259) (xy 127.513652 -58.965274)
			(xy 127.537184 -59.024707) (xy 127.553081 -59.086621) (xy 127.561092 -59.150039) (xy 127.561594 -59.182)
			(xy 127.561092 -59.213961) (xy 136.299696 -59.213961) (xy 136.299696 -59.150039) (xy 136.307707 -59.086621)
			(xy 136.323604 -59.024707) (xy 136.347136 -58.965274) (xy 136.37793 -58.909259) (xy 136.415503 -58.857544)
			(xy 136.45926 -58.810947) (xy 136.508513 -58.770202) (xy 136.562484 -58.735951) (xy 136.620323 -58.708734)
			(xy 136.681116 -58.688981) (xy 136.743906 -58.677003) (xy 136.807702 -58.67299) (xy 136.871498 -58.677003)
			(xy 136.934288 -58.688981) (xy 136.995081 -58.708734) (xy 137.05292 -58.735951) (xy 137.106891 -58.770202)
			(xy 137.156144 -58.810947) (xy 137.199901 -58.857544) (xy 137.237474 -58.909259) (xy 137.268268 -58.965274)
			(xy 137.2918 -59.024707) (xy 137.307697 -59.086621) (xy 137.315708 -59.150039) (xy 137.31621 -59.182)
			(xy 137.315708 -59.213961) (xy 137.307697 -59.277379) (xy 137.2918 -59.339293) (xy 137.268268 -59.398726)
			(xy 137.237474 -59.454741) (xy 137.199901 -59.506456) (xy 137.156144 -59.553053) (xy 137.106891 -59.593798)
			(xy 137.05292 -59.628049) (xy 136.995081 -59.655266) (xy 136.934288 -59.675019) (xy 136.871498 -59.686997)
			(xy 136.807702 -59.691011) (xy 136.743906 -59.686997) (xy 136.681116 -59.675019) (xy 136.620323 -59.655266)
			(xy 136.562484 -59.628049) (xy 136.508513 -59.593798) (xy 136.45926 -59.553053) (xy 136.415503 -59.506456)
			(xy 136.37793 -59.454741) (xy 136.347136 -59.398726) (xy 136.323604 -59.339293) (xy 136.307707 -59.277379)
			(xy 136.299696 -59.213961) (xy 127.561092 -59.213961) (xy 127.553081 -59.277379) (xy 127.537184 -59.339293)
			(xy 127.513652 -59.398726) (xy 127.482858 -59.454741) (xy 127.445285 -59.506456) (xy 127.401528 -59.553053)
			(xy 127.352275 -59.593798) (xy 127.298304 -59.628049) (xy 127.240465 -59.655266) (xy 127.179672 -59.675019)
			(xy 127.116882 -59.686997) (xy 127.053086 -59.691011) (xy 126.98929 -59.686997) (xy 126.9265 -59.675019)
			(xy 126.865707 -59.655266) (xy 126.807868 -59.628049) (xy 126.753897 -59.593798) (xy 126.704644 -59.553053)
			(xy 126.660887 -59.506456) (xy 126.623314 -59.454741) (xy 126.59252 -59.398726) (xy 126.568988 -59.339293)
			(xy 126.553091 -59.277379) (xy 126.54508 -59.213961) (xy 125.440192 -59.213961) (xy 125.432181 -59.277379)
			(xy 125.416284 -59.339293) (xy 125.392752 -59.398726) (xy 125.361958 -59.454741) (xy 125.324385 -59.506456)
			(xy 125.280628 -59.553053) (xy 125.231375 -59.593798) (xy 125.177404 -59.628049) (xy 125.119565 -59.655266)
			(xy 125.058772 -59.675019) (xy 124.995982 -59.686997) (xy 124.932186 -59.691011) (xy 124.86839 -59.686997)
			(xy 124.8056 -59.675019) (xy 124.744807 -59.655266) (xy 124.686968 -59.628049) (xy 124.632997 -59.593798)
			(xy 124.583744 -59.553053) (xy 124.539987 -59.506456) (xy 124.502414 -59.454741) (xy 124.47162 -59.398726)
			(xy 124.448088 -59.339293) (xy 124.432191 -59.277379) (xy 124.42418 -59.213961) (xy 119.888413 -59.213961)
			(xy 119.85158 -59.229613) (xy 119.797623 -59.243719) (xy 119.742186 -59.249819) (xy 119.686452 -59.247782)
			(xy 119.631609 -59.237652) (xy 119.578825 -59.219645) (xy 119.529225 -59.194144) (xy 119.483867 -59.161693)
			(xy 119.443718 -59.122984) (xy 119.409632 -59.078841) (xy 119.382336 -59.030206) (xy 119.362413 -58.978115)
			(xy 119.350287 -58.923678) (xy 119.346216 -58.868056) (xy 116.304102 -58.868056) (xy 116.312446 -58.879541)
			(xy 116.34324 -58.935556) (xy 116.366772 -58.994989) (xy 116.382669 -59.056903) (xy 116.39068 -59.120321)
			(xy 116.391182 -59.152282) (xy 116.39068 -59.184243) (xy 116.382669 -59.247661) (xy 116.366772 -59.309575)
			(xy 116.34324 -59.369008) (xy 116.312446 -59.425023) (xy 116.274873 -59.476738) (xy 116.231116 -59.523335)
			(xy 116.181863 -59.56408) (xy 116.127892 -59.598331) (xy 116.070053 -59.625548) (xy 116.00926 -59.645301)
			(xy 115.94647 -59.657279) (xy 115.882674 -59.661293) (xy 115.818878 -59.657279) (xy 115.756088 -59.645301)
			(xy 115.695295 -59.625548) (xy 115.637456 -59.598331) (xy 115.583485 -59.56408) (xy 115.534232 -59.523335)
			(xy 115.490475 -59.476738) (xy 115.452902 -59.425023) (xy 115.422108 -59.369008) (xy 115.398576 -59.309575)
			(xy 115.382679 -59.247661) (xy 115.374668 -59.184243) (xy 107.802777 -59.184243) (xy 107.798988 -59.210598)
			(xy 107.783635 -59.262892) (xy 107.760995 -59.312469) (xy 107.731532 -59.35832) (xy 107.695843 -59.399512)
			(xy 107.654655 -59.435205) (xy 107.608808 -59.464674) (xy 107.559233 -59.487319) (xy 107.506941 -59.502679)
			(xy 107.452995 -59.510441) (xy 107.425744 -59.51093) (xy 107.396772 -59.51037) (xy 107.339501 -59.50157)
			(xy 107.311698 -59.493404) (xy 107.302542 -59.490897) (xy 107.283613 -59.492183) (xy 107.266442 -59.500254)
			(xy 107.259628 -59.506866) (xy 107.19689 -59.57316) (xy 107.190624 -59.580269) (xy 107.183415 -59.597783)
			(xy 107.183058 -59.616719) (xy 107.185968 -59.625738) (xy 107.196029 -59.654068) (xy 107.210149 -59.712508)
			(xy 107.217267 -59.772207) (xy 107.217718 -59.802268) (xy 107.217266 -59.833812) (xy 107.209467 -59.896415)
			(xy 107.193983 -59.957572) (xy 107.171054 -60.016345) (xy 107.141031 -60.07183) (xy 107.104375 -60.123175)
			(xy 107.061649 -60.169592) (xy 107.013511 -60.210368) (xy 106.960698 -60.244876) (xy 106.904022 -60.272586)
			(xy 106.844354 -60.293073) (xy 106.818279 -60.298541) (xy 110.601754 -60.298541) (xy 110.601754 -60.234619)
			(xy 110.609765 -60.171201) (xy 110.625662 -60.109287) (xy 110.649194 -60.049854) (xy 110.679988 -59.993839)
			(xy 110.717561 -59.942124) (xy 110.761318 -59.895527) (xy 110.810571 -59.854782) (xy 110.864542 -59.820531)
			(xy 110.922381 -59.793314) (xy 110.983174 -59.773561) (xy 111.045964 -59.761583) (xy 111.10976 -59.75757)
			(xy 111.173556 -59.761583) (xy 111.236346 -59.773561) (xy 111.297139 -59.793314) (xy 111.354978 -59.820531)
			(xy 111.408949 -59.854782) (xy 111.458202 -59.895527) (xy 111.501959 -59.942124) (xy 111.539532 -59.993839)
			(xy 111.570326 -60.049854) (xy 111.593858 -60.109287) (xy 111.609755 -60.171201) (xy 111.617766 -60.234619)
			(xy 111.618268 -60.26658) (xy 111.617766 -60.298541) (xy 111.609755 -60.361959) (xy 111.593858 -60.423873)
			(xy 111.570326 -60.483306) (xy 111.539532 -60.539321) (xy 111.501959 -60.591036) (xy 111.458202 -60.637633)
			(xy 111.408949 -60.678378) (xy 111.354978 -60.712629) (xy 111.297139 -60.739846) (xy 111.236346 -60.759599)
			(xy 111.173556 -60.771577) (xy 111.10976 -60.775591) (xy 111.045964 -60.771577) (xy 110.983174 -60.759599)
			(xy 110.922381 -60.739846) (xy 110.864542 -60.712629) (xy 110.810571 -60.678378) (xy 110.761318 -60.637633)
			(xy 110.717561 -60.591036) (xy 110.679988 -60.539321) (xy 110.649194 -60.483306) (xy 110.625662 -60.423873)
			(xy 110.609765 -60.361959) (xy 110.601754 -60.298541) (xy 106.818279 -60.298541) (xy 106.78261 -60.306021)
			(xy 106.719739 -60.311233) (xy 106.656705 -60.308629) (xy 106.594478 -60.298247) (xy 106.534013 -60.280248)
			(xy 106.476239 -60.254907) (xy 106.422043 -60.222615) (xy 106.372257 -60.183868) (xy 106.327647 -60.139259)
			(xy 106.288897 -60.089475) (xy 106.256603 -60.035281) (xy 106.23126 -59.977508) (xy 106.213258 -59.917043)
			(xy 106.202874 -59.854817) (xy 106.200266 -59.791783) (xy 106.205475 -59.728912) (xy 106.218422 -59.667167)
			(xy 106.238906 -59.607498) (xy 106.266614 -59.550821) (xy 106.301119 -59.498007) (xy 106.341892 -59.449866)
			(xy 106.388307 -59.407139) (xy 106.439651 -59.370481) (xy 106.495135 -59.340455) (xy 106.553907 -59.317524)
			(xy 106.615064 -59.302037) (xy 106.677666 -59.294235) (xy 106.70921 -59.29376) (xy 106.744618 -59.294389)
			(xy 106.814749 -59.304208) (xy 106.882841 -59.323656) (xy 106.915458 -59.337448) (xy 106.924258 -59.340946)
			(xy 106.943165 -59.341772) (xy 106.961072 -59.335647) (xy 106.968544 -59.329828) (xy 107.049824 -59.26201)
			(xy 107.058714 -59.234578) (xy 107.055158 -59.220354) (xy 107.050067 -59.198095) (xy 107.044588 -59.152761)
			(xy 107.044236 -59.12993) (xy 107.044236 -59.129422) (xy 107.044341 -59.116426) (xy 107.046123 -59.090495)
			(xy 107.047792 -59.077606) (xy 107.04957 -59.06389) (xy 107.03941 -59.038744) (xy 106.947208 -58.968386)
			(xy 106.920284 -58.96483) (xy 106.907584 -58.970418) (xy 106.876184 -58.983057) (xy 106.810893 -59.000904)
			(xy 106.743814 -59.009952) (xy 106.709972 -59.01055) (xy 106.70921 -59.01055) (xy 106.67725 -59.009986)
			(xy 106.613834 -59.001976) (xy 106.551921 -58.98608) (xy 106.492489 -58.962551) (xy 106.436475 -58.931757)
			(xy 106.384762 -58.894187) (xy 106.338166 -58.850431) (xy 106.297421 -58.80118) (xy 106.263171 -58.74721)
			(xy 106.235954 -58.689374) (xy 106.216202 -58.628582) (xy 106.204224 -58.565794) (xy 106.20021 -58.502)
			(xy 94.589453 -58.502) (xy 94.593317 -58.504986) (xy 94.609505 -58.510434) (xy 94.618048 -58.510678)
			(xy 94.622112 -58.510678) (xy 94.649362 -58.511193) (xy 94.703306 -58.518951) (xy 94.755597 -58.534306)
			(xy 94.805171 -58.556947) (xy 94.851018 -58.586413) (xy 94.892206 -58.622103) (xy 94.927894 -58.663291)
			(xy 94.957359 -58.709139) (xy 94.979998 -58.758714) (xy 94.995352 -58.811006) (xy 95.003108 -58.86495)
			(xy 95.003108 -58.91945) (xy 94.995352 -58.973394) (xy 94.979998 -59.025686) (xy 94.959768 -59.069986)
			(xy 95.891094 -59.069986) (xy 95.895165 -59.014364) (xy 95.907291 -58.959927) (xy 95.927214 -58.907836)
			(xy 95.95451 -58.859201) (xy 95.988596 -58.815058) (xy 96.028745 -58.776349) (xy 96.074103 -58.743898)
			(xy 96.123703 -58.718397) (xy 96.176487 -58.70039) (xy 96.23133 -58.69026) (xy 96.287064 -58.688223)
			(xy 96.342501 -58.694323) (xy 96.396458 -58.708429) (xy 96.447787 -58.730241) (xy 96.495393 -58.759295)
			(xy 96.538261 -58.79497) (xy 96.575478 -58.836507) (xy 96.606251 -58.88302) (xy 96.629923 -58.933517)
			(xy 96.645991 -58.986924) (xy 96.654111 -59.0421) (xy 96.65462 -59.069986) (xy 96.654111 -59.097872)
			(xy 96.645991 -59.153048) (xy 96.629923 -59.206455) (xy 96.606251 -59.256952) (xy 96.575478 -59.303465)
			(xy 96.538261 -59.345002) (xy 96.495393 -59.380677) (xy 96.447787 -59.409731) (xy 96.396458 -59.431543)
			(xy 96.342501 -59.445649) (xy 96.287064 -59.451749) (xy 96.23133 -59.449712) (xy 96.176487 -59.439582)
			(xy 96.123703 -59.421575) (xy 96.074103 -59.396074) (xy 96.028745 -59.363623) (xy 95.988596 -59.324914)
			(xy 95.95451 -59.280771) (xy 95.927214 -59.232136) (xy 95.907291 -59.180045) (xy 95.895165 -59.125608)
			(xy 95.891094 -59.069986) (xy 94.959768 -59.069986) (xy 94.957359 -59.075261) (xy 94.927894 -59.121109)
			(xy 94.892206 -59.162297) (xy 94.851018 -59.197987) (xy 94.805171 -59.227453) (xy 94.755597 -59.250094)
			(xy 94.703306 -59.265449) (xy 94.649362 -59.273207) (xy 94.622112 -59.273694) (xy 94.595246 -59.273234)
			(xy 94.542044 -59.265708) (xy 94.490424 -59.250789) (xy 94.44141 -59.228773) (xy 94.395971 -59.200095)
			(xy 94.355007 -59.165323) (xy 94.31933 -59.125146) (xy 94.304104 -59.103006) (xy 94.296826 -59.093252)
			(xy 94.27559 -59.081442) (xy 94.263464 -59.0804) (xy 94.168214 -59.077098) (xy 94.145862 -59.087766)
			(xy 94.138496 -59.097672) (xy 94.131074 -59.107251) (xy 94.115186 -59.125552) (xy 94.106746 -59.134248)
			(xy 94.10059 -59.141063) (xy 94.093183 -59.157854) (xy 94.09217 -59.176179) (xy 94.094554 -59.185048)
			(xy 94.12605 -59.284362) (xy 94.146878 -59.302904) (xy 94.160848 -59.305444) (xy 94.192376 -59.311695)
			(xy 94.25365 -59.331113) (xy 94.311986 -59.3581) (xy 94.366455 -59.392227) (xy 94.416187 -59.432948)
			(xy 94.460389 -59.479614) (xy 94.498354 -59.531479) (xy 94.529479 -59.587718) (xy 94.553265 -59.647431)
			(xy 94.569334 -59.709667) (xy 94.577428 -59.773432) (xy 94.577916 -59.80557) (xy 94.577414 -59.837531)
			(xy 94.569403 -59.900949) (xy 94.553506 -59.962863) (xy 94.529974 -60.022296) (xy 94.49918 -60.078311)
			(xy 94.472382 -60.115196) (xy 96.183956 -60.115196) (xy 96.188027 -60.059574) (xy 96.200153 -60.005137)
			(xy 96.220076 -59.953046) (xy 96.247372 -59.904411) (xy 96.281458 -59.860268) (xy 96.321607 -59.821559)
			(xy 96.366965 -59.789108) (xy 96.416565 -59.763607) (xy 96.469349 -59.7456) (xy 96.524192 -59.73547)
			(xy 96.579926 -59.733433) (xy 96.635363 -59.739533) (xy 96.68932 -59.753639) (xy 96.740649 -59.775451)
			(xy 96.788255 -59.804505) (xy 96.831123 -59.84018) (xy 96.86834 -59.881717) (xy 96.899113 -59.92823)
			(xy 96.922785 -59.978727) (xy 96.938853 -60.032134) (xy 96.946973 -60.08731) (xy 96.947482 -60.115196)
			(xy 96.946973 -60.143082) (xy 96.938853 -60.198258) (xy 96.922785 -60.251665) (xy 96.899113 -60.302162)
			(xy 96.86834 -60.348675) (xy 96.831123 -60.390212) (xy 96.788255 -60.425887) (xy 96.740649 -60.454941)
			(xy 96.68932 -60.476753) (xy 96.635363 -60.490859) (xy 96.579926 -60.496959) (xy 96.524192 -60.494922)
			(xy 96.469349 -60.484792) (xy 96.416565 -60.466785) (xy 96.366965 -60.441284) (xy 96.321607 -60.408833)
			(xy 96.281458 -60.370124) (xy 96.247372 -60.325981) (xy 96.220076 -60.277346) (xy 96.200153 -60.225255)
			(xy 96.188027 -60.170818) (xy 96.183956 -60.115196) (xy 94.472382 -60.115196) (xy 94.461607 -60.130026)
			(xy 94.41785 -60.176623) (xy 94.368597 -60.217368) (xy 94.314626 -60.251619) (xy 94.256787 -60.278836)
			(xy 94.195994 -60.298589) (xy 94.133204 -60.310567) (xy 94.069408 -60.314581) (xy 94.005612 -60.310567)
			(xy 93.942822 -60.298589) (xy 93.882029 -60.278836) (xy 93.82419 -60.251619) (xy 93.770219 -60.217368)
			(xy 93.720966 -60.176623) (xy 93.677209 -60.130026) (xy 93.639636 -60.078311) (xy 93.608842 -60.022296)
			(xy 93.58531 -59.962863) (xy 93.569413 -59.900949) (xy 93.561402 -59.837531) (xy 93.5609 -59.80557)
			(xy 93.561409 -59.772876) (xy 93.569772 -59.708024) (xy 93.586384 -59.644781) (xy 93.610968 -59.58419)
			(xy 93.64312 -59.527253) (xy 93.682308 -59.474908) (xy 93.727886 -59.428022) (xy 93.753178 -59.407298)
			(xy 93.760194 -59.401249) (xy 93.769754 -59.385403) (xy 93.773034 -59.36719) (xy 93.77172 -59.358022)
			(xy 93.75521 -59.269884) (xy 93.753094 -59.260933) (xy 93.743524 -59.245241) (xy 93.729058 -59.233904)
			(xy 93.720412 -59.230768) (xy 93.694925 -59.222291) (xy 93.646443 -59.199171) (xy 93.601684 -59.169479)
			(xy 93.561532 -59.133802) (xy 93.526781 -59.092846) (xy 93.498118 -59.04742) (xy 93.476111 -58.998423)
			(xy 93.461193 -58.946824) (xy 93.453661 -58.893642) (xy 93.453204 -58.866786) (xy 89.829981 -58.866786)
			(xy 89.800199 -58.907778) (xy 89.756442 -58.954375) (xy 89.707189 -58.99512) (xy 89.653218 -59.029371)
			(xy 89.595379 -59.056588) (xy 89.534586 -59.076341) (xy 89.471796 -59.088319) (xy 89.408 -59.092333)
			(xy 89.344204 -59.088319) (xy 89.281414 -59.076341) (xy 89.220621 -59.056588) (xy 89.162782 -59.029371)
			(xy 89.108811 -58.99512) (xy 89.059558 -58.954375) (xy 89.015801 -58.907778) (xy 88.978228 -58.856063)
			(xy 88.947434 -58.800048) (xy 88.923902 -58.740615) (xy 88.908005 -58.678701) (xy 88.899994 -58.615283)
			(xy 81.739635 -58.615283) (xy 81.742788 -58.622692) (xy 81.759368 -58.652039) (xy 81.785485 -58.714178)
			(xy 81.803154 -58.779225) (xy 81.812065 -58.846038) (xy 81.812638 -58.87974) (xy 81.812136 -58.911701)
			(xy 81.804125 -58.975119) (xy 81.788228 -59.037033) (xy 81.764696 -59.096466) (xy 81.733902 -59.152481)
			(xy 81.696329 -59.204196) (xy 81.652572 -59.250793) (xy 81.603319 -59.291538) (xy 81.549348 -59.325789)
			(xy 81.491509 -59.353006) (xy 81.430716 -59.372759) (xy 81.367926 -59.384737) (xy 81.30413 -59.388751)
			(xy 81.240334 -59.384737) (xy 81.177544 -59.372759) (xy 81.116751 -59.353006) (xy 81.058912 -59.325789)
			(xy 81.004941 -59.291538) (xy 80.955688 -59.250793) (xy 80.911931 -59.204196) (xy 80.874358 -59.152481)
			(xy 80.843564 -59.096466) (xy 80.820032 -59.037033) (xy 80.804135 -58.975119) (xy 80.796124 -58.911701)
			(xy 80.795622 -58.87974) (xy 80.796193 -58.845223) (xy 80.80553 -58.776824) (xy 80.824052 -58.710322)
			(xy 80.851416 -58.646944) (xy 80.868774 -58.617104) (xy 80.869028 -58.61685) (xy 80.872218 -58.61105)
			(xy 80.875814 -58.598316) (xy 80.87614 -58.591704) (xy 80.876394 -58.577988) (xy 80.825848 -58.488834)
			(xy 80.821133 -58.481182) (xy 80.80747 -58.46952) (xy 80.790632 -58.463264) (xy 80.781652 -58.462926)
			(xy 55.67172 -58.462926) (xy 55.665711 -58.463097) (xy 55.654033 -58.465928) (xy 55.648606 -58.468514)
			(xy 55.645131 -58.470353) (xy 55.638751 -58.474945) (xy 55.635906 -58.477658) (xy 54.658514 -59.45505)
			(xy 70.610982 -59.45505) (xy 70.615053 -59.399428) (xy 70.627179 -59.344991) (xy 70.647102 -59.2929)
			(xy 70.674398 -59.244265) (xy 70.708484 -59.200122) (xy 70.748633 -59.161413) (xy 70.793991 -59.128962)
			(xy 70.843591 -59.103461) (xy 70.896375 -59.085454) (xy 70.951218 -59.075324) (xy 71.006952 -59.073287)
			(xy 71.062389 -59.079387) (xy 71.116346 -59.093493) (xy 71.167675 -59.115305) (xy 71.215281 -59.144359)
			(xy 71.258149 -59.180034) (xy 71.295366 -59.221571) (xy 71.326139 -59.268084) (xy 71.349811 -59.318581)
			(xy 71.365879 -59.371988) (xy 71.373999 -59.427164) (xy 71.37416 -59.436) (xy 72.074022 -59.436)
			(xy 72.078093 -59.380378) (xy 72.090219 -59.325941) (xy 72.110142 -59.27385) (xy 72.137438 -59.225215)
			(xy 72.171524 -59.181072) (xy 72.211673 -59.142363) (xy 72.257031 -59.109912) (xy 72.306631 -59.084411)
			(xy 72.359415 -59.066404) (xy 72.414258 -59.056274) (xy 72.469992 -59.054237) (xy 72.525429 -59.060337)
			(xy 72.579386 -59.074443) (xy 72.630715 -59.096255) (xy 72.678321 -59.125309) (xy 72.721189 -59.160984)
			(xy 72.758406 -59.202521) (xy 72.789179 -59.249034) (xy 72.812851 -59.299531) (xy 72.828919 -59.352938)
			(xy 72.837039 -59.408114) (xy 72.837548 -59.436) (xy 72.837057 -59.462881) (xy 86.333324 -59.462881)
			(xy 86.333324 -59.398959) (xy 86.341335 -59.335541) (xy 86.357232 -59.273627) (xy 86.380764 -59.214194)
			(xy 86.411558 -59.158179) (xy 86.449131 -59.106464) (xy 86.492888 -59.059867) (xy 86.542141 -59.019122)
			(xy 86.596112 -58.984871) (xy 86.653951 -58.957654) (xy 86.714744 -58.937901) (xy 86.777534 -58.925923)
			(xy 86.84133 -58.92191) (xy 86.905126 -58.925923) (xy 86.967916 -58.937901) (xy 87.028709 -58.957654)
			(xy 87.086548 -58.984871) (xy 87.140519 -59.019122) (xy 87.189772 -59.059867) (xy 87.233529 -59.106464)
			(xy 87.271102 -59.158179) (xy 87.301896 -59.214194) (xy 87.325428 -59.273627) (xy 87.341325 -59.335541)
			(xy 87.349336 -59.398959) (xy 87.349838 -59.43092) (xy 87.349336 -59.462881) (xy 87.341325 -59.526299)
			(xy 87.325428 -59.588213) (xy 87.301896 -59.647646) (xy 87.271102 -59.703661) (xy 87.233529 -59.755376)
			(xy 87.189772 -59.801973) (xy 87.140519 -59.842718) (xy 87.086548 -59.876969) (xy 87.06888 -59.885283)
			(xy 88.899994 -59.885283) (xy 88.899994 -59.821361) (xy 88.908005 -59.757943) (xy 88.923902 -59.696029)
			(xy 88.947434 -59.636596) (xy 88.978228 -59.580581) (xy 89.015801 -59.528866) (xy 89.059558 -59.482269)
			(xy 89.108811 -59.441524) (xy 89.162782 -59.407273) (xy 89.220621 -59.380056) (xy 89.281414 -59.360303)
			(xy 89.344204 -59.348325) (xy 89.408 -59.344312) (xy 89.471796 -59.348325) (xy 89.534586 -59.360303)
			(xy 89.595379 -59.380056) (xy 89.653218 -59.407273) (xy 89.707189 -59.441524) (xy 89.756442 -59.482269)
			(xy 89.800199 -59.528866) (xy 89.837772 -59.580581) (xy 89.868566 -59.636596) (xy 89.892098 -59.696029)
			(xy 89.907995 -59.757943) (xy 89.916006 -59.821361) (xy 89.916508 -59.853322) (xy 89.916006 -59.885283)
			(xy 89.907995 -59.948701) (xy 89.892098 -60.010615) (xy 89.868566 -60.070048) (xy 89.837772 -60.126063)
			(xy 89.800199 -60.177778) (xy 89.756442 -60.224375) (xy 89.707189 -60.26512) (xy 89.653218 -60.299371)
			(xy 89.595379 -60.326588) (xy 89.534586 -60.346341) (xy 89.471796 -60.358319) (xy 89.408 -60.362333)
			(xy 89.344204 -60.358319) (xy 89.281414 -60.346341) (xy 89.220621 -60.326588) (xy 89.162782 -60.299371)
			(xy 89.108811 -60.26512) (xy 89.059558 -60.224375) (xy 89.015801 -60.177778) (xy 88.978228 -60.126063)
			(xy 88.947434 -60.070048) (xy 88.923902 -60.010615) (xy 88.908005 -59.948701) (xy 88.899994 -59.885283)
			(xy 87.06888 -59.885283) (xy 87.028709 -59.904186) (xy 86.967916 -59.923939) (xy 86.905126 -59.935917)
			(xy 86.84133 -59.939931) (xy 86.777534 -59.935917) (xy 86.714744 -59.923939) (xy 86.653951 -59.904186)
			(xy 86.596112 -59.876969) (xy 86.542141 -59.842718) (xy 86.492888 -59.801973) (xy 86.449131 -59.755376)
			(xy 86.411558 -59.703661) (xy 86.380764 -59.647646) (xy 86.357232 -59.588213) (xy 86.341335 -59.526299)
			(xy 86.333324 -59.462881) (xy 72.837057 -59.462881) (xy 72.837039 -59.463886) (xy 72.828919 -59.519062)
			(xy 72.812851 -59.572469) (xy 72.789179 -59.622966) (xy 72.758406 -59.669479) (xy 72.721189 -59.711016)
			(xy 72.678321 -59.746691) (xy 72.630715 -59.775745) (xy 72.579386 -59.797557) (xy 72.525429 -59.811663)
			(xy 72.469992 -59.817763) (xy 72.414258 -59.815726) (xy 72.359415 -59.805596) (xy 72.306631 -59.787589)
			(xy 72.257031 -59.762088) (xy 72.211673 -59.729637) (xy 72.171524 -59.690928) (xy 72.137438 -59.646785)
			(xy 72.110142 -59.59815) (xy 72.090219 -59.546059) (xy 72.078093 -59.491622) (xy 72.074022 -59.436)
			(xy 71.37416 -59.436) (xy 71.374508 -59.45505) (xy 71.373999 -59.482936) (xy 71.365879 -59.538112)
			(xy 71.349811 -59.591519) (xy 71.326139 -59.642016) (xy 71.295366 -59.688529) (xy 71.258149 -59.730066)
			(xy 71.215281 -59.765741) (xy 71.167675 -59.794795) (xy 71.116346 -59.816607) (xy 71.062389 -59.830713)
			(xy 71.006952 -59.836813) (xy 70.951218 -59.834776) (xy 70.896375 -59.824646) (xy 70.843591 -59.806639)
			(xy 70.793991 -59.781138) (xy 70.748633 -59.748687) (xy 70.708484 -59.709978) (xy 70.674398 -59.665835)
			(xy 70.647102 -59.6172) (xy 70.627179 -59.565109) (xy 70.615053 -59.510672) (xy 70.610982 -59.45505)
			(xy 54.658514 -59.45505) (xy 53.402019 -60.711545) (xy 92.34398 -60.711545) (xy 92.34398 -60.647623)
			(xy 92.351991 -60.584205) (xy 92.367888 -60.522291) (xy 92.39142 -60.462858) (xy 92.422214 -60.406843)
			(xy 92.459787 -60.355128) (xy 92.503544 -60.308531) (xy 92.552797 -60.267786) (xy 92.606768 -60.233535)
			(xy 92.664607 -60.206318) (xy 92.7254 -60.186565) (xy 92.78819 -60.174587) (xy 92.851986 -60.170574)
			(xy 92.915782 -60.174587) (xy 92.978572 -60.186565) (xy 93.039365 -60.206318) (xy 93.097204 -60.233535)
			(xy 93.151175 -60.267786) (xy 93.200428 -60.308531) (xy 93.244185 -60.355128) (xy 93.281758 -60.406843)
			(xy 93.312552 -60.462858) (xy 93.336084 -60.522291) (xy 93.351981 -60.584205) (xy 93.359992 -60.647623)
			(xy 93.360494 -60.679584) (xy 93.359992 -60.711545) (xy 93.351981 -60.774963) (xy 93.336084 -60.836877)
			(xy 93.312552 -60.89631) (xy 93.281758 -60.952325) (xy 93.244185 -61.00404) (xy 93.200428 -61.050637)
			(xy 93.151175 -61.091382) (xy 93.107317 -61.119215) (xy 104.124754 -61.119215) (xy 104.124754 -61.055293)
			(xy 104.132765 -60.991875) (xy 104.148662 -60.929961) (xy 104.172194 -60.870528) (xy 104.202988 -60.814513)
			(xy 104.240561 -60.762798) (xy 104.284318 -60.716201) (xy 104.333571 -60.675456) (xy 104.387542 -60.641205)
			(xy 104.445381 -60.613988) (xy 104.506174 -60.594235) (xy 104.568964 -60.582257) (xy 104.63276 -60.578244)
			(xy 104.696556 -60.582257) (xy 104.759346 -60.594235) (xy 104.820139 -60.613988) (xy 104.877978 -60.641205)
			(xy 104.931949 -60.675456) (xy 104.981202 -60.716201) (xy 105.024959 -60.762798) (xy 105.062532 -60.814513)
			(xy 105.093326 -60.870528) (xy 105.116858 -60.929961) (xy 105.132755 -60.991875) (xy 105.140766 -61.055293)
			(xy 105.141268 -61.087254) (xy 106.200702 -61.087254) (xy 106.201204 -61.055293) (xy 106.209215 -60.991875)
			(xy 106.225112 -60.929961) (xy 106.248644 -60.870528) (xy 106.279438 -60.814513) (xy 106.317011 -60.762798)
			(xy 106.360768 -60.716201) (xy 106.410021 -60.675456) (xy 106.463992 -60.641205) (xy 106.521831 -60.613988)
			(xy 106.582624 -60.594235) (xy 106.645414 -60.582257) (xy 106.70921 -60.578244) (xy 106.773006 -60.582257)
			(xy 106.835796 -60.594235) (xy 106.896589 -60.613988) (xy 106.954428 -60.641205) (xy 107.008399 -60.675456)
			(xy 107.057652 -60.716201) (xy 107.101409 -60.762798) (xy 107.138982 -60.814513) (xy 107.169776 -60.870528)
			(xy 107.193308 -60.929961) (xy 107.196456 -60.94222) (xy 109.960662 -60.94222) (xy 109.964733 -60.886598)
			(xy 109.976859 -60.832161) (xy 109.996782 -60.78007) (xy 110.024078 -60.731435) (xy 110.058164 -60.687292)
			(xy 110.098313 -60.648583) (xy 110.143671 -60.616132) (xy 110.193271 -60.590631) (xy 110.246055 -60.572624)
			(xy 110.300898 -60.562494) (xy 110.356632 -60.560457) (xy 110.412069 -60.566557) (xy 110.466026 -60.580663)
			(xy 110.517355 -60.602475) (xy 110.564961 -60.631529) (xy 110.607829 -60.667204) (xy 110.645046 -60.708741)
			(xy 110.675819 -60.755254) (xy 110.699491 -60.805751) (xy 110.715559 -60.859158) (xy 110.723679 -60.914334)
			(xy 110.724188 -60.94222) (xy 110.723679 -60.970106) (xy 110.715559 -61.025282) (xy 110.714267 -61.029578)
			(xy 111.38635 -61.029578) (xy 111.394102 -60.975627) (xy 111.409454 -60.923327) (xy 111.432092 -60.873745)
			(xy 111.461557 -60.827889) (xy 111.497247 -60.786693) (xy 111.538437 -60.750996) (xy 111.584287 -60.721524)
			(xy 111.633866 -60.698877) (xy 111.686163 -60.683516) (xy 111.740113 -60.675754) (xy 111.767366 -60.675266)
			(xy 111.784287 -60.675485) (xy 111.817991 -60.678539) (xy 111.834676 -60.681362) (xy 111.848848 -60.683339)
			(xy 111.877289 -60.680352) (xy 111.90379 -60.669603) (xy 111.926274 -60.651932) (xy 111.942983 -60.628723)
			(xy 111.952608 -60.601794) (xy 111.954395 -60.573252) (xy 111.95177 -60.559188) (xy 111.946171 -60.532167)
			(xy 111.940192 -60.477307) (xy 111.939832 -60.449714) (xy 111.939832 -60.44946) (xy 111.94031 -60.417923)
			(xy 111.948117 -60.355332) (xy 111.963605 -60.294189) (xy 111.986537 -60.23543) (xy 112.016561 -60.179959)
			(xy 112.053215 -60.128628) (xy 112.095937 -60.082224) (xy 112.144071 -60.041461) (xy 112.196877 -60.006965)
			(xy 112.253544 -59.979265) (xy 112.313202 -59.958787) (xy 112.374935 -59.945845) (xy 112.437795 -59.940638)
			(xy 112.500816 -59.943246) (xy 112.56303 -59.953629) (xy 112.623483 -59.971628) (xy 112.681245 -59.996965)
			(xy 112.73543 -60.029253) (xy 112.785205 -60.067995) (xy 112.829805 -60.112595) (xy 112.868547 -60.16237)
			(xy 112.900835 -60.216555) (xy 112.926172 -60.274317) (xy 112.944171 -60.33477) (xy 112.950827 -60.374653)
			(xy 115.88263 -60.374653) (xy 115.88263 -60.320147) (xy 115.890387 -60.266194) (xy 115.905742 -60.213895)
			(xy 115.928384 -60.164313) (xy 115.957852 -60.118458) (xy 115.993545 -60.077264) (xy 116.034738 -60.041568)
			(xy 116.08059 -60.012097) (xy 116.130171 -59.989451) (xy 116.182469 -59.974092) (xy 116.236421 -59.966332)
			(xy 116.263674 -59.965844) (xy 116.28657 -59.966175) (xy 116.332032 -59.971652) (xy 116.354352 -59.976766)
			(xy 116.354606 -59.976766) (xy 116.366748 -59.979103) (xy 116.390711 -59.973111) (xy 116.400326 -59.965336)
			(xy 116.472462 -59.901328) (xy 116.481098 -59.87796) (xy 116.479574 -59.865514) (xy 116.477703 -59.849769)
			(xy 116.475668 -59.818123) (xy 116.47551 -59.802268) (xy 116.476012 -59.770307) (xy 116.484023 -59.706889)
			(xy 116.49992 -59.644975) (xy 116.523452 -59.585542) (xy 116.554246 -59.529527) (xy 116.591819 -59.477812)
			(xy 116.635576 -59.431215) (xy 116.684829 -59.39047) (xy 116.7388 -59.356219) (xy 116.796639 -59.329002)
			(xy 116.857432 -59.309249) (xy 116.920222 -59.297271) (xy 116.984018 -59.293258) (xy 117.047814 -59.297271)
			(xy 117.110604 -59.309249) (xy 117.171397 -59.329002) (xy 117.229236 -59.356219) (xy 117.283207 -59.39047)
			(xy 117.33246 -59.431215) (xy 117.376217 -59.477812) (xy 117.41379 -59.529527) (xy 117.444584 -59.585542)
			(xy 117.468116 -59.644975) (xy 117.484013 -59.706889) (xy 117.492024 -59.770307) (xy 117.492526 -59.802268)
			(xy 117.491256 -59.839606) (xy 117.49024 -59.85256) (xy 117.495681 -59.864201) (xy 135.198352 -59.864201)
			(xy 135.198352 -59.800279) (xy 135.206363 -59.736861) (xy 135.22226 -59.674947) (xy 135.245792 -59.615514)
			(xy 135.276586 -59.559499) (xy 135.314159 -59.507784) (xy 135.357916 -59.461187) (xy 135.407169 -59.420442)
			(xy 135.46114 -59.386191) (xy 135.518979 -59.358974) (xy 135.579772 -59.339221) (xy 135.642562 -59.327243)
			(xy 135.706358 -59.32323) (xy 135.770154 -59.327243) (xy 135.832944 -59.339221) (xy 135.893737 -59.358974)
			(xy 135.951576 -59.386191) (xy 136.005547 -59.420442) (xy 136.0548 -59.461187) (xy 136.098557 -59.507784)
			(xy 136.13613 -59.559499) (xy 136.166924 -59.615514) (xy 136.190456 -59.674947) (xy 136.206353 -59.736861)
			(xy 136.214364 -59.800279) (xy 136.214866 -59.83224) (xy 136.214364 -59.864201) (xy 136.206353 -59.927619)
			(xy 136.190456 -59.989533) (xy 136.166924 -60.048966) (xy 136.13613 -60.104981) (xy 136.098557 -60.156696)
			(xy 136.0548 -60.203293) (xy 136.005547 -60.244038) (xy 135.951576 -60.278289) (xy 135.893737 -60.305506)
			(xy 135.832944 -60.325259) (xy 135.770154 -60.337237) (xy 135.706358 -60.341251) (xy 135.642562 -60.337237)
			(xy 135.579772 -60.325259) (xy 135.518979 -60.305506) (xy 135.46114 -60.278289) (xy 135.407169 -60.244038)
			(xy 135.357916 -60.203293) (xy 135.314159 -60.156696) (xy 135.276586 -60.104981) (xy 135.245792 -60.048966)
			(xy 135.22226 -59.989533) (xy 135.206363 -59.927619) (xy 135.198352 -59.864201) (xy 117.495681 -59.864201)
			(xy 117.501162 -59.875928) (xy 117.580664 -59.934856) (xy 117.587719 -59.93978) (xy 117.604126 -59.944926)
			(xy 117.62131 -59.944301) (xy 117.629432 -59.94146) (xy 117.651492 -59.933262) (xy 117.697122 -59.921738)
			(xy 117.743823 -59.915916) (xy 117.767354 -59.915552) (xy 117.767862 -59.915552) (xy 117.795114 -59.916093)
			(xy 117.849063 -59.923844) (xy 117.90136 -59.939196) (xy 117.95094 -59.961834) (xy 117.996793 -59.991297)
			(xy 118.037986 -60.026987) (xy 118.07368 -60.068177) (xy 118.103148 -60.114027) (xy 118.125791 -60.163604)
			(xy 118.141148 -60.2159) (xy 118.148905 -60.269848) (xy 118.148905 -60.324352) (xy 118.141148 -60.3783)
			(xy 118.125791 -60.430596) (xy 118.103148 -60.480173) (xy 118.07368 -60.526023) (xy 118.037986 -60.567213)
			(xy 117.996793 -60.602903) (xy 117.95094 -60.632367) (xy 117.90136 -60.655004) (xy 117.849063 -60.670356)
			(xy 117.795114 -60.678107) (xy 117.767862 -60.678568) (xy 117.739281 -60.678047) (xy 117.682757 -60.669527)
			(xy 117.628137 -60.652667) (xy 117.576644 -60.627847) (xy 117.529431 -60.59562) (xy 117.487556 -60.55671)
			(xy 117.451955 -60.511987) (xy 117.423427 -60.462452) (xy 117.402609 -60.409215) (xy 117.389968 -60.353468)
			(xy 117.38737 -60.325) (xy 117.386354 -60.311792) (xy 117.372384 -60.290202) (xy 117.27307 -60.237116)
			(xy 117.247162 -60.23737) (xy 117.235986 -60.243974) (xy 117.235732 -60.243974) (xy 117.206858 -60.259819)
			(xy 117.145914 -60.284794) (xy 117.082256 -60.301693) (xy 117.016949 -60.310235) (xy 116.984018 -60.310776)
			(xy 116.95013 -60.310211) (xy 116.882956 -60.301203) (xy 116.817579 -60.283333) (xy 116.786152 -60.270644)
			(xy 116.774473 -60.266447) (xy 116.749774 -60.268455) (xy 116.738908 -60.274454) (xy 116.657628 -60.32627)
			(xy 116.645436 -60.34786) (xy 116.644928 -60.36056) (xy 116.64357 -60.38718) (xy 116.634333 -60.439677)
			(xy 116.617877 -60.490376) (xy 116.594524 -60.53829) (xy 116.564727 -60.582487) (xy 116.529068 -60.622106)
			(xy 116.488241 -60.656374) (xy 116.443041 -60.684625) (xy 116.394347 -60.706308) (xy 116.34311 -60.721001)
			(xy 116.290325 -60.728418) (xy 116.263674 -60.72886) (xy 116.236421 -60.728468) (xy 116.182469 -60.720708)
			(xy 116.130171 -60.705349) (xy 116.08059 -60.682703) (xy 116.034738 -60.653232) (xy 115.993545 -60.617536)
			(xy 115.957852 -60.576342) (xy 115.928384 -60.530487) (xy 115.905742 -60.480905) (xy 115.890387 -60.428606)
			(xy 115.88263 -60.374653) (xy 112.950827 -60.374653) (xy 112.954554 -60.396984) (xy 112.957162 -60.460005)
			(xy 112.951955 -60.522865) (xy 112.939013 -60.584598) (xy 112.918535 -60.644256) (xy 112.890835 -60.700923)
			(xy 112.856339 -60.753729) (xy 112.815576 -60.801863) (xy 112.769172 -60.844585) (xy 112.717841 -60.881239)
			(xy 112.66237 -60.911263) (xy 112.603611 -60.934195) (xy 112.542468 -60.949683) (xy 112.479877 -60.95749)
			(xy 112.44834 -60.957968) (xy 112.448086 -60.957968) (xy 112.420007 -60.957587) (xy 112.364192 -60.951394)
			(xy 112.309402 -60.939073) (xy 112.282732 -60.930282) (xy 112.269058 -60.926082) (xy 112.240507 -60.924588)
			(xy 112.21266 -60.931069) (xy 112.187702 -60.945016) (xy 112.167588 -60.965335) (xy 112.153897 -60.990435)
			(xy 112.147701 -61.018346) (xy 112.148112 -61.032644) (xy 112.148874 -61.056774) (xy 112.14845 -61.084027)
			(xy 112.140697 -61.137979) (xy 112.125344 -61.190278) (xy 112.102705 -61.23986) (xy 112.07324 -61.285715)
			(xy 112.037549 -61.326911) (xy 111.996359 -61.362607) (xy 111.950508 -61.392079) (xy 111.900929 -61.414725)
			(xy 111.848632 -61.430085) (xy 111.794682 -61.437846) (xy 111.740176 -61.43785) (xy 111.686224 -61.430097)
			(xy 111.633925 -61.414745) (xy 111.584343 -61.392106) (xy 111.538487 -61.362642) (xy 111.497291 -61.326951)
			(xy 111.461594 -61.285761) (xy 111.432122 -61.23991) (xy 111.409476 -61.190332) (xy 111.394115 -61.138035)
			(xy 111.386354 -61.084084) (xy 111.38635 -61.029578) (xy 110.714267 -61.029578) (xy 110.699491 -61.078689)
			(xy 110.675819 -61.129186) (xy 110.645046 -61.175699) (xy 110.607829 -61.217236) (xy 110.564961 -61.252911)
			(xy 110.517355 -61.281965) (xy 110.466026 -61.303777) (xy 110.412069 -61.317883) (xy 110.356632 -61.323983)
			(xy 110.300898 -61.321946) (xy 110.246055 -61.311816) (xy 110.193271 -61.293809) (xy 110.143671 -61.268308)
			(xy 110.098313 -61.235857) (xy 110.058164 -61.197148) (xy 110.024078 -61.153005) (xy 109.996782 -61.10437)
			(xy 109.976859 -61.052279) (xy 109.964733 -60.997842) (xy 109.960662 -60.94222) (xy 107.196456 -60.94222)
			(xy 107.209205 -60.991875) (xy 107.217216 -61.055293) (xy 107.217718 -61.087254) (xy 107.217167 -61.120586)
			(xy 107.208462 -61.186679) (xy 107.191194 -61.251068) (xy 107.165661 -61.312648) (xy 107.1323 -61.370363)
			(xy 107.091683 -61.423224) (xy 107.044506 -61.470325) (xy 106.991579 -61.510856) (xy 106.962956 -61.527944)
			(xy 106.950288 -61.5358) (xy 106.929859 -61.557488) (xy 106.916561 -61.584152) (xy 106.911528 -61.613519)
			(xy 106.915186 -61.643089) (xy 106.927226 -61.670343) (xy 106.946622 -61.692961) (xy 106.958892 -61.701426)
			(xy 106.98162 -61.716553) (xy 107.022925 -61.752254) (xy 107.058721 -61.793477) (xy 107.088278 -61.83938)
			(xy 107.110993 -61.889025) (xy 107.126401 -61.941401) (xy 107.13419 -61.995438) (xy 107.13466 -62.022736)
			(xy 107.13454 -62.029454) (xy 116.61744 -62.029454) (xy 116.61744 -61.974946) (xy 116.625197 -61.920993)
			(xy 116.640553 -61.868694) (xy 116.663197 -61.819112) (xy 116.692665 -61.773257) (xy 116.72836 -61.732063)
			(xy 116.769554 -61.696368) (xy 116.815408 -61.666899) (xy 116.86499 -61.644255) (xy 116.91729 -61.628898)
			(xy 116.971242 -61.62114) (xy 116.998496 -61.620654) (xy 117.034818 -61.622432) (xy 117.048352 -61.62333)
			(xy 117.075083 -61.618793) (xy 117.099674 -61.607373) (xy 117.120387 -61.589877) (xy 117.135758 -61.567542)
			(xy 117.144701 -61.541946) (xy 117.14607 -61.528452) (xy 117.148551 -61.4999) (xy 117.161007 -61.44396)
			(xy 117.181694 -61.390513) (xy 117.210146 -61.340764) (xy 117.245722 -61.295833) (xy 117.287622 -61.256731)
			(xy 117.3349 -61.22434) (xy 117.386494 -61.199388) (xy 117.44124 -61.182438) (xy 117.497907 -61.173871)
			(xy 117.526562 -61.17336) (xy 117.553814 -61.173885) (xy 117.607765 -61.181637) (xy 117.660063 -61.196988)
			(xy 117.709644 -61.219626) (xy 117.755498 -61.249091) (xy 117.796691 -61.284782) (xy 117.832386 -61.325972)
			(xy 117.861855 -61.371823) (xy 117.884499 -61.421401) (xy 117.899855 -61.473698) (xy 117.907613 -61.527648)
			(xy 117.907613 -61.582152) (xy 117.899855 -61.636102) (xy 117.884982 -61.686753) (xy 123.801571 -61.686753)
			(xy 123.801571 -61.632247) (xy 123.809329 -61.578295) (xy 123.824686 -61.525997) (xy 123.84733 -61.476417)
			(xy 123.8768 -61.430564) (xy 123.912495 -61.389372) (xy 123.95369 -61.35368) (xy 123.999545 -61.324214)
			(xy 124.049127 -61.301575) (xy 124.101427 -61.286222) (xy 124.155379 -61.278469) (xy 124.182632 -61.278008)
			(xy 124.211519 -61.278613) (xy 124.268626 -61.287382) (xy 124.323759 -61.304653) (xy 124.375662 -61.330034)
			(xy 124.423148 -61.362944) (xy 124.444506 -61.382402) (xy 124.451393 -61.388364) (xy 124.468191 -61.395385)
			(xy 124.477272 -61.396118) (xy 124.50826 -61.397642) (xy 124.517445 -61.397602) (xy 124.534886 -61.391891)
			(xy 124.542296 -61.386466) (xy 124.569482 -61.365373) (xy 124.628463 -61.329936) (xy 124.691679 -61.302765)
			(xy 124.757979 -61.284355) (xy 124.826154 -61.275042) (xy 124.860558 -61.274452) (xy 124.89252 -61.27501)
			(xy 124.955939 -61.283017) (xy 125.017855 -61.29891) (xy 125.077291 -61.322438) (xy 125.133309 -61.35323)
			(xy 125.185025 -61.3908) (xy 125.231625 -61.434557) (xy 125.272373 -61.483809) (xy 125.306626 -61.53778)
			(xy 125.333845 -61.595618) (xy 125.353599 -61.656412) (xy 125.365578 -61.719203) (xy 125.368519 -61.765942)
			(xy 126.521718 -61.765942) (xy 126.522117 -61.735212) (xy 126.529554 -61.674202) (xy 126.544288 -61.614533)
			(xy 126.566105 -61.557075) (xy 126.594687 -61.502663) (xy 126.629617 -61.452093) (xy 126.670386 -61.4061)
			(xy 126.7164 -61.365355) (xy 126.766989 -61.330451) (xy 126.821415 -61.301897) (xy 126.878885 -61.28011)
			(xy 126.938561 -61.265407) (xy 126.969012 -61.261244) (xy 126.978918 -61.259974) (xy 126.996444 -61.250068)
			(xy 127.053594 -61.177424) (xy 127.058928 -61.157866) (xy 127.057658 -61.14796) (xy 127.056338 -61.136449)
			(xy 127.054941 -61.113318) (xy 127.054864 -61.101732) (xy 127.055118 -61.087762) (xy 127.055372 -61.078618)
			(xy 127.04953 -61.061092) (xy 126.995174 -60.994544) (xy 126.97968 -60.9854) (xy 126.970536 -60.983876)
			(xy 126.970028 -60.983876) (xy 126.938036 -60.977991) (xy 126.875739 -60.959279) (xy 126.816337 -60.932773)
			(xy 126.760801 -60.898908) (xy 126.710038 -60.858235) (xy 126.664877 -60.811421) (xy 126.626056 -60.759228)
			(xy 126.59421 -60.702511) (xy 126.569857 -60.642194) (xy 126.553396 -60.579265) (xy 126.545096 -60.514749)
			(xy 126.544578 -60.482226) (xy 126.54508 -60.450265) (xy 126.553091 -60.386847) (xy 126.568988 -60.324933)
			(xy 126.59252 -60.2655) (xy 126.623314 -60.209485) (xy 126.660887 -60.15777) (xy 126.704644 -60.111173)
			(xy 126.753897 -60.070428) (xy 126.807868 -60.036177) (xy 126.865707 -60.00896) (xy 126.9265 -59.989207)
			(xy 126.98929 -59.977229) (xy 127.053086 -59.973216) (xy 127.116882 -59.977229) (xy 127.179672 -59.989207)
			(xy 127.240465 -60.00896) (xy 127.298304 -60.036177) (xy 127.352275 -60.070428) (xy 127.401528 -60.111173)
			(xy 127.445285 -60.15777) (xy 127.482858 -60.209485) (xy 127.513652 -60.2655) (xy 127.537184 -60.324933)
			(xy 127.553081 -60.386847) (xy 127.561092 -60.450265) (xy 127.561594 -60.482226) (xy 127.560968 -60.514187)
			(xy 136.299696 -60.514187) (xy 136.299696 -60.450265) (xy 136.307707 -60.386847) (xy 136.323604 -60.324933)
			(xy 136.347136 -60.2655) (xy 136.37793 -60.209485) (xy 136.415503 -60.15777) (xy 136.45926 -60.111173)
			(xy 136.508513 -60.070428) (xy 136.562484 -60.036177) (xy 136.620323 -60.00896) (xy 136.681116 -59.989207)
			(xy 136.743906 -59.977229) (xy 136.807702 -59.973216) (xy 136.871498 -59.977229) (xy 136.934288 -59.989207)
			(xy 136.995081 -60.00896) (xy 137.05292 -60.036177) (xy 137.106891 -60.070428) (xy 137.156144 -60.111173)
			(xy 137.199901 -60.15777) (xy 137.237474 -60.209485) (xy 137.268268 -60.2655) (xy 137.2918 -60.324933)
			(xy 137.307697 -60.386847) (xy 137.308799 -60.395569) (xy 139.000986 -60.395569) (xy 139.000986 -60.331647)
			(xy 139.008997 -60.268229) (xy 139.024894 -60.206315) (xy 139.048426 -60.146882) (xy 139.07922 -60.090867)
			(xy 139.116793 -60.039152) (xy 139.16055 -59.992555) (xy 139.209803 -59.95181) (xy 139.263774 -59.917559)
			(xy 139.321613 -59.890342) (xy 139.382406 -59.870589) (xy 139.445196 -59.858611) (xy 139.508992 -59.854598)
			(xy 139.572788 -59.858611) (xy 139.635578 -59.870589) (xy 139.696371 -59.890342) (xy 139.75421 -59.917559)
			(xy 139.808181 -59.95181) (xy 139.857434 -59.992555) (xy 139.901191 -60.039152) (xy 139.938764 -60.090867)
			(xy 139.969558 -60.146882) (xy 139.99309 -60.206315) (xy 140.008987 -60.268229) (xy 140.016998 -60.331647)
			(xy 140.0175 -60.363608) (xy 140.016998 -60.395569) (xy 140.008987 -60.458987) (xy 139.99309 -60.520901)
			(xy 139.969558 -60.580334) (xy 139.938764 -60.636349) (xy 139.901191 -60.688064) (xy 139.857434 -60.734661)
			(xy 139.808181 -60.775406) (xy 139.75421 -60.809657) (xy 139.696371 -60.836874) (xy 139.635578 -60.856627)
			(xy 139.572788 -60.868605) (xy 139.508992 -60.872619) (xy 139.445196 -60.868605) (xy 139.382406 -60.856627)
			(xy 139.321613 -60.836874) (xy 139.263774 -60.809657) (xy 139.209803 -60.775406) (xy 139.16055 -60.734661)
			(xy 139.116793 -60.688064) (xy 139.07922 -60.636349) (xy 139.048426 -60.580334) (xy 139.024894 -60.520901)
			(xy 139.008997 -60.458987) (xy 139.000986 -60.395569) (xy 137.308799 -60.395569) (xy 137.315708 -60.450265)
			(xy 137.31621 -60.482226) (xy 137.315708 -60.514187) (xy 137.307697 -60.577605) (xy 137.2918 -60.639519)
			(xy 137.268268 -60.698952) (xy 137.237474 -60.754967) (xy 137.199901 -60.806682) (xy 137.156144 -60.853279)
			(xy 137.106891 -60.894024) (xy 137.05292 -60.928275) (xy 136.995081 -60.955492) (xy 136.934288 -60.975245)
			(xy 136.871498 -60.987223) (xy 136.807702 -60.991237) (xy 136.743906 -60.987223) (xy 136.681116 -60.975245)
			(xy 136.620323 -60.955492) (xy 136.562484 -60.928275) (xy 136.508513 -60.894024) (xy 136.45926 -60.853279)
			(xy 136.415503 -60.806682) (xy 136.37793 -60.754967) (xy 136.347136 -60.698952) (xy 136.323604 -60.639519)
			(xy 136.307707 -60.577605) (xy 136.299696 -60.514187) (xy 127.560968 -60.514187) (xy 127.56085 -60.52021)
			(xy 127.549505 -60.595326) (xy 127.538988 -60.631832) (xy 127.538988 -60.632086) (xy 127.53669 -60.640933)
			(xy 127.537869 -60.659162) (xy 127.541274 -60.667646) (xy 127.572516 -60.737242) (xy 127.585724 -60.75045)
			(xy 127.594106 -60.75426) (xy 127.61877 -60.765995) (xy 127.664771 -60.795441) (xy 127.706103 -60.831146)
			(xy 127.741922 -60.872378) (xy 127.771496 -60.918297) (xy 127.794221 -60.967963) (xy 127.809633 -61.020362)
			(xy 127.80964 -61.020409) (xy 149.089866 -61.020409) (xy 149.089866 -60.956487) (xy 149.097877 -60.893069)
			(xy 149.113774 -60.831155) (xy 149.137306 -60.771722) (xy 149.1681 -60.715707) (xy 149.205673 -60.663992)
			(xy 149.24943 -60.617395) (xy 149.298683 -60.57665) (xy 149.352654 -60.542399) (xy 149.410493 -60.515182)
			(xy 149.471286 -60.495429) (xy 149.534076 -60.483451) (xy 149.597872 -60.479438) (xy 149.661668 -60.483451)
			(xy 149.724458 -60.495429) (xy 149.785251 -60.515182) (xy 149.84309 -60.542399) (xy 149.897061 -60.57665)
			(xy 149.946314 -60.617395) (xy 149.990071 -60.663992) (xy 150.027644 -60.715707) (xy 150.055156 -60.765752)
			(xy 150.891967 -60.765752) (xy 150.891967 -60.711248) (xy 150.899724 -60.657299) (xy 150.91508 -60.605002)
			(xy 150.937722 -60.555423) (xy 150.967189 -60.509572) (xy 151.002882 -60.46838) (xy 151.044073 -60.432688)
			(xy 151.089925 -60.403221) (xy 151.139504 -60.380579) (xy 151.1918 -60.365224) (xy 151.24575 -60.357467)
			(xy 151.273002 -60.357004) (xy 151.301539 -60.357542) (xy 151.357975 -60.366052) (xy 151.412511 -60.382881)
			(xy 151.463928 -60.407653) (xy 151.511077 -60.439814) (xy 151.532336 -60.458858) (xy 151.541239 -60.466314)
			(xy 151.563475 -60.472923) (xy 151.575008 -60.471558) (xy 151.65451 -60.458604) (xy 151.665887 -60.456152)
			(xy 151.684814 -60.442657) (xy 151.690832 -60.432696) (xy 151.705735 -60.406251) (xy 151.7408 -60.356701)
			(xy 151.781515 -60.31168) (xy 151.827302 -60.271827) (xy 151.877509 -60.237709) (xy 151.931421 -60.209813)
			(xy 151.988272 -60.188535) (xy 152.047252 -60.174179) (xy 152.107521 -60.166947) (xy 152.137872 -60.166504)
			(xy 152.169836 -60.166959) (xy 152.233261 -60.174968) (xy 152.295182 -60.190864) (xy 152.354622 -60.214395)
			(xy 152.410644 -60.245191) (xy 152.462364 -60.282765) (xy 152.508968 -60.326526) (xy 152.549718 -60.375783)
			(xy 152.583974 -60.429759) (xy 152.611194 -60.487602) (xy 152.63095 -60.548402) (xy 152.642929 -60.611198)
			(xy 152.646944 -60.675) (xy 152.642929 -60.738802) (xy 152.63095 -60.801598) (xy 152.611194 -60.862398)
			(xy 152.583974 -60.920241) (xy 152.549718 -60.974217) (xy 152.508968 -61.023474) (xy 152.462364 -61.067235)
			(xy 152.410644 -61.104809) (xy 152.354622 -61.135605) (xy 152.295182 -61.159136) (xy 152.233261 -61.175032)
			(xy 152.169836 -61.183041) (xy 152.137872 -61.18352) (xy 152.104171 -61.182954) (xy 152.037362 -61.174039)
			(xy 151.972313 -61.156384) (xy 151.910165 -61.130296) (xy 151.852004 -61.096233) (xy 151.798849 -61.05479)
			(xy 151.75163 -61.006693) (xy 151.730964 -60.980066) (xy 151.723525 -60.971034) (xy 151.702757 -60.960313)
			(xy 151.691086 -60.959492) (xy 151.610822 -60.958476) (xy 151.599332 -60.958915) (xy 151.578492 -60.968568)
			(xy 151.57069 -60.977018) (xy 151.570436 -60.977526) (xy 151.552215 -60.999365) (xy 151.510416 -61.037931)
			(xy 151.463349 -61.069855) (xy 151.412059 -61.094429) (xy 151.357686 -61.111105) (xy 151.301439 -61.119515)
			(xy 151.273002 -61.12002) (xy 151.24575 -61.119533) (xy 151.1918 -61.111776) (xy 151.139504 -61.096421)
			(xy 151.089925 -61.073779) (xy 151.044073 -61.044312) (xy 151.002882 -61.00862) (xy 150.967189 -60.967428)
			(xy 150.937722 -60.921577) (xy 150.91508 -60.871998) (xy 150.899724 -60.819701) (xy 150.891967 -60.765752)
			(xy 150.055156 -60.765752) (xy 150.058438 -60.771722) (xy 150.08197 -60.831155) (xy 150.097867 -60.893069)
			(xy 150.105878 -60.956487) (xy 150.10638 -60.988448) (xy 150.105878 -61.020409) (xy 150.097867 -61.083827)
			(xy 150.08197 -61.145741) (xy 150.058438 -61.205174) (xy 150.027644 -61.261189) (xy 149.990071 -61.312904)
			(xy 149.946314 -61.359501) (xy 149.897061 -61.400246) (xy 149.84309 -61.434497) (xy 149.785251 -61.461714)
			(xy 149.724458 -61.481467) (xy 149.661668 -61.493445) (xy 149.597872 -61.497459) (xy 149.534076 -61.493445)
			(xy 149.471286 -61.481467) (xy 149.410493 -61.461714) (xy 149.352654 -61.434497) (xy 149.298683 -61.400246)
			(xy 149.24943 -61.359501) (xy 149.205673 -61.312904) (xy 149.1681 -61.261189) (xy 149.137306 -61.205174)
			(xy 149.113774 -61.145741) (xy 149.097877 -61.083827) (xy 149.089866 -61.020409) (xy 127.80964 -61.020409)
			(xy 127.817416 -61.074423) (xy 127.81788 -61.101732) (xy 127.817348 -61.130819) (xy 127.808498 -61.188315)
			(xy 127.791024 -61.243803) (xy 127.765331 -61.295995) (xy 127.732014 -61.343683) (xy 127.691845 -61.385762)
			(xy 127.645754 -61.421256) (xy 127.59481 -61.449344) (xy 127.56769 -61.459872) (xy 127.567436 -61.459872)
			(xy 127.558411 -61.463833) (xy 127.544034 -61.477286) (xy 127.539496 -61.486034) (xy 127.504698 -61.56071)
			(xy 127.503936 -61.580776) (xy 127.507492 -61.590428) (xy 127.517386 -61.618621) (xy 127.531295 -61.676729)
			(xy 127.538301 -61.736067) (xy 127.538734 -61.765942) (xy 127.538722 -61.7667) (xy 141.673593 -61.7667)
			(xy 141.677607 -61.702905) (xy 141.689585 -61.640116) (xy 141.709337 -61.579323) (xy 141.736554 -61.521485)
			(xy 141.770804 -61.467515) (xy 141.811549 -61.418262) (xy 141.858145 -61.374505) (xy 141.909859 -61.336933)
			(xy 141.965873 -61.306138) (xy 142.025305 -61.282607) (xy 142.087218 -61.26671) (xy 142.150635 -61.258698)
			(xy 142.182596 -61.258196) (xy 142.212108 -61.258612) (xy 142.270733 -61.265471) (xy 142.328172 -61.279061)
			(xy 142.383654 -61.299202) (xy 142.436436 -61.325621) (xy 142.485809 -61.357967) (xy 142.508732 -61.37656)
			(xy 142.51621 -61.382188) (xy 142.533918 -61.388191) (xy 142.543276 -61.388244) (xy 142.57401 -61.387228)
			(xy 142.58316 -61.386554) (xy 142.600087 -61.37951) (xy 142.60703 -61.373512) (xy 142.628386 -61.354115)
			(xy 142.675845 -61.321315) (xy 142.727702 -61.296036) (xy 142.782774 -61.278853) (xy 142.839805 -61.270159)
			(xy 142.86865 -61.269626) (xy 142.868904 -61.269626) (xy 142.901097 -61.270276) (xy 142.964574 -61.281056)
			(xy 143.025334 -61.302357) (xy 143.053816 -61.317378) (xy 143.06154 -61.321219) (xy 143.078538 -61.324087)
			(xy 143.08709 -61.322966) (xy 143.116554 -61.317886) (xy 143.125175 -61.316009) (xy 143.14051 -61.30732)
			(xy 143.146526 -61.300868) (xy 143.167287 -61.277253) (xy 143.213637 -61.234762) (xy 143.264874 -61.198312)
			(xy 143.320216 -61.168462) (xy 143.378817 -61.145667) (xy 143.439783 -61.130275) (xy 143.502182 -61.122521)
			(xy 143.533622 -61.122052) (xy 143.56558 -61.122635) (xy 143.628991 -61.130648) (xy 143.690897 -61.146546)
			(xy 143.750323 -61.170076) (xy 143.806332 -61.20087) (xy 143.85804 -61.238439) (xy 143.904631 -61.282193)
			(xy 143.945371 -61.331442) (xy 143.979618 -61.385408) (xy 144.006831 -61.44324) (xy 144.026581 -61.504028)
			(xy 144.038557 -61.566811) (xy 144.042571 -61.6306) (xy 144.038557 -61.694389) (xy 144.026581 -61.757172)
			(xy 144.007392 -61.816234) (xy 161.493708 -61.816234) (xy 161.494165 -61.784946) (xy 161.501844 -61.722842)
			(xy 161.51709 -61.662152) (xy 161.539672 -61.603792) (xy 161.569249 -61.548647) (xy 161.605373 -61.49755)
			(xy 161.647497 -61.451276) (xy 161.694984 -61.410523) (xy 161.720784 -61.392816) (xy 161.730913 -61.385269)
			(xy 161.742784 -61.363014) (xy 161.74339 -61.350398) (xy 161.74339 -61.26607) (xy 161.742702 -61.253471)
			(xy 161.730874 -61.231223) (xy 161.720784 -61.223652) (xy 161.695028 -61.205891) (xy 161.647565 -61.16513)
			(xy 161.605462 -61.118853) (xy 161.569357 -61.067758) (xy 161.539795 -61.01262) (xy 161.517223 -60.95427)
			(xy 161.501982 -60.893591) (xy 161.494302 -60.831501) (xy 161.494299 -60.768937) (xy 161.501975 -60.706846)
			(xy 161.517211 -60.646166) (xy 161.539779 -60.587815) (xy 161.569337 -60.532674) (xy 161.605439 -60.481577)
			(xy 161.647538 -60.435296) (xy 161.694998 -60.394531) (xy 161.720784 -60.376816) (xy 161.730913 -60.369269)
			(xy 161.742784 -60.347014) (xy 161.74339 -60.334398) (xy 161.74339 -60.25007) (xy 161.742702 -60.237471)
			(xy 161.730874 -60.215223) (xy 161.720784 -60.207652) (xy 161.694983 -60.18995) (xy 161.647506 -60.149189)
			(xy 161.605391 -60.102909) (xy 161.569274 -60.051811) (xy 161.539702 -59.996666) (xy 161.517121 -59.938309)
			(xy 161.501874 -59.877621) (xy 161.49419 -59.815521) (xy 161.493708 -59.784234) (xy 161.49417 -59.753502)
			(xy 161.501575 -59.692486) (xy 161.516281 -59.632807) (xy 161.538074 -59.575336) (xy 161.566635 -59.520912)
			(xy 161.60155 -59.470327) (xy 161.642307 -59.424319) (xy 161.688313 -59.383561) (xy 161.738896 -59.348645)
			(xy 161.79332 -59.320081) (xy 161.85079 -59.298286) (xy 161.910468 -59.283578) (xy 161.971484 -59.276171)
			(xy 162.002216 -59.275726) (xy 162.00247 -59.275726) (xy 162.032678 -59.27617) (xy 162.09267 -59.283307)
			(xy 162.151392 -59.297506) (xy 162.208017 -59.318569) (xy 162.261744 -59.346197) (xy 162.311817 -59.380001)
			(xy 162.334956 -59.399424) (xy 162.342021 -59.405078) (xy 162.358937 -59.41146) (xy 162.367976 -59.41187)
			(xy 162.398456 -59.41187) (xy 162.407492 -59.411447) (xy 162.424409 -59.405071) (xy 162.431476 -59.399424)
			(xy 162.45461 -59.379996) (xy 162.504693 -59.34621) (xy 162.558424 -59.31859) (xy 162.615048 -59.297528)
			(xy 162.673767 -59.283317) (xy 162.733755 -59.27616) (xy 162.763962 -59.275726) (xy 162.764216 -59.275726)
			(xy 162.79495 -59.276123) (xy 162.855969 -59.283534) (xy 162.91565 -59.298246) (xy 162.973122 -59.320045)
			(xy 163.027548 -59.348613) (xy 163.078133 -59.383533) (xy 163.12414 -59.424295) (xy 163.164898 -59.470307)
			(xy 163.199813 -59.520895) (xy 163.228375 -59.575324) (xy 163.23351 -59.588865) (xy 168.126404 -59.588865)
			(xy 168.126404 -59.524943) (xy 168.134415 -59.461525) (xy 168.150312 -59.399611) (xy 168.173844 -59.340178)
			(xy 168.204638 -59.284163) (xy 168.242211 -59.232448) (xy 168.285968 -59.185851) (xy 168.335221 -59.145106)
			(xy 168.389192 -59.110855) (xy 168.447031 -59.083638) (xy 168.507824 -59.063885) (xy 168.570614 -59.051907)
			(xy 168.63441 -59.047894) (xy 168.698206 -59.051907) (xy 168.760996 -59.063885) (xy 168.821789 -59.083638)
			(xy 168.879628 -59.110855) (xy 168.933599 -59.145106) (xy 168.982852 -59.185851) (xy 169.026609 -59.232448)
			(xy 169.064182 -59.284163) (xy 169.094976 -59.340178) (xy 169.118508 -59.399611) (xy 169.134405 -59.461525)
			(xy 169.142416 -59.524943) (xy 169.142918 -59.556904) (xy 169.142416 -59.588865) (xy 169.134405 -59.652283)
			(xy 169.118508 -59.714197) (xy 169.094976 -59.77363) (xy 169.064182 -59.829645) (xy 169.026609 -59.88136)
			(xy 168.982852 -59.927957) (xy 168.933599 -59.968702) (xy 168.879628 -60.002953) (xy 168.821789 -60.03017)
			(xy 168.760996 -60.049923) (xy 168.698206 -60.061901) (xy 168.63441 -60.065915) (xy 168.570614 -60.061901)
			(xy 168.507824 -60.049923) (xy 168.447031 -60.03017) (xy 168.389192 -60.002953) (xy 168.335221 -59.968702)
			(xy 168.285968 -59.927957) (xy 168.242211 -59.88136) (xy 168.204638 -59.829645) (xy 168.173844 -59.77363)
			(xy 168.150312 -59.714197) (xy 168.134415 -59.652283) (xy 168.126404 -59.588865) (xy 163.23351 -59.588865)
			(xy 163.250169 -59.632798) (xy 163.264875 -59.69248) (xy 163.27228 -59.7535) (xy 163.272724 -59.784234)
			(xy 163.272228 -59.815521) (xy 163.264553 -59.877622) (xy 163.249312 -59.938311) (xy 163.226735 -59.99667)
			(xy 163.197164 -60.051815) (xy 163.161046 -60.102912) (xy 163.118927 -60.149189) (xy 163.071445 -60.189944)
			(xy 163.045648 -60.207652) (xy 163.035493 -60.215171) (xy 163.023634 -60.237447) (xy 163.023042 -60.25007)
			(xy 163.023042 -60.334398) (xy 163.023676 -60.347005) (xy 163.035541 -60.369252) (xy 163.045648 -60.376816)
			(xy 163.071467 -60.394487) (xy 163.11893 -60.435258) (xy 163.161031 -60.481544) (xy 163.197134 -60.532647)
			(xy 163.226693 -60.587794) (xy 163.249262 -60.646152) (xy 163.264499 -60.706837) (xy 163.272175 -60.768934)
			(xy 163.272173 -60.831504) (xy 163.264492 -60.8936) (xy 163.24925 -60.954284) (xy 163.226677 -61.01264)
			(xy 163.197114 -61.067785) (xy 163.161007 -61.118885) (xy 163.118903 -61.165168) (xy 163.071437 -61.205935)
			(xy 163.045648 -61.223652) (xy 163.035493 -61.231171) (xy 163.023634 -61.253447) (xy 163.023042 -61.26607)
			(xy 163.023042 -61.350398) (xy 163.023676 -61.363005) (xy 163.035541 -61.385252) (xy 163.045648 -61.392816)
			(xy 163.071419 -61.410561) (xy 163.118899 -61.451314) (xy 163.161018 -61.497586) (xy 163.197139 -61.548677)
			(xy 163.226715 -61.603816) (xy 163.2493 -61.662169) (xy 163.264552 -61.722852) (xy 163.27224 -61.784949)
			(xy 163.272724 -61.816234) (xy 163.272276 -61.846965) (xy 163.264864 -61.907979) (xy 163.250152 -61.967654)
			(xy 163.228355 -62.025122) (xy 163.19979 -62.079543) (xy 163.164874 -62.130124) (xy 163.124116 -62.176129)
			(xy 163.07811 -62.216885) (xy 163.027527 -62.251799) (xy 162.973105 -62.280362) (xy 162.915637 -62.302158)
			(xy 162.855961 -62.316868) (xy 162.794947 -62.324277) (xy 162.764216 -62.324742) (xy 162.763962 -62.324742)
			(xy 162.733754 -62.324322) (xy 162.673761 -62.317178) (xy 162.615039 -62.302973) (xy 162.558415 -62.281906)
			(xy 162.504688 -62.254274) (xy 162.454615 -62.220468) (xy 162.431476 -62.201044) (xy 162.424405 -62.195399)
			(xy 162.407493 -62.189012) (xy 162.398456 -62.188598) (xy 162.367976 -62.188598) (xy 162.358942 -62.189043)
			(xy 162.342026 -62.195404) (xy 162.334956 -62.201044) (xy 162.311805 -62.220452) (xy 162.261727 -62.254242)
			(xy 162.207999 -62.281864) (xy 162.151379 -62.302931) (xy 162.092662 -62.317145) (xy 162.032676 -62.324306)
			(xy 162.00247 -62.324742) (xy 162.002216 -62.324742) (xy 161.971487 -62.324229) (xy 161.910476 -62.316823)
			(xy 161.850802 -62.302117) (xy 161.793337 -62.280326) (xy 161.738917 -62.251767) (xy 161.688336 -62.216857)
			(xy 161.642331 -62.176104) (xy 161.601574 -62.130104) (xy 161.566659 -62.079526) (xy 161.538095 -62.025109)
			(xy 161.516298 -61.967645) (xy 161.501586 -61.907973) (xy 161.494174 -61.846963) (xy 161.493708 -61.816234)
			(xy 144.007392 -61.816234) (xy 144.006831 -61.81796) (xy 143.979618 -61.875792) (xy 143.945371 -61.929758)
			(xy 143.904631 -61.979007) (xy 143.85804 -62.022761) (xy 143.806332 -62.06033) (xy 143.750323 -62.091124)
			(xy 143.690897 -62.114654) (xy 143.628991 -62.130552) (xy 143.56558 -62.138565) (xy 143.533622 -62.139068)
			(xy 143.49956 -62.138551) (xy 143.432043 -62.129468) (xy 143.366345 -62.111448) (xy 143.303643 -62.084814)
			(xy 143.24506 -62.050044) (xy 143.191646 -62.00776) (xy 143.167608 -61.98362) (xy 143.161221 -61.977506)
			(xy 143.145361 -61.969718) (xy 143.13662 -61.96838) (xy 143.106902 -61.965078) (xy 143.098258 -61.964486)
			(xy 143.081386 -61.968369) (xy 143.073882 -61.972698) (xy 143.050776 -61.986867) (xy 143.001428 -62.009281)
			(xy 142.949403 -62.024481) (xy 142.89575 -62.032163) (xy 142.86865 -62.032642) (xy 142.868396 -62.032642)
			(xy 142.841599 -62.032169) (xy 142.78854 -62.024613) (xy 142.737065 -62.009693) (xy 142.71244 -61.999114)
			(xy 142.703928 -61.995806) (xy 142.685711 -61.994757) (xy 142.67688 -61.997082) (xy 142.647416 -62.005972)
			(xy 142.638547 -62.009059) (xy 142.623697 -62.020529) (xy 142.61846 -62.028324) (xy 142.601158 -62.056136)
			(xy 142.560545 -62.107525) (xy 142.513666 -62.15327) (xy 142.461297 -62.192611) (xy 142.404307 -62.224897)
			(xy 142.34364 -62.249592) (xy 142.280303 -62.266285) (xy 142.215346 -62.274702) (xy 142.182596 -62.275212)
			(xy 142.150635 -62.274702) (xy 142.087218 -62.26669) (xy 142.025305 -62.250793) (xy 141.965873 -62.227262)
			(xy 141.909859 -62.196467) (xy 141.858145 -62.158895) (xy 141.811549 -62.115138) (xy 141.770804 -62.065885)
			(xy 141.736554 -62.011915) (xy 141.709337 -61.954077) (xy 141.689585 -61.893284) (xy 141.677607 -61.830495)
			(xy 141.673593 -61.7667) (xy 127.538722 -61.7667) (xy 127.538232 -61.797903) (xy 127.530221 -61.861321)
			(xy 127.514324 -61.923235) (xy 127.490792 -61.982668) (xy 127.459998 -62.038683) (xy 127.422425 -62.090398)
			(xy 127.378668 -62.136995) (xy 127.329415 -62.17774) (xy 127.275444 -62.211991) (xy 127.217605 -62.239208)
			(xy 127.156812 -62.258961) (xy 127.094022 -62.270939) (xy 127.030226 -62.274953) (xy 126.96643 -62.270939)
			(xy 126.90364 -62.258961) (xy 126.842847 -62.239208) (xy 126.785008 -62.211991) (xy 126.731037 -62.17774)
			(xy 126.681784 -62.136995) (xy 126.638027 -62.090398) (xy 126.600454 -62.038683) (xy 126.56966 -61.982668)
			(xy 126.546128 -61.923235) (xy 126.530231 -61.861321) (xy 126.52222 -61.797903) (xy 126.521718 -61.765942)
			(xy 125.368519 -61.765942) (xy 125.369592 -61.783) (xy 125.365578 -61.846797) (xy 125.353599 -61.909588)
			(xy 125.333845 -61.970382) (xy 125.306626 -62.02822) (xy 125.272373 -62.082191) (xy 125.231625 -62.131443)
			(xy 125.185025 -62.1752) (xy 125.133309 -62.21277) (xy 125.077291 -62.243562) (xy 125.017855 -62.26709)
			(xy 124.955939 -62.282983) (xy 124.89252 -62.29099) (xy 124.860558 -62.291468) (xy 124.827583 -62.290981)
			(xy 124.762186 -62.282466) (xy 124.698438 -62.265571) (xy 124.637407 -62.240579) (xy 124.580118 -62.207909)
			(xy 124.527532 -62.16811) (xy 124.480529 -62.121849) (xy 124.4399 -62.069901) (xy 124.422662 -62.041786)
			(xy 124.417711 -62.034116) (xy 124.403517 -62.022658) (xy 124.394976 -62.019434) (xy 124.365766 -62.009782)
			(xy 124.356974 -62.007328) (xy 124.338752 -62.008101) (xy 124.330206 -62.011306) (xy 124.306754 -62.020715)
			(xy 124.257986 -62.033947) (xy 124.207898 -62.040617) (xy 124.182632 -62.041024) (xy 124.155379 -62.040531)
			(xy 124.101427 -62.032778) (xy 124.049127 -62.017425) (xy 123.999545 -61.994786) (xy 123.95369 -61.96532)
			(xy 123.912495 -61.929628) (xy 123.876799 -61.888436) (xy 123.84733 -61.842583) (xy 123.824686 -61.793003)
			(xy 123.809329 -61.740705) (xy 123.801571 -61.686753) (xy 117.884982 -61.686753) (xy 117.884499 -61.688399)
			(xy 117.861855 -61.737977) (xy 117.832386 -61.783828) (xy 117.796691 -61.825018) (xy 117.755498 -61.860709)
			(xy 117.709644 -61.890174) (xy 117.660063 -61.912812) (xy 117.607765 -61.928163) (xy 117.553814 -61.935915)
			(xy 117.526562 -61.936376) (xy 117.49024 -61.934598) (xy 117.476707 -61.933724) (xy 117.449984 -61.938268)
			(xy 117.425401 -61.949688) (xy 117.404691 -61.967177) (xy 117.389317 -61.989503) (xy 117.380364 -62.015088)
			(xy 117.378988 -62.028578) (xy 117.376574 -62.057137) (xy 117.364111 -62.113082) (xy 117.343418 -62.166532)
			(xy 117.314958 -62.216283) (xy 117.279375 -62.261215) (xy 117.237468 -62.300316) (xy 117.190181 -62.332706)
			(xy 117.13858 -62.357655) (xy 117.083827 -62.374601) (xy 117.027154 -62.383162) (xy 116.998496 -62.38367)
			(xy 116.971242 -62.38326) (xy 116.91729 -62.375502) (xy 116.86499 -62.360145) (xy 116.815408 -62.337501)
			(xy 116.769554 -62.308032) (xy 116.72836 -62.272337) (xy 116.692665 -62.231143) (xy 116.663197 -62.185288)
			(xy 116.640553 -62.135706) (xy 116.625197 -62.083407) (xy 116.61744 -62.029454) (xy 107.13454 -62.029454)
			(xy 107.134174 -62.049987) (xy 107.126418 -62.103935) (xy 107.111063 -62.15623) (xy 107.088421 -62.205807)
			(xy 107.058955 -62.251657) (xy 107.023264 -62.292848) (xy 106.982073 -62.328539) (xy 106.936223 -62.358005)
			(xy 106.886646 -62.380647) (xy 106.834351 -62.396002) (xy 106.780403 -62.403758) (xy 106.725901 -62.403758)
			(xy 106.671953 -62.396002) (xy 106.619658 -62.380647) (xy 106.570081 -62.358005) (xy 106.524231 -62.328539)
			(xy 106.48304 -62.292848) (xy 106.447349 -62.251657) (xy 106.417883 -62.205807) (xy 106.395241 -62.15623)
			(xy 106.379886 -62.103935) (xy 106.37213 -62.049987) (xy 106.371644 -62.022736) (xy 106.372141 -61.99388)
			(xy 106.380836 -61.936825) (xy 106.398032 -61.881734) (xy 106.423336 -61.829864) (xy 106.456171 -61.782402)
			(xy 106.495785 -61.740432) (xy 106.518202 -61.722254) (xy 106.52967 -61.712705) (xy 106.546893 -61.68835)
			(xy 106.556343 -61.660056) (xy 106.557213 -61.630239) (xy 106.54943 -61.601443) (xy 106.533656 -61.576124)
			(xy 106.51124 -61.556444) (xy 106.497882 -61.549788) (xy 106.468737 -61.535903) (xy 106.413888 -61.501852)
			(xy 106.363789 -61.461135) (xy 106.319246 -61.414404) (xy 106.280975 -61.362413) (xy 106.24959 -61.305996)
			(xy 106.225598 -61.246061) (xy 106.209383 -61.183572) (xy 106.201206 -61.119533) (xy 106.200702 -61.087254)
			(xy 105.141268 -61.087254) (xy 105.140766 -61.119215) (xy 105.132755 -61.182633) (xy 105.116858 -61.244547)
			(xy 105.093326 -61.30398) (xy 105.062532 -61.359995) (xy 105.024959 -61.41171) (xy 104.981202 -61.458307)
			(xy 104.931949 -61.499052) (xy 104.877978 -61.533303) (xy 104.820139 -61.56052) (xy 104.759346 -61.580273)
			(xy 104.696556 -61.592251) (xy 104.63276 -61.596265) (xy 104.568964 -61.592251) (xy 104.506174 -61.580273)
			(xy 104.445381 -61.56052) (xy 104.387542 -61.533303) (xy 104.333571 -61.499052) (xy 104.284318 -61.458307)
			(xy 104.240561 -61.41171) (xy 104.202988 -61.359995) (xy 104.172194 -61.30398) (xy 104.148662 -61.244547)
			(xy 104.132765 -61.182633) (xy 104.124754 -61.119215) (xy 93.107317 -61.119215) (xy 93.097204 -61.125633)
			(xy 93.039365 -61.15285) (xy 92.978572 -61.172603) (xy 92.915782 -61.184581) (xy 92.851986 -61.188595)
			(xy 92.78819 -61.184581) (xy 92.7254 -61.172603) (xy 92.664607 -61.15285) (xy 92.606768 -61.125633)
			(xy 92.552797 -61.091382) (xy 92.503544 -61.050637) (xy 92.459787 -61.00404) (xy 92.422214 -60.952325)
			(xy 92.39142 -60.89631) (xy 92.367888 -60.836877) (xy 92.351991 -60.774963) (xy 92.34398 -60.711545)
			(xy 53.402019 -60.711545) (xy 52.514289 -61.599275) (xy 74.747876 -61.599275) (xy 74.747876 -61.535353)
			(xy 74.755887 -61.471935) (xy 74.771784 -61.410021) (xy 74.795316 -61.350588) (xy 74.82611 -61.294573)
			(xy 74.863683 -61.242858) (xy 74.90744 -61.196261) (xy 74.956693 -61.155516) (xy 75.010664 -61.121265)
			(xy 75.068503 -61.094048) (xy 75.129296 -61.074295) (xy 75.192086 -61.062317) (xy 75.255882 -61.058304)
			(xy 75.319678 -61.062317) (xy 75.382468 -61.074295) (xy 75.443261 -61.094048) (xy 75.5011 -61.121265)
			(xy 75.555071 -61.155516) (xy 75.604324 -61.196261) (xy 75.648081 -61.242858) (xy 75.685654 -61.294573)
			(xy 75.716448 -61.350588) (xy 75.73998 -61.410021) (xy 75.755877 -61.471935) (xy 75.763888 -61.535353)
			(xy 75.76439 -61.567314) (xy 75.763888 -61.599275) (xy 75.755877 -61.662693) (xy 75.73998 -61.724607)
			(xy 75.716448 -61.78404) (xy 75.685654 -61.840055) (xy 75.648081 -61.89177) (xy 75.604324 -61.938367)
			(xy 75.581861 -61.95695) (xy 78.465932 -61.95695) (xy 78.470003 -61.901328) (xy 78.482129 -61.846891)
			(xy 78.502052 -61.7948) (xy 78.529348 -61.746165) (xy 78.563434 -61.702022) (xy 78.603583 -61.663313)
			(xy 78.648941 -61.630862) (xy 78.698541 -61.605361) (xy 78.751325 -61.587354) (xy 78.806168 -61.577224)
			(xy 78.861902 -61.575187) (xy 78.917339 -61.581287) (xy 78.971296 -61.595393) (xy 79.022625 -61.617205)
			(xy 79.070231 -61.646259) (xy 79.113099 -61.681934) (xy 79.150316 -61.723471) (xy 79.181089 -61.769984)
			(xy 79.204761 -61.820481) (xy 79.220829 -61.873888) (xy 79.221465 -61.87821) (xy 96.14103 -61.87821)
			(xy 96.145101 -61.822588) (xy 96.157227 -61.768151) (xy 96.17715 -61.71606) (xy 96.204446 -61.667425)
			(xy 96.238532 -61.623282) (xy 96.278681 -61.584573) (xy 96.324039 -61.552122) (xy 96.373639 -61.526621)
			(xy 96.426423 -61.508614) (xy 96.481266 -61.498484) (xy 96.537 -61.496447) (xy 96.592437 -61.502547)
			(xy 96.646394 -61.516653) (xy 96.697723 -61.538465) (xy 96.745329 -61.567519) (xy 96.788197 -61.603194)
			(xy 96.825414 -61.644731) (xy 96.856187 -61.691244) (xy 96.879859 -61.741741) (xy 96.895927 -61.795148)
			(xy 96.904047 -61.850324) (xy 96.904556 -61.87821) (xy 96.904047 -61.906096) (xy 96.895927 -61.961272)
			(xy 96.879859 -62.014679) (xy 96.856187 -62.065176) (xy 96.825414 -62.111689) (xy 96.788197 -62.153226)
			(xy 96.745329 -62.188901) (xy 96.697723 -62.217955) (xy 96.646394 -62.239767) (xy 96.592437 -62.253873)
			(xy 96.537 -62.259973) (xy 96.481266 -62.257936) (xy 96.426423 -62.247806) (xy 96.373639 -62.229799)
			(xy 96.324039 -62.204298) (xy 96.278681 -62.171847) (xy 96.238532 -62.133138) (xy 96.204446 -62.088995)
			(xy 96.17715 -62.04036) (xy 96.157227 -61.988269) (xy 96.145101 -61.933832) (xy 96.14103 -61.87821)
			(xy 79.221465 -61.87821) (xy 79.228949 -61.929064) (xy 79.229458 -61.95695) (xy 79.228949 -61.984836)
			(xy 79.220829 -62.040012) (xy 79.204761 -62.093419) (xy 79.181089 -62.143916) (xy 79.150316 -62.190429)
			(xy 79.113099 -62.231966) (xy 79.070231 -62.267641) (xy 79.022625 -62.296695) (xy 78.971296 -62.318507)
			(xy 78.917339 -62.332613) (xy 78.861902 -62.338713) (xy 78.806168 -62.336676) (xy 78.751325 -62.326546)
			(xy 78.698541 -62.308539) (xy 78.648941 -62.283038) (xy 78.603583 -62.250587) (xy 78.563434 -62.211878)
			(xy 78.529348 -62.167735) (xy 78.502052 -62.1191) (xy 78.482129 -62.067009) (xy 78.470003 -62.012572)
			(xy 78.465932 -61.95695) (xy 75.581861 -61.95695) (xy 75.555071 -61.979112) (xy 75.5011 -62.013363)
			(xy 75.443261 -62.04058) (xy 75.382468 -62.060333) (xy 75.319678 -62.072311) (xy 75.255882 -62.076325)
			(xy 75.192086 -62.072311) (xy 75.129296 -62.060333) (xy 75.068503 -62.04058) (xy 75.010664 -62.013363)
			(xy 74.956693 -61.979112) (xy 74.90744 -61.938367) (xy 74.863683 -61.89177) (xy 74.82611 -61.840055)
			(xy 74.795316 -61.78404) (xy 74.771784 -61.724607) (xy 74.755887 -61.662693) (xy 74.747876 -61.599275)
			(xy 52.514289 -61.599275) (xy 51.691286 -62.422278) (xy 51.688581 -62.42513) (xy 51.68399 -62.431509)
			(xy 51.682142 -62.434978) (xy 51.679561 -62.440405) (xy 51.676743 -62.452085) (xy 51.676554 -62.458092)
			(xy 51.676554 -63.39078) (xy 107.245402 -63.39078) (xy 107.249473 -63.335158) (xy 107.261599 -63.280721)
			(xy 107.281522 -63.22863) (xy 107.308818 -63.179995) (xy 107.342904 -63.135852) (xy 107.383053 -63.097143)
			(xy 107.428411 -63.064692) (xy 107.478011 -63.039191) (xy 107.530795 -63.021184) (xy 107.585638 -63.011054)
			(xy 107.641372 -63.009017) (xy 107.696809 -63.015117) (xy 107.750766 -63.029223) (xy 107.802095 -63.051035)
			(xy 107.849701 -63.080089) (xy 107.892569 -63.115764) (xy 107.929786 -63.157301) (xy 107.960559 -63.203814)
			(xy 107.984231 -63.254311) (xy 108.000299 -63.307718) (xy 108.008419 -63.362894) (xy 108.008928 -63.39078)
			(xy 108.008419 -63.418666) (xy 108.000299 -63.473842) (xy 107.984231 -63.527249) (xy 107.960559 -63.577746)
			(xy 107.933715 -63.618321) (xy 110.162334 -63.618321) (xy 110.162334 -63.554399) (xy 110.170345 -63.490981)
			(xy 110.186242 -63.429067) (xy 110.209774 -63.369634) (xy 110.240568 -63.313619) (xy 110.278141 -63.261904)
			(xy 110.321898 -63.215307) (xy 110.371151 -63.174562) (xy 110.425122 -63.140311) (xy 110.482961 -63.113094)
			(xy 110.543754 -63.093341) (xy 110.606544 -63.081363) (xy 110.67034 -63.07735) (xy 110.734136 -63.081363)
			(xy 110.796926 -63.093341) (xy 110.857719 -63.113094) (xy 110.915558 -63.140311) (xy 110.969529 -63.174562)
			(xy 111.018782 -63.215307) (xy 111.062539 -63.261904) (xy 111.100112 -63.313619) (xy 111.130906 -63.369634)
			(xy 111.154438 -63.429067) (xy 111.170335 -63.490981) (xy 111.178346 -63.554399) (xy 111.178683 -63.575866)
			(xy 111.431359 -63.575866) (xy 111.43657 -63.512992) (xy 111.449519 -63.451246) (xy 111.470006 -63.391576)
			(xy 111.497717 -63.334899) (xy 111.532226 -63.282084) (xy 111.573003 -63.233944) (xy 111.619421 -63.191217)
			(xy 111.670769 -63.154561) (xy 111.726256 -63.124537) (xy 111.78503 -63.101607) (xy 111.84619 -63.086124)
			(xy 111.908795 -63.078325) (xy 111.94034 -63.077852) (xy 111.969048 -63.078245) (xy 112.026095 -63.084742)
			(xy 112.082047 -63.097627) (xy 112.10925 -63.106808) (xy 112.109504 -63.106808) (xy 112.117631 -63.10929)
			(xy 112.134614 -63.109282) (xy 112.150653 -63.103698) (xy 112.15751 -63.09868) (xy 112.235234 -63.037466)
			(xy 112.245394 -63.01359) (xy 112.244124 -63.000636) (xy 112.243179 -62.990884) (xy 112.242162 -62.971317)
			(xy 112.242092 -62.96152) (xy 112.242574 -62.934268) (xy 112.250328 -62.880317) (xy 112.265682 -62.82802)
			(xy 112.288322 -62.77844) (xy 112.317788 -62.732587) (xy 112.35348 -62.691394) (xy 112.394671 -62.6557)
			(xy 112.440522 -62.626231) (xy 112.490101 -62.603589) (xy 112.542398 -62.588232) (xy 112.596348 -62.580475)
			(xy 112.6236 -62.580012) (xy 112.651881 -62.580492) (xy 112.707822 -62.588843) (xy 112.761917 -62.605361)
			(xy 112.812981 -62.629685) (xy 112.859895 -62.661281) (xy 112.882676 -62.68212) (xy 135.02462 -62.68212)
			(xy 135.028691 -62.626498) (xy 135.040817 -62.572061) (xy 135.06074 -62.51997) (xy 135.088036 -62.471335)
			(xy 135.122122 -62.427192) (xy 135.162271 -62.388483) (xy 135.207629 -62.356032) (xy 135.257229 -62.330531)
			(xy 135.310013 -62.312524) (xy 135.364856 -62.302394) (xy 135.42059 -62.300357) (xy 135.476027 -62.306457)
			(xy 135.529984 -62.320563) (xy 135.581313 -62.342375) (xy 135.628919 -62.371429) (xy 135.671787 -62.407104)
			(xy 135.709004 -62.448641) (xy 135.739777 -62.495154) (xy 135.763449 -62.545651) (xy 135.779517 -62.599058)
			(xy 135.787637 -62.654234) (xy 135.788146 -62.68212) (xy 135.787637 -62.710006) (xy 135.779517 -62.765182)
			(xy 135.763449 -62.818589) (xy 135.739777 -62.869086) (xy 135.709004 -62.915599) (xy 135.671787 -62.957136)
			(xy 135.628919 -62.992811) (xy 135.581313 -63.021865) (xy 135.529984 -63.043677) (xy 135.476027 -63.057783)
			(xy 135.42059 -63.063883) (xy 135.364856 -63.061846) (xy 135.310013 -63.051716) (xy 135.257229 -63.033709)
			(xy 135.207629 -63.008208) (xy 135.162271 -62.975757) (xy 135.122122 -62.937048) (xy 135.088036 -62.892905)
			(xy 135.06074 -62.84427) (xy 135.040817 -62.792179) (xy 135.028691 -62.737742) (xy 135.02462 -62.68212)
			(xy 112.882676 -62.68212) (xy 112.901629 -62.699457) (xy 112.93727 -62.743377) (xy 112.966036 -62.792076)
			(xy 112.987296 -62.84449) (xy 112.99444 -62.871858) (xy 112.997488 -62.884558) (xy 113.01476 -62.903608)
			(xy 113.119408 -62.940692) (xy 113.144554 -62.936628) (xy 113.154968 -62.928754) (xy 113.181702 -62.908945)
			(xy 113.239342 -62.875705) (xy 113.300825 -62.850267) (xy 113.365101 -62.833065) (xy 113.431071 -62.824392)
			(xy 113.46434 -62.823852) (xy 113.496297 -62.824436) (xy 113.559706 -62.832451) (xy 113.621611 -62.84835)
			(xy 113.681035 -62.871882) (xy 113.737042 -62.902676) (xy 113.788747 -62.940246) (xy 113.835337 -62.984)
			(xy 113.876075 -63.033248) (xy 113.91032 -63.087213) (xy 113.937532 -63.145044) (xy 113.957282 -63.20583)
			(xy 113.969258 -63.268612) (xy 113.973271 -63.3324) (xy 113.969258 -63.396188) (xy 113.957282 -63.45897)
			(xy 113.937532 -63.519756) (xy 113.91032 -63.577587) (xy 113.876075 -63.631552) (xy 113.835337 -63.6808)
			(xy 113.788747 -63.724554) (xy 113.737042 -63.762124) (xy 113.681035 -63.792918) (xy 113.621611 -63.81645)
			(xy 113.559706 -63.832349) (xy 113.496297 -63.840364) (xy 113.46434 -63.840868) (xy 113.432861 -63.840495)
			(xy 113.370384 -63.83274) (xy 113.309341 -63.81733) (xy 113.250669 -63.794502) (xy 113.195263 -63.764604)
			(xy 113.143973 -63.728095) (xy 113.097582 -63.685533) (xy 113.056801 -63.637569) (xy 113.022254 -63.584938)
			(xy 112.994469 -63.528443) (xy 112.973871 -63.468951) (xy 112.960776 -63.407371) (xy 112.95761 -63.376048)
			(xy 112.956594 -63.363094) (xy 112.942624 -63.341758) (xy 112.844326 -63.289434) (xy 112.818926 -63.289434)
			(xy 112.807496 -63.295784) (xy 112.779143 -63.310637) (xy 112.718705 -63.331696) (xy 112.655601 -63.342376)
			(xy 112.6236 -63.343028) (xy 112.605321 -63.342783) (xy 112.568935 -63.339222) (xy 112.550956 -63.335916)
			(xy 112.550702 -63.335916) (xy 112.542322 -63.334698) (xy 112.525584 -63.337212) (xy 112.510564 -63.345016)
			(xy 112.504474 -63.350902) (xy 112.445292 -63.413386) (xy 112.439681 -63.419852) (xy 112.432707 -63.435473)
			(xy 112.43128 -63.45252) (xy 112.4331 -63.460884) (xy 112.440461 -63.49173) (xy 112.448362 -63.554652)
			(xy 112.448848 -63.58636) (xy 112.448375 -63.617905) (xy 112.440576 -63.68051) (xy 112.425093 -63.74167)
			(xy 112.402163 -63.800444) (xy 112.372139 -63.855931) (xy 112.335483 -63.907279) (xy 112.292756 -63.953697)
			(xy 112.244616 -63.994474) (xy 112.191801 -64.028983) (xy 112.135124 -64.056694) (xy 112.075454 -64.077181)
			(xy 112.013708 -64.09013) (xy 111.950834 -64.095341) (xy 111.887799 -64.092736) (xy 111.82557 -64.082353)
			(xy 111.765103 -64.064352) (xy 111.707328 -64.039011) (xy 111.65313 -64.006717) (xy 111.603344 -63.967967)
			(xy 111.558733 -63.923356) (xy 111.519983 -63.87357) (xy 111.487689 -63.819372) (xy 111.462348 -63.761597)
			(xy 111.444347 -63.70113) (xy 111.433964 -63.638901) (xy 111.431359 -63.575866) (xy 111.178683 -63.575866)
			(xy 111.178848 -63.58636) (xy 111.178346 -63.618321) (xy 111.170335 -63.681739) (xy 111.154438 -63.743653)
			(xy 111.130906 -63.803086) (xy 111.100112 -63.859101) (xy 111.062539 -63.910816) (xy 111.018782 -63.957413)
			(xy 110.969529 -63.998158) (xy 110.915558 -64.032409) (xy 110.857719 -64.059626) (xy 110.796926 -64.079379)
			(xy 110.734136 -64.091357) (xy 110.67034 -64.095371) (xy 110.606544 -64.091357) (xy 110.543754 -64.079379)
			(xy 110.482961 -64.059626) (xy 110.425122 -64.032409) (xy 110.371151 -63.998158) (xy 110.321898 -63.957413)
			(xy 110.278141 -63.910816) (xy 110.240568 -63.859101) (xy 110.209774 -63.803086) (xy 110.186242 -63.743653)
			(xy 110.170345 -63.681739) (xy 110.162334 -63.618321) (xy 107.933715 -63.618321) (xy 107.929786 -63.624259)
			(xy 107.892569 -63.665796) (xy 107.849701 -63.701471) (xy 107.802095 -63.730525) (xy 107.750766 -63.752337)
			(xy 107.696809 -63.766443) (xy 107.641372 -63.772543) (xy 107.585638 -63.770506) (xy 107.530795 -63.760376)
			(xy 107.478011 -63.742369) (xy 107.428411 -63.716868) (xy 107.383053 -63.684417) (xy 107.342904 -63.645708)
			(xy 107.308818 -63.601565) (xy 107.281522 -63.55293) (xy 107.261599 -63.500839) (xy 107.249473 -63.446402)
			(xy 107.245402 -63.39078) (xy 51.676554 -63.39078) (xy 51.676554 -64.25438) (xy 80.196942 -64.25438)
			(xy 80.201013 -64.198758) (xy 80.213139 -64.144321) (xy 80.233062 -64.09223) (xy 80.260358 -64.043595)
			(xy 80.294444 -63.999452) (xy 80.334593 -63.960743) (xy 80.379951 -63.928292) (xy 80.429551 -63.902791)
			(xy 80.482335 -63.884784) (xy 80.537178 -63.874654) (xy 80.592912 -63.872617) (xy 80.648349 -63.878717)
			(xy 80.702306 -63.892823) (xy 80.753635 -63.914635) (xy 80.801241 -63.943689) (xy 80.844109 -63.979364)
			(xy 80.881326 -64.020901) (xy 80.912099 -64.067414) (xy 80.935771 -64.117911) (xy 80.951839 -64.171318)
			(xy 80.959959 -64.226494) (xy 80.960468 -64.25438) (xy 80.959959 -64.282266) (xy 80.951839 -64.337442)
			(xy 80.935771 -64.390849) (xy 80.912099 -64.441346) (xy 80.881326 -64.487859) (xy 80.844109 -64.529396)
			(xy 80.809846 -64.55791) (xy 104.447592 -64.55791) (xy 104.451663 -64.502288) (xy 104.463789 -64.447851)
			(xy 104.483712 -64.39576) (xy 104.511008 -64.347125) (xy 104.545094 -64.302982) (xy 104.585243 -64.264273)
			(xy 104.630601 -64.231822) (xy 104.680201 -64.206321) (xy 104.732985 -64.188314) (xy 104.787828 -64.178184)
			(xy 104.843562 -64.176147) (xy 104.898999 -64.182247) (xy 104.952956 -64.196353) (xy 105.004285 -64.218165)
			(xy 105.051891 -64.247219) (xy 105.094759 -64.282894) (xy 105.131976 -64.324431) (xy 105.162749 -64.370944)
			(xy 105.186421 -64.421441) (xy 105.202489 -64.474848) (xy 105.210609 -64.530024) (xy 105.211118 -64.55791)
			(xy 105.210609 -64.585796) (xy 105.202489 -64.640972) (xy 105.186421 -64.694379) (xy 105.162749 -64.744876)
			(xy 105.131976 -64.791389) (xy 105.094759 -64.832926) (xy 105.051891 -64.868601) (xy 105.004285 -64.897655)
			(xy 104.952956 -64.919467) (xy 104.898999 -64.933573) (xy 104.843562 -64.939673) (xy 104.787828 -64.937636)
			(xy 104.732985 -64.927506) (xy 104.680201 -64.909499) (xy 104.630601 -64.883998) (xy 104.585243 -64.851547)
			(xy 104.545094 -64.812838) (xy 104.511008 -64.768695) (xy 104.483712 -64.72006) (xy 104.463789 -64.667969)
			(xy 104.451663 -64.613532) (xy 104.447592 -64.55791) (xy 80.809846 -64.55791) (xy 80.801241 -64.565071)
			(xy 80.753635 -64.594125) (xy 80.702306 -64.615937) (xy 80.648349 -64.630043) (xy 80.592912 -64.636143)
			(xy 80.537178 -64.634106) (xy 80.482335 -64.623976) (xy 80.429551 -64.605969) (xy 80.379951 -64.580468)
			(xy 80.334593 -64.548017) (xy 80.294444 -64.509308) (xy 80.260358 -64.465165) (xy 80.233062 -64.41653)
			(xy 80.213139 -64.364439) (xy 80.201013 -64.310002) (xy 80.196942 -64.25438) (xy 51.676554 -64.25438)
			(xy 51.676554 -65.190073) (xy 77.350106 -65.190073) (xy 77.350106 -65.126151) (xy 77.358117 -65.062733)
			(xy 77.374014 -65.000819) (xy 77.397546 -64.941386) (xy 77.42834 -64.885371) (xy 77.465913 -64.833656)
			(xy 77.50967 -64.787059) (xy 77.558923 -64.746314) (xy 77.612894 -64.712063) (xy 77.670733 -64.684846)
			(xy 77.731526 -64.665093) (xy 77.794316 -64.653115) (xy 77.858112 -64.649102) (xy 77.921908 -64.653115)
			(xy 77.984698 -64.665093) (xy 78.045491 -64.684846) (xy 78.10333 -64.712063) (xy 78.157301 -64.746314)
			(xy 78.206554 -64.787059) (xy 78.250311 -64.833656) (xy 78.287884 -64.885371) (xy 78.318678 -64.941386)
			(xy 78.34221 -65.000819) (xy 78.358107 -65.062733) (xy 78.366118 -65.126151) (xy 78.36662 -65.158112)
			(xy 78.366118 -65.190073) (xy 78.358107 -65.253491) (xy 78.34221 -65.315405) (xy 78.318678 -65.374838)
			(xy 78.287884 -65.430853) (xy 78.282677 -65.43802) (xy 148.751542 -65.43802) (xy 148.755613 -65.382398)
			(xy 148.767739 -65.327961) (xy 148.787662 -65.27587) (xy 148.814958 -65.227235) (xy 148.849044 -65.183092)
			(xy 148.889193 -65.144383) (xy 148.934551 -65.111932) (xy 148.984151 -65.086431) (xy 149.036935 -65.068424)
			(xy 149.091778 -65.058294) (xy 149.147512 -65.056257) (xy 149.202949 -65.062357) (xy 149.256906 -65.076463)
			(xy 149.308235 -65.098275) (xy 149.355841 -65.127329) (xy 149.398709 -65.163004) (xy 149.435926 -65.204541)
			(xy 149.466699 -65.251054) (xy 149.490371 -65.301551) (xy 149.506439 -65.354958) (xy 149.514559 -65.410134)
			(xy 149.514753 -65.420748) (xy 153.216354 -65.420748) (xy 153.220425 -65.365126) (xy 153.232551 -65.310689)
			(xy 153.252474 -65.258598) (xy 153.27977 -65.209963) (xy 153.313856 -65.16582) (xy 153.354005 -65.127111)
			(xy 153.399363 -65.09466) (xy 153.448963 -65.069159) (xy 153.501747 -65.051152) (xy 153.55659 -65.041022)
			(xy 153.612324 -65.038985) (xy 153.667761 -65.045085) (xy 153.721718 -65.059191) (xy 153.773047 -65.081003)
			(xy 153.820653 -65.110057) (xy 153.863521 -65.145732) (xy 153.900738 -65.187269) (xy 153.931511 -65.233782)
			(xy 153.955183 -65.284279) (xy 153.971251 -65.337686) (xy 153.979371 -65.392862) (xy 153.97988 -65.420748)
			(xy 153.979371 -65.448634) (xy 153.971251 -65.50381) (xy 153.955183 -65.557217) (xy 153.931511 -65.607714)
			(xy 153.900738 -65.654227) (xy 153.863521 -65.695764) (xy 153.820653 -65.731439) (xy 153.773047 -65.760493)
			(xy 153.721718 -65.782305) (xy 153.667761 -65.796411) (xy 153.612324 -65.802511) (xy 153.55659 -65.800474)
			(xy 153.501747 -65.790344) (xy 153.448963 -65.772337) (xy 153.399363 -65.746836) (xy 153.354005 -65.714385)
			(xy 153.313856 -65.675676) (xy 153.27977 -65.631533) (xy 153.252474 -65.582898) (xy 153.232551 -65.530807)
			(xy 153.220425 -65.47637) (xy 153.216354 -65.420748) (xy 149.514753 -65.420748) (xy 149.515068 -65.43802)
			(xy 149.514559 -65.465906) (xy 149.506439 -65.521082) (xy 149.490371 -65.574489) (xy 149.466699 -65.624986)
			(xy 149.435926 -65.671499) (xy 149.398709 -65.713036) (xy 149.355841 -65.748711) (xy 149.308235 -65.777765)
			(xy 149.256906 -65.799577) (xy 149.202949 -65.813683) (xy 149.147512 -65.819783) (xy 149.091778 -65.817746)
			(xy 149.036935 -65.807616) (xy 148.984151 -65.789609) (xy 148.934551 -65.764108) (xy 148.889193 -65.731657)
			(xy 148.849044 -65.692948) (xy 148.814958 -65.648805) (xy 148.787662 -65.60017) (xy 148.767739 -65.548079)
			(xy 148.755613 -65.493642) (xy 148.751542 -65.43802) (xy 78.282677 -65.43802) (xy 78.250311 -65.482568)
			(xy 78.206554 -65.529165) (xy 78.157301 -65.56991) (xy 78.10333 -65.604161) (xy 78.045491 -65.631378)
			(xy 77.984698 -65.651131) (xy 77.921908 -65.663109) (xy 77.858112 -65.667123) (xy 77.794316 -65.663109)
			(xy 77.731526 -65.651131) (xy 77.670733 -65.631378) (xy 77.612894 -65.604161) (xy 77.558923 -65.56991)
			(xy 77.50967 -65.529165) (xy 77.465913 -65.482568) (xy 77.42834 -65.430853) (xy 77.397546 -65.374838)
			(xy 77.374014 -65.315405) (xy 77.358117 -65.253491) (xy 77.350106 -65.190073) (xy 51.676554 -65.190073)
			(xy 51.676554 -66.05905) (xy 78.084932 -66.05905) (xy 78.089003 -66.003428) (xy 78.101129 -65.948991)
			(xy 78.121052 -65.8969) (xy 78.148348 -65.848265) (xy 78.182434 -65.804122) (xy 78.222583 -65.765413)
			(xy 78.267941 -65.732962) (xy 78.317541 -65.707461) (xy 78.370325 -65.689454) (xy 78.425168 -65.679324)
			(xy 78.480902 -65.677287) (xy 78.536339 -65.683387) (xy 78.590296 -65.697493) (xy 78.641625 -65.719305)
			(xy 78.689231 -65.748359) (xy 78.732099 -65.784034) (xy 78.769316 -65.825571) (xy 78.800089 -65.872084)
			(xy 78.823761 -65.922581) (xy 78.839829 -65.975988) (xy 78.847949 -66.031164) (xy 78.848458 -66.05905)
			(xy 78.847949 -66.086936) (xy 78.847349 -66.091011) (xy 80.537044 -66.091011) (xy 80.537044 -66.027089)
			(xy 80.545055 -65.963671) (xy 80.560952 -65.901757) (xy 80.584484 -65.842324) (xy 80.615278 -65.786309)
			(xy 80.652851 -65.734594) (xy 80.696608 -65.687997) (xy 80.745861 -65.647252) (xy 80.799832 -65.613001)
			(xy 80.857671 -65.585784) (xy 80.918464 -65.566031) (xy 80.981254 -65.554053) (xy 81.04505 -65.55004)
			(xy 81.108846 -65.554053) (xy 81.171636 -65.566031) (xy 81.232429 -65.585784) (xy 81.290268 -65.613001)
			(xy 81.344239 -65.647252) (xy 81.393492 -65.687997) (xy 81.437249 -65.734594) (xy 81.474822 -65.786309)
			(xy 81.505616 -65.842324) (xy 81.529148 -65.901757) (xy 81.545045 -65.963671) (xy 81.553056 -66.027089)
			(xy 81.553558 -66.05905) (xy 81.553056 -66.091011) (xy 81.545045 -66.154429) (xy 81.529148 -66.216343)
			(xy 81.505616 -66.275776) (xy 81.474822 -66.331791) (xy 81.437249 -66.383506) (xy 81.393492 -66.430103)
			(xy 81.344239 -66.470848) (xy 81.290268 -66.505099) (xy 81.232429 -66.532316) (xy 81.171636 -66.552069)
			(xy 81.108846 -66.564047) (xy 81.04505 -66.568061) (xy 80.981254 -66.564047) (xy 80.918464 -66.552069)
			(xy 80.857671 -66.532316) (xy 80.799832 -66.505099) (xy 80.745861 -66.470848) (xy 80.696608 -66.430103)
			(xy 80.652851 -66.383506) (xy 80.615278 -66.331791) (xy 80.584484 -66.275776) (xy 80.560952 -66.216343)
			(xy 80.545055 -66.154429) (xy 80.537044 -66.091011) (xy 78.847349 -66.091011) (xy 78.839829 -66.142112)
			(xy 78.823761 -66.195519) (xy 78.800089 -66.246016) (xy 78.769316 -66.292529) (xy 78.732099 -66.334066)
			(xy 78.689231 -66.369741) (xy 78.641625 -66.398795) (xy 78.590296 -66.420607) (xy 78.536339 -66.434713)
			(xy 78.480902 -66.440813) (xy 78.425168 -66.438776) (xy 78.370325 -66.428646) (xy 78.317541 -66.410639)
			(xy 78.267941 -66.385138) (xy 78.222583 -66.352687) (xy 78.182434 -66.313978) (xy 78.148348 -66.269835)
			(xy 78.121052 -66.2212) (xy 78.101129 -66.169109) (xy 78.089003 -66.114672) (xy 78.084932 -66.05905)
			(xy 51.676554 -66.05905) (xy 51.676554 -66.58991) (xy 104.447592 -66.58991) (xy 104.451663 -66.534288)
			(xy 104.463789 -66.479851) (xy 104.483712 -66.42776) (xy 104.511008 -66.379125) (xy 104.545094 -66.334982)
			(xy 104.585243 -66.296273) (xy 104.630601 -66.263822) (xy 104.680201 -66.238321) (xy 104.732985 -66.220314)
			(xy 104.787828 -66.210184) (xy 104.843562 -66.208147) (xy 104.898999 -66.214247) (xy 104.952956 -66.228353)
			(xy 105.004285 -66.250165) (xy 105.051891 -66.279219) (xy 105.094759 -66.314894) (xy 105.114955 -66.337434)
			(xy 145.801078 -66.337434) (xy 145.805149 -66.281812) (xy 145.817275 -66.227375) (xy 145.837198 -66.175284)
			(xy 145.864494 -66.126649) (xy 145.89858 -66.082506) (xy 145.938729 -66.043797) (xy 145.984087 -66.011346)
			(xy 146.033687 -65.985845) (xy 146.086471 -65.967838) (xy 146.141314 -65.957708) (xy 146.197048 -65.955671)
			(xy 146.252485 -65.961771) (xy 146.306442 -65.975877) (xy 146.357771 -65.997689) (xy 146.405377 -66.026743)
			(xy 146.448245 -66.062418) (xy 146.485462 -66.103955) (xy 146.516235 -66.150468) (xy 146.539907 -66.200965)
			(xy 146.555975 -66.254372) (xy 146.564095 -66.309548) (xy 146.564604 -66.337434) (xy 146.564095 -66.36532)
			(xy 146.555975 -66.420496) (xy 146.539907 -66.473903) (xy 146.516235 -66.5244) (xy 146.485462 -66.570913)
			(xy 146.448245 -66.61245) (xy 146.405377 -66.648125) (xy 146.357771 -66.677179) (xy 146.306442 -66.698991)
			(xy 146.252485 -66.713097) (xy 146.197048 -66.719197) (xy 146.141314 -66.71716) (xy 146.086471 -66.70703)
			(xy 146.033687 -66.689023) (xy 145.984087 -66.663522) (xy 145.938729 -66.631071) (xy 145.89858 -66.592362)
			(xy 145.864494 -66.548219) (xy 145.837198 -66.499584) (xy 145.817275 -66.447493) (xy 145.805149 -66.393056)
			(xy 145.801078 -66.337434) (xy 105.114955 -66.337434) (xy 105.131976 -66.356431) (xy 105.162749 -66.402944)
			(xy 105.186421 -66.453441) (xy 105.202489 -66.506848) (xy 105.210609 -66.562024) (xy 105.211118 -66.58991)
			(xy 105.210609 -66.617796) (xy 105.202489 -66.672972) (xy 105.186421 -66.726379) (xy 105.174785 -66.7512)
			(xy 138.505182 -66.7512) (xy 138.509253 -66.695578) (xy 138.521379 -66.641141) (xy 138.541302 -66.58905)
			(xy 138.568598 -66.540415) (xy 138.602684 -66.496272) (xy 138.642833 -66.457563) (xy 138.688191 -66.425112)
			(xy 138.737791 -66.399611) (xy 138.790575 -66.381604) (xy 138.845418 -66.371474) (xy 138.901152 -66.369437)
			(xy 138.956589 -66.375537) (xy 139.010546 -66.389643) (xy 139.061875 -66.411455) (xy 139.109481 -66.440509)
			(xy 139.152349 -66.476184) (xy 139.189566 -66.517721) (xy 139.220339 -66.564234) (xy 139.244011 -66.614731)
			(xy 139.260079 -66.668138) (xy 139.268199 -66.723314) (xy 139.268708 -66.7512) (xy 139.268199 -66.779086)
			(xy 139.260079 -66.834262) (xy 139.244011 -66.887669) (xy 139.220339 -66.938166) (xy 139.189566 -66.984679)
			(xy 139.169852 -67.006681) (xy 147.09114 -67.006681) (xy 147.09114 -66.942759) (xy 147.099151 -66.879341)
			(xy 147.115048 -66.817427) (xy 147.13858 -66.757994) (xy 147.169374 -66.701979) (xy 147.206947 -66.650264)
			(xy 147.250704 -66.603667) (xy 147.299957 -66.562922) (xy 147.353928 -66.528671) (xy 147.411767 -66.501454)
			(xy 147.47256 -66.481701) (xy 147.53535 -66.469723) (xy 147.599146 -66.46571) (xy 147.662942 -66.469723)
			(xy 147.725732 -66.481701) (xy 147.786525 -66.501454) (xy 147.844364 -66.528671) (xy 147.898335 -66.562922)
			(xy 147.947588 -66.603667) (xy 147.991345 -66.650264) (xy 148.028918 -66.701979) (xy 148.059712 -66.757994)
			(xy 148.083244 -66.817427) (xy 148.099141 -66.879341) (xy 148.107152 -66.942759) (xy 148.107654 -66.97472)
			(xy 148.107152 -67.006681) (xy 148.099141 -67.070099) (xy 148.083244 -67.132013) (xy 148.059712 -67.191446)
			(xy 148.028918 -67.247461) (xy 147.991345 -67.299176) (xy 147.947588 -67.345773) (xy 147.898335 -67.386518)
			(xy 147.844364 -67.420769) (xy 147.786525 -67.447986) (xy 147.725732 -67.467739) (xy 147.662942 -67.479717)
			(xy 147.599146 -67.483731) (xy 147.53535 -67.479717) (xy 147.47256 -67.467739) (xy 147.411767 -67.447986)
			(xy 147.353928 -67.420769) (xy 147.299957 -67.386518) (xy 147.250704 -67.345773) (xy 147.206947 -67.299176)
			(xy 147.169374 -67.247461) (xy 147.13858 -67.191446) (xy 147.115048 -67.132013) (xy 147.099151 -67.070099)
			(xy 147.09114 -67.006681) (xy 139.169852 -67.006681) (xy 139.152349 -67.026216) (xy 139.109481 -67.061891)
			(xy 139.061875 -67.090945) (xy 139.010546 -67.112757) (xy 138.956589 -67.126863) (xy 138.901152 -67.132963)
			(xy 138.845418 -67.130926) (xy 138.790575 -67.120796) (xy 138.737791 -67.102789) (xy 138.688191 -67.077288)
			(xy 138.642833 -67.044837) (xy 138.602684 -67.006128) (xy 138.568598 -66.961985) (xy 138.541302 -66.91335)
			(xy 138.521379 -66.861259) (xy 138.509253 -66.806822) (xy 138.505182 -66.7512) (xy 105.174785 -66.7512)
			(xy 105.162749 -66.776876) (xy 105.131976 -66.823389) (xy 105.094759 -66.864926) (xy 105.051891 -66.900601)
			(xy 105.004285 -66.929655) (xy 104.952956 -66.951467) (xy 104.898999 -66.965573) (xy 104.843562 -66.971673)
			(xy 104.787828 -66.969636) (xy 104.732985 -66.959506) (xy 104.680201 -66.941499) (xy 104.630601 -66.915998)
			(xy 104.585243 -66.883547) (xy 104.545094 -66.844838) (xy 104.511008 -66.800695) (xy 104.483712 -66.75206)
			(xy 104.463789 -66.699969) (xy 104.451663 -66.645532) (xy 104.447592 -66.58991) (xy 51.676554 -66.58991)
			(xy 51.676554 -66.598546) (xy 51.676121 -66.608611) (xy 51.66839 -66.627199) (xy 51.661568 -66.634614)
			(xy 50.6222 -67.673982) (xy 50.612191 -67.67447) (xy 50.593696 -67.682129) (xy 50.579539 -67.696281)
			(xy 50.571873 -67.714773) (xy 50.5714 -67.724782) (xy 50.5714 -68.64604) (xy 83.691982 -68.64604)
			(xy 83.696053 -68.590418) (xy 83.708179 -68.535981) (xy 83.728102 -68.48389) (xy 83.755398 -68.435255)
			(xy 83.789484 -68.391112) (xy 83.829633 -68.352403) (xy 83.874991 -68.319952) (xy 83.924591 -68.294451)
			(xy 83.977375 -68.276444) (xy 84.032218 -68.266314) (xy 84.087952 -68.264277) (xy 84.143389 -68.270377)
			(xy 84.197346 -68.284483) (xy 84.248675 -68.306295) (xy 84.296281 -68.335349) (xy 84.339149 -68.371024)
			(xy 84.376366 -68.412561) (xy 84.407139 -68.459074) (xy 84.430811 -68.509571) (xy 84.446879 -68.562978)
			(xy 84.454999 -68.618154) (xy 84.455508 -68.64604) (xy 84.454999 -68.673926) (xy 84.446879 -68.729102)
			(xy 84.438703 -68.756276) (xy 98.795586 -68.756276) (xy 98.796126 -68.72736) (xy 98.804846 -68.670188)
			(xy 98.822098 -68.614988) (xy 98.847485 -68.563026) (xy 98.880426 -68.515491) (xy 98.920167 -68.473475)
			(xy 98.942652 -68.455286) (xy 98.951464 -68.447684) (xy 98.961643 -68.426779) (xy 98.96221 -68.415154)
			(xy 98.96221 -68.335398) (xy 98.961654 -68.323768) (xy 98.951477 -68.302859) (xy 98.942652 -68.295266)
			(xy 98.920142 -68.277106) (xy 98.880411 -68.235079) (xy 98.847476 -68.187537) (xy 98.822093 -68.13557)
			(xy 98.804842 -68.080367) (xy 98.796118 -68.023194) (xy 98.795586 -67.994276) (xy 98.796072 -67.967025)
			(xy 98.803828 -67.913077) (xy 98.819183 -67.860782) (xy 98.841825 -67.811205) (xy 98.871291 -67.765355)
			(xy 98.906982 -67.724164) (xy 98.948173 -67.688473) (xy 98.994023 -67.659007) (xy 99.0436 -67.636365)
			(xy 99.095895 -67.62101) (xy 99.149843 -67.613254) (xy 99.204345 -67.613254) (xy 99.258293 -67.62101)
			(xy 99.310588 -67.636365) (xy 99.360165 -67.659007) (xy 99.406015 -67.688473) (xy 99.447206 -67.724164)
			(xy 99.482897 -67.765355) (xy 99.512363 -67.811205) (xy 99.535005 -67.860782) (xy 99.55036 -67.913077)
			(xy 99.558116 -67.967025) (xy 99.558602 -67.994276) (xy 99.558066 -68.023192) (xy 99.54934 -68.080363)
			(xy 99.532086 -68.135561) (xy 99.506698 -68.187523) (xy 99.473757 -68.235057) (xy 99.43402 -68.277075)
			(xy 99.411536 -68.295266) (xy 99.402743 -68.302887) (xy 99.392554 -68.323778) (xy 99.391978 -68.335398)
			(xy 99.391978 -68.415154) (xy 99.392508 -68.426787) (xy 99.402704 -68.447695) (xy 99.411536 -68.455286)
			(xy 99.43402 -68.473476) (xy 99.473754 -68.515497) (xy 99.506692 -68.563032) (xy 99.53208 -68.614994)
			(xy 99.534242 -68.62191) (xy 104.447592 -68.62191) (xy 104.451663 -68.566288) (xy 104.463789 -68.511851)
			(xy 104.483712 -68.45976) (xy 104.511008 -68.411125) (xy 104.545094 -68.366982) (xy 104.585243 -68.328273)
			(xy 104.630601 -68.295822) (xy 104.680201 -68.270321) (xy 104.732985 -68.252314) (xy 104.787828 -68.242184)
			(xy 104.843562 -68.240147) (xy 104.898999 -68.246247) (xy 104.952956 -68.260353) (xy 105.004285 -68.282165)
			(xy 105.051891 -68.311219) (xy 105.094759 -68.346894) (xy 105.131976 -68.388431) (xy 105.162749 -68.434944)
			(xy 105.186421 -68.485441) (xy 105.202489 -68.538848) (xy 105.210609 -68.594024) (xy 105.211118 -68.62191)
			(xy 105.210609 -68.649796) (xy 105.202489 -68.704972) (xy 105.199905 -68.713561) (xy 121.378974 -68.713561)
			(xy 121.378974 -68.649639) (xy 121.386985 -68.586221) (xy 121.402882 -68.524307) (xy 121.426414 -68.464874)
			(xy 121.457208 -68.408859) (xy 121.494781 -68.357144) (xy 121.538538 -68.310547) (xy 121.587791 -68.269802)
			(xy 121.641762 -68.235551) (xy 121.699601 -68.208334) (xy 121.760394 -68.188581) (xy 121.823184 -68.176603)
			(xy 121.88698 -68.17259) (xy 121.950776 -68.176603) (xy 122.013566 -68.188581) (xy 122.074359 -68.208334)
			(xy 122.132198 -68.235551) (xy 122.186169 -68.269802) (xy 122.235422 -68.310547) (xy 122.279179 -68.357144)
			(xy 122.316752 -68.408859) (xy 122.347546 -68.464874) (xy 122.371078 -68.524307) (xy 122.386975 -68.586221)
			(xy 122.394986 -68.649639) (xy 122.395488 -68.6816) (xy 122.394986 -68.713561) (xy 122.394292 -68.719054)
			(xy 122.504138 -68.719054) (xy 122.504138 -68.664546) (xy 122.511895 -68.610593) (xy 122.527252 -68.558292)
			(xy 122.549895 -68.50871) (xy 122.579365 -68.462855) (xy 122.61506 -68.42166) (xy 122.656255 -68.385965)
			(xy 122.70211 -68.356495) (xy 122.751692 -68.333852) (xy 122.803993 -68.318495) (xy 122.857946 -68.310738)
			(xy 122.8852 -68.310252) (xy 122.912943 -68.310787) (xy 122.967845 -68.318824) (xy 123.021003 -68.334731)
			(xy 123.071296 -68.35817) (xy 123.117664 -68.388647) (xy 123.159127 -68.42552) (xy 123.194811 -68.46801)
			(xy 123.209812 -68.491354) (xy 123.217494 -68.502881) (xy 123.23787 -68.521632) (xy 123.262534 -68.53422)
			(xy 123.289673 -68.539719) (xy 123.317292 -68.537726) (xy 123.34336 -68.528387) (xy 123.365961 -68.512389)
			(xy 123.383434 -68.490907) (xy 123.38939 -68.4784) (xy 123.402896 -68.448534) (xy 123.436591 -68.392307)
			(xy 123.477234 -68.340877) (xy 123.524149 -68.295098) (xy 123.576559 -68.255728) (xy 123.633595 -68.223421)
			(xy 123.69431 -68.198713) (xy 123.757697 -68.182012) (xy 123.822705 -68.173598) (xy 123.85548 -68.173092)
			(xy 123.887443 -68.173572) (xy 123.950866 -68.181582) (xy 124.012784 -68.197477) (xy 124.072222 -68.221008)
			(xy 124.128242 -68.251804) (xy 124.17996 -68.289377) (xy 124.226561 -68.333137) (xy 124.26731 -68.382392)
			(xy 124.301565 -68.436367) (xy 124.328784 -68.494209) (xy 124.348539 -68.555006) (xy 124.360517 -68.6178)
			(xy 124.364532 -68.6816) (xy 124.360517 -68.7454) (xy 124.348539 -68.808194) (xy 124.328784 -68.868991)
			(xy 124.301565 -68.926833) (xy 124.26731 -68.980808) (xy 124.226561 -69.030063) (xy 124.17996 -69.073823)
			(xy 124.128242 -69.111396) (xy 124.072222 -69.142192) (xy 124.012784 -69.165723) (xy 123.950866 -69.181618)
			(xy 123.887443 -69.189628) (xy 123.85548 -69.190108) (xy 123.823297 -69.189616) (xy 123.759446 -69.18148)
			(xy 123.697132 -69.165353) (xy 123.637351 -69.141492) (xy 123.581058 -69.11028) (xy 123.529153 -69.072215)
			(xy 123.482465 -69.027904) (xy 123.441741 -68.978058) (xy 123.407632 -68.923472) (xy 123.393708 -68.894452)
			(xy 123.387528 -68.882048) (xy 123.369569 -68.860954) (xy 123.346601 -68.845462) (xy 123.320315 -68.836713)
			(xy 123.292644 -68.83535) (xy 123.265626 -68.841473) (xy 123.241246 -68.854632) (xy 123.2213 -68.873858)
			(xy 123.213876 -68.885562) (xy 123.199004 -68.909645) (xy 123.163362 -68.953611) (xy 123.121618 -68.991831)
			(xy 123.074687 -69.023467) (xy 123.023599 -69.047826) (xy 122.969474 -69.064374) (xy 122.913499 -69.072746)
			(xy 122.8852 -69.073268) (xy 122.857946 -69.072862) (xy 122.803993 -69.065105) (xy 122.751692 -69.049748)
			(xy 122.70211 -69.027105) (xy 122.656255 -68.997635) (xy 122.61506 -68.96194) (xy 122.579365 -68.920745)
			(xy 122.549895 -68.87489) (xy 122.527252 -68.825308) (xy 122.511895 -68.773007) (xy 122.504138 -68.719054)
			(xy 122.394292 -68.719054) (xy 122.386975 -68.776979) (xy 122.371078 -68.838893) (xy 122.347546 -68.898326)
			(xy 122.316752 -68.954341) (xy 122.279179 -69.006056) (xy 122.235422 -69.052653) (xy 122.186169 -69.093398)
			(xy 122.132198 -69.127649) (xy 122.074359 -69.154866) (xy 122.013566 -69.174619) (xy 121.950776 -69.186597)
			(xy 121.88698 -69.190611) (xy 121.823184 -69.186597) (xy 121.760394 -69.174619) (xy 121.699601 -69.154866)
			(xy 121.641762 -69.127649) (xy 121.587791 -69.093398) (xy 121.538538 -69.052653) (xy 121.494781 -69.006056)
			(xy 121.457208 -68.954341) (xy 121.426414 -68.898326) (xy 121.402882 -68.838893) (xy 121.386985 -68.776979)
			(xy 121.378974 -68.713561) (xy 105.199905 -68.713561) (xy 105.186421 -68.758379) (xy 105.162749 -68.808876)
			(xy 105.131976 -68.855389) (xy 105.094759 -68.896926) (xy 105.051891 -68.932601) (xy 105.004285 -68.961655)
			(xy 104.952956 -68.983467) (xy 104.898999 -68.997573) (xy 104.843562 -69.003673) (xy 104.787828 -69.001636)
			(xy 104.732985 -68.991506) (xy 104.680201 -68.973499) (xy 104.630601 -68.947998) (xy 104.585243 -68.915547)
			(xy 104.545094 -68.876838) (xy 104.511008 -68.832695) (xy 104.483712 -68.78406) (xy 104.463789 -68.731969)
			(xy 104.451663 -68.677532) (xy 104.447592 -68.62191) (xy 99.534242 -68.62191) (xy 99.549336 -68.670191)
			(xy 99.558066 -68.72736) (xy 99.558602 -68.756276) (xy 99.558116 -68.783527) (xy 99.55036 -68.837475)
			(xy 99.535005 -68.88977) (xy 99.512363 -68.939347) (xy 99.482897 -68.985197) (xy 99.447206 -69.026388)
			(xy 99.406015 -69.062079) (xy 99.360165 -69.091545) (xy 99.310588 -69.114187) (xy 99.258293 -69.129542)
			(xy 99.204345 -69.137298) (xy 99.149843 -69.137298) (xy 99.095895 -69.129542) (xy 99.0436 -69.114187)
			(xy 98.994023 -69.091545) (xy 98.948173 -69.062079) (xy 98.906982 -69.026388) (xy 98.871291 -68.985197)
			(xy 98.841825 -68.939347) (xy 98.819183 -68.88977) (xy 98.803828 -68.837475) (xy 98.796072 -68.783527)
			(xy 98.795586 -68.756276) (xy 84.438703 -68.756276) (xy 84.430811 -68.782509) (xy 84.407139 -68.833006)
			(xy 84.376366 -68.879519) (xy 84.339149 -68.921056) (xy 84.296281 -68.956731) (xy 84.248675 -68.985785)
			(xy 84.197346 -69.007597) (xy 84.143389 -69.021703) (xy 84.087952 -69.027803) (xy 84.032218 -69.025766)
			(xy 83.977375 -69.015636) (xy 83.924591 -68.997629) (xy 83.874991 -68.972128) (xy 83.829633 -68.939677)
			(xy 83.789484 -68.900968) (xy 83.755398 -68.856825) (xy 83.728102 -68.80819) (xy 83.708179 -68.756099)
			(xy 83.696053 -68.701662) (xy 83.691982 -68.64604) (xy 50.5714 -68.64604) (xy 50.5714 -69.864986)
			(xy 89.974164 -69.864986) (xy 89.978235 -69.809364) (xy 89.990361 -69.754927) (xy 90.010284 -69.702836)
			(xy 90.03758 -69.654201) (xy 90.071666 -69.610058) (xy 90.111815 -69.571349) (xy 90.157173 -69.538898)
			(xy 90.206773 -69.513397) (xy 90.259557 -69.49539) (xy 90.3144 -69.48526) (xy 90.370134 -69.483223)
			(xy 90.425571 -69.489323) (xy 90.479528 -69.503429) (xy 90.530857 -69.525241) (xy 90.578463 -69.554295)
			(xy 90.621331 -69.58997) (xy 90.658548 -69.631507) (xy 90.689321 -69.67802) (xy 90.712993 -69.728517)
			(xy 90.729061 -69.781924) (xy 90.737181 -69.8371) (xy 90.73769 -69.864986) (xy 90.737181 -69.892872)
			(xy 90.736239 -69.899276) (xy 98.795076 -69.899276) (xy 98.799147 -69.843654) (xy 98.811273 -69.789217)
			(xy 98.831196 -69.737126) (xy 98.858492 -69.688491) (xy 98.892578 -69.644348) (xy 98.932727 -69.605639)
			(xy 98.978085 -69.573188) (xy 99.027685 -69.547687) (xy 99.080469 -69.52968) (xy 99.135312 -69.51955)
			(xy 99.191046 -69.517513) (xy 99.246483 -69.523613) (xy 99.30044 -69.537719) (xy 99.351769 -69.559531)
			(xy 99.399375 -69.588585) (xy 99.442243 -69.62426) (xy 99.47946 -69.665797) (xy 99.510233 -69.71231)
			(xy 99.533905 -69.762807) (xy 99.549973 -69.816214) (xy 99.558093 -69.87139) (xy 99.558602 -69.899276)
			(xy 99.558093 -69.927162) (xy 99.549973 -69.982338) (xy 99.533905 -70.035745) (xy 99.510233 -70.086242)
			(xy 99.47946 -70.132755) (xy 99.442243 -70.174292) (xy 99.399375 -70.209967) (xy 99.351769 -70.239021)
			(xy 99.30044 -70.260833) (xy 99.246483 -70.274939) (xy 99.191046 -70.281039) (xy 99.135312 -70.279002)
			(xy 99.080469 -70.268872) (xy 99.027685 -70.250865) (xy 98.978085 -70.225364) (xy 98.932727 -70.192913)
			(xy 98.892578 -70.154204) (xy 98.858492 -70.110061) (xy 98.831196 -70.061426) (xy 98.811273 -70.009335)
			(xy 98.799147 -69.954898) (xy 98.795076 -69.899276) (xy 90.736239 -69.899276) (xy 90.729061 -69.948048)
			(xy 90.712993 -70.001455) (xy 90.689321 -70.051952) (xy 90.658548 -70.098465) (xy 90.621331 -70.140002)
			(xy 90.578463 -70.175677) (xy 90.530857 -70.204731) (xy 90.479528 -70.226543) (xy 90.425571 -70.240649)
			(xy 90.370134 -70.246749) (xy 90.3144 -70.244712) (xy 90.259557 -70.234582) (xy 90.206773 -70.216575)
			(xy 90.157173 -70.191074) (xy 90.111815 -70.158623) (xy 90.071666 -70.119914) (xy 90.03758 -70.075771)
			(xy 90.010284 -70.027136) (xy 89.990361 -69.975045) (xy 89.978235 -69.920608) (xy 89.974164 -69.864986)
			(xy 50.5714 -69.864986) (xy 50.5714 -70.283832) (xy 88.435686 -70.283832) (xy 88.439757 -70.22821)
			(xy 88.451883 -70.173773) (xy 88.471806 -70.121682) (xy 88.499102 -70.073047) (xy 88.533188 -70.028904)
			(xy 88.573337 -69.990195) (xy 88.618695 -69.957744) (xy 88.668295 -69.932243) (xy 88.721079 -69.914236)
			(xy 88.775922 -69.904106) (xy 88.831656 -69.902069) (xy 88.887093 -69.908169) (xy 88.94105 -69.922275)
			(xy 88.992379 -69.944087) (xy 89.039985 -69.973141) (xy 89.082853 -70.008816) (xy 89.12007 -70.050353)
			(xy 89.150843 -70.096866) (xy 89.174515 -70.147363) (xy 89.190583 -70.20077) (xy 89.198703 -70.255946)
			(xy 89.199212 -70.283832) (xy 89.198703 -70.311718) (xy 89.190583 -70.366894) (xy 89.174515 -70.420301)
			(xy 89.150843 -70.470798) (xy 89.12007 -70.517311) (xy 89.082853 -70.558848) (xy 89.039985 -70.594523)
			(xy 88.992379 -70.623577) (xy 88.94105 -70.645389) (xy 88.887093 -70.659495) (xy 88.831656 -70.665595)
			(xy 88.775922 -70.663558) (xy 88.721079 -70.653428) (xy 88.668295 -70.635421) (xy 88.618695 -70.60992)
			(xy 88.573337 -70.577469) (xy 88.533188 -70.53876) (xy 88.499102 -70.494617) (xy 88.471806 -70.445982)
			(xy 88.451883 -70.393891) (xy 88.439757 -70.339454) (xy 88.435686 -70.283832) (xy 50.5714 -70.283832)
			(xy 50.5714 -71.241254) (xy 97.805935 -71.241254) (xy 97.805935 -71.186746) (xy 97.813692 -71.132792)
			(xy 97.829049 -71.080491) (xy 97.851693 -71.030908) (xy 97.881163 -70.985052) (xy 97.916859 -70.943857)
			(xy 97.958054 -70.908162) (xy 98.00391 -70.878692) (xy 98.053493 -70.856049) (xy 98.105794 -70.840692)
			(xy 98.159748 -70.832935) (xy 98.187002 -70.832472) (xy 98.216944 -70.833054) (xy 98.27609 -70.842423)
			(xy 98.333048 -70.860915) (xy 98.386418 -70.888077) (xy 98.43489 -70.92324) (xy 98.456496 -70.943978)
			(xy 98.464624 -70.952106) (xy 98.48596 -70.959726) (xy 98.587306 -70.949312) (xy 98.60661 -70.937628)
			(xy 98.61296 -70.927976) (xy 98.630602 -70.901964) (xy 98.671377 -70.854129) (xy 98.717737 -70.811685)
			(xy 98.768975 -70.775279) (xy 98.82431 -70.745465) (xy 98.882897 -70.7227) (xy 98.943844 -70.707329)
			(xy 99.00622 -70.699588) (xy 99.037648 -70.699122) (xy 99.068381 -70.699511) (xy 99.129399 -70.706925)
			(xy 99.189078 -70.72164) (xy 99.246548 -70.743442) (xy 99.300972 -70.772011) (xy 99.351555 -70.806932)
			(xy 99.39756 -70.847695) (xy 99.438316 -70.893707) (xy 99.473229 -70.944295) (xy 99.50179 -70.998723)
			(xy 99.523583 -71.056197) (xy 99.538289 -71.115878) (xy 99.545694 -71.176897) (xy 99.546156 -71.20763)
			(xy 99.545714 -71.237729) (xy 99.538609 -71.297506) (xy 99.524492 -71.356025) (xy 99.503559 -71.412467)
			(xy 99.476105 -71.466039) (xy 99.442513 -71.515993) (xy 99.42322 -71.5391) (xy 99.415807 -71.548813)
			(xy 99.410239 -71.572567) (xy 99.412552 -71.584566) (xy 99.436428 -71.67753) (xy 99.45243 -71.695564)
			(xy 99.464368 -71.700136) (xy 99.492925 -71.711473) (xy 99.547309 -71.740068) (xy 99.597853 -71.775006)
			(xy 99.64382 -71.815778) (xy 99.684541 -71.86179) (xy 99.719423 -71.912372) (xy 99.747958 -71.966788)
			(xy 99.76973 -72.024245) (xy 99.784422 -72.083906) (xy 99.791821 -72.144902) (xy 99.792282 -72.175624)
			(xy 99.79178 -72.207585) (xy 99.783769 -72.271003) (xy 99.767872 -72.332917) (xy 99.74434 -72.39235)
			(xy 99.713546 -72.448365) (xy 99.675973 -72.50008) (xy 99.632216 -72.546677) (xy 99.582963 -72.587422)
			(xy 99.528992 -72.621673) (xy 99.471153 -72.64889) (xy 99.41036 -72.668643) (xy 99.34757 -72.680621)
			(xy 99.283774 -72.684635) (xy 99.219978 -72.680621) (xy 99.157188 -72.668643) (xy 99.096395 -72.64889)
			(xy 99.038556 -72.621673) (xy 98.984585 -72.587422) (xy 98.935332 -72.546677) (xy 98.891575 -72.50008)
			(xy 98.854002 -72.448365) (xy 98.823208 -72.39235) (xy 98.799676 -72.332917) (xy 98.783779 -72.271003)
			(xy 98.775768 -72.207585) (xy 98.775266 -72.175624) (xy 98.775735 -72.145526) (xy 98.782833 -72.085749)
			(xy 98.796945 -72.027231) (xy 98.817873 -71.970789) (xy 98.845323 -71.917216) (xy 98.878911 -71.867262)
			(xy 98.898202 -71.844154) (xy 98.905585 -71.834422) (xy 98.91117 -71.810683) (xy 98.90887 -71.798688)
			(xy 98.888296 -71.71817) (xy 98.884607 -71.706449) (xy 98.86827 -71.68814) (xy 98.857054 -71.683118)
			(xy 98.828193 -71.671654) (xy 98.773268 -71.64267) (xy 98.722284 -71.607209) (xy 98.676001 -71.5658)
			(xy 98.635109 -71.51906) (xy 98.617278 -71.493634) (xy 98.617024 -71.49338) (xy 98.610207 -71.484563)
			(xy 98.590974 -71.473358) (xy 98.57994 -71.47179) (xy 98.490024 -71.463662) (xy 98.468434 -71.47179)
			(xy 98.46056 -71.479918) (xy 98.442539 -71.497863) (xy 98.402554 -71.529291) (xy 98.358749 -71.55513)
			(xy 98.3119 -71.57492) (xy 98.262838 -71.588312) (xy 98.212431 -71.595068) (xy 98.187002 -71.595488)
			(xy 98.159748 -71.595065) (xy 98.105794 -71.587308) (xy 98.053493 -71.571951) (xy 98.00391 -71.549308)
			(xy 97.958054 -71.519838) (xy 97.916859 -71.484143) (xy 97.881163 -71.442948) (xy 97.851693 -71.397092)
			(xy 97.829049 -71.347509) (xy 97.813692 -71.295208) (xy 97.805935 -71.241254) (xy 50.5714 -71.241254)
			(xy 50.5714 -73.13295) (xy 86.505032 -73.13295) (xy 86.509103 -73.077328) (xy 86.521229 -73.022891)
			(xy 86.541152 -72.9708) (xy 86.568448 -72.922165) (xy 86.602534 -72.878022) (xy 86.642683 -72.839313)
			(xy 86.688041 -72.806862) (xy 86.737641 -72.781361) (xy 86.790425 -72.763354) (xy 86.845268 -72.753224)
			(xy 86.901002 -72.751187) (xy 86.956439 -72.757287) (xy 87.010396 -72.771393) (xy 87.061725 -72.793205)
			(xy 87.109331 -72.822259) (xy 87.112442 -72.824848) (xy 88.440512 -72.824848) (xy 88.444583 -72.769226)
			(xy 88.456709 -72.714789) (xy 88.476632 -72.662698) (xy 88.503928 -72.614063) (xy 88.538014 -72.56992)
			(xy 88.578163 -72.531211) (xy 88.623521 -72.49876) (xy 88.673121 -72.473259) (xy 88.725905 -72.455252)
			(xy 88.780748 -72.445122) (xy 88.836482 -72.443085) (xy 88.891919 -72.449185) (xy 88.945876 -72.463291)
			(xy 88.997205 -72.485103) (xy 89.044811 -72.514157) (xy 89.087679 -72.549832) (xy 89.124896 -72.591369)
			(xy 89.155669 -72.637882) (xy 89.179341 -72.688379) (xy 89.195409 -72.741786) (xy 89.203529 -72.796962)
			(xy 89.204038 -72.824848) (xy 89.203529 -72.852734) (xy 89.195409 -72.90791) (xy 89.179341 -72.961317)
			(xy 89.155669 -73.011814) (xy 89.124896 -73.058327) (xy 89.087679 -73.099864) (xy 89.044811 -73.135539)
			(xy 88.997205 -73.164593) (xy 88.945876 -73.186405) (xy 88.891919 -73.200511) (xy 88.836482 -73.206611)
			(xy 88.780748 -73.204574) (xy 88.725905 -73.194444) (xy 88.673121 -73.176437) (xy 88.623521 -73.150936)
			(xy 88.578163 -73.118485) (xy 88.538014 -73.079776) (xy 88.503928 -73.035633) (xy 88.476632 -72.986998)
			(xy 88.456709 -72.934907) (xy 88.444583 -72.88047) (xy 88.440512 -72.824848) (xy 87.112442 -72.824848)
			(xy 87.152199 -72.857934) (xy 87.189416 -72.899471) (xy 87.220189 -72.945984) (xy 87.243861 -72.996481)
			(xy 87.259929 -73.049888) (xy 87.268049 -73.105064) (xy 87.268558 -73.13295) (xy 87.268049 -73.160836)
			(xy 87.259929 -73.216012) (xy 87.243861 -73.269419) (xy 87.220189 -73.319916) (xy 87.202223 -73.347072)
			(xy 90.990418 -73.347072) (xy 90.994489 -73.29145) (xy 91.006615 -73.237013) (xy 91.026538 -73.184922)
			(xy 91.053834 -73.136287) (xy 91.08792 -73.092144) (xy 91.128069 -73.053435) (xy 91.173427 -73.020984)
			(xy 91.223027 -72.995483) (xy 91.275811 -72.977476) (xy 91.330654 -72.967346) (xy 91.386388 -72.965309)
			(xy 91.441825 -72.971409) (xy 91.495782 -72.985515) (xy 91.547111 -73.007327) (xy 91.594717 -73.036381)
			(xy 91.637585 -73.072056) (xy 91.674802 -73.113593) (xy 91.705575 -73.160106) (xy 91.729247 -73.210603)
			(xy 91.745315 -73.26401) (xy 91.753435 -73.319186) (xy 91.753944 -73.347072) (xy 91.753435 -73.374958)
			(xy 91.745315 -73.430134) (xy 91.729247 -73.483541) (xy 91.705575 -73.534038) (xy 91.674802 -73.580551)
			(xy 91.637585 -73.622088) (xy 91.594717 -73.657763) (xy 91.547111 -73.686817) (xy 91.495782 -73.708629)
			(xy 91.441825 -73.722735) (xy 91.386388 -73.728835) (xy 91.330654 -73.726798) (xy 91.275811 -73.716668)
			(xy 91.223027 -73.698661) (xy 91.173427 -73.67316) (xy 91.128069 -73.640709) (xy 91.08792 -73.602)
			(xy 91.053834 -73.557857) (xy 91.026538 -73.509222) (xy 91.006615 -73.457131) (xy 90.994489 -73.402694)
			(xy 90.990418 -73.347072) (xy 87.202223 -73.347072) (xy 87.189416 -73.366429) (xy 87.152199 -73.407966)
			(xy 87.109331 -73.443641) (xy 87.061725 -73.472695) (xy 87.010396 -73.494507) (xy 86.956439 -73.508613)
			(xy 86.901002 -73.514713) (xy 86.845268 -73.512676) (xy 86.790425 -73.502546) (xy 86.737641 -73.484539)
			(xy 86.688041 -73.459038) (xy 86.642683 -73.426587) (xy 86.602534 -73.387878) (xy 86.568448 -73.343735)
			(xy 86.541152 -73.2951) (xy 86.521229 -73.243009) (xy 86.509103 -73.188572) (xy 86.505032 -73.13295)
			(xy 50.5714 -73.13295) (xy 50.5714 -74.68362) (xy 91.167964 -74.68362) (xy 91.172035 -74.627998)
			(xy 91.184161 -74.573561) (xy 91.204084 -74.52147) (xy 91.23138 -74.472835) (xy 91.265466 -74.428692)
			(xy 91.305615 -74.389983) (xy 91.350973 -74.357532) (xy 91.400573 -74.332031) (xy 91.453357 -74.314024)
			(xy 91.5082 -74.303894) (xy 91.563934 -74.301857) (xy 91.619371 -74.307957) (xy 91.673328 -74.322063)
			(xy 91.724657 -74.343875) (xy 91.772263 -74.372929) (xy 91.815131 -74.408604) (xy 91.852348 -74.450141)
			(xy 91.883121 -74.496654) (xy 91.906793 -74.547151) (xy 91.922861 -74.600558) (xy 91.930981 -74.655734)
			(xy 91.93149 -74.68362) (xy 91.930981 -74.711506) (xy 91.922861 -74.766682) (xy 91.906793 -74.820089)
			(xy 91.883121 -74.870586) (xy 91.852348 -74.917099) (xy 91.815131 -74.958636) (xy 91.772263 -74.994311)
			(xy 91.724657 -75.023365) (xy 91.673328 -75.045177) (xy 91.619371 -75.059283) (xy 91.563934 -75.065383)
			(xy 91.5082 -75.063346) (xy 91.453357 -75.053216) (xy 91.400573 -75.035209) (xy 91.350973 -75.009708)
			(xy 91.305615 -74.977257) (xy 91.265466 -74.938548) (xy 91.23138 -74.894405) (xy 91.204084 -74.84577)
			(xy 91.184161 -74.793679) (xy 91.172035 -74.739242) (xy 91.167964 -74.68362) (xy 50.5714 -74.68362)
			(xy 50.5714 -74.760836) (xy 50.570895 -74.86636) (xy 50.562811 -75.077254) (xy 50.546655 -75.287683)
			(xy 50.522452 -75.49734) (xy 50.498073 -75.65517) (xy 89.99931 -75.65517) (xy 90.003381 -75.599548)
			(xy 90.015507 -75.545111) (xy 90.03543 -75.49302) (xy 90.062726 -75.444385) (xy 90.096812 -75.400242)
			(xy 90.136961 -75.361533) (xy 90.182319 -75.329082) (xy 90.231919 -75.303581) (xy 90.284703 -75.285574)
			(xy 90.339546 -75.275444) (xy 90.39528 -75.273407) (xy 90.450717 -75.279507) (xy 90.504674 -75.293613)
			(xy 90.556003 -75.315425) (xy 90.603609 -75.344479) (xy 90.646477 -75.380154) (xy 90.683694 -75.421691)
			(xy 90.714467 -75.468204) (xy 90.738139 -75.518701) (xy 90.754207 -75.572108) (xy 90.762327 -75.627284)
			(xy 90.762836 -75.65517) (xy 90.762327 -75.683056) (xy 90.754207 -75.738232) (xy 90.738139 -75.791639)
			(xy 90.714467 -75.842136) (xy 90.684065 -75.888088) (xy 95.934782 -75.888088) (xy 95.938853 -75.832466)
			(xy 95.950979 -75.778029) (xy 95.970902 -75.725938) (xy 95.998198 -75.677303) (xy 96.032284 -75.63316)
			(xy 96.072433 -75.594451) (xy 96.117791 -75.562) (xy 96.167391 -75.536499) (xy 96.220175 -75.518492)
			(xy 96.275018 -75.508362) (xy 96.330752 -75.506325) (xy 96.386189 -75.512425) (xy 96.440146 -75.526531)
			(xy 96.491475 -75.548343) (xy 96.539081 -75.577397) (xy 96.581949 -75.613072) (xy 96.619166 -75.654609)
			(xy 96.649939 -75.701122) (xy 96.673611 -75.751619) (xy 96.689679 -75.805026) (xy 96.697799 -75.860202)
			(xy 96.698308 -75.888088) (xy 96.697799 -75.915974) (xy 96.689679 -75.97115) (xy 96.673611 -76.024557)
			(xy 96.649939 -76.075054) (xy 96.619166 -76.121567) (xy 96.581949 -76.163104) (xy 96.539081 -76.198779)
			(xy 96.491475 -76.227833) (xy 96.440146 -76.249645) (xy 96.386189 -76.263751) (xy 96.330752 -76.269851)
			(xy 96.275018 -76.267814) (xy 96.220175 -76.257684) (xy 96.167391 -76.239677) (xy 96.117791 -76.214176)
			(xy 96.072433 -76.181725) (xy 96.032284 -76.143016) (xy 95.998198 -76.098873) (xy 95.970902 -76.050238)
			(xy 95.950979 -75.998147) (xy 95.938853 -75.94371) (xy 95.934782 -75.888088) (xy 90.684065 -75.888088)
			(xy 90.683694 -75.888649) (xy 90.646477 -75.930186) (xy 90.603609 -75.965861) (xy 90.556003 -75.994915)
			(xy 90.504674 -76.016727) (xy 90.450717 -76.030833) (xy 90.39528 -76.036933) (xy 90.339546 -76.034896)
			(xy 90.284703 -76.024766) (xy 90.231919 -76.006759) (xy 90.182319 -75.981258) (xy 90.136961 -75.948807)
			(xy 90.096812 -75.910098) (xy 90.062726 -75.865955) (xy 90.03543 -75.81732) (xy 90.015507 -75.765229)
			(xy 90.003381 -75.710792) (xy 89.99931 -75.65517) (xy 50.498073 -75.65517) (xy 50.490235 -75.705915)
			(xy 50.450053 -75.913103) (xy 50.401965 -76.1186) (xy 50.346041 -76.322104) (xy 50.282364 -76.523317)
			(xy 50.211026 -76.721944) (xy 50.132132 -76.917692) (xy 50.045799 -77.110274) (xy 49.967313 -77.268789)
			(xy 90.404944 -77.268789) (xy 90.404944 -77.204867) (xy 90.412955 -77.141449) (xy 90.428852 -77.079535)
			(xy 90.452384 -77.020102) (xy 90.483178 -76.964087) (xy 90.520751 -76.912372) (xy 90.564508 -76.865775)
			(xy 90.613761 -76.82503) (xy 90.667732 -76.790779) (xy 90.725571 -76.763562) (xy 90.786364 -76.743809)
			(xy 90.849154 -76.731831) (xy 90.91295 -76.727818) (xy 90.976746 -76.731831) (xy 91.039536 -76.743809)
			(xy 91.100329 -76.763562) (xy 91.158168 -76.790779) (xy 91.212139 -76.82503) (xy 91.261392 -76.865775)
			(xy 91.305149 -76.912372) (xy 91.342722 -76.964087) (xy 91.373516 -77.020102) (xy 91.397048 -77.079535)
			(xy 91.412945 -77.141449) (xy 91.414662 -77.15504) (xy 93.06509 -77.15504) (xy 93.069161 -77.099418)
			(xy 93.081287 -77.044981) (xy 93.10121 -76.99289) (xy 93.128506 -76.944255) (xy 93.162592 -76.900112)
			(xy 93.202741 -76.861403) (xy 93.248099 -76.828952) (xy 93.297699 -76.803451) (xy 93.350483 -76.785444)
			(xy 93.405326 -76.775314) (xy 93.46106 -76.773277) (xy 93.516497 -76.779377) (xy 93.570454 -76.793483)
			(xy 93.621783 -76.815295) (xy 93.669389 -76.844349) (xy 93.712257 -76.880024) (xy 93.749474 -76.921561)
			(xy 93.780247 -76.968074) (xy 93.803919 -77.018571) (xy 93.819987 -77.071978) (xy 93.828107 -77.127154)
			(xy 93.828616 -77.15504) (xy 93.828107 -77.182926) (xy 93.819987 -77.238102) (xy 93.803919 -77.291509)
			(xy 93.780247 -77.342006) (xy 93.749474 -77.388519) (xy 93.712257 -77.430056) (xy 93.669389 -77.465731)
			(xy 93.621783 -77.494785) (xy 93.570454 -77.516597) (xy 93.516497 -77.530703) (xy 93.46106 -77.536803)
			(xy 93.405326 -77.534766) (xy 93.350483 -77.524636) (xy 93.297699 -77.506629) (xy 93.248099 -77.481128)
			(xy 93.202741 -77.448677) (xy 93.162592 -77.409968) (xy 93.128506 -77.365825) (xy 93.10121 -77.31719)
			(xy 93.081287 -77.265099) (xy 93.069161 -77.210662) (xy 93.06509 -77.15504) (xy 91.414662 -77.15504)
			(xy 91.420956 -77.204867) (xy 91.421458 -77.236828) (xy 91.420956 -77.268789) (xy 91.412945 -77.332207)
			(xy 91.397048 -77.394121) (xy 91.373516 -77.453554) (xy 91.342722 -77.509569) (xy 91.305149 -77.561284)
			(xy 91.261392 -77.607881) (xy 91.212139 -77.648626) (xy 91.158168 -77.682877) (xy 91.100329 -77.710094)
			(xy 91.039536 -77.729847) (xy 90.976746 -77.741825) (xy 90.91295 -77.745839) (xy 90.849154 -77.741825)
			(xy 90.786364 -77.729847) (xy 90.725571 -77.710094) (xy 90.667732 -77.682877) (xy 90.613761 -77.648626)
			(xy 90.564508 -77.607881) (xy 90.520751 -77.561284) (xy 90.483178 -77.509569) (xy 90.452384 -77.453554)
			(xy 90.428852 -77.394121) (xy 90.412955 -77.332207) (xy 90.404944 -77.268789) (xy 49.967313 -77.268789)
			(xy 49.952152 -77.299409) (xy 49.85133 -77.484818) (xy 49.74348 -77.666229) (xy 49.628761 -77.843376)
			(xy 49.507341 -78.015998) (xy 49.379398 -78.183844) (xy 49.313326 -78.263961) (xy 106.074712 -78.263961)
			(xy 106.074712 -78.200039) (xy 106.082723 -78.136621) (xy 106.09862 -78.074707) (xy 106.122152 -78.015274)
			(xy 106.152946 -77.959259) (xy 106.190519 -77.907544) (xy 106.234276 -77.860947) (xy 106.283529 -77.820202)
			(xy 106.3375 -77.785951) (xy 106.395339 -77.758734) (xy 106.456132 -77.738981) (xy 106.518922 -77.727003)
			(xy 106.582718 -77.72299) (xy 106.646514 -77.727003) (xy 106.709304 -77.738981) (xy 106.770097 -77.758734)
			(xy 106.827936 -77.785951) (xy 106.881907 -77.820202) (xy 106.93116 -77.860947) (xy 106.974917 -77.907544)
			(xy 107.01249 -77.959259) (xy 107.043284 -78.015274) (xy 107.066816 -78.074707) (xy 107.082713 -78.136621)
			(xy 107.090724 -78.200039) (xy 107.091226 -78.232) (xy 107.090724 -78.263961) (xy 107.082713 -78.327379)
			(xy 107.066816 -78.389293) (xy 107.043284 -78.448726) (xy 107.01249 -78.504741) (xy 106.974917 -78.556456)
			(xy 106.93116 -78.603053) (xy 106.881907 -78.643798) (xy 106.827936 -78.678049) (xy 106.770097 -78.705266)
			(xy 106.709304 -78.725019) (xy 106.646514 -78.736997) (xy 106.582718 -78.741011) (xy 106.518922 -78.736997)
			(xy 106.456132 -78.725019) (xy 106.395339 -78.705266) (xy 106.3375 -78.678049) (xy 106.283529 -78.643798)
			(xy 106.234276 -78.603053) (xy 106.190519 -78.556456) (xy 106.152946 -78.504741) (xy 106.122152 -78.448726)
			(xy 106.09862 -78.389293) (xy 106.082723 -78.327379) (xy 106.074712 -78.263961) (xy 49.313326 -78.263961)
			(xy 49.24512 -78.346666) (xy 49.104704 -78.504225) (xy 48.958356 -78.65629) (xy 48.806291 -78.802638)
			(xy 48.648732 -78.943054) (xy 48.48591 -79.077332) (xy 48.318064 -79.205275) (xy 48.145442 -79.326695)
			(xy 47.968295 -79.441414) (xy 47.786884 -79.549264) (xy 47.601475 -79.650086) (xy 47.41234 -79.743733)
			(xy 47.219758 -79.830066) (xy 47.02401 -79.90896) (xy 46.825383 -79.980298) (xy 46.62417 -80.043975)
			(xy 46.420666 -80.099899) (xy 46.254522 -80.138778) (xy 100.26218 -80.138778) (xy 100.266251 -80.083156)
			(xy 100.278377 -80.028719) (xy 100.2983 -79.976628) (xy 100.325596 -79.927993) (xy 100.359682 -79.88385)
			(xy 100.399831 -79.845141) (xy 100.445189 -79.81269) (xy 100.494789 -79.787189) (xy 100.547573 -79.769182)
			(xy 100.602416 -79.759052) (xy 100.65815 -79.757015) (xy 100.713587 -79.763115) (xy 100.767544 -79.777221)
			(xy 100.818873 -79.799033) (xy 100.866479 -79.828087) (xy 100.909347 -79.863762) (xy 100.946564 -79.905299)
			(xy 100.977337 -79.951812) (xy 101.001009 -80.002309) (xy 101.017077 -80.055716) (xy 101.025197 -80.110892)
			(xy 101.025706 -80.138778) (xy 101.025197 -80.166664) (xy 101.017077 -80.22184) (xy 101.001009 -80.275247)
			(xy 100.986039 -80.30718) (xy 111.586772 -80.30718) (xy 111.586772 -80.306926) (xy 111.587227 -80.276719)
			(xy 111.594363 -80.216728) (xy 111.608562 -80.158006) (xy 111.629622 -80.101381) (xy 111.657248 -80.047653)
			(xy 111.691048 -79.99758) (xy 111.71047 -79.97444) (xy 111.716131 -79.967381) (xy 111.722508 -79.95046)
			(xy 111.722916 -79.94142) (xy 111.722916 -79.91094) (xy 111.722485 -79.901905) (xy 111.716114 -79.884989)
			(xy 111.71047 -79.87792) (xy 111.691048 -79.854781) (xy 111.657259 -79.8047) (xy 111.629638 -79.75097)
			(xy 111.608574 -79.694347) (xy 111.594363 -79.635629) (xy 111.587206 -79.575641) (xy 111.586772 -79.545434)
			(xy 111.586772 -79.54518) (xy 111.587268 -79.51303) (xy 111.595359 -79.44924) (xy 111.611435 -79.386982)
			(xy 111.635239 -79.32725) (xy 111.66639 -79.270999) (xy 111.704391 -79.219129) (xy 111.748633 -79.172469)
			(xy 111.773208 -79.151734) (xy 111.780469 -79.145278) (xy 111.789871 -79.128294) (xy 111.791496 -79.118714)
			(xy 111.799878 -79.048864) (xy 111.8006 -79.039138) (xy 111.795492 -79.02033) (xy 111.789972 -79.012288)
			(xy 111.789972 -79.012034) (xy 111.773969 -78.989934) (xy 111.747811 -78.942048) (xy 111.728736 -78.890926)
			(xy 111.717135 -78.837609) (xy 111.713243 -78.783184) (xy 111.717139 -78.728759) (xy 111.728745 -78.675443)
			(xy 111.747824 -78.624323) (xy 111.773987 -78.57644) (xy 111.789972 -78.554326) (xy 111.789972 -78.554072)
			(xy 111.795511 -78.546039) (xy 111.800612 -78.527225) (xy 111.799878 -78.517496) (xy 111.791496 -78.447646)
			(xy 111.789838 -78.438079) (xy 111.78044 -78.421105) (xy 111.773208 -78.414626) (xy 111.748613 -78.393912)
			(xy 111.704371 -78.347246) (xy 111.666367 -78.295374) (xy 111.635209 -78.239122) (xy 111.611395 -78.17939)
			(xy 111.595305 -78.117131) (xy 111.587196 -78.05334) (xy 111.587198 -77.989035) (xy 111.59531 -77.925244)
			(xy 111.611403 -77.862986) (xy 111.63522 -77.803255) (xy 111.666381 -77.747005) (xy 111.704387 -77.695134)
			(xy 111.748632 -77.648471) (xy 111.773208 -77.627734) (xy 111.780469 -77.621278) (xy 111.789871 -77.604294)
			(xy 111.791496 -77.594714) (xy 111.799878 -77.524864) (xy 111.8006 -77.515138) (xy 111.795492 -77.49633)
			(xy 111.789972 -77.488288) (xy 111.789972 -77.488034) (xy 111.773969 -77.465934) (xy 111.747811 -77.418048)
			(xy 111.728736 -77.366926) (xy 111.717135 -77.313609) (xy 111.713243 -77.259184) (xy 111.717139 -77.204759)
			(xy 111.728745 -77.151443) (xy 111.747824 -77.100323) (xy 111.773987 -77.05244) (xy 111.789972 -77.030326)
			(xy 111.789972 -77.030072) (xy 111.795511 -77.022039) (xy 111.800612 -77.003225) (xy 111.799878 -76.993496)
			(xy 111.791496 -76.923646) (xy 111.789838 -76.914079) (xy 111.78044 -76.897105) (xy 111.773208 -76.890626)
			(xy 111.748613 -76.869912) (xy 111.704371 -76.823246) (xy 111.666367 -76.771374) (xy 111.635209 -76.715122)
			(xy 111.611395 -76.65539) (xy 111.595305 -76.593131) (xy 111.587196 -76.52934) (xy 111.587198 -76.465035)
			(xy 111.59531 -76.401244) (xy 111.611403 -76.338986) (xy 111.63522 -76.279255) (xy 111.666381 -76.223005)
			(xy 111.704387 -76.171134) (xy 111.748632 -76.124471) (xy 111.773208 -76.103734) (xy 111.780469 -76.097278)
			(xy 111.789871 -76.080294) (xy 111.791496 -76.070714) (xy 111.799878 -76.000864) (xy 111.8006 -75.991138)
			(xy 111.795492 -75.97233) (xy 111.789972 -75.964288) (xy 111.789972 -75.964034) (xy 111.773969 -75.941934)
			(xy 111.747811 -75.894048) (xy 111.728736 -75.842926) (xy 111.717135 -75.789609) (xy 111.713243 -75.735184)
			(xy 111.717139 -75.680759) (xy 111.728745 -75.627443) (xy 111.747824 -75.576323) (xy 111.773987 -75.52844)
			(xy 111.789972 -75.506326) (xy 111.789972 -75.506072) (xy 111.795511 -75.498039) (xy 111.800612 -75.479225)
			(xy 111.799878 -75.469496) (xy 111.791496 -75.399646) (xy 111.789838 -75.390079) (xy 111.78044 -75.373105)
			(xy 111.773208 -75.366626) (xy 111.748646 -75.345879) (xy 111.70442 -75.299208) (xy 111.666431 -75.247335)
			(xy 111.635283 -75.191087) (xy 111.611475 -75.131361) (xy 111.595385 -75.06911) (xy 111.58727 -75.005328)
			(xy 111.586772 -74.97318) (xy 111.587274 -74.941219) (xy 111.595285 -74.877801) (xy 111.611182 -74.815887)
			(xy 111.634714 -74.756454) (xy 111.665508 -74.700439) (xy 111.703081 -74.648724) (xy 111.746838 -74.602127)
			(xy 111.796091 -74.561382) (xy 111.850062 -74.527131) (xy 111.907901 -74.499914) (xy 111.968694 -74.480161)
			(xy 112.031484 -74.468183) (xy 112.09528 -74.46417) (xy 112.159076 -74.468183) (xy 112.221866 -74.480161)
			(xy 112.282659 -74.499914) (xy 112.340498 -74.527131) (xy 112.394469 -74.561382) (xy 112.443722 -74.602127)
			(xy 112.487479 -74.648724) (xy 112.525052 -74.700439) (xy 112.555846 -74.756454) (xy 112.579378 -74.815887)
			(xy 112.595275 -74.877801) (xy 112.603286 -74.941219) (xy 112.603788 -74.97318) (xy 112.603313 -75.005331)
			(xy 112.595215 -75.06912) (xy 112.579134 -75.131378) (xy 112.555326 -75.191109) (xy 112.524172 -75.24736)
			(xy 112.48617 -75.29923) (xy 112.441927 -75.345891) (xy 112.417352 -75.366626) (xy 112.410099 -75.37309)
			(xy 112.400693 -75.390069) (xy 112.399064 -75.399646) (xy 112.390682 -75.469496) (xy 112.389989 -75.479222)
			(xy 112.395078 -75.498027) (xy 112.400588 -75.506072) (xy 112.400588 -75.506326) (xy 112.416551 -75.528453)
			(xy 112.442708 -75.576334) (xy 112.461782 -75.627451) (xy 112.473386 -75.680763) (xy 112.477281 -75.735184)
			(xy 112.47339 -75.789605) (xy 112.461791 -75.842918) (xy 112.442721 -75.894036) (xy 112.416568 -75.94192)
			(xy 112.400588 -75.964034) (xy 112.400588 -75.964288) (xy 112.395025 -75.972307) (xy 112.389936 -75.991132)
			(xy 112.390682 -76.000864) (xy 112.399064 -76.070714) (xy 112.400752 -76.080274) (xy 112.41013 -76.09725)
			(xy 112.417352 -76.103734) (xy 112.441905 -76.124495) (xy 112.486142 -76.171157) (xy 112.524142 -76.223026)
			(xy 112.555297 -76.279273) (xy 112.579109 -76.339) (xy 112.595199 -76.401253) (xy 112.60331 -76.465038)
			(xy 112.603311 -76.529337) (xy 112.595204 -76.593122) (xy 112.579117 -76.655376) (xy 112.555308 -76.715104)
			(xy 112.524156 -76.771353) (xy 112.486159 -76.823223) (xy 112.441923 -76.869888) (xy 112.417352 -76.890626)
			(xy 112.410099 -76.89709) (xy 112.400693 -76.914069) (xy 112.399064 -76.923646) (xy 112.390682 -76.993496)
			(xy 112.389989 -77.003222) (xy 112.395078 -77.022027) (xy 112.400588 -77.030072) (xy 112.400588 -77.030326)
			(xy 112.416551 -77.052453) (xy 112.442708 -77.100334) (xy 112.461782 -77.151451) (xy 112.473386 -77.204763)
			(xy 112.477281 -77.259184) (xy 112.47339 -77.313605) (xy 112.461791 -77.366918) (xy 112.442721 -77.418036)
			(xy 112.416568 -77.46592) (xy 112.400588 -77.488034) (xy 112.400588 -77.488288) (xy 112.395025 -77.496307)
			(xy 112.389936 -77.515132) (xy 112.390682 -77.524864) (xy 112.399064 -77.594714) (xy 112.400752 -77.604274)
			(xy 112.41013 -77.62125) (xy 112.417352 -77.627734) (xy 112.441905 -77.648495) (xy 112.486142 -77.695157)
			(xy 112.524142 -77.747026) (xy 112.555297 -77.803273) (xy 112.579109 -77.863) (xy 112.595199 -77.925253)
			(xy 112.60331 -77.989038) (xy 112.603311 -78.053337) (xy 112.595204 -78.117122) (xy 112.579117 -78.179376)
			(xy 112.555308 -78.239104) (xy 112.524156 -78.295353) (xy 112.486159 -78.347223) (xy 112.441923 -78.393888)
			(xy 112.417352 -78.414626) (xy 112.410099 -78.42109) (xy 112.400693 -78.438069) (xy 112.399064 -78.447646)
			(xy 112.390682 -78.517496) (xy 112.389989 -78.527222) (xy 112.395078 -78.546027) (xy 112.400588 -78.554072)
			(xy 112.400588 -78.554326) (xy 112.416551 -78.576453) (xy 112.442708 -78.624334) (xy 112.461782 -78.675451)
			(xy 112.473386 -78.728763) (xy 112.477281 -78.783184) (xy 112.47339 -78.837605) (xy 112.461791 -78.890918)
			(xy 112.442721 -78.942036) (xy 112.416568 -78.98992) (xy 112.400588 -79.012034) (xy 112.400588 -79.012288)
			(xy 112.395025 -79.020307) (xy 112.389936 -79.039132) (xy 112.390682 -79.048864) (xy 112.399064 -79.118714)
			(xy 112.400752 -79.128274) (xy 112.41013 -79.14525) (xy 112.417352 -79.151734) (xy 112.441935 -79.172458)
			(xy 112.486161 -79.219132) (xy 112.524149 -79.271009) (xy 112.555295 -79.327261) (xy 112.5791 -79.386991)
			(xy 112.595185 -79.449245) (xy 112.603294 -79.513031) (xy 112.603788 -79.54518) (xy 112.603788 -79.545434)
			(xy 112.603378 -79.575643) (xy 112.596235 -79.635636) (xy 112.582028 -79.694359) (xy 112.560959 -79.750983)
			(xy 112.533325 -79.80471) (xy 112.499516 -79.854782) (xy 112.48009 -79.87792) (xy 112.474453 -79.884996)
			(xy 112.46806 -79.901904) (xy 112.467644 -79.91094) (xy 112.467644 -79.94142) (xy 112.468081 -79.950455)
			(xy 112.474447 -79.967372) (xy 112.48009 -79.97444) (xy 112.499503 -79.997586) (xy 112.533291 -80.047667)
			(xy 112.560912 -80.101395) (xy 112.581977 -80.158016) (xy 112.596191 -80.216733) (xy 112.603352 -80.27672)
			(xy 112.603788 -80.306926) (xy 112.603788 -80.30718) (xy 112.603286 -80.339141) (xy 112.595275 -80.402559)
			(xy 112.579378 -80.464473) (xy 112.555846 -80.523906) (xy 112.525052 -80.579921) (xy 112.487479 -80.631636)
			(xy 112.443722 -80.678233) (xy 112.394469 -80.718978) (xy 112.340498 -80.753229) (xy 112.282659 -80.780446)
			(xy 112.221866 -80.800199) (xy 112.159076 -80.812177) (xy 112.09528 -80.816191) (xy 112.031484 -80.812177)
			(xy 111.968694 -80.800199) (xy 111.907901 -80.780446) (xy 111.850062 -80.753229) (xy 111.796091 -80.718978)
			(xy 111.746838 -80.678233) (xy 111.703081 -80.631636) (xy 111.665508 -80.579921) (xy 111.634714 -80.523906)
			(xy 111.611182 -80.464473) (xy 111.595285 -80.402559) (xy 111.587274 -80.339141) (xy 111.586772 -80.30718)
			(xy 100.986039 -80.30718) (xy 100.977337 -80.325744) (xy 100.946564 -80.372257) (xy 100.909347 -80.413794)
			(xy 100.866479 -80.449469) (xy 100.818873 -80.478523) (xy 100.767544 -80.500335) (xy 100.713587 -80.514441)
			(xy 100.65815 -80.520541) (xy 100.602416 -80.518504) (xy 100.547573 -80.508374) (xy 100.494789 -80.490367)
			(xy 100.445189 -80.464866) (xy 100.399831 -80.432415) (xy 100.359682 -80.393706) (xy 100.325596 -80.349563)
			(xy 100.2983 -80.300928) (xy 100.278377 -80.248837) (xy 100.266251 -80.1944) (xy 100.26218 -80.138778)
			(xy 46.254522 -80.138778) (xy 46.215169 -80.147987) (xy 46.007981 -80.188169) (xy 45.799406 -80.220386)
			(xy 45.589749 -80.244589) (xy 45.37932 -80.260745) (xy 45.168426 -80.268829) (xy 44.957378 -80.268829)
			(xy 44.746484 -80.260745) (xy 44.536055 -80.244589) (xy 44.326398 -80.220386) (xy 44.117823 -80.188169)
			(xy 43.910635 -80.147987) (xy 43.705138 -80.099899) (xy 43.501634 -80.043975) (xy 43.300421 -79.980298)
			(xy 43.101794 -79.90896) (xy 42.906046 -79.830066) (xy 42.713464 -79.743733) (xy 42.524329 -79.650086)
			(xy 42.33892 -79.549264) (xy 42.157509 -79.441414) (xy 41.980362 -79.326695) (xy 41.80774 -79.205275)
			(xy 41.639894 -79.077332) (xy 41.477072 -78.943054) (xy 41.319513 -78.802638) (xy 41.167448 -78.65629)
			(xy 41.0211 -78.504225) (xy 40.880684 -78.346666) (xy 40.746406 -78.183844) (xy 40.618463 -78.015998)
			(xy 40.497043 -77.843376) (xy 40.382324 -77.666229) (xy 40.274474 -77.484818) (xy 40.173652 -77.299409)
			(xy 40.080005 -77.110274) (xy 39.993672 -76.917692) (xy 39.914778 -76.721944) (xy 39.84344 -76.523317)
			(xy 39.779763 -76.322104) (xy 39.723839 -76.1186) (xy 39.675751 -75.913103) (xy 39.635569 -75.705915)
			(xy 39.603352 -75.49734) (xy 39.579149 -75.287683) (xy 39.562993 -75.077254) (xy 39.554909 -74.86636)
			(xy 39.554404 -74.760836) (xy 39.554404 -67.724782) (xy 39.553913 -67.714776) (xy 39.54625 -67.69629)
			(xy 39.532098 -67.682142) (xy 39.51361 -67.674484) (xy 39.503604 -67.673982) (xy 17.376648 -67.673982)
			(xy 17.366617 -67.674637) (xy 17.348191 -67.682623) (xy 17.340834 -67.689476) (xy 17.336516 -67.694302)
			(xy 17.317292 -67.719289) (xy 17.273644 -67.764782) (xy 17.224703 -67.804526) (xy 17.171222 -67.837911)
			(xy 17.114023 -67.864424) (xy 17.053983 -67.883659) (xy 16.992025 -67.895319) (xy 16.9291 -67.899226)
			(xy 16.866175 -67.895319) (xy 16.804217 -67.883659) (xy 16.744177 -67.864424) (xy 16.686978 -67.837911)
			(xy 16.633497 -67.804526) (xy 16.584556 -67.764782) (xy 16.540908 -67.719289) (xy 16.521684 -67.694302)
			(xy 16.517366 -67.689476) (xy 16.510074 -67.68253) (xy 16.491607 -67.674536) (xy 16.481552 -67.673982)
			(xy 9.341866 -67.673982) (xy 9.335856 -67.674147) (xy 9.324171 -67.676967) (xy 9.318752 -67.67957)
			(xy 9.315278 -67.68141) (xy 9.3089 -67.686005) (xy 9.306052 -67.688714) (xy 9.303004 -67.691762)
			(xy 9.284462 -67.699382) (xy 9.269984 -67.699382) (xy 7.696708 -69.272658) (xy 7.694001 -69.275508)
			(xy 7.689406 -69.281886) (xy 7.687564 -69.285358) (xy 7.68498 -69.290785) (xy 7.682156 -69.302464)
			(xy 7.681976 -69.308472) (xy 7.681976 -71.850142) (xy 10.273152 -71.850142) (xy 10.278361 -71.787276)
			(xy 10.291306 -71.725537) (xy 10.311789 -71.665873) (xy 10.339493 -71.609202) (xy 10.373995 -71.556392)
			(xy 10.414765 -71.508255) (xy 10.461175 -71.465531) (xy 10.512513 -71.428876) (xy 10.567992 -71.398852)
			(xy 10.626757 -71.375921) (xy 10.687908 -71.360435) (xy 10.750505 -71.352632) (xy 10.782046 -71.352156)
			(xy 10.795661 -71.352208) (xy 10.822853 -71.353609) (xy 10.836402 -71.35495) (xy 10.847578 -71.35622)
			(xy 10.869422 -71.348854) (xy 10.941558 -71.277734) (xy 10.949432 -71.256144) (xy 10.948416 -71.244968)
			(xy 10.946892 -71.210678) (xy 10.948416 -71.176388) (xy 10.949432 -71.165212) (xy 10.941558 -71.143622)
			(xy 10.869422 -71.072502) (xy 10.847578 -71.065136) (xy 10.836402 -71.066406) (xy 10.822853 -71.067738)
			(xy 10.79566 -71.069135) (xy 10.782046 -71.0692) (xy 10.750505 -71.068718) (xy 10.687908 -71.060915)
			(xy 10.626757 -71.045429) (xy 10.567991 -71.022498) (xy 10.512513 -70.992474) (xy 10.461174 -70.955818)
			(xy 10.414764 -70.913094) (xy 10.373995 -70.864957) (xy 10.339493 -70.812147) (xy 10.311788 -70.755475)
			(xy 10.291306 -70.695811) (xy 10.278361 -70.634072) (xy 10.273152 -70.571206) (xy 10.275759 -70.508179)
			(xy 10.286143 -70.445958) (xy 10.304143 -70.385499) (xy 10.329482 -70.32773) (xy 10.361773 -70.27354)
			(xy 10.400519 -70.22376) (xy 10.445125 -70.179155) (xy 10.494905 -70.14041) (xy 10.549096 -70.10812)
			(xy 10.606864 -70.08278) (xy 10.667323 -70.064781) (xy 10.729545 -70.054399) (xy 10.792572 -70.051792)
			(xy 10.855438 -70.057002) (xy 10.917177 -70.069947) (xy 10.976841 -70.09043) (xy 11.033512 -70.118136)
			(xy 11.086322 -70.152638) (xy 11.134458 -70.193408) (xy 11.177182 -70.239819) (xy 11.213837 -70.291158)
			(xy 11.24386 -70.346637) (xy 11.266791 -70.405403) (xy 11.282276 -70.466554) (xy 11.290078 -70.529151)
			(xy 11.290554 -70.560692) (xy 11.289915 -70.596285) (xy 11.279972 -70.666773) (xy 11.270742 -70.701154)
			(xy 11.268194 -70.712175) (xy 11.271898 -70.734462) (xy 11.277854 -70.74408) (xy 11.328908 -70.818248)
			(xy 11.348466 -70.829424) (xy 11.359896 -70.83044) (xy 11.386814 -70.833147) (xy 11.439557 -70.845183)
			(xy 11.49007 -70.864549) (xy 11.537342 -70.890857) (xy 11.580423 -70.923577) (xy 11.618451 -70.962056)
			(xy 11.650662 -71.00552) (xy 11.676411 -71.053098) (xy 11.695181 -71.103836) (xy 11.706595 -71.156717)
			(xy 11.710426 -71.21068) (xy 11.706595 -71.264643) (xy 11.695181 -71.317524) (xy 11.676411 -71.368262)
			(xy 11.650662 -71.41584) (xy 11.618451 -71.459304) (xy 11.580424 -71.497782) (xy 11.537342 -71.530503)
			(xy 11.49007 -71.55681) (xy 11.439557 -71.576177) (xy 11.386814 -71.588213) (xy 11.359896 -71.590916)
			(xy 11.348466 -71.591932) (xy 11.328908 -71.603108) (xy 11.277854 -71.677276) (xy 11.271887 -71.686886)
			(xy 11.268205 -71.709177) (xy 11.270742 -71.720202) (xy 11.28001 -71.754575) (xy 11.289957 -71.825068)
			(xy 11.290341 -71.847964) (xy 15.602202 -71.847964) (xy 15.606273 -71.792342) (xy 15.618399 -71.737905)
			(xy 15.638322 -71.685814) (xy 15.665618 -71.637179) (xy 15.699704 -71.593036) (xy 15.739853 -71.554327)
			(xy 15.785211 -71.521876) (xy 15.834811 -71.496375) (xy 15.887595 -71.478368) (xy 15.942438 -71.468238)
			(xy 15.998172 -71.466201) (xy 16.053609 -71.472301) (xy 16.107566 -71.486407) (xy 16.158895 -71.508219)
			(xy 16.206501 -71.537273) (xy 16.249369 -71.572948) (xy 16.286586 -71.614485) (xy 16.317359 -71.660998)
			(xy 16.341031 -71.711495) (xy 16.357099 -71.764902) (xy 16.365219 -71.820078) (xy 16.365728 -71.847964)
			(xy 16.365219 -71.87585) (xy 16.357099 -71.931026) (xy 16.341031 -71.984433) (xy 16.317359 -72.03493)
			(xy 16.286586 -72.081443) (xy 16.249369 -72.12298) (xy 16.206501 -72.158655) (xy 16.158895 -72.187709)
			(xy 16.107566 -72.209521) (xy 16.053609 -72.223627) (xy 15.998172 -72.229727) (xy 15.942438 -72.22769)
			(xy 15.887595 -72.21756) (xy 15.834811 -72.199553) (xy 15.785211 -72.174052) (xy 15.739853 -72.141601)
			(xy 15.699704 -72.102892) (xy 15.665618 -72.058749) (xy 15.638322 -72.010114) (xy 15.618399 -71.958023)
			(xy 15.606273 -71.903586) (xy 15.602202 -71.847964) (xy 11.290341 -71.847964) (xy 11.290554 -71.860664)
			(xy 11.290078 -71.892205) (xy 11.282275 -71.954802) (xy 11.266789 -72.015953) (xy 11.243858 -72.074718)
			(xy 11.213834 -72.130197) (xy 11.177179 -72.181535) (xy 11.134455 -72.227945) (xy 11.086318 -72.268715)
			(xy 11.033508 -72.303217) (xy 10.976837 -72.330921) (xy 10.917173 -72.351404) (xy 10.855434 -72.364349)
			(xy 10.792568 -72.369558) (xy 10.729541 -72.366951) (xy 10.66732 -72.356568) (xy 10.606861 -72.338568)
			(xy 10.549093 -72.313229) (xy 10.494902 -72.280938) (xy 10.445122 -72.242193) (xy 10.400517 -72.197588)
			(xy 10.361772 -72.147808) (xy 10.329481 -72.093617) (xy 10.304142 -72.035849) (xy 10.286142 -71.97539)
			(xy 10.275759 -71.913169) (xy 10.273152 -71.850142) (xy 7.681976 -71.850142) (xy 7.681976 -73.310961)
			(xy 9.778994 -73.310961) (xy 9.778994 -73.247039) (xy 9.787005 -73.183621) (xy 9.802902 -73.121707)
			(xy 9.826434 -73.062274) (xy 9.857228 -73.006259) (xy 9.894801 -72.954544) (xy 9.938558 -72.907947)
			(xy 9.987811 -72.867202) (xy 10.041782 -72.832951) (xy 10.099621 -72.805734) (xy 10.160414 -72.785981)
			(xy 10.223204 -72.774003) (xy 10.287 -72.76999) (xy 10.350796 -72.774003) (xy 10.413586 -72.785981)
			(xy 10.474379 -72.805734) (xy 10.532218 -72.832951) (xy 10.586189 -72.867202) (xy 10.635442 -72.907947)
			(xy 10.679199 -72.954544) (xy 10.716772 -73.006259) (xy 10.727075 -73.025) (xy 16.782032 -73.025)
			(xy 16.786103 -72.969378) (xy 16.798229 -72.914941) (xy 16.818152 -72.86285) (xy 16.845448 -72.814215)
			(xy 16.879534 -72.770072) (xy 16.919683 -72.731363) (xy 16.965041 -72.698912) (xy 17.014641 -72.673411)
			(xy 17.067425 -72.655404) (xy 17.122268 -72.645274) (xy 17.178002 -72.643237) (xy 17.233439 -72.649337)
			(xy 17.287396 -72.663443) (xy 17.338725 -72.685255) (xy 17.386331 -72.714309) (xy 17.429199 -72.749984)
			(xy 17.466416 -72.791521) (xy 17.497189 -72.838034) (xy 17.520861 -72.888531) (xy 17.536929 -72.941938)
			(xy 17.545049 -72.997114) (xy 17.545558 -73.025) (xy 17.545049 -73.052886) (xy 17.536929 -73.108062)
			(xy 17.520861 -73.161469) (xy 17.497189 -73.211966) (xy 17.466416 -73.258479) (xy 17.429199 -73.300016)
			(xy 17.386331 -73.335691) (xy 17.338725 -73.364745) (xy 17.287396 -73.386557) (xy 17.233439 -73.400663)
			(xy 17.178002 -73.406763) (xy 17.122268 -73.404726) (xy 17.067425 -73.394596) (xy 17.014641 -73.376589)
			(xy 16.965041 -73.351088) (xy 16.919683 -73.318637) (xy 16.879534 -73.279928) (xy 16.845448 -73.235785)
			(xy 16.818152 -73.18715) (xy 16.798229 -73.135059) (xy 16.786103 -73.080622) (xy 16.782032 -73.025)
			(xy 10.727075 -73.025) (xy 10.747566 -73.062274) (xy 10.771098 -73.121707) (xy 10.786995 -73.183621)
			(xy 10.795006 -73.247039) (xy 10.795508 -73.279) (xy 10.795006 -73.310961) (xy 10.786995 -73.374379)
			(xy 10.771098 -73.436293) (xy 10.747566 -73.495726) (xy 10.716772 -73.551741) (xy 10.679199 -73.603456)
			(xy 10.635442 -73.650053) (xy 10.586189 -73.690798) (xy 10.579886 -73.694798) (xy 11.78255 -73.694798)
			(xy 11.786621 -73.639176) (xy 11.798747 -73.584739) (xy 11.81867 -73.532648) (xy 11.845966 -73.484013)
			(xy 11.880052 -73.43987) (xy 11.920201 -73.401161) (xy 11.965559 -73.36871) (xy 12.015159 -73.343209)
			(xy 12.067943 -73.325202) (xy 12.122786 -73.315072) (xy 12.17852 -73.313035) (xy 12.233957 -73.319135)
			(xy 12.287914 -73.333241) (xy 12.339243 -73.355053) (xy 12.386849 -73.384107) (xy 12.429717 -73.419782)
			(xy 12.466934 -73.461319) (xy 12.497707 -73.507832) (xy 12.521379 -73.558329) (xy 12.537447 -73.611736)
			(xy 12.537896 -73.614788) (xy 19.221454 -73.614788) (xy 19.225483 -73.523782) (xy 19.23754 -73.433488)
			(xy 19.25753 -73.344613) (xy 19.285296 -73.257853) (xy 19.320622 -73.173886) (xy 19.36323 -73.09337)
			(xy 19.412788 -73.016934) (xy 19.468907 -72.945178) (xy 19.531148 -72.878662) (xy 19.599025 -72.817907)
			(xy 19.672005 -72.763389) (xy 19.749518 -72.715535) (xy 19.830957 -72.674718) (xy 19.915685 -72.641259)
			(xy 20.003039 -72.615418) (xy 20.092334 -72.5974) (xy 20.182872 -72.587343) (xy 20.273945 -72.585328)
			(xy 20.36484 -72.59137) (xy 20.454845 -72.605421) (xy 20.543256 -72.627372) (xy 20.629381 -72.657051)
			(xy 20.712546 -72.694225) (xy 20.7921 -72.738604) (xy 20.86742 -72.789841) (xy 20.937918 -72.847534)
			(xy 21.00304 -72.911231) (xy 21.062278 -72.980435) (xy 21.115168 -73.054604) (xy 21.161297 -73.133156)
			(xy 21.200302 -73.215479) (xy 21.231879 -73.300926) (xy 21.25578 -73.38883) (xy 21.271819 -73.478502)
			(xy 21.27987 -73.56924) (xy 21.280374 -73.614788) (xy 21.761454 -73.614788) (xy 21.765483 -73.523782)
			(xy 21.77754 -73.433488) (xy 21.79753 -73.344613) (xy 21.825296 -73.257853) (xy 21.860622 -73.173886)
			(xy 21.90323 -73.09337) (xy 21.952788 -73.016934) (xy 22.008907 -72.945178) (xy 22.071148 -72.878662)
			(xy 22.139025 -72.817907) (xy 22.212005 -72.763389) (xy 22.289518 -72.715535) (xy 22.370957 -72.674718)
			(xy 22.455685 -72.641259) (xy 22.543039 -72.615418) (xy 22.632334 -72.5974) (xy 22.722872 -72.587343)
			(xy 22.813945 -72.585328) (xy 22.90484 -72.59137) (xy 22.994845 -72.605421) (xy 23.083256 -72.627372)
			(xy 23.169381 -72.657051) (xy 23.252546 -72.694225) (xy 23.3321 -72.738604) (xy 23.40742 -72.789841)
			(xy 23.477918 -72.847534) (xy 23.54304 -72.911231) (xy 23.602278 -72.980435) (xy 23.655168 -73.054604)
			(xy 23.701297 -73.133156) (xy 23.740302 -73.215479) (xy 23.771879 -73.300926) (xy 23.79578 -73.38883)
			(xy 23.811819 -73.478502) (xy 23.81987 -73.56924) (xy 23.820374 -73.614788) (xy 24.301454 -73.614788)
			(xy 24.305483 -73.523782) (xy 24.31754 -73.433488) (xy 24.33753 -73.344613) (xy 24.365296 -73.257853)
			(xy 24.400622 -73.173886) (xy 24.44323 -73.09337) (xy 24.492788 -73.016934) (xy 24.548907 -72.945178)
			(xy 24.611148 -72.878662) (xy 24.679025 -72.817907) (xy 24.752005 -72.763389) (xy 24.829518 -72.715535)
			(xy 24.910957 -72.674718) (xy 24.995685 -72.641259) (xy 25.083039 -72.615418) (xy 25.172334 -72.5974)
			(xy 25.262872 -72.587343) (xy 25.353945 -72.585328) (xy 25.44484 -72.59137) (xy 25.534845 -72.605421)
			(xy 25.623256 -72.627372) (xy 25.709381 -72.657051) (xy 25.792546 -72.694225) (xy 25.8721 -72.738604)
			(xy 25.94742 -72.789841) (xy 26.017918 -72.847534) (xy 26.08304 -72.911231) (xy 26.142278 -72.980435)
			(xy 26.195168 -73.054604) (xy 26.241297 -73.133156) (xy 26.280302 -73.215479) (xy 26.311879 -73.300926)
			(xy 26.33578 -73.38883) (xy 26.351819 -73.478502) (xy 26.35987 -73.56924) (xy 26.360374 -73.614788)
			(xy 26.35987 -73.660336) (xy 26.351819 -73.751074) (xy 26.33578 -73.840746) (xy 26.311879 -73.92865)
			(xy 26.280302 -74.014097) (xy 26.241297 -74.09642) (xy 26.195168 -74.174972) (xy 26.142278 -74.249141)
			(xy 26.08304 -74.318345) (xy 26.017918 -74.382042) (xy 25.94742 -74.439735) (xy 25.8721 -74.490972)
			(xy 25.792546 -74.535351) (xy 25.709381 -74.572525) (xy 25.623256 -74.602204) (xy 25.534845 -74.624155)
			(xy 25.44484 -74.638206) (xy 25.353945 -74.644248) (xy 25.262872 -74.642233) (xy 25.172334 -74.632176)
			(xy 25.083039 -74.614158) (xy 24.995685 -74.588317) (xy 24.910957 -74.554858) (xy 24.829518 -74.514041)
			(xy 24.752005 -74.466187) (xy 24.679025 -74.411669) (xy 24.611148 -74.350914) (xy 24.548907 -74.284398)
			(xy 24.492788 -74.212642) (xy 24.44323 -74.136206) (xy 24.400622 -74.05569) (xy 24.365296 -73.971723)
			(xy 24.33753 -73.884963) (xy 24.31754 -73.796088) (xy 24.305483 -73.705794) (xy 24.301454 -73.614788)
			(xy 23.820374 -73.614788) (xy 23.81987 -73.660336) (xy 23.811819 -73.751074) (xy 23.79578 -73.840746)
			(xy 23.771879 -73.92865) (xy 23.740302 -74.014097) (xy 23.701297 -74.09642) (xy 23.655168 -74.174972)
			(xy 23.602278 -74.249141) (xy 23.54304 -74.318345) (xy 23.477918 -74.382042) (xy 23.40742 -74.439735)
			(xy 23.3321 -74.490972) (xy 23.252546 -74.535351) (xy 23.169381 -74.572525) (xy 23.083256 -74.602204)
			(xy 22.994845 -74.624155) (xy 22.90484 -74.638206) (xy 22.813945 -74.644248) (xy 22.722872 -74.642233)
			(xy 22.632334 -74.632176) (xy 22.543039 -74.614158) (xy 22.455685 -74.588317) (xy 22.370957 -74.554858)
			(xy 22.289518 -74.514041) (xy 22.212005 -74.466187) (xy 22.139025 -74.411669) (xy 22.071148 -74.350914)
			(xy 22.008907 -74.284398) (xy 21.952788 -74.212642) (xy 21.90323 -74.136206) (xy 21.860622 -74.05569)
			(xy 21.825296 -73.971723) (xy 21.79753 -73.884963) (xy 21.77754 -73.796088) (xy 21.765483 -73.705794)
			(xy 21.761454 -73.614788) (xy 21.280374 -73.614788) (xy 21.27987 -73.660336) (xy 21.271819 -73.751074)
			(xy 21.25578 -73.840746) (xy 21.231879 -73.92865) (xy 21.200302 -74.014097) (xy 21.161297 -74.09642)
			(xy 21.115168 -74.174972) (xy 21.062278 -74.249141) (xy 21.00304 -74.318345) (xy 20.937918 -74.382042)
			(xy 20.86742 -74.439735) (xy 20.7921 -74.490972) (xy 20.712546 -74.535351) (xy 20.629381 -74.572525)
			(xy 20.543256 -74.602204) (xy 20.454845 -74.624155) (xy 20.36484 -74.638206) (xy 20.273945 -74.644248)
			(xy 20.182872 -74.642233) (xy 20.092334 -74.632176) (xy 20.003039 -74.614158) (xy 19.915685 -74.588317)
			(xy 19.830957 -74.554858) (xy 19.749518 -74.514041) (xy 19.672005 -74.466187) (xy 19.599025 -74.411669)
			(xy 19.531148 -74.350914) (xy 19.468907 -74.284398) (xy 19.412788 -74.212642) (xy 19.36323 -74.136206)
			(xy 19.320622 -74.05569) (xy 19.285296 -73.971723) (xy 19.25753 -73.884963) (xy 19.23754 -73.796088)
			(xy 19.225483 -73.705794) (xy 19.221454 -73.614788) (xy 12.537896 -73.614788) (xy 12.545567 -73.666912)
			(xy 12.546076 -73.694798) (xy 12.545567 -73.722684) (xy 12.537447 -73.77786) (xy 12.521379 -73.831267)
			(xy 12.497707 -73.881764) (xy 12.466934 -73.928277) (xy 12.429717 -73.969814) (xy 12.386849 -74.005489)
			(xy 12.339243 -74.034543) (xy 12.287914 -74.056355) (xy 12.233957 -74.070461) (xy 12.17852 -74.076561)
			(xy 12.122786 -74.074524) (xy 12.067943 -74.064394) (xy 12.015159 -74.046387) (xy 11.965559 -74.020886)
			(xy 11.920201 -73.988435) (xy 11.880052 -73.949726) (xy 11.845966 -73.905583) (xy 11.81867 -73.856948)
			(xy 11.798747 -73.804857) (xy 11.786621 -73.75042) (xy 11.78255 -73.694798) (xy 10.579886 -73.694798)
			(xy 10.532218 -73.725049) (xy 10.474379 -73.752266) (xy 10.413586 -73.772019) (xy 10.350796 -73.783997)
			(xy 10.287 -73.788011) (xy 10.223204 -73.783997) (xy 10.160414 -73.772019) (xy 10.099621 -73.752266)
			(xy 10.041782 -73.725049) (xy 9.987811 -73.690798) (xy 9.938558 -73.650053) (xy 9.894801 -73.603456)
			(xy 9.857228 -73.551741) (xy 9.826434 -73.495726) (xy 9.802902 -73.436293) (xy 9.787005 -73.374379)
			(xy 9.778994 -73.310961) (xy 7.681976 -73.310961) (xy 7.681976 -74.426529) (xy 10.030962 -74.426529)
			(xy 10.030962 -74.362607) (xy 10.038973 -74.299189) (xy 10.05487 -74.237275) (xy 10.078402 -74.177842)
			(xy 10.109196 -74.121827) (xy 10.146769 -74.070112) (xy 10.190526 -74.023515) (xy 10.239779 -73.98277)
			(xy 10.29375 -73.948519) (xy 10.351589 -73.921302) (xy 10.412382 -73.901549) (xy 10.475172 -73.889571)
			(xy 10.538968 -73.885558) (xy 10.602764 -73.889571) (xy 10.665554 -73.901549) (xy 10.726347 -73.921302)
			(xy 10.784186 -73.948519) (xy 10.838157 -73.98277) (xy 10.88741 -74.023515) (xy 10.931167 -74.070112)
			(xy 10.96874 -74.121827) (xy 10.999534 -74.177842) (xy 11.023066 -74.237275) (xy 11.038963 -74.299189)
			(xy 11.046974 -74.362607) (xy 11.047476 -74.394568) (xy 11.046974 -74.426529) (xy 13.52651 -74.426529)
			(xy 13.52651 -74.362607) (xy 13.534521 -74.299189) (xy 13.550418 -74.237275) (xy 13.57395 -74.177842)
			(xy 13.604744 -74.121827) (xy 13.642317 -74.070112) (xy 13.686074 -74.023515) (xy 13.735327 -73.98277)
			(xy 13.789298 -73.948519) (xy 13.847137 -73.921302) (xy 13.90793 -73.901549) (xy 13.97072 -73.889571)
			(xy 14.034516 -73.885558) (xy 14.098312 -73.889571) (xy 14.161102 -73.901549) (xy 14.221895 -73.921302)
			(xy 14.279734 -73.948519) (xy 14.333705 -73.98277) (xy 14.382958 -74.023515) (xy 14.426715 -74.070112)
			(xy 14.464288 -74.121827) (xy 14.495082 -74.177842) (xy 14.518614 -74.237275) (xy 14.534511 -74.299189)
			(xy 14.542522 -74.362607) (xy 14.543024 -74.394568) (xy 14.542522 -74.426529) (xy 14.534511 -74.489947)
			(xy 14.518614 -74.551861) (xy 14.495082 -74.611294) (xy 14.464288 -74.667309) (xy 14.426715 -74.719024)
			(xy 14.382958 -74.765621) (xy 14.333705 -74.806366) (xy 14.279734 -74.840617) (xy 14.221895 -74.867834)
			(xy 14.161102 -74.887587) (xy 14.098312 -74.899565) (xy 14.034516 -74.903579) (xy 13.97072 -74.899565)
			(xy 13.90793 -74.887587) (xy 13.847137 -74.867834) (xy 13.789298 -74.840617) (xy 13.735327 -74.806366)
			(xy 13.686074 -74.765621) (xy 13.642317 -74.719024) (xy 13.604744 -74.667309) (xy 13.57395 -74.611294)
			(xy 13.550418 -74.551861) (xy 13.534521 -74.489947) (xy 13.52651 -74.426529) (xy 11.046974 -74.426529)
			(xy 11.038963 -74.489947) (xy 11.023066 -74.551861) (xy 10.999534 -74.611294) (xy 10.96874 -74.667309)
			(xy 10.931167 -74.719024) (xy 10.88741 -74.765621) (xy 10.838157 -74.806366) (xy 10.784186 -74.840617)
			(xy 10.726347 -74.867834) (xy 10.665554 -74.887587) (xy 10.602764 -74.899565) (xy 10.538968 -74.903579)
			(xy 10.475172 -74.899565) (xy 10.412382 -74.887587) (xy 10.351589 -74.867834) (xy 10.29375 -74.840617)
			(xy 10.239779 -74.806366) (xy 10.190526 -74.765621) (xy 10.146769 -74.719024) (xy 10.109196 -74.667309)
			(xy 10.078402 -74.611294) (xy 10.05487 -74.551861) (xy 10.038973 -74.489947) (xy 10.030962 -74.426529)
			(xy 7.681976 -74.426529) (xy 7.681976 -75.076769) (xy 11.656562 -75.076769) (xy 11.656562 -75.012847)
			(xy 11.664573 -74.949429) (xy 11.68047 -74.887515) (xy 11.704002 -74.828082) (xy 11.734796 -74.772067)
			(xy 11.772369 -74.720352) (xy 11.816126 -74.673755) (xy 11.865379 -74.63301) (xy 11.91935 -74.598759)
			(xy 11.977189 -74.571542) (xy 12.037982 -74.551789) (xy 12.100772 -74.539811) (xy 12.164568 -74.535798)
			(xy 12.228364 -74.539811) (xy 12.291154 -74.551789) (xy 12.351947 -74.571542) (xy 12.409786 -74.598759)
			(xy 12.463757 -74.63301) (xy 12.51301 -74.673755) (xy 12.556767 -74.720352) (xy 12.59434 -74.772067)
			(xy 12.625134 -74.828082) (xy 12.648666 -74.887515) (xy 12.664563 -74.949429) (xy 12.669451 -74.988123)
			(xy 15.384012 -74.988123) (xy 15.384012 -74.924201) (xy 15.392023 -74.860783) (xy 15.40792 -74.798869)
			(xy 15.431452 -74.739436) (xy 15.462246 -74.683421) (xy 15.499819 -74.631706) (xy 15.543576 -74.585109)
			(xy 15.592829 -74.544364) (xy 15.6468 -74.510113) (xy 15.704639 -74.482896) (xy 15.765432 -74.463143)
			(xy 15.828222 -74.451165) (xy 15.892018 -74.447152) (xy 15.955814 -74.451165) (xy 16.018604 -74.463143)
			(xy 16.079397 -74.482896) (xy 16.137236 -74.510113) (xy 16.191207 -74.544364) (xy 16.24046 -74.585109)
			(xy 16.284217 -74.631706) (xy 16.32179 -74.683421) (xy 16.352584 -74.739436) (xy 16.376116 -74.798869)
			(xy 16.392013 -74.860783) (xy 16.400024 -74.924201) (xy 16.400526 -74.956162) (xy 16.400024 -74.988123)
			(xy 16.392013 -75.051541) (xy 16.376116 -75.113455) (xy 16.352584 -75.172888) (xy 16.32179 -75.228903)
			(xy 16.284217 -75.280618) (xy 16.24046 -75.327215) (xy 16.191207 -75.36796) (xy 16.137236 -75.402211)
			(xy 16.079397 -75.429428) (xy 16.018604 -75.449181) (xy 15.955814 -75.461159) (xy 15.892018 -75.465173)
			(xy 15.828222 -75.461159) (xy 15.765432 -75.449181) (xy 15.704639 -75.429428) (xy 15.6468 -75.402211)
			(xy 15.592829 -75.36796) (xy 15.543576 -75.327215) (xy 15.499819 -75.280618) (xy 15.462246 -75.228903)
			(xy 15.431452 -75.172888) (xy 15.40792 -75.113455) (xy 15.392023 -75.051541) (xy 15.384012 -74.988123)
			(xy 12.669451 -74.988123) (xy 12.672574 -75.012847) (xy 12.673076 -75.044808) (xy 12.672574 -75.076769)
			(xy 12.664563 -75.140187) (xy 12.648666 -75.202101) (xy 12.625134 -75.261534) (xy 12.59434 -75.317549)
			(xy 12.556767 -75.369264) (xy 12.51301 -75.415861) (xy 12.463757 -75.456606) (xy 12.409786 -75.490857)
			(xy 12.351947 -75.518074) (xy 12.291154 -75.537827) (xy 12.228364 -75.549805) (xy 12.164568 -75.553819)
			(xy 12.100772 -75.549805) (xy 12.037982 -75.537827) (xy 11.977189 -75.518074) (xy 11.91935 -75.490857)
			(xy 11.865379 -75.456606) (xy 11.816126 -75.415861) (xy 11.772369 -75.369264) (xy 11.734796 -75.317549)
			(xy 11.704002 -75.261534) (xy 11.68047 -75.202101) (xy 11.664573 -75.140187) (xy 11.656562 -75.076769)
			(xy 7.681976 -75.076769) (xy 7.681976 -75.776539) (xy 10.030962 -75.776539) (xy 10.030962 -75.712617)
			(xy 10.038973 -75.649199) (xy 10.05487 -75.587285) (xy 10.078402 -75.527852) (xy 10.109196 -75.471837)
			(xy 10.146769 -75.420122) (xy 10.190526 -75.373525) (xy 10.239779 -75.33278) (xy 10.29375 -75.298529)
			(xy 10.351589 -75.271312) (xy 10.412382 -75.251559) (xy 10.475172 -75.239581) (xy 10.538968 -75.235568)
			(xy 10.602764 -75.239581) (xy 10.665554 -75.251559) (xy 10.726347 -75.271312) (xy 10.784186 -75.298529)
			(xy 10.838157 -75.33278) (xy 10.88741 -75.373525) (xy 10.931167 -75.420122) (xy 10.96874 -75.471837)
			(xy 10.999534 -75.527852) (xy 11.023066 -75.587285) (xy 11.038963 -75.649199) (xy 11.046974 -75.712617)
			(xy 11.047476 -75.744578) (xy 11.046974 -75.776539) (xy 11.038963 -75.839957) (xy 11.023066 -75.901871)
			(xy 10.999534 -75.961304) (xy 10.96874 -76.017319) (xy 10.931167 -76.069034) (xy 10.88741 -76.115631)
			(xy 10.838157 -76.156376) (xy 10.784186 -76.190627) (xy 10.726347 -76.217844) (xy 10.665554 -76.237597)
			(xy 10.602764 -76.249575) (xy 10.538968 -76.253589) (xy 10.475172 -76.249575) (xy 10.412382 -76.237597)
			(xy 10.351589 -76.217844) (xy 10.29375 -76.190627) (xy 10.239779 -76.156376) (xy 10.190526 -76.115631)
			(xy 10.146769 -76.069034) (xy 10.109196 -76.017319) (xy 10.078402 -75.961304) (xy 10.05487 -75.901871)
			(xy 10.038973 -75.839957) (xy 10.030962 -75.776539) (xy 7.681976 -75.776539) (xy 7.681976 -76.544678)
			(xy 8.682988 -76.544678) (xy 8.687059 -76.489056) (xy 8.699185 -76.434619) (xy 8.719108 -76.382528)
			(xy 8.746404 -76.333893) (xy 8.78049 -76.28975) (xy 8.820639 -76.251041) (xy 8.865997 -76.21859)
			(xy 8.915597 -76.193089) (xy 8.968381 -76.175082) (xy 9.023224 -76.164952) (xy 9.078958 -76.162915)
			(xy 9.134395 -76.169015) (xy 9.188352 -76.183121) (xy 9.239681 -76.204933) (xy 9.287287 -76.233987)
			(xy 9.330155 -76.269662) (xy 9.367372 -76.311199) (xy 9.398145 -76.357712) (xy 9.421817 -76.408209)
			(xy 9.437885 -76.461616) (xy 9.446005 -76.516792) (xy 9.446514 -76.544678) (xy 16.455388 -76.544678)
			(xy 16.459459 -76.489056) (xy 16.471585 -76.434619) (xy 16.491508 -76.382528) (xy 16.518804 -76.333893)
			(xy 16.55289 -76.28975) (xy 16.593039 -76.251041) (xy 16.638397 -76.21859) (xy 16.687997 -76.193089)
			(xy 16.740781 -76.175082) (xy 16.795624 -76.164952) (xy 16.851358 -76.162915) (xy 16.906795 -76.169015)
			(xy 16.960752 -76.183121) (xy 17.012081 -76.204933) (xy 17.059687 -76.233987) (xy 17.102555 -76.269662)
			(xy 17.139772 -76.311199) (xy 17.170545 -76.357712) (xy 17.174485 -76.366116) (xy 30.102046 -76.366116)
			(xy 30.106117 -76.310494) (xy 30.118243 -76.256057) (xy 30.138166 -76.203966) (xy 30.165462 -76.155331)
			(xy 30.199548 -76.111188) (xy 30.239697 -76.072479) (xy 30.285055 -76.040028) (xy 30.334655 -76.014527)
			(xy 30.387439 -75.99652) (xy 30.442282 -75.98639) (xy 30.498016 -75.984353) (xy 30.553453 -75.990453)
			(xy 30.60741 -76.004559) (xy 30.658739 -76.026371) (xy 30.706345 -76.055425) (xy 30.749213 -76.0911)
			(xy 30.78643 -76.132637) (xy 30.817203 -76.17915) (xy 30.840875 -76.229647) (xy 30.856943 -76.283054)
			(xy 30.865063 -76.33823) (xy 30.865572 -76.366116) (xy 30.865063 -76.394002) (xy 30.856943 -76.449178)
			(xy 30.840875 -76.502585) (xy 30.817203 -76.553082) (xy 30.78643 -76.599595) (xy 30.749213 -76.641132)
			(xy 30.706345 -76.676807) (xy 30.658739 -76.705861) (xy 30.60741 -76.727673) (xy 30.553453 -76.741779)
			(xy 30.498016 -76.747879) (xy 30.442282 -76.745842) (xy 30.387439 -76.735712) (xy 30.334655 -76.717705)
			(xy 30.285055 -76.692204) (xy 30.239697 -76.659753) (xy 30.199548 -76.621044) (xy 30.165462 -76.576901)
			(xy 30.138166 -76.528266) (xy 30.118243 -76.476175) (xy 30.106117 -76.421738) (xy 30.102046 -76.366116)
			(xy 17.174485 -76.366116) (xy 17.194217 -76.408209) (xy 17.210285 -76.461616) (xy 17.218405 -76.516792)
			(xy 17.218914 -76.544678) (xy 17.218405 -76.572564) (xy 17.210285 -76.62774) (xy 17.194217 -76.681147)
			(xy 17.170545 -76.731644) (xy 17.139772 -76.778157) (xy 17.102555 -76.819694) (xy 17.059687 -76.855369)
			(xy 17.012081 -76.884423) (xy 16.960752 -76.906235) (xy 16.906795 -76.920341) (xy 16.851358 -76.926441)
			(xy 16.795624 -76.924404) (xy 16.740781 -76.914274) (xy 16.687997 -76.896267) (xy 16.638397 -76.870766)
			(xy 16.593039 -76.838315) (xy 16.55289 -76.799606) (xy 16.518804 -76.755463) (xy 16.491508 -76.706828)
			(xy 16.471585 -76.654737) (xy 16.459459 -76.6003) (xy 16.455388 -76.544678) (xy 9.446514 -76.544678)
			(xy 9.446005 -76.572564) (xy 9.437885 -76.62774) (xy 9.421817 -76.681147) (xy 9.398145 -76.731644)
			(xy 9.367372 -76.778157) (xy 9.330155 -76.819694) (xy 9.287287 -76.855369) (xy 9.239681 -76.884423)
			(xy 9.188352 -76.906235) (xy 9.134395 -76.920341) (xy 9.078958 -76.926441) (xy 9.023224 -76.924404)
			(xy 8.968381 -76.914274) (xy 8.915597 -76.896267) (xy 8.865997 -76.870766) (xy 8.820639 -76.838315)
			(xy 8.78049 -76.799606) (xy 8.746404 -76.755463) (xy 8.719108 -76.706828) (xy 8.699185 -76.654737)
			(xy 8.687059 -76.6003) (xy 8.682988 -76.544678) (xy 7.681976 -76.544678) (xy 7.681976 -77.089) (xy 13.999462 -77.089)
			(xy 14.003533 -77.033378) (xy 14.015659 -76.978941) (xy 14.035582 -76.92685) (xy 14.062878 -76.878215)
			(xy 14.096964 -76.834072) (xy 14.137113 -76.795363) (xy 14.182471 -76.762912) (xy 14.232071 -76.737411)
			(xy 14.284855 -76.719404) (xy 14.339698 -76.709274) (xy 14.395432 -76.707237) (xy 14.450869 -76.713337)
			(xy 14.504826 -76.727443) (xy 14.556155 -76.749255) (xy 14.603761 -76.778309) (xy 14.646629 -76.813984)
			(xy 14.683846 -76.855521) (xy 14.714619 -76.902034) (xy 14.738291 -76.952531) (xy 14.754359 -77.005938)
			(xy 14.762479 -77.061114) (xy 14.762988 -77.089) (xy 14.762479 -77.116886) (xy 14.754359 -77.172062)
			(xy 14.738291 -77.225469) (xy 14.714619 -77.275966) (xy 14.683846 -77.322479) (xy 14.646629 -77.364016)
			(xy 14.603761 -77.399691) (xy 14.556155 -77.428745) (xy 14.504826 -77.450557) (xy 14.450869 -77.464663)
			(xy 14.395432 -77.470763) (xy 14.339698 -77.468726) (xy 14.284855 -77.458596) (xy 14.232071 -77.440589)
			(xy 14.182471 -77.415088) (xy 14.137113 -77.382637) (xy 14.096964 -77.343928) (xy 14.062878 -77.299785)
			(xy 14.035582 -77.25115) (xy 14.015659 -77.199059) (xy 14.003533 -77.144622) (xy 13.999462 -77.089)
			(xy 7.681976 -77.089) (xy 7.681976 -78.212653) (xy 10.27404 -78.212653) (xy 10.27404 -78.148731)
			(xy 10.282051 -78.085313) (xy 10.297948 -78.023399) (xy 10.32148 -77.963966) (xy 10.352274 -77.907951)
			(xy 10.389847 -77.856236) (xy 10.433604 -77.809639) (xy 10.482857 -77.768894) (xy 10.536828 -77.734643)
			(xy 10.594667 -77.707426) (xy 10.65546 -77.687673) (xy 10.71825 -77.675695) (xy 10.782046 -77.671682)
			(xy 10.845842 -77.675695) (xy 10.908632 -77.687673) (xy 10.969425 -77.707426) (xy 11.027264 -77.734643)
			(xy 11.081235 -77.768894) (xy 11.130488 -77.809639) (xy 11.174245 -77.856236) (xy 11.211818 -77.907951)
			(xy 11.242612 -77.963966) (xy 11.266144 -78.023399) (xy 11.282041 -78.085313) (xy 11.290052 -78.148731)
			(xy 11.290554 -78.180692) (xy 11.290052 -78.212653) (xy 11.282041 -78.276071) (xy 11.266144 -78.337985)
			(xy 11.242612 -78.397418) (xy 11.211818 -78.453433) (xy 11.174245 -78.505148) (xy 11.130488 -78.551745)
			(xy 11.081235 -78.59249) (xy 11.027264 -78.626741) (xy 10.969425 -78.653958) (xy 10.908632 -78.673711)
			(xy 10.845842 -78.685689) (xy 10.782046 -78.689703) (xy 10.71825 -78.685689) (xy 10.65546 -78.673711)
			(xy 10.594667 -78.653958) (xy 10.536828 -78.626741) (xy 10.482857 -78.59249) (xy 10.433604 -78.551745)
			(xy 10.389847 -78.505148) (xy 10.352274 -78.453433) (xy 10.32148 -78.397418) (xy 10.297948 -78.337985)
			(xy 10.282051 -78.276071) (xy 10.27404 -78.212653) (xy 7.681976 -78.212653) (xy 7.681976 -79.512625)
			(xy 10.27404 -79.512625) (xy 10.27404 -79.448703) (xy 10.282051 -79.385285) (xy 10.297948 -79.323371)
			(xy 10.32148 -79.263938) (xy 10.352274 -79.207923) (xy 10.389847 -79.156208) (xy 10.433604 -79.109611)
			(xy 10.482857 -79.068866) (xy 10.536828 -79.034615) (xy 10.594667 -79.007398) (xy 10.65546 -78.987645)
			(xy 10.71825 -78.975667) (xy 10.782046 -78.971654) (xy 10.845842 -78.975667) (xy 10.908632 -78.987645)
			(xy 10.969425 -79.007398) (xy 10.994931 -79.0194) (xy 12.444982 -79.0194) (xy 12.449053 -78.963778)
			(xy 12.461179 -78.909341) (xy 12.481102 -78.85725) (xy 12.508398 -78.808615) (xy 12.542484 -78.764472)
			(xy 12.582633 -78.725763) (xy 12.627991 -78.693312) (xy 12.677591 -78.667811) (xy 12.730375 -78.649804)
			(xy 12.785218 -78.639674) (xy 12.840952 -78.637637) (xy 12.896389 -78.643737) (xy 12.950346 -78.657843)
			(xy 13.001675 -78.679655) (xy 13.049281 -78.708709) (xy 13.092149 -78.744384) (xy 13.129366 -78.785921)
			(xy 13.142005 -78.805024) (xy 19.221454 -78.805024) (xy 19.225483 -78.714018) (xy 19.23754 -78.623724)
			(xy 19.25753 -78.534849) (xy 19.285296 -78.448089) (xy 19.320622 -78.364122) (xy 19.36323 -78.283606)
			(xy 19.412788 -78.20717) (xy 19.468907 -78.135414) (xy 19.531148 -78.068898) (xy 19.599025 -78.008143)
			(xy 19.672005 -77.953625) (xy 19.749518 -77.905771) (xy 19.830957 -77.864954) (xy 19.915685 -77.831495)
			(xy 20.003039 -77.805654) (xy 20.092334 -77.787636) (xy 20.182872 -77.777579) (xy 20.273945 -77.775564)
			(xy 20.36484 -77.781606) (xy 20.454845 -77.795657) (xy 20.543256 -77.817608) (xy 20.629381 -77.847287)
			(xy 20.712546 -77.884461) (xy 20.7921 -77.92884) (xy 20.86742 -77.980077) (xy 20.937918 -78.03777)
			(xy 21.00304 -78.101467) (xy 21.062278 -78.170671) (xy 21.115168 -78.24484) (xy 21.161297 -78.323392)
			(xy 21.200302 -78.405715) (xy 21.231879 -78.491162) (xy 21.25578 -78.579066) (xy 21.271819 -78.668738)
			(xy 21.27987 -78.759476) (xy 21.280374 -78.805024) (xy 21.761454 -78.805024) (xy 21.765483 -78.714018)
			(xy 21.77754 -78.623724) (xy 21.79753 -78.534849) (xy 21.825296 -78.448089) (xy 21.860622 -78.364122)
			(xy 21.90323 -78.283606) (xy 21.952788 -78.20717) (xy 22.008907 -78.135414) (xy 22.071148 -78.068898)
			(xy 22.139025 -78.008143) (xy 22.212005 -77.953625) (xy 22.289518 -77.905771) (xy 22.370957 -77.864954)
			(xy 22.455685 -77.831495) (xy 22.543039 -77.805654) (xy 22.632334 -77.787636) (xy 22.722872 -77.777579)
			(xy 22.813945 -77.775564) (xy 22.90484 -77.781606) (xy 22.994845 -77.795657) (xy 23.083256 -77.817608)
			(xy 23.169381 -77.847287) (xy 23.252546 -77.884461) (xy 23.3321 -77.92884) (xy 23.40742 -77.980077)
			(xy 23.477918 -78.03777) (xy 23.54304 -78.101467) (xy 23.602278 -78.170671) (xy 23.655168 -78.24484)
			(xy 23.701297 -78.323392) (xy 23.740302 -78.405715) (xy 23.771879 -78.491162) (xy 23.79578 -78.579066)
			(xy 23.811819 -78.668738) (xy 23.81987 -78.759476) (xy 23.820374 -78.805024) (xy 24.301454 -78.805024)
			(xy 24.305483 -78.714018) (xy 24.31754 -78.623724) (xy 24.33753 -78.534849) (xy 24.365296 -78.448089)
			(xy 24.400622 -78.364122) (xy 24.44323 -78.283606) (xy 24.492788 -78.20717) (xy 24.548907 -78.135414)
			(xy 24.611148 -78.068898) (xy 24.679025 -78.008143) (xy 24.752005 -77.953625) (xy 24.829518 -77.905771)
			(xy 24.910957 -77.864954) (xy 24.995685 -77.831495) (xy 25.083039 -77.805654) (xy 25.172334 -77.787636)
			(xy 25.262872 -77.777579) (xy 25.353945 -77.775564) (xy 25.44484 -77.781606) (xy 25.534845 -77.795657)
			(xy 25.623256 -77.817608) (xy 25.709381 -77.847287) (xy 25.792546 -77.884461) (xy 25.8721 -77.92884)
			(xy 25.94742 -77.980077) (xy 26.017918 -78.03777) (xy 26.08304 -78.101467) (xy 26.142278 -78.170671)
			(xy 26.195168 -78.24484) (xy 26.241297 -78.323392) (xy 26.280302 -78.405715) (xy 26.311879 -78.491162)
			(xy 26.33578 -78.579066) (xy 26.351819 -78.668738) (xy 26.35987 -78.759476) (xy 26.360374 -78.805024)
			(xy 26.35987 -78.850572) (xy 26.351819 -78.94131) (xy 26.33578 -79.030982) (xy 26.311879 -79.118886)
			(xy 26.280302 -79.204333) (xy 26.241297 -79.286656) (xy 26.195168 -79.365208) (xy 26.142278 -79.439377)
			(xy 26.08304 -79.508581) (xy 26.017918 -79.572278) (xy 25.94742 -79.629971) (xy 25.8721 -79.681208)
			(xy 25.792546 -79.725587) (xy 25.709381 -79.762761) (xy 25.623256 -79.79244) (xy 25.534845 -79.814391)
			(xy 25.44484 -79.828442) (xy 25.353945 -79.834484) (xy 25.262872 -79.832469) (xy 25.172334 -79.822412)
			(xy 25.083039 -79.804394) (xy 24.995685 -79.778553) (xy 24.910957 -79.745094) (xy 24.829518 -79.704277)
			(xy 24.752005 -79.656423) (xy 24.679025 -79.601905) (xy 24.611148 -79.54115) (xy 24.548907 -79.474634)
			(xy 24.492788 -79.402878) (xy 24.44323 -79.326442) (xy 24.400622 -79.245926) (xy 24.365296 -79.161959)
			(xy 24.33753 -79.075199) (xy 24.31754 -78.986324) (xy 24.305483 -78.89603) (xy 24.301454 -78.805024)
			(xy 23.820374 -78.805024) (xy 23.81987 -78.850572) (xy 23.811819 -78.94131) (xy 23.79578 -79.030982)
			(xy 23.771879 -79.118886) (xy 23.740302 -79.204333) (xy 23.701297 -79.286656) (xy 23.655168 -79.365208)
			(xy 23.602278 -79.439377) (xy 23.54304 -79.508581) (xy 23.477918 -79.572278) (xy 23.40742 -79.629971)
			(xy 23.3321 -79.681208) (xy 23.252546 -79.725587) (xy 23.169381 -79.762761) (xy 23.083256 -79.79244)
			(xy 22.994845 -79.814391) (xy 22.90484 -79.828442) (xy 22.813945 -79.834484) (xy 22.722872 -79.832469)
			(xy 22.632334 -79.822412) (xy 22.543039 -79.804394) (xy 22.455685 -79.778553) (xy 22.370957 -79.745094)
			(xy 22.289518 -79.704277) (xy 22.212005 -79.656423) (xy 22.139025 -79.601905) (xy 22.071148 -79.54115)
			(xy 22.008907 -79.474634) (xy 21.952788 -79.402878) (xy 21.90323 -79.326442) (xy 21.860622 -79.245926)
			(xy 21.825296 -79.161959) (xy 21.79753 -79.075199) (xy 21.77754 -78.986324) (xy 21.765483 -78.89603)
			(xy 21.761454 -78.805024) (xy 21.280374 -78.805024) (xy 21.27987 -78.850572) (xy 21.271819 -78.94131)
			(xy 21.25578 -79.030982) (xy 21.231879 -79.118886) (xy 21.200302 -79.204333) (xy 21.161297 -79.286656)
			(xy 21.115168 -79.365208) (xy 21.062278 -79.439377) (xy 21.00304 -79.508581) (xy 20.937918 -79.572278)
			(xy 20.86742 -79.629971) (xy 20.7921 -79.681208) (xy 20.712546 -79.725587) (xy 20.629381 -79.762761)
			(xy 20.543256 -79.79244) (xy 20.454845 -79.814391) (xy 20.36484 -79.828442) (xy 20.273945 -79.834484)
			(xy 20.182872 -79.832469) (xy 20.092334 -79.822412) (xy 20.003039 -79.804394) (xy 19.915685 -79.778553)
			(xy 19.830957 -79.745094) (xy 19.749518 -79.704277) (xy 19.672005 -79.656423) (xy 19.599025 -79.601905)
			(xy 19.531148 -79.54115) (xy 19.468907 -79.474634) (xy 19.412788 -79.402878) (xy 19.36323 -79.326442)
			(xy 19.320622 -79.245926) (xy 19.285296 -79.161959) (xy 19.25753 -79.075199) (xy 19.23754 -78.986324)
			(xy 19.225483 -78.89603) (xy 19.221454 -78.805024) (xy 13.142005 -78.805024) (xy 13.160139 -78.832434)
			(xy 13.183811 -78.882931) (xy 13.199879 -78.936338) (xy 13.207999 -78.991514) (xy 13.208508 -79.0194)
			(xy 13.207999 -79.047286) (xy 13.199879 -79.102462) (xy 13.183811 -79.155869) (xy 13.160139 -79.206366)
			(xy 13.129366 -79.252879) (xy 13.092149 -79.294416) (xy 13.049281 -79.330091) (xy 13.001675 -79.359145)
			(xy 12.950346 -79.380957) (xy 12.896389 -79.395063) (xy 12.840952 -79.401163) (xy 12.785218 -79.399126)
			(xy 12.730375 -79.388996) (xy 12.677591 -79.370989) (xy 12.627991 -79.345488) (xy 12.582633 -79.313037)
			(xy 12.542484 -79.274328) (xy 12.508398 -79.230185) (xy 12.481102 -79.18155) (xy 12.461179 -79.129459)
			(xy 12.449053 -79.075022) (xy 12.444982 -79.0194) (xy 10.994931 -79.0194) (xy 11.027264 -79.034615)
			(xy 11.081235 -79.068866) (xy 11.130488 -79.109611) (xy 11.174245 -79.156208) (xy 11.211818 -79.207923)
			(xy 11.242612 -79.263938) (xy 11.266144 -79.323371) (xy 11.282041 -79.385285) (xy 11.290052 -79.448703)
			(xy 11.290355 -79.467964) (xy 15.602202 -79.467964) (xy 15.606273 -79.412342) (xy 15.618399 -79.357905)
			(xy 15.638322 -79.305814) (xy 15.665618 -79.257179) (xy 15.699704 -79.213036) (xy 15.739853 -79.174327)
			(xy 15.785211 -79.141876) (xy 15.834811 -79.116375) (xy 15.887595 -79.098368) (xy 15.942438 -79.088238)
			(xy 15.998172 -79.086201) (xy 16.053609 -79.092301) (xy 16.107566 -79.106407) (xy 16.158895 -79.128219)
			(xy 16.206501 -79.157273) (xy 16.249369 -79.192948) (xy 16.286586 -79.234485) (xy 16.317359 -79.280998)
			(xy 16.341031 -79.331495) (xy 16.357099 -79.384902) (xy 16.365219 -79.440078) (xy 16.365728 -79.467964)
			(xy 16.365219 -79.49585) (xy 16.357099 -79.551026) (xy 16.341031 -79.604433) (xy 16.317359 -79.65493)
			(xy 16.286586 -79.701443) (xy 16.249369 -79.74298) (xy 16.206501 -79.778655) (xy 16.158895 -79.807709)
			(xy 16.107566 -79.829521) (xy 16.053609 -79.843627) (xy 15.998172 -79.849727) (xy 15.942438 -79.84769)
			(xy 15.887595 -79.83756) (xy 15.834811 -79.819553) (xy 15.785211 -79.794052) (xy 15.739853 -79.761601)
			(xy 15.699704 -79.722892) (xy 15.665618 -79.678749) (xy 15.638322 -79.630114) (xy 15.618399 -79.578023)
			(xy 15.606273 -79.523586) (xy 15.602202 -79.467964) (xy 11.290355 -79.467964) (xy 11.290554 -79.480664)
			(xy 11.290052 -79.512625) (xy 11.282041 -79.576043) (xy 11.266144 -79.637957) (xy 11.242612 -79.69739)
			(xy 11.211818 -79.753405) (xy 11.174245 -79.80512) (xy 11.130488 -79.851717) (xy 11.081235 -79.892462)
			(xy 11.027264 -79.926713) (xy 10.969425 -79.95393) (xy 10.908632 -79.973683) (xy 10.845842 -79.985661)
			(xy 10.782046 -79.989675) (xy 10.71825 -79.985661) (xy 10.65546 -79.973683) (xy 10.594667 -79.95393)
			(xy 10.536828 -79.926713) (xy 10.482857 -79.892462) (xy 10.433604 -79.851717) (xy 10.389847 -79.80512)
			(xy 10.352274 -79.753405) (xy 10.32148 -79.69739) (xy 10.297948 -79.637957) (xy 10.282051 -79.576043)
			(xy 10.27404 -79.512625) (xy 7.681976 -79.512625) (xy 7.681976 -81.440274) (xy 30.102046 -81.440274)
			(xy 30.106117 -81.384652) (xy 30.118243 -81.330215) (xy 30.138166 -81.278124) (xy 30.165462 -81.229489)
			(xy 30.199548 -81.185346) (xy 30.239697 -81.146637) (xy 30.285055 -81.114186) (xy 30.334655 -81.088685)
			(xy 30.387439 -81.070678) (xy 30.442282 -81.060548) (xy 30.498016 -81.058511) (xy 30.553453 -81.064611)
			(xy 30.60741 -81.078717) (xy 30.658739 -81.100529) (xy 30.706345 -81.129583) (xy 30.749213 -81.165258)
			(xy 30.78643 -81.206795) (xy 30.817203 -81.253308) (xy 30.840875 -81.303805) (xy 30.856943 -81.357212)
			(xy 30.865063 -81.412388) (xy 30.865572 -81.440274) (xy 30.865063 -81.46816) (xy 30.860052 -81.502207)
			(xy 107.936532 -81.502207) (xy 107.936532 -81.438285) (xy 107.944543 -81.374867) (xy 107.96044 -81.312953)
			(xy 107.983972 -81.25352) (xy 108.014766 -81.197505) (xy 108.052339 -81.14579) (xy 108.096096 -81.099193)
			(xy 108.145349 -81.058448) (xy 108.19932 -81.024197) (xy 108.257159 -80.99698) (xy 108.317952 -80.977227)
			(xy 108.380742 -80.965249) (xy 108.444538 -80.961236) (xy 108.508334 -80.965249) (xy 108.571124 -80.977227)
			(xy 108.631917 -80.99698) (xy 108.689756 -81.024197) (xy 108.743727 -81.058448) (xy 108.79298 -81.099193)
			(xy 108.836737 -81.14579) (xy 108.87431 -81.197505) (xy 108.898437 -81.241392) (xy 113.57864 -81.241392)
			(xy 113.57864 -70.637654) (xy 113.578776 -70.632763) (xy 113.580695 -70.623171) (xy 113.58245 -70.618604)
			(xy 113.621312 -70.522846) (xy 113.623414 -70.518026) (xy 113.629299 -70.509314) (xy 113.632996 -70.505574)
			(xy 113.669572 -70.470268) (xy 113.67008 -70.46976) (xy 113.778538 -70.361048) (xy 113.778792 -70.361048)
			(xy 114.466624 -69.673216) (xy 114.48013 -69.660096) (xy 114.509806 -69.636917) (xy 114.525806 -69.626988)
			(xy 114.532631 -69.622563) (xy 114.543251 -69.610255) (xy 114.546634 -69.602858) (xy 114.558064 -69.57568)
			(xy 114.56092 -69.567937) (xy 114.562099 -69.551487) (xy 114.56035 -69.543422) (xy 114.554779 -69.520133)
			(xy 114.548789 -69.472623) (xy 114.548412 -69.44868) (xy 114.548898 -69.421429) (xy 114.556654 -69.367481)
			(xy 114.572009 -69.315186) (xy 114.594651 -69.265609) (xy 114.624117 -69.219759) (xy 114.659808 -69.178568)
			(xy 114.700999 -69.142877) (xy 114.746849 -69.113411) (xy 114.796426 -69.090769) (xy 114.848721 -69.075414)
			(xy 114.902669 -69.067658) (xy 114.957171 -69.067658) (xy 115.011119 -69.075414) (xy 115.063414 -69.090769)
			(xy 115.112991 -69.113411) (xy 115.158841 -69.142877) (xy 115.200032 -69.178568) (xy 115.235723 -69.219759)
			(xy 115.265189 -69.265609) (xy 115.287831 -69.315186) (xy 115.303186 -69.367481) (xy 115.310942 -69.421429)
			(xy 115.311428 -69.44868) (xy 115.310412 -69.475096) (xy 115.310196 -69.485597) (xy 115.317134 -69.505396)
			(xy 115.323874 -69.51345) (xy 115.374674 -69.567552) (xy 115.382168 -69.574853) (xy 115.401311 -69.583245)
			(xy 115.411758 -69.583808) (xy 132.627624 -69.583808) (xy 132.632514 -69.583953) (xy 132.642107 -69.585866)
			(xy 132.646674 -69.587618) (xy 132.742432 -69.626226) (xy 132.747255 -69.628408) (xy 132.755967 -69.634416)
			(xy 132.759704 -69.638164) (xy 132.785875 -69.665088) (xy 135.81685 -69.665088) (xy 135.820896 -69.57111)
			(xy 135.833007 -69.477828) (xy 135.853092 -69.385932) (xy 135.881002 -69.296103) (xy 135.916531 -69.209006)
			(xy 135.959416 -69.125285) (xy 136.009339 -69.045561) (xy 136.065931 -68.970424) (xy 136.128773 -68.90043)
			(xy 136.197399 -68.836097) (xy 136.271301 -68.777902) (xy 136.349932 -68.726275) (xy 136.432711 -68.681598)
			(xy 136.519023 -68.644204) (xy 136.608231 -68.614367) (xy 136.699673 -68.59231) (xy 136.792673 -68.578195)
			(xy 136.886542 -68.572127) (xy 136.980586 -68.57415) (xy 137.074107 -68.584251) (xy 137.166413 -68.602354)
			(xy 137.256822 -68.628325) (xy 137.344664 -68.661972) (xy 137.429287 -68.703046) (xy 137.510067 -68.751242)
			(xy 137.586405 -68.806204) (xy 137.657735 -68.867525) (xy 137.723529 -68.934751) (xy 137.783301 -69.007384)
			(xy 137.836608 -69.084886) (xy 137.883055 -69.166684) (xy 137.922298 -69.252172) (xy 137.954048 -69.340717)
			(xy 137.978067 -69.431664) (xy 137.99418 -69.524339) (xy 138.002266 -69.618055) (xy 138.002772 -69.665088)
			(xy 138.483855 -69.665088) (xy 138.487858 -69.577226) (xy 138.499834 -69.490092) (xy 138.519685 -69.404408)
			(xy 138.547244 -69.320884) (xy 138.582285 -69.240212) (xy 138.624516 -69.163061) (xy 138.673588 -69.09007)
			(xy 138.729095 -69.021844) (xy 138.790575 -68.958948) (xy 138.85752 -68.901903) (xy 138.929375 -68.851182)
			(xy 139.005545 -68.807205) (xy 139.085398 -68.770337) (xy 139.168273 -68.740884) (xy 139.253483 -68.719088)
			(xy 139.340322 -68.705132) (xy 139.42807 -68.699129) (xy 139.516 -68.701131) (xy 139.603385 -68.711121)
			(xy 139.689498 -68.729016) (xy 139.773628 -68.754667) (xy 139.855076 -68.787862) (xy 139.933169 -68.828326)
			(xy 140.007258 -68.875724) (xy 140.07673 -68.929663) (xy 140.141009 -68.989696) (xy 140.199563 -69.055325)
			(xy 140.251907 -69.126007) (xy 140.297606 -69.201156) (xy 140.336282 -69.280149) (xy 140.367614 -69.362332)
			(xy 140.391344 -69.447024) (xy 140.407274 -69.533523) (xy 140.415272 -69.621111) (xy 140.415772 -69.665088)
			(xy 140.89685 -69.665088) (xy 140.900896 -69.57111) (xy 140.913007 -69.477828) (xy 140.933092 -69.385932)
			(xy 140.961002 -69.296103) (xy 140.996531 -69.209006) (xy 141.039416 -69.125285) (xy 141.089339 -69.045561)
			(xy 141.145931 -68.970424) (xy 141.208773 -68.90043) (xy 141.277399 -68.836097) (xy 141.351301 -68.777902)
			(xy 141.429932 -68.726275) (xy 141.512711 -68.681598) (xy 141.599023 -68.644204) (xy 141.688231 -68.614367)
			(xy 141.779673 -68.59231) (xy 141.872673 -68.578195) (xy 141.966542 -68.572127) (xy 142.060586 -68.57415)
			(xy 142.154107 -68.584251) (xy 142.246413 -68.602354) (xy 142.336822 -68.628325) (xy 142.424664 -68.661972)
			(xy 142.509287 -68.703046) (xy 142.590067 -68.751242) (xy 142.666405 -68.806204) (xy 142.737735 -68.867525)
			(xy 142.803529 -68.934751) (xy 142.863301 -69.007384) (xy 142.916608 -69.084886) (xy 142.963055 -69.166684)
			(xy 143.002298 -69.252172) (xy 143.034048 -69.340717) (xy 143.058067 -69.431664) (xy 143.07418 -69.524339)
			(xy 143.082266 -69.618055) (xy 143.082772 -69.665088) (xy 143.43685 -69.665088) (xy 143.440896 -69.57111)
			(xy 143.453007 -69.477828) (xy 143.473092 -69.385932) (xy 143.501002 -69.296103) (xy 143.536531 -69.209006)
			(xy 143.579416 -69.125285) (xy 143.629339 -69.045561) (xy 143.685931 -68.970424) (xy 143.748773 -68.90043)
			(xy 143.817399 -68.836097) (xy 143.891301 -68.777902) (xy 143.969932 -68.726275) (xy 144.052711 -68.681598)
			(xy 144.139023 -68.644204) (xy 144.228231 -68.614367) (xy 144.319673 -68.59231) (xy 144.412673 -68.578195)
			(xy 144.506542 -68.572127) (xy 144.600586 -68.57415) (xy 144.694107 -68.584251) (xy 144.786413 -68.602354)
			(xy 144.876822 -68.628325) (xy 144.964664 -68.661972) (xy 145.049287 -68.703046) (xy 145.130067 -68.751242)
			(xy 145.206405 -68.806204) (xy 145.277735 -68.867525) (xy 145.343529 -68.934751) (xy 145.403301 -69.007384)
			(xy 145.456608 -69.084886) (xy 145.503055 -69.166684) (xy 145.542298 -69.252172) (xy 145.574048 -69.340717)
			(xy 145.598067 -69.431664) (xy 145.61418 -69.524339) (xy 145.622266 -69.618055) (xy 145.622772 -69.665088)
			(xy 145.97685 -69.665088) (xy 145.980896 -69.57111) (xy 145.993007 -69.477828) (xy 146.013092 -69.385932)
			(xy 146.041002 -69.296103) (xy 146.076531 -69.209006) (xy 146.119416 -69.125285) (xy 146.169339 -69.045561)
			(xy 146.225931 -68.970424) (xy 146.288773 -68.90043) (xy 146.357399 -68.836097) (xy 146.431301 -68.777902)
			(xy 146.509932 -68.726275) (xy 146.592711 -68.681598) (xy 146.679023 -68.644204) (xy 146.768231 -68.614367)
			(xy 146.859673 -68.59231) (xy 146.952673 -68.578195) (xy 147.046542 -68.572127) (xy 147.140586 -68.57415)
			(xy 147.234107 -68.584251) (xy 147.326413 -68.602354) (xy 147.416822 -68.628325) (xy 147.504664 -68.661972)
			(xy 147.589287 -68.703046) (xy 147.670067 -68.751242) (xy 147.746405 -68.806204) (xy 147.817735 -68.867525)
			(xy 147.883529 -68.934751) (xy 147.943301 -69.007384) (xy 147.996608 -69.084886) (xy 148.043055 -69.166684)
			(xy 148.082298 -69.252172) (xy 148.114048 -69.340717) (xy 148.138067 -69.431664) (xy 148.15418 -69.524339)
			(xy 148.162266 -69.618055) (xy 148.162772 -69.665088) (xy 148.51685 -69.665088) (xy 148.520896 -69.57111)
			(xy 148.533007 -69.477828) (xy 148.553092 -69.385932) (xy 148.581002 -69.296103) (xy 148.616531 -69.209006)
			(xy 148.659416 -69.125285) (xy 148.709339 -69.045561) (xy 148.765931 -68.970424) (xy 148.828773 -68.90043)
			(xy 148.897399 -68.836097) (xy 148.971301 -68.777902) (xy 149.049932 -68.726275) (xy 149.132711 -68.681598)
			(xy 149.219023 -68.644204) (xy 149.308231 -68.614367) (xy 149.399673 -68.59231) (xy 149.492673 -68.578195)
			(xy 149.586542 -68.572127) (xy 149.680586 -68.57415) (xy 149.774107 -68.584251) (xy 149.866413 -68.602354)
			(xy 149.956822 -68.628325) (xy 150.044664 -68.661972) (xy 150.129287 -68.703046) (xy 150.210067 -68.751242)
			(xy 150.286405 -68.806204) (xy 150.357735 -68.867525) (xy 150.423529 -68.934751) (xy 150.483301 -69.007384)
			(xy 150.536608 -69.084886) (xy 150.583055 -69.166684) (xy 150.622298 -69.252172) (xy 150.654048 -69.340717)
			(xy 150.678067 -69.431664) (xy 150.69418 -69.524339) (xy 150.702266 -69.618055) (xy 150.702772 -69.665088)
			(xy 150.702266 -69.712121) (xy 150.69418 -69.805837) (xy 150.678067 -69.898512) (xy 150.654048 -69.989459)
			(xy 150.622298 -70.078004) (xy 150.583055 -70.163492) (xy 150.536608 -70.24529) (xy 150.483301 -70.322792)
			(xy 150.423529 -70.395425) (xy 150.357735 -70.462651) (xy 150.286405 -70.523972) (xy 150.210067 -70.578934)
			(xy 150.129287 -70.62713) (xy 150.044664 -70.668204) (xy 149.956822 -70.701851) (xy 149.866413 -70.727822)
			(xy 149.774107 -70.745925) (xy 149.680586 -70.756026) (xy 149.586542 -70.758049) (xy 149.492673 -70.751981)
			(xy 149.399673 -70.737866) (xy 149.308231 -70.715809) (xy 149.219023 -70.685972) (xy 149.132711 -70.648578)
			(xy 149.049932 -70.603901) (xy 148.971301 -70.552274) (xy 148.897399 -70.494079) (xy 148.828773 -70.429746)
			(xy 148.765931 -70.359752) (xy 148.709339 -70.284615) (xy 148.659416 -70.204891) (xy 148.616531 -70.12117)
			(xy 148.581002 -70.034073) (xy 148.553092 -69.944244) (xy 148.533007 -69.852348) (xy 148.520896 -69.759066)
			(xy 148.51685 -69.665088) (xy 148.162772 -69.665088) (xy 148.162266 -69.712121) (xy 148.15418 -69.805837)
			(xy 148.138067 -69.898512) (xy 148.114048 -69.989459) (xy 148.082298 -70.078004) (xy 148.043055 -70.163492)
			(xy 147.996608 -70.24529) (xy 147.943301 -70.322792) (xy 147.883529 -70.395425) (xy 147.817735 -70.462651)
			(xy 147.746405 -70.523972) (xy 147.670067 -70.578934) (xy 147.589287 -70.62713) (xy 147.504664 -70.668204)
			(xy 147.416822 -70.701851) (xy 147.326413 -70.727822) (xy 147.234107 -70.745925) (xy 147.140586 -70.756026)
			(xy 147.046542 -70.758049) (xy 146.952673 -70.751981) (xy 146.859673 -70.737866) (xy 146.768231 -70.715809)
			(xy 146.679023 -70.685972) (xy 146.592711 -70.648578) (xy 146.509932 -70.603901) (xy 146.431301 -70.552274)
			(xy 146.357399 -70.494079) (xy 146.288773 -70.429746) (xy 146.225931 -70.359752) (xy 146.169339 -70.284615)
			(xy 146.119416 -70.204891) (xy 146.076531 -70.12117) (xy 146.041002 -70.034073) (xy 146.013092 -69.944244)
			(xy 145.993007 -69.852348) (xy 145.980896 -69.759066) (xy 145.97685 -69.665088) (xy 145.622772 -69.665088)
			(xy 145.622266 -69.712121) (xy 145.61418 -69.805837) (xy 145.598067 -69.898512) (xy 145.574048 -69.989459)
			(xy 145.542298 -70.078004) (xy 145.503055 -70.163492) (xy 145.456608 -70.24529) (xy 145.403301 -70.322792)
			(xy 145.343529 -70.395425) (xy 145.277735 -70.462651) (xy 145.206405 -70.523972) (xy 145.130067 -70.578934)
			(xy 145.049287 -70.62713) (xy 144.964664 -70.668204) (xy 144.876822 -70.701851) (xy 144.786413 -70.727822)
			(xy 144.694107 -70.745925) (xy 144.600586 -70.756026) (xy 144.506542 -70.758049) (xy 144.412673 -70.751981)
			(xy 144.319673 -70.737866) (xy 144.228231 -70.715809) (xy 144.139023 -70.685972) (xy 144.052711 -70.648578)
			(xy 143.969932 -70.603901) (xy 143.891301 -70.552274) (xy 143.817399 -70.494079) (xy 143.748773 -70.429746)
			(xy 143.685931 -70.359752) (xy 143.629339 -70.284615) (xy 143.579416 -70.204891) (xy 143.536531 -70.12117)
			(xy 143.501002 -70.034073) (xy 143.473092 -69.944244) (xy 143.453007 -69.852348) (xy 143.440896 -69.759066)
			(xy 143.43685 -69.665088) (xy 143.082772 -69.665088) (xy 143.082266 -69.712121) (xy 143.07418 -69.805837)
			(xy 143.058067 -69.898512) (xy 143.034048 -69.989459) (xy 143.002298 -70.078004) (xy 142.963055 -70.163492)
			(xy 142.916608 -70.24529) (xy 142.863301 -70.322792) (xy 142.803529 -70.395425) (xy 142.737735 -70.462651)
			(xy 142.666405 -70.523972) (xy 142.590067 -70.578934) (xy 142.509287 -70.62713) (xy 142.424664 -70.668204)
			(xy 142.336822 -70.701851) (xy 142.246413 -70.727822) (xy 142.154107 -70.745925) (xy 142.060586 -70.756026)
			(xy 141.966542 -70.758049) (xy 141.872673 -70.751981) (xy 141.779673 -70.737866) (xy 141.688231 -70.715809)
			(xy 141.599023 -70.685972) (xy 141.512711 -70.648578) (xy 141.429932 -70.603901) (xy 141.351301 -70.552274)
			(xy 141.277399 -70.494079) (xy 141.208773 -70.429746) (xy 141.145931 -70.359752) (xy 141.089339 -70.284615)
			(xy 141.039416 -70.204891) (xy 140.996531 -70.12117) (xy 140.961002 -70.034073) (xy 140.933092 -69.944244)
			(xy 140.913007 -69.852348) (xy 140.900896 -69.759066) (xy 140.89685 -69.665088) (xy 140.415772 -69.665088)
			(xy 140.415272 -69.709065) (xy 140.407274 -69.796653) (xy 140.391344 -69.883152) (xy 140.367614 -69.967844)
			(xy 140.336282 -70.050027) (xy 140.297606 -70.12902) (xy 140.251907 -70.204169) (xy 140.199563 -70.274851)
			(xy 140.141009 -70.34048) (xy 140.07673 -70.400513) (xy 140.007258 -70.454452) (xy 139.933169 -70.50185)
			(xy 139.855076 -70.542314) (xy 139.773628 -70.575509) (xy 139.689498 -70.60116) (xy 139.603385 -70.619055)
			(xy 139.516 -70.629045) (xy 139.42807 -70.631047) (xy 139.340322 -70.625044) (xy 139.253483 -70.611088)
			(xy 139.168273 -70.589292) (xy 139.085398 -70.559839) (xy 139.005545 -70.522971) (xy 138.929375 -70.478994)
			(xy 138.85752 -70.428273) (xy 138.790575 -70.371228) (xy 138.729095 -70.308332) (xy 138.673588 -70.240106)
			(xy 138.624516 -70.167115) (xy 138.582285 -70.089964) (xy 138.547244 -70.009292) (xy 138.519685 -69.925768)
			(xy 138.499834 -69.840084) (xy 138.487858 -69.75295) (xy 138.483855 -69.665088) (xy 138.002772 -69.665088)
			(xy 138.002266 -69.712121) (xy 137.99418 -69.805837) (xy 137.978067 -69.898512) (xy 137.954048 -69.989459)
			(xy 137.922298 -70.078004) (xy 137.883055 -70.163492) (xy 137.836608 -70.24529) (xy 137.783301 -70.322792)
			(xy 137.723529 -70.395425) (xy 137.657735 -70.462651) (xy 137.586405 -70.523972) (xy 137.510067 -70.578934)
			(xy 137.429287 -70.62713) (xy 137.344664 -70.668204) (xy 137.256822 -70.701851) (xy 137.166413 -70.727822)
			(xy 137.074107 -70.745925) (xy 136.980586 -70.756026) (xy 136.886542 -70.758049) (xy 136.792673 -70.751981)
			(xy 136.699673 -70.737866) (xy 136.608231 -70.715809) (xy 136.519023 -70.685972) (xy 136.432711 -70.648578)
			(xy 136.349932 -70.603901) (xy 136.271301 -70.552274) (xy 136.197399 -70.494079) (xy 136.128773 -70.429746)
			(xy 136.065931 -70.359752) (xy 136.009339 -70.284615) (xy 135.959416 -70.204891) (xy 135.916531 -70.12117)
			(xy 135.881002 -70.034073) (xy 135.853092 -69.944244) (xy 135.833007 -69.852348) (xy 135.820896 -69.759066)
			(xy 135.81685 -69.665088) (xy 132.785875 -69.665088) (xy 132.79501 -69.674486) (xy 132.795518 -69.674994)
			(xy 133.471666 -70.350888) (xy 133.488322 -70.368178) (xy 133.516579 -70.406986) (xy 133.538418 -70.449737)
			(xy 133.553299 -70.495378) (xy 133.560857 -70.542786) (xy 133.561328 -70.566788) (xy 133.561328 -74.900657)
			(xy 136.414913 -74.900657) (xy 136.414913 -74.846143) (xy 136.422671 -74.792185) (xy 136.43803 -74.73988)
			(xy 136.460676 -74.690293) (xy 136.490149 -74.644434) (xy 136.525849 -74.603236) (xy 136.567048 -74.567538)
			(xy 136.612909 -74.538068) (xy 136.662497 -74.515424) (xy 136.714802 -74.500067) (xy 136.768761 -74.492312)
			(xy 136.796018 -74.49185) (xy 136.821717 -74.492292) (xy 136.87265 -74.499189) (xy 136.922198 -74.512857)
			(xy 136.969464 -74.533048) (xy 137.013594 -74.559397) (xy 137.053791 -74.591429) (xy 137.071862 -74.609706)
			(xy 137.078607 -74.616184) (xy 137.09547 -74.624229) (xy 137.114096 -74.625684) (xy 137.12317 -74.623422)
			(xy 137.210038 -74.597514) (xy 137.218788 -74.594457) (xy 137.233476 -74.583176) (xy 137.243202 -74.567416)
			(xy 137.245344 -74.558398) (xy 137.245344 -74.557636) (xy 137.250051 -74.533165) (xy 137.26187 -74.48475)
			(xy 137.268966 -74.460862) (xy 137.271251 -74.452059) (xy 137.270029 -74.433921) (xy 137.262589 -74.417334)
			(xy 137.249855 -74.40436) (xy 137.241788 -74.400156) (xy 137.203985 -74.381886) (xy 137.131647 -74.339252)
			(xy 137.063649 -74.28999) (xy 137.000596 -74.23454) (xy 136.94305 -74.173393) (xy 136.891522 -74.107096)
			(xy 136.846471 -74.036238) (xy 136.808299 -73.961449) (xy 136.777345 -73.883396) (xy 136.753885 -73.802773)
			(xy 136.738127 -73.720298) (xy 136.730211 -73.636705) (xy 136.729724 -73.594722) (xy 136.730173 -73.553618)
			(xy 136.737757 -73.471761) (xy 136.752861 -73.390953) (xy 136.775357 -73.311884) (xy 136.805053 -73.235227)
			(xy 136.841695 -73.161638) (xy 136.884972 -73.091744) (xy 136.934513 -73.026141) (xy 136.989896 -72.965389)
			(xy 137.050648 -72.910006) (xy 137.116252 -72.860466) (xy 137.186147 -72.81719) (xy 137.259736 -72.780549)
			(xy 137.336393 -72.750854) (xy 137.415463 -72.728358) (xy 137.496271 -72.713255) (xy 137.578128 -72.705673)
			(xy 137.619232 -72.705214) (xy 137.660884 -72.705677) (xy 137.743824 -72.713441) (xy 137.78484 -72.720708)
			(xy 137.79494 -72.722132) (xy 137.814857 -72.717822) (xy 137.823448 -72.712326) (xy 137.860964 -72.686615)
			(xy 137.940309 -72.642151) (xy 138.023775 -72.606011) (xy 138.110492 -72.578572) (xy 138.199554 -72.560118)
			(xy 138.290035 -72.550844) (xy 138.335512 -72.550274) (xy 138.376614 -72.550755) (xy 138.458468 -72.558341)
			(xy 138.539272 -72.573447) (xy 138.618338 -72.595944) (xy 138.694991 -72.62564) (xy 138.768578 -72.662282)
			(xy 138.838469 -72.705557) (xy 138.90407 -72.755096) (xy 138.964819 -72.810476) (xy 139.0202 -72.871226)
			(xy 139.06974 -72.936826) (xy 139.113016 -73.006717) (xy 139.149658 -73.080303) (xy 139.179354 -73.156956)
			(xy 139.201852 -73.236022) (xy 139.216958 -73.316826) (xy 139.224545 -73.39868) (xy 139.22502 -73.439782)
			(xy 139.224597 -73.47807) (xy 139.217972 -73.554361) (xy 139.21191 -73.589134) (xy 150.931624 -73.589134)
			(xy 150.935695 -73.533512) (xy 150.947821 -73.479075) (xy 150.967744 -73.426984) (xy 150.99504 -73.378349)
			(xy 151.029126 -73.334206) (xy 151.069275 -73.295497) (xy 151.114633 -73.263046) (xy 151.164233 -73.237545)
			(xy 151.217017 -73.219538) (xy 151.27186 -73.209408) (xy 151.327594 -73.207371) (xy 151.383031 -73.213471)
			(xy 151.436988 -73.227577) (xy 151.488317 -73.249389) (xy 151.535923 -73.278443) (xy 151.578791 -73.314118)
			(xy 151.616008 -73.355655) (xy 151.646781 -73.402168) (xy 151.670453 -73.452665) (xy 151.686521 -73.506072)
			(xy 151.694641 -73.561248) (xy 151.69515 -73.589134) (xy 151.694641 -73.61702) (xy 151.686521 -73.672196)
			(xy 151.670453 -73.725603) (xy 151.646781 -73.7761) (xy 151.616008 -73.822613) (xy 151.578791 -73.86415)
			(xy 151.535923 -73.899825) (xy 151.488317 -73.928879) (xy 151.436988 -73.950691) (xy 151.383031 -73.964797)
			(xy 151.327594 -73.970897) (xy 151.27186 -73.96886) (xy 151.217017 -73.95873) (xy 151.164233 -73.940723)
			(xy 151.114633 -73.915222) (xy 151.069275 -73.882771) (xy 151.029126 -73.844062) (xy 150.99504 -73.799919)
			(xy 150.967744 -73.751284) (xy 150.947821 -73.699193) (xy 150.935695 -73.644756) (xy 150.931624 -73.589134)
			(xy 139.21191 -73.589134) (xy 139.204821 -73.629801) (xy 139.185242 -73.703833) (xy 139.172696 -73.74001)
			(xy 139.170052 -73.748449) (xy 139.170046 -73.766118) (xy 139.172696 -73.774554) (xy 139.185276 -73.810721)
			(xy 139.204866 -73.884753) (xy 139.218011 -73.960197) (xy 139.224613 -74.036492) (xy 139.22502 -74.074782)
			(xy 139.224495 -74.11877) (xy 139.223819 -74.125582) (xy 140.003528 -74.125582) (xy 140.007599 -74.06996)
			(xy 140.019725 -74.015523) (xy 140.039648 -73.963432) (xy 140.066944 -73.914797) (xy 140.10103 -73.870654)
			(xy 140.141179 -73.831945) (xy 140.186537 -73.799494) (xy 140.236137 -73.773993) (xy 140.288921 -73.755986)
			(xy 140.343764 -73.745856) (xy 140.399498 -73.743819) (xy 140.454935 -73.749919) (xy 140.508892 -73.764025)
			(xy 140.560221 -73.785837) (xy 140.607827 -73.814891) (xy 140.650695 -73.850566) (xy 140.687912 -73.892103)
			(xy 140.718685 -73.938616) (xy 140.742357 -73.989113) (xy 140.758425 -74.04252) (xy 140.766545 -74.097696)
			(xy 140.767054 -74.125582) (xy 140.766545 -74.153468) (xy 140.758425 -74.208644) (xy 140.742357 -74.262051)
			(xy 140.718685 -74.312548) (xy 140.687912 -74.359061) (xy 140.650695 -74.400598) (xy 140.607827 -74.436273)
			(xy 140.560221 -74.465327) (xy 140.508892 -74.487139) (xy 140.454935 -74.501245) (xy 140.399498 -74.507345)
			(xy 140.343764 -74.505308) (xy 140.288921 -74.495178) (xy 140.236137 -74.477171) (xy 140.186537 -74.45167)
			(xy 140.141179 -74.419219) (xy 140.10103 -74.38051) (xy 140.066944 -74.336367) (xy 140.039648 -74.287732)
			(xy 140.019725 -74.235641) (xy 140.007599 -74.181204) (xy 140.003528 -74.125582) (xy 139.223819 -74.125582)
			(xy 139.215803 -74.206315) (xy 139.198513 -74.292574) (xy 139.172792 -74.376705) (xy 139.138893 -74.457887)
			(xy 139.097145 -74.535326) (xy 139.047958 -74.608267) (xy 139.020296 -74.642472) (xy 139.014616 -74.649994)
			(xy 139.008621 -74.667845) (xy 139.008612 -74.67727) (xy 139.009628 -74.718672) (xy 139.009121 -74.759774)
			(xy 139.001539 -74.841628) (xy 138.993623 -74.883983) (xy 141.031716 -74.883983) (xy 141.031716 -74.820061)
			(xy 141.039727 -74.756643) (xy 141.055624 -74.694729) (xy 141.079156 -74.635296) (xy 141.10995 -74.579281)
			(xy 141.147523 -74.527566) (xy 141.19128 -74.480969) (xy 141.240533 -74.440224) (xy 141.294504 -74.405973)
			(xy 141.352343 -74.378756) (xy 141.413136 -74.359003) (xy 141.475926 -74.347025) (xy 141.539722 -74.343012)
			(xy 141.603518 -74.347025) (xy 141.666308 -74.359003) (xy 141.727101 -74.378756) (xy 141.78494 -74.405973)
			(xy 141.838911 -74.440224) (xy 141.888164 -74.480969) (xy 141.931921 -74.527566) (xy 141.969494 -74.579281)
			(xy 142.000288 -74.635296) (xy 142.02382 -74.694729) (xy 142.039717 -74.756643) (xy 142.047728 -74.820061)
			(xy 142.04823 -74.852022) (xy 142.047728 -74.883983) (xy 142.039717 -74.947401) (xy 142.02382 -75.009315)
			(xy 142.000288 -75.068748) (xy 141.969494 -75.124763) (xy 141.931921 -75.176478) (xy 141.888164 -75.223075)
			(xy 141.838911 -75.26382) (xy 141.78494 -75.298071) (xy 141.727101 -75.325288) (xy 141.666308 -75.345041)
			(xy 141.603518 -75.357019) (xy 141.539722 -75.361033) (xy 141.475926 -75.357019) (xy 141.413136 -75.345041)
			(xy 141.352343 -75.325288) (xy 141.294504 -75.298071) (xy 141.240533 -75.26382) (xy 141.19128 -75.223075)
			(xy 141.147523 -75.176478) (xy 141.10995 -75.124763) (xy 141.079156 -75.068748) (xy 141.055624 -75.009315)
			(xy 141.039727 -74.947401) (xy 141.031716 -74.883983) (xy 138.993623 -74.883983) (xy 138.986436 -74.922433)
			(xy 138.963942 -75.0015) (xy 138.934249 -75.078154) (xy 138.89761 -75.151741) (xy 138.854337 -75.221634)
			(xy 138.804799 -75.287235) (xy 138.74942 -75.347986) (xy 138.688672 -75.403369) (xy 138.623073 -75.45291)
			(xy 138.553183 -75.496186) (xy 138.479598 -75.53283) (xy 138.402945 -75.562527) (xy 138.32388 -75.585025)
			(xy 138.243075 -75.600132) (xy 138.161222 -75.607719) (xy 138.12012 -75.60818) (xy 138.077249 -75.607693)
			(xy 137.991906 -75.599429) (xy 137.907754 -75.582995) (xy 137.825573 -75.558544) (xy 137.746124 -75.526301)
			(xy 137.670145 -75.486567) (xy 137.59834 -75.439709) (xy 137.531374 -75.386162) (xy 137.469869 -75.326422)
			(xy 137.414395 -75.261044) (xy 137.365466 -75.190634) (xy 137.323536 -75.115844) (xy 137.305796 -75.076812)
			(xy 137.299954 -75.063604) (xy 137.276586 -75.047094) (xy 137.15746 -75.04049) (xy 137.132568 -75.053698)
			(xy 137.125202 -75.066144) (xy 137.110367 -75.090344) (xy 137.074757 -75.134541) (xy 137.03299 -75.172972)
			(xy 136.985989 -75.204789) (xy 136.934791 -75.229288) (xy 136.880527 -75.245929) (xy 136.824397 -75.254343)
			(xy 136.796018 -75.254866) (xy 136.768761 -75.254488) (xy 136.714802 -75.246733) (xy 136.662497 -75.231376)
			(xy 136.612909 -75.208732) (xy 136.567048 -75.179262) (xy 136.525849 -75.143564) (xy 136.490149 -75.102366)
			(xy 136.460676 -75.056507) (xy 136.43803 -75.00692) (xy 136.422671 -74.954615) (xy 136.414913 -74.900657)
			(xy 133.561328 -74.900657) (xy 133.561328 -76.356929) (xy 142.191226 -76.356929) (xy 142.191226 -76.293007)
			(xy 142.199237 -76.229589) (xy 142.215134 -76.167675) (xy 142.238666 -76.108242) (xy 142.26946 -76.052227)
			(xy 142.307033 -76.000512) (xy 142.35079 -75.953915) (xy 142.400043 -75.91317) (xy 142.454014 -75.878919)
			(xy 142.511853 -75.851702) (xy 142.572646 -75.831949) (xy 142.635436 -75.819971) (xy 142.699232 -75.815958)
			(xy 142.763028 -75.819971) (xy 142.825818 -75.831949) (xy 142.886611 -75.851702) (xy 142.94445 -75.878919)
			(xy 142.998421 -75.91317) (xy 143.047674 -75.953915) (xy 143.091431 -76.000512) (xy 143.129004 -76.052227)
			(xy 143.159798 -76.108242) (xy 143.18333 -76.167675) (xy 143.199227 -76.229589) (xy 143.199664 -76.233052)
			(xy 143.718997 -76.233052) (xy 143.718997 -76.178548) (xy 143.726755 -76.1246) (xy 143.742111 -76.072304)
			(xy 143.764754 -76.022727) (xy 143.794223 -75.976877) (xy 143.829917 -75.935687) (xy 143.87111 -75.899998)
			(xy 143.916964 -75.870534) (xy 143.966544 -75.847896) (xy 144.018841 -75.832546) (xy 144.07279 -75.824794)
			(xy 144.100042 -75.824334) (xy 144.100296 -75.824334) (xy 144.130163 -75.824942) (xy 144.189166 -75.834272)
			(xy 144.245997 -75.852673) (xy 144.29927 -75.879698) (xy 144.323816 -75.896724) (xy 144.330938 -75.901442)
			(xy 144.347278 -75.906383) (xy 144.35582 -75.906376) (xy 144.385792 -75.905106) (xy 144.394378 -75.904332)
			(xy 144.410339 -75.897839) (xy 144.417034 -75.892406) (xy 144.440294 -75.872563) (xy 144.490726 -75.837997)
			(xy 144.544942 -75.809733) (xy 144.602158 -75.78818) (xy 144.661547 -75.773649) (xy 144.722251 -75.76635)
			(xy 144.752822 -75.765914) (xy 144.781934 -75.766313) (xy 144.839775 -75.772967) (xy 144.896475 -75.786197)
			(xy 144.924018 -75.795632) (xy 144.934714 -75.798874) (xy 144.956942 -75.796806) (xy 144.976175 -75.785474)
			(xy 144.982946 -75.776582) (xy 145.000789 -75.751549) (xy 145.041558 -75.705535) (xy 145.087575 -75.664769)
			(xy 145.138169 -75.629846) (xy 145.192603 -75.601275) (xy 145.250083 -75.579472) (xy 145.309772 -75.564756)
			(xy 145.3708 -75.557339) (xy 145.401538 -75.556872) (xy 145.433496 -75.557416) (xy 145.496908 -75.565431)
			(xy 145.558816 -75.581331) (xy 145.618242 -75.604863) (xy 145.674251 -75.635658) (xy 145.725959 -75.67323)
			(xy 145.772551 -75.716985) (xy 145.813291 -75.766235) (xy 145.847538 -75.820203) (xy 145.874751 -75.878037)
			(xy 145.894501 -75.938825) (xy 145.906477 -76.00161) (xy 145.910491 -76.0654) (xy 145.906477 -76.12919)
			(xy 145.894501 -76.191975) (xy 145.874751 -76.252763) (xy 145.847538 -76.310597) (xy 145.813291 -76.364565)
			(xy 145.772551 -76.413815) (xy 145.725959 -76.45757) (xy 145.674251 -76.495142) (xy 145.618242 -76.525937)
			(xy 145.558816 -76.549469) (xy 145.496908 -76.565369) (xy 145.433496 -76.573384) (xy 145.401538 -76.573888)
			(xy 145.372426 -76.5735) (xy 145.314584 -76.566841) (xy 145.257885 -76.553607) (xy 145.230342 -76.54417)
			(xy 145.219655 -76.54089) (xy 145.197419 -76.542973) (xy 145.178184 -76.554321) (xy 145.171414 -76.56322)
			(xy 145.153597 -76.588273) (xy 145.112824 -76.634286) (xy 145.066804 -76.675051) (xy 145.016206 -76.709972)
			(xy 144.961768 -76.73854) (xy 144.904284 -76.76034) (xy 144.844592 -76.775053) (xy 144.783561 -76.782465)
			(xy 144.752822 -76.78293) (xy 144.718991 -76.782409) (xy 144.651929 -76.773415) (xy 144.586652 -76.75561)
			(xy 144.524311 -76.729308) (xy 144.466007 -76.694973) (xy 144.41277 -76.653212) (xy 144.365539 -76.604762)
			(xy 144.344898 -76.577952) (xy 144.339503 -76.571233) (xy 144.325215 -76.561622) (xy 144.316958 -76.559156)
			(xy 144.288002 -76.55179) (xy 144.279654 -76.550019) (xy 144.262659 -76.551437) (xy 144.254728 -76.554584)
			(xy 144.230262 -76.564921) (xy 144.179195 -76.579517) (xy 144.126598 -76.586889) (xy 144.100042 -76.58735)
			(xy 144.07279 -76.586806) (xy 144.018841 -76.579054) (xy 143.966544 -76.563704) (xy 143.916964 -76.541066)
			(xy 143.87111 -76.511602) (xy 143.829917 -76.475913) (xy 143.794223 -76.434723) (xy 143.764754 -76.388873)
			(xy 143.742111 -76.339296) (xy 143.726755 -76.287) (xy 143.718997 -76.233052) (xy 143.199664 -76.233052)
			(xy 143.207238 -76.293007) (xy 143.20774 -76.324968) (xy 143.207238 -76.356929) (xy 143.199227 -76.420347)
			(xy 143.18333 -76.482261) (xy 143.159798 -76.541694) (xy 143.129004 -76.597709) (xy 143.091431 -76.649424)
			(xy 143.047674 -76.696021) (xy 142.998421 -76.736766) (xy 142.94445 -76.771017) (xy 142.886611 -76.798234)
			(xy 142.825818 -76.817987) (xy 142.763028 -76.829965) (xy 142.699232 -76.833979) (xy 142.635436 -76.829965)
			(xy 142.572646 -76.817987) (xy 142.511853 -76.798234) (xy 142.454014 -76.771017) (xy 142.400043 -76.736766)
			(xy 142.35079 -76.696021) (xy 142.307033 -76.649424) (xy 142.26946 -76.597709) (xy 142.238666 -76.541694)
			(xy 142.215134 -76.482261) (xy 142.199237 -76.420347) (xy 142.191226 -76.356929) (xy 133.561328 -76.356929)
			(xy 133.561328 -81.09715) (xy 137.493497 -81.09715) (xy 137.493497 -81.04265) (xy 137.501253 -80.988705)
			(xy 137.516608 -80.936413) (xy 137.539248 -80.886838) (xy 137.568713 -80.84099) (xy 137.604403 -80.799801)
			(xy 137.645591 -80.764112) (xy 137.69144 -80.734647) (xy 137.741015 -80.712007) (xy 137.793307 -80.696653)
			(xy 137.847252 -80.688897) (xy 137.874502 -80.688434) (xy 137.904236 -80.688955) (xy 137.962982 -80.698189)
			(xy 138.019582 -80.716434) (xy 138.072663 -80.743246) (xy 138.120935 -80.777976) (xy 138.16323 -80.81978)
			(xy 138.181334 -80.843374) (xy 138.188971 -80.852569) (xy 138.210293 -80.863302) (xy 138.222228 -80.863948)
			(xy 138.304016 -80.863948) (xy 138.315957 -80.863308) (xy 138.337294 -80.852591) (xy 138.34491 -80.843374)
			(xy 138.363057 -80.819818) (xy 138.405348 -80.778023) (xy 138.453615 -80.743301) (xy 138.506687 -80.716492)
			(xy 138.563277 -80.698247) (xy 138.622013 -80.689008) (xy 138.651742 -80.688434) (xy 138.678841 -80.688917)
			(xy 138.732494 -80.696592) (xy 138.784521 -80.711782) (xy 138.833874 -80.734182) (xy 138.879561 -80.76334)
			(xy 138.920663 -80.79867) (xy 138.956351 -80.83946) (xy 138.971528 -80.861916) (xy 138.97864 -80.872838)
			(xy 139.001754 -80.885284) (xy 139.114022 -80.883506) (xy 139.136628 -80.870298) (xy 139.143486 -80.859122)
			(xy 139.158416 -80.835494) (xy 139.194108 -80.792482) (xy 139.23569 -80.755135) (xy 139.282275 -80.724253)
			(xy 139.332866 -80.700495) (xy 139.386381 -80.684369) (xy 139.441676 -80.67622) (xy 139.469622 -80.675734)
			(xy 139.499354 -80.676313) (xy 139.558097 -80.685535) (xy 139.614696 -80.703768) (xy 139.667777 -80.73057)
			(xy 139.716051 -80.765289) (xy 139.758349 -80.807084) (xy 139.776454 -80.830674) (xy 139.784081 -80.839878)
			(xy 139.805411 -80.850606) (xy 139.817348 -80.851248) (xy 139.899136 -80.851248) (xy 139.911078 -80.850619)
			(xy 139.932415 -80.839894) (xy 139.94003 -80.830674) (xy 139.958165 -80.807108) (xy 140.000459 -80.765314)
			(xy 140.048728 -80.730593) (xy 140.101802 -80.703786) (xy 140.158394 -80.685543) (xy 140.217132 -80.676307)
			(xy 140.246862 -80.675734) (xy 140.276377 -80.67628) (xy 140.3347 -80.685386) (xy 140.390918 -80.703386)
			(xy 140.41755 -80.71612) (xy 140.428795 -80.720928) (xy 140.453208 -80.720536) (xy 140.464286 -80.715358)
			(xy 140.537438 -80.675988) (xy 140.548071 -80.669631) (xy 140.561906 -80.649109) (xy 140.563854 -80.636872)
			(xy 140.567375 -80.610785) (xy 140.580666 -80.559851) (xy 140.600828 -80.511226) (xy 140.62748 -80.465832)
			(xy 140.660115 -80.42453) (xy 140.698115 -80.388104) (xy 140.740759 -80.357243) (xy 140.787239 -80.332534)
			(xy 140.836672 -80.314444) (xy 140.862304 -80.30845) (xy 140.872464 -80.306164) (xy 140.889482 -80.293972)
			(xy 140.93317 -80.221836) (xy 140.938085 -80.212676) (xy 140.940834 -80.19209) (xy 140.938504 -80.181958)
			(xy 140.931998 -80.156933) (xy 140.924984 -80.105703) (xy 140.924534 -80.07985) (xy 140.924534 -80.079342)
			(xy 140.924995 -80.052088) (xy 140.932747 -79.998135) (xy 140.9481 -79.945835) (xy 140.97074 -79.896252)
			(xy 141.000208 -79.850396) (xy 141.035902 -79.809202) (xy 141.077096 -79.773508) (xy 141.122952 -79.74404)
			(xy 141.172535 -79.7214) (xy 141.224835 -79.706047) (xy 141.278788 -79.698295) (xy 141.306042 -79.697834)
			(xy 141.30655 -79.697834) (xy 141.335721 -79.698424) (xy 141.393377 -79.707347) (xy 141.421358 -79.715614)
			(xy 141.421612 -79.715614) (xy 141.431629 -79.718232) (xy 141.452208 -79.716137) (xy 141.46149 -79.71155)
			(xy 141.526006 -79.675482) (xy 141.534868 -79.669968) (xy 141.547598 -79.653459) (xy 141.550644 -79.643478)
			(xy 141.558004 -79.616364) (xy 141.57955 -79.564479) (xy 141.608469 -79.516312) (xy 141.644136 -79.472906)
			(xy 141.685781 -79.435197) (xy 141.732505 -79.404) (xy 141.783297 -79.37999) (xy 141.837059 -79.363686)
			(xy 141.892632 -79.355438) (xy 141.920722 -79.354934) (xy 141.949447 -79.355499) (xy 142.006248 -79.364116)
			(xy 142.061115 -79.381153) (xy 142.112807 -79.406223) (xy 142.160156 -79.43876) (xy 142.202091 -79.478029)
			(xy 142.237664 -79.523142) (xy 142.266071 -79.573078) (xy 142.28667 -79.626709) (xy 142.29334 -79.654654)
			(xy 142.296134 -79.6671) (xy 142.31239 -79.68615) (xy 142.403068 -79.72171) (xy 142.415076 -79.725633)
			(xy 142.440119 -79.722579) (xy 142.45082 -79.715868) (xy 142.475 -79.699627) (xy 142.52726 -79.673908)
			(xy 142.58282 -79.656425) (xy 142.640391 -79.647581) (xy 142.669514 -79.647034) (xy 142.696769 -79.647442)
			(xy 142.750724 -79.655202) (xy 142.803026 -79.670562) (xy 142.852609 -79.693209) (xy 142.898464 -79.722683)
			(xy 142.939658 -79.758382) (xy 142.975351 -79.799581) (xy 143.004818 -79.84544) (xy 143.027458 -79.895027)
			(xy 143.04281 -79.947331) (xy 143.050562 -80.001287) (xy 143.051022 -80.028542) (xy 143.050472 -80.057491)
			(xy 143.041704 -80.114723) (xy 143.024392 -80.169974) (xy 142.998931 -80.221975) (xy 142.965908 -80.269533)
			(xy 142.934284 -80.3029) (xy 143.70523 -80.3029) (xy 143.709245 -80.239093) (xy 143.721226 -80.176293)
			(xy 143.740983 -80.11549) (xy 143.768205 -80.057642) (xy 143.802464 -80.003663) (xy 143.843218 -79.954403)
			(xy 143.889825 -79.91064) (xy 143.94155 -79.873064) (xy 143.997576 -79.842267) (xy 144.057021 -79.818736)
			(xy 144.118946 -79.802841) (xy 144.182376 -79.794832) (xy 144.214342 -79.794354) (xy 144.214596 -79.794354)
			(xy 144.250702 -79.795021) (xy 144.322186 -79.805258) (xy 144.391509 -79.825486) (xy 144.424654 -79.83982)
			(xy 144.43456 -79.844392) (xy 144.456404 -79.844646) (xy 144.53616 -79.808578) (xy 144.545813 -79.803692)
			(xy 144.56014 -79.787502) (xy 144.563846 -79.777336) (xy 144.563846 -79.777082) (xy 144.573792 -79.746247)
			(xy 144.600457 -79.687197) (xy 144.63441 -79.632015) (xy 144.675101 -79.581595) (xy 144.721869 -79.536755)
			(xy 144.773956 -79.498222) (xy 144.830518 -79.46662) (xy 144.890637 -79.442463) (xy 144.953339 -79.426142)
			(xy 145.017606 -79.417921) (xy 145.050002 -79.417418) (xy 145.081965 -79.417868) (xy 145.145386 -79.42588)
			(xy 145.207302 -79.441778) (xy 145.266739 -79.465311) (xy 145.322756 -79.496107) (xy 145.374473 -79.533681)
			(xy 145.421072 -79.577441) (xy 145.46182 -79.626697) (xy 145.496072 -79.68067) (xy 145.52329 -79.738512)
			(xy 145.543044 -79.799308) (xy 145.555023 -79.862101) (xy 145.559037 -79.9259) (xy 145.555023 -79.989699)
			(xy 145.543044 -80.052492) (xy 145.52329 -80.113288) (xy 145.496072 -80.17113) (xy 145.46182 -80.225103)
			(xy 145.421072 -80.274359) (xy 145.374473 -80.318119) (xy 145.322756 -80.355693) (xy 145.266739 -80.386489)
			(xy 145.207302 -80.410022) (xy 145.145386 -80.42592) (xy 145.081965 -80.433932) (xy 145.050002 -80.434434)
			(xy 145.049748 -80.434434) (xy 145.013641 -80.433787) (xy 144.942156 -80.423542) (xy 144.872835 -80.403306)
			(xy 144.83969 -80.388968) (xy 144.829784 -80.384396) (xy 144.80794 -80.384142) (xy 144.728184 -80.42021)
			(xy 144.718543 -80.425115) (xy 144.704208 -80.441291) (xy 144.700498 -80.451452) (xy 144.700498 -80.451706)
			(xy 144.690506 -80.482525) (xy 144.663845 -80.541573) (xy 144.629897 -80.596754) (xy 144.589212 -80.647174)
			(xy 144.542449 -80.692014) (xy 144.490367 -80.730549) (xy 144.43381 -80.762153) (xy 144.373696 -80.786313)
			(xy 144.310999 -80.802639) (xy 144.246736 -80.810864) (xy 144.214342 -80.81137) (xy 144.182376 -80.810968)
			(xy 144.118946 -80.802959) (xy 144.057021 -80.787064) (xy 143.997576 -80.763533) (xy 143.94155 -80.732736)
			(xy 143.889825 -80.69516) (xy 143.843218 -80.651397) (xy 143.802464 -80.602137) (xy 143.768205 -80.548158)
			(xy 143.740983 -80.49031) (xy 143.721226 -80.429507) (xy 143.709245 -80.366707) (xy 143.70523 -80.3029)
			(xy 142.934284 -80.3029) (xy 142.926079 -80.311557) (xy 142.88036 -80.347082) (xy 142.829798 -80.375293)
			(xy 142.802864 -80.38592) (xy 142.793096 -80.390138) (xy 142.777873 -80.404968) (xy 142.7734 -80.414622)
			(xy 142.741396 -80.494632) (xy 142.742158 -80.515714) (xy 142.74673 -80.525366) (xy 142.758746 -80.551393)
			(xy 142.775725 -80.606144) (xy 142.784312 -80.66282) (xy 142.78483 -80.691482) (xy 142.784305 -80.718732)
			(xy 142.776552 -80.772677) (xy 142.7612 -80.82497) (xy 142.738562 -80.874545) (xy 142.7091 -80.920395)
			(xy 142.673413 -80.961584) (xy 142.632227 -80.997276) (xy 142.58638 -81.026743) (xy 142.536807 -81.049386)
			(xy 142.484516 -81.064743) (xy 142.430572 -81.072502) (xy 142.403322 -81.07299) (xy 142.377862 -81.072605)
			(xy 142.327393 -81.065833) (xy 142.278275 -81.052406) (xy 142.231379 -81.032563) (xy 142.187541 -81.006656)
			(xy 142.14754 -80.975147) (xy 142.12951 -80.957166) (xy 142.122174 -80.950288) (xy 142.103732 -80.942317)
			(xy 142.093696 -80.941672) (xy 142.021814 -80.940656) (xy 142.011892 -80.941008) (xy 141.99346 -80.94833)
			(xy 141.986 -80.95488) (xy 141.985746 -80.955134) (xy 141.96949 -80.969866) (xy 141.969236 -80.97012)
			(xy 141.961267 -80.977853) (xy 141.952302 -80.998138) (xy 141.951964 -81.009236) (xy 141.953234 -81.087468)
			(xy 141.954038 -81.09862) (xy 141.963928 -81.118645) (xy 141.972284 -81.126076) (xy 141.994044 -81.14429)
			(xy 142.032448 -81.186063) (xy 142.06424 -81.233065) (xy 142.088719 -81.284258) (xy 142.105345 -81.338512)
			(xy 142.11375 -81.39463) (xy 142.11427 -81.423002) (xy 142.113846 -81.450257) (xy 142.106088 -81.504211)
			(xy 142.09073 -81.556512) (xy 142.068084 -81.606095) (xy 142.038613 -81.651949) (xy 142.002915 -81.693143)
			(xy 141.961717 -81.728837) (xy 141.915859 -81.758304) (xy 141.866274 -81.780944) (xy 141.848294 -81.786222)
			(xy 144.035524 -81.786222) (xy 144.039595 -81.7306) (xy 144.051721 -81.676163) (xy 144.071644 -81.624072)
			(xy 144.09894 -81.575437) (xy 144.133026 -81.531294) (xy 144.173175 -81.492585) (xy 144.218533 -81.460134)
			(xy 144.268133 -81.434633) (xy 144.320917 -81.416626) (xy 144.37576 -81.406496) (xy 144.431494 -81.404459)
			(xy 144.486931 -81.410559) (xy 144.540888 -81.424665) (xy 144.592217 -81.446477) (xy 144.639823 -81.475531)
			(xy 144.682691 -81.511206) (xy 144.719908 -81.552743) (xy 144.750681 -81.599256) (xy 144.774353 -81.649753)
			(xy 144.790421 -81.70316) (xy 144.798541 -81.758336) (xy 144.79905 -81.786222) (xy 144.798541 -81.814108)
			(xy 144.790421 -81.869284) (xy 144.774353 -81.922691) (xy 144.750681 -81.973188) (xy 144.719908 -82.019701)
			(xy 144.682691 -82.061238) (xy 144.639823 -82.096913) (xy 144.592217 -82.125967) (xy 144.540888 -82.147779)
			(xy 144.486931 -82.161885) (xy 144.431494 -82.167985) (xy 144.37576 -82.165948) (xy 144.320917 -82.155818)
			(xy 144.268133 -82.137811) (xy 144.218533 -82.11231) (xy 144.173175 -82.079859) (xy 144.133026 -82.04115)
			(xy 144.09894 -81.997007) (xy 144.071644 -81.948372) (xy 144.051721 -81.896281) (xy 144.039595 -81.841844)
			(xy 144.035524 -81.786222) (xy 141.848294 -81.786222) (xy 141.813972 -81.796297) (xy 141.760017 -81.804049)
			(xy 141.732762 -81.80451) (xy 141.703031 -81.803925) (xy 141.644288 -81.794701) (xy 141.58769 -81.776468)
			(xy 141.53461 -81.749668) (xy 141.486335 -81.714951) (xy 141.444037 -81.673158) (xy 141.42593 -81.64957)
			(xy 141.418301 -81.640366) (xy 141.396973 -81.629637) (xy 141.385036 -81.628996) (xy 141.303248 -81.628996)
			(xy 141.291302 -81.629599) (xy 141.269964 -81.640341) (xy 141.262354 -81.64957) (xy 141.24424 -81.673153)
			(xy 141.201941 -81.714944) (xy 141.153667 -81.749662) (xy 141.100589 -81.776465) (xy 141.043993 -81.794705)
			(xy 140.985253 -81.803939) (xy 140.955522 -81.80451) (xy 140.927894 -81.804011) (xy 140.873214 -81.796069)
			(xy 140.820251 -81.78032) (xy 140.770116 -81.757093) (xy 140.723857 -81.726874) (xy 140.682443 -81.690295)
			(xy 140.646741 -81.648124) (xy 140.617498 -81.601242) (xy 140.595327 -81.55063) (xy 140.580692 -81.497349)
			(xy 140.576808 -81.469992) (xy 140.574716 -81.457713) (xy 140.560434 -81.437334) (xy 140.54963 -81.43113)
			(xy 140.475462 -81.392522) (xy 140.464071 -81.387536) (xy 140.439247 -81.387803) (xy 140.427964 -81.39303)
			(xy 140.399968 -81.407414) (xy 140.340417 -81.427787) (xy 140.278331 -81.438109) (xy 140.246862 -81.43875)
			(xy 140.217132 -81.438149) (xy 140.158391 -81.428926) (xy 140.101794 -81.410695) (xy 140.048714 -81.383898)
			(xy 140.000438 -81.349184) (xy 139.958138 -81.307396) (xy 139.94003 -81.28381) (xy 139.932413 -81.274596)
			(xy 139.911075 -81.263874) (xy 139.899136 -81.263236) (xy 139.817348 -81.263236) (xy 139.805399 -81.263824)
			(xy 139.784061 -81.274575) (xy 139.776454 -81.28381) (xy 139.758351 -81.307401) (xy 139.716048 -81.34919)
			(xy 139.667771 -81.383906) (xy 139.614692 -81.410708) (xy 139.558095 -81.428946) (xy 139.499353 -81.438179)
			(xy 139.469622 -81.43875) (xy 139.442521 -81.438302) (xy 139.388867 -81.430621) (xy 139.336839 -81.415426)
			(xy 139.287485 -81.39302) (xy 139.241798 -81.363857) (xy 139.200698 -81.328522) (xy 139.165011 -81.287726)
			(xy 139.149836 -81.265268) (xy 139.142724 -81.254346) (xy 139.11961 -81.2419) (xy 139.007342 -81.243678)
			(xy 138.984736 -81.256886) (xy 138.977878 -81.268062) (xy 138.962966 -81.291703) (xy 138.927273 -81.334715)
			(xy 138.885687 -81.372062) (xy 138.839099 -81.402943) (xy 138.788505 -81.426699) (xy 138.734986 -81.442822)
			(xy 138.679689 -81.450966) (xy 138.651742 -81.45145) (xy 138.622011 -81.450864) (xy 138.563269 -81.441638)
			(xy 138.506672 -81.423404) (xy 138.453592 -81.396604) (xy 138.405317 -81.361888) (xy 138.363018 -81.320097)
			(xy 138.34491 -81.29651) (xy 138.337302 -81.287287) (xy 138.315958 -81.27657) (xy 138.304016 -81.275936)
			(xy 138.222228 -81.275936) (xy 138.210278 -81.276513) (xy 138.188939 -81.287271) (xy 138.181334 -81.29651)
			(xy 138.163243 -81.320111) (xy 138.120937 -81.361899) (xy 138.072658 -81.396613) (xy 138.019576 -81.423414)
			(xy 137.962977 -81.44165) (xy 137.904234 -81.45088) (xy 137.874502 -81.45145) (xy 137.847252 -81.450903)
			(xy 137.793307 -81.443147) (xy 137.741015 -81.427793) (xy 137.69144 -81.405153) (xy 137.645591 -81.375688)
			(xy 137.604403 -81.339999) (xy 137.568713 -81.29881) (xy 137.539248 -81.252962) (xy 137.516608 -81.203387)
			(xy 137.501253 -81.151095) (xy 137.493497 -81.09715) (xy 133.561328 -81.09715) (xy 133.561328 -81.26222)
			(xy 133.560856 -81.286211) (xy 133.553347 -81.333601) (xy 133.538519 -81.379234) (xy 133.516734 -81.421985)
			(xy 133.488531 -81.460803) (xy 133.454603 -81.494731) (xy 133.415785 -81.522934) (xy 133.373034 -81.544719)
			(xy 133.327401 -81.559547) (xy 133.280011 -81.567056) (xy 133.25602 -81.567528) (xy 113.904776 -81.567528)
			(xy 113.881274 -81.567068) (xy 113.834827 -81.559853) (xy 113.790036 -81.545597) (xy 113.747963 -81.524639)
			(xy 113.709603 -81.497475) (xy 113.692432 -81.481422) (xy 113.689892 -81.478882) (xy 113.688876 -81.477612)
			(xy 113.688622 -81.477612) (xy 113.667286 -81.456022) (xy 113.6508 -81.438804) (xy 113.622889 -81.40016)
			(xy 113.60132 -81.357649) (xy 113.586617 -81.312304) (xy 113.579136 -81.265226) (xy 113.57864 -81.241392)
			(xy 108.898437 -81.241392) (xy 108.905104 -81.25352) (xy 108.928636 -81.312953) (xy 108.944533 -81.374867)
			(xy 108.952544 -81.438285) (xy 108.953046 -81.470246) (xy 108.952544 -81.502207) (xy 108.944533 -81.565625)
			(xy 108.928636 -81.627539) (xy 108.905104 -81.686972) (xy 108.87431 -81.742987) (xy 108.836737 -81.794702)
			(xy 108.79298 -81.841299) (xy 108.743727 -81.882044) (xy 108.689756 -81.916295) (xy 108.631917 -81.943512)
			(xy 108.571124 -81.963265) (xy 108.508334 -81.975243) (xy 108.444538 -81.979257) (xy 108.380742 -81.975243)
			(xy 108.317952 -81.963265) (xy 108.257159 -81.943512) (xy 108.19932 -81.916295) (xy 108.145349 -81.882044)
			(xy 108.096096 -81.841299) (xy 108.052339 -81.794702) (xy 108.014766 -81.742987) (xy 107.983972 -81.686972)
			(xy 107.96044 -81.627539) (xy 107.944543 -81.565625) (xy 107.936532 -81.502207) (xy 30.860052 -81.502207)
			(xy 30.856943 -81.523336) (xy 30.840875 -81.576743) (xy 30.817203 -81.62724) (xy 30.78643 -81.673753)
			(xy 30.749213 -81.71529) (xy 30.706345 -81.750965) (xy 30.658739 -81.780019) (xy 30.60741 -81.801831)
			(xy 30.553453 -81.815937) (xy 30.498016 -81.822037) (xy 30.442282 -81.82) (xy 30.387439 -81.80987)
			(xy 30.334655 -81.791863) (xy 30.285055 -81.766362) (xy 30.239697 -81.733911) (xy 30.199548 -81.695202)
			(xy 30.165462 -81.651059) (xy 30.138166 -81.602424) (xy 30.118243 -81.550333) (xy 30.106117 -81.495896)
			(xy 30.102046 -81.440274) (xy 7.681976 -81.440274) (xy 7.681976 -82.169) (xy 8.888982 -82.169) (xy 8.893053 -82.113378)
			(xy 8.905179 -82.058941) (xy 8.925102 -82.00685) (xy 8.952398 -81.958215) (xy 8.986484 -81.914072)
			(xy 9.026633 -81.875363) (xy 9.071991 -81.842912) (xy 9.121591 -81.817411) (xy 9.174375 -81.799404)
			(xy 9.229218 -81.789274) (xy 9.284952 -81.787237) (xy 9.340389 -81.793337) (xy 9.394346 -81.807443)
			(xy 9.445675 -81.829255) (xy 9.493281 -81.858309) (xy 9.536149 -81.893984) (xy 9.573366 -81.935521)
			(xy 9.604139 -81.982034) (xy 9.627811 -82.032531) (xy 9.643879 -82.085938) (xy 9.651999 -82.141114)
			(xy 9.652508 -82.169) (xy 9.777982 -82.169) (xy 9.782053 -82.113378) (xy 9.794179 -82.058941) (xy 9.814102 -82.00685)
			(xy 9.841398 -81.958215) (xy 9.875484 -81.914072) (xy 9.915633 -81.875363) (xy 9.960991 -81.842912)
			(xy 10.010591 -81.817411) (xy 10.063375 -81.799404) (xy 10.118218 -81.789274) (xy 10.173952 -81.787237)
			(xy 10.229389 -81.793337) (xy 10.283346 -81.807443) (xy 10.334675 -81.829255) (xy 10.382281 -81.858309)
			(xy 10.425149 -81.893984) (xy 10.462366 -81.935521) (xy 10.493139 -81.982034) (xy 10.516811 -82.032531)
			(xy 10.532879 -82.085938) (xy 10.540999 -82.141114) (xy 10.541508 -82.169) (xy 10.540999 -82.196886)
			(xy 10.532879 -82.252062) (xy 10.516811 -82.305469) (xy 10.493139 -82.355966) (xy 10.462366 -82.402479)
			(xy 10.425149 -82.444016) (xy 10.382281 -82.479691) (xy 10.334675 -82.508745) (xy 10.283346 -82.530557)
			(xy 10.229389 -82.544663) (xy 10.173952 -82.550763) (xy 10.118218 -82.548726) (xy 10.063375 -82.538596)
			(xy 10.010591 -82.520589) (xy 9.960991 -82.495088) (xy 9.915633 -82.462637) (xy 9.875484 -82.423928)
			(xy 9.841398 -82.379785) (xy 9.814102 -82.33115) (xy 9.794179 -82.279059) (xy 9.782053 -82.224622)
			(xy 9.777982 -82.169) (xy 9.652508 -82.169) (xy 9.651999 -82.196886) (xy 9.643879 -82.252062) (xy 9.627811 -82.305469)
			(xy 9.604139 -82.355966) (xy 9.573366 -82.402479) (xy 9.536149 -82.444016) (xy 9.493281 -82.479691)
			(xy 9.445675 -82.508745) (xy 9.394346 -82.530557) (xy 9.340389 -82.544663) (xy 9.284952 -82.550763)
			(xy 9.229218 -82.548726) (xy 9.174375 -82.538596) (xy 9.121591 -82.520589) (xy 9.071991 -82.495088)
			(xy 9.026633 -82.462637) (xy 8.986484 -82.423928) (xy 8.952398 -82.379785) (xy 8.925102 -82.33115)
			(xy 8.905179 -82.279059) (xy 8.893053 -82.224622) (xy 8.888982 -82.169) (xy 7.681976 -82.169) (xy 7.681976 -85.277663)
			(xy 130.434836 -85.277663) (xy 130.434836 -85.213741) (xy 130.442847 -85.150323) (xy 130.458744 -85.088409)
			(xy 130.482276 -85.028976) (xy 130.51307 -84.972961) (xy 130.550643 -84.921246) (xy 130.5944 -84.874649)
			(xy 130.643653 -84.833904) (xy 130.697624 -84.799653) (xy 130.755463 -84.772436) (xy 130.816256 -84.752683)
			(xy 130.879046 -84.740705) (xy 130.942842 -84.736692) (xy 131.006638 -84.740705) (xy 131.069428 -84.752683)
			(xy 131.130221 -84.772436) (xy 131.18806 -84.799653) (xy 131.242031 -84.833904) (xy 131.291284 -84.874649)
			(xy 131.335041 -84.921246) (xy 131.372614 -84.972961) (xy 131.389037 -85.002835) (xy 137.409676 -85.002835)
			(xy 137.409676 -84.938913) (xy 137.417687 -84.875495) (xy 137.433584 -84.813581) (xy 137.457116 -84.754148)
			(xy 137.48791 -84.698133) (xy 137.525483 -84.646418) (xy 137.56924 -84.599821) (xy 137.618493 -84.559076)
			(xy 137.672464 -84.524825) (xy 137.730303 -84.497608) (xy 137.791096 -84.477855) (xy 137.853886 -84.465877)
			(xy 137.917682 -84.461864) (xy 137.981478 -84.465877) (xy 138.044268 -84.477855) (xy 138.105061 -84.497608)
			(xy 138.1629 -84.524825) (xy 138.216871 -84.559076) (xy 138.266124 -84.599821) (xy 138.309881 -84.646418)
			(xy 138.347454 -84.698133) (xy 138.378248 -84.754148) (xy 138.40178 -84.813581) (xy 138.417677 -84.875495)
			(xy 138.425688 -84.938913) (xy 138.42619 -84.970874) (xy 138.425688 -85.002835) (xy 138.417677 -85.066253)
			(xy 138.40178 -85.128167) (xy 138.378248 -85.1876) (xy 138.347454 -85.243615) (xy 138.309881 -85.29533)
			(xy 138.266124 -85.341927) (xy 138.216871 -85.382672) (xy 138.1629 -85.416923) (xy 138.105061 -85.44414)
			(xy 138.044268 -85.463893) (xy 137.981478 -85.475871) (xy 137.917682 -85.479885) (xy 137.853886 -85.475871)
			(xy 137.791096 -85.463893) (xy 137.730303 -85.44414) (xy 137.672464 -85.416923) (xy 137.618493 -85.382672)
			(xy 137.56924 -85.341927) (xy 137.525483 -85.29533) (xy 137.48791 -85.243615) (xy 137.457116 -85.1876)
			(xy 137.433584 -85.128167) (xy 137.417687 -85.066253) (xy 137.409676 -85.002835) (xy 131.389037 -85.002835)
			(xy 131.403408 -85.028976) (xy 131.42694 -85.088409) (xy 131.442837 -85.150323) (xy 131.450848 -85.213741)
			(xy 131.45135 -85.245702) (xy 131.450848 -85.277663) (xy 131.442837 -85.341081) (xy 131.42694 -85.402995)
			(xy 131.403408 -85.462428) (xy 131.372614 -85.518443) (xy 131.335041 -85.570158) (xy 131.291284 -85.616755)
			(xy 131.242031 -85.6575) (xy 131.18806 -85.691751) (xy 131.130221 -85.718968) (xy 131.069428 -85.738721)
			(xy 131.006638 -85.750699) (xy 130.942842 -85.754713) (xy 130.879046 -85.750699) (xy 130.816256 -85.738721)
			(xy 130.755463 -85.718968) (xy 130.697624 -85.691751) (xy 130.643653 -85.6575) (xy 130.5944 -85.616755)
			(xy 130.550643 -85.570158) (xy 130.51307 -85.518443) (xy 130.482276 -85.462428) (xy 130.458744 -85.402995)
			(xy 130.442847 -85.341081) (xy 130.434836 -85.277663) (xy 7.681976 -85.277663) (xy 7.681976 -89.712249)
			(xy 48.410362 -89.712249) (xy 48.410362 -89.648327) (xy 48.418373 -89.584909) (xy 48.43427 -89.522995)
			(xy 48.457802 -89.463562) (xy 48.488596 -89.407547) (xy 48.526169 -89.355832) (xy 48.569926 -89.309235)
			(xy 48.619179 -89.26849) (xy 48.67315 -89.234239) (xy 48.730989 -89.207022) (xy 48.791782 -89.187269)
			(xy 48.854572 -89.175291) (xy 48.918368 -89.171278) (xy 48.982164 -89.175291) (xy 49.044954 -89.187269)
			(xy 49.105747 -89.207022) (xy 49.163586 -89.234239) (xy 49.217557 -89.26849) (xy 49.26681 -89.309235)
			(xy 49.310567 -89.355832) (xy 49.34814 -89.407547) (xy 49.378934 -89.463562) (xy 49.402466 -89.522995)
			(xy 49.418363 -89.584909) (xy 49.426374 -89.648327) (xy 49.426876 -89.680288) (xy 49.426374 -89.712249)
			(xy 49.418363 -89.775667) (xy 49.402466 -89.837581) (xy 49.378934 -89.897014) (xy 49.34814 -89.953029)
			(xy 49.310567 -90.004744) (xy 49.26681 -90.051341) (xy 49.217557 -90.092086) (xy 49.163586 -90.126337)
			(xy 49.105747 -90.153554) (xy 49.044954 -90.173307) (xy 48.982164 -90.185285) (xy 48.918368 -90.189299)
			(xy 48.854572 -90.185285) (xy 48.791782 -90.173307) (xy 48.730989 -90.153554) (xy 48.67315 -90.126337)
			(xy 48.619179 -90.092086) (xy 48.569926 -90.051341) (xy 48.526169 -90.004744) (xy 48.488596 -89.953029)
			(xy 48.457802 -89.897014) (xy 48.43427 -89.837581) (xy 48.418373 -89.775667) (xy 48.410362 -89.712249)
			(xy 7.681976 -89.712249) (xy 7.681976 -90.643456) (xy 118.247922 -90.643456) (xy 118.248469 -90.610379)
			(xy 118.25703 -90.544782) (xy 118.274028 -90.480849) (xy 118.299176 -90.419662) (xy 118.332048 -90.362254)
			(xy 118.37209 -90.309595) (xy 118.418624 -90.262575) (xy 118.470865 -90.221989) (xy 118.499128 -90.204798)
			(xy 118.509542 -90.198702) (xy 118.522496 -90.17889) (xy 118.533164 -90.086434) (xy 118.533957 -90.074632)
			(xy 118.526022 -90.052382) (xy 118.517924 -90.043762) (xy 118.499652 -90.025684) (xy 118.467613 -89.985492)
			(xy 118.441256 -89.941365) (xy 118.42106 -89.8941) (xy 118.407388 -89.844552) (xy 118.400488 -89.793618)
			(xy 118.400068 -89.767918) (xy 118.400554 -89.740667) (xy 118.40831 -89.686719) (xy 118.423665 -89.634424)
			(xy 118.446307 -89.584847) (xy 118.475773 -89.538997) (xy 118.511464 -89.497806) (xy 118.552655 -89.462115)
			(xy 118.598505 -89.432649) (xy 118.648082 -89.410007) (xy 118.700377 -89.394652) (xy 118.754325 -89.386896)
			(xy 118.808827 -89.386896) (xy 118.862775 -89.394652) (xy 118.91507 -89.410007) (xy 118.964647 -89.432649)
			(xy 119.010497 -89.462115) (xy 119.051688 -89.497806) (xy 119.087379 -89.538997) (xy 119.116845 -89.584847)
			(xy 119.139487 -89.634424) (xy 119.154842 -89.686719) (xy 119.162598 -89.740667) (xy 119.163084 -89.767918)
			(xy 119.162637 -89.795452) (xy 119.154733 -89.84995) (xy 119.139079 -89.902747) (xy 119.130967 -89.920318)
			(xy 123.39955 -89.920318) (xy 123.400076 -89.888273) (xy 123.408127 -89.82469) (xy 123.424103 -89.762623)
			(xy 123.447753 -89.703056) (xy 123.4787 -89.646932) (xy 123.516453 -89.595142) (xy 123.560416 -89.548507)
			(xy 123.60989 -89.507765) (xy 123.664091 -89.473563) (xy 123.69292 -89.459562) (xy 123.705725 -89.453002)
			(xy 123.72739 -89.434098) (xy 123.742916 -89.409897) (xy 123.751066 -89.382323) (xy 123.751193 -89.35357)
			(xy 123.743287 -89.325925) (xy 123.727976 -89.301587) (xy 123.717558 -89.291668) (xy 123.697829 -89.273486)
			(xy 123.663167 -89.232535) (xy 123.634581 -89.187133) (xy 123.612635 -89.138176) (xy 123.59776 -89.086628)
			(xy 123.59025 -89.033506) (xy 123.589796 -89.00668) (xy 123.590282 -88.979429) (xy 123.598038 -88.925481)
			(xy 123.613393 -88.873186) (xy 123.636035 -88.823609) (xy 123.665501 -88.777759) (xy 123.701192 -88.736568)
			(xy 123.742383 -88.700877) (xy 123.788233 -88.671411) (xy 123.83781 -88.648769) (xy 123.890105 -88.633414)
			(xy 123.944053 -88.625658) (xy 123.998555 -88.625658) (xy 124.052503 -88.633414) (xy 124.104798 -88.648769)
			(xy 124.154375 -88.671411) (xy 124.200225 -88.700877) (xy 124.241416 -88.736568) (xy 124.277107 -88.777759)
			(xy 124.306573 -88.823609) (xy 124.329215 -88.873186) (xy 124.34457 -88.925481) (xy 124.352326 -88.979429)
			(xy 124.352812 -89.00668) (xy 124.352315 -89.033439) (xy 124.344843 -89.086434) (xy 124.330043 -89.137865)
			(xy 124.326938 -89.144813) (xy 134.927588 -89.144813) (xy 134.927588 -89.080891) (xy 134.935599 -89.017473)
			(xy 134.951496 -88.955559) (xy 134.975028 -88.896126) (xy 135.005822 -88.840111) (xy 135.043395 -88.788396)
			(xy 135.087152 -88.741799) (xy 135.136405 -88.701054) (xy 135.190376 -88.666803) (xy 135.248215 -88.639586)
			(xy 135.309008 -88.619833) (xy 135.371798 -88.607855) (xy 135.435594 -88.603842) (xy 135.49939 -88.607855)
			(xy 135.56218 -88.619833) (xy 135.622973 -88.639586) (xy 135.680812 -88.666803) (xy 135.734783 -88.701054)
			(xy 135.784036 -88.741799) (xy 135.827793 -88.788396) (xy 135.865366 -88.840111) (xy 135.89616 -88.896126)
			(xy 135.919692 -88.955559) (xy 135.935589 -89.017473) (xy 135.9436 -89.080891) (xy 135.94386 -89.097466)
			(xy 155.336625 -89.097466) (xy 155.341835 -89.034603) (xy 155.354782 -88.972867) (xy 155.375265 -88.913207)
			(xy 155.40297 -88.856539) (xy 155.437472 -88.803733) (xy 155.478241 -88.755599) (xy 155.524651 -88.712879)
			(xy 155.575988 -88.676227) (xy 155.631464 -88.646206) (xy 155.690228 -88.623278) (xy 155.751377 -88.607794)
			(xy 155.813971 -88.599993) (xy 155.84551 -88.599518) (xy 155.85753 -88.599585) (xy 155.881544 -88.60073)
			(xy 155.893516 -88.601804) (xy 155.907251 -88.602646) (xy 155.934332 -88.597833) (xy 155.959143 -88.585961)
			(xy 155.979881 -88.567892) (xy 155.99504 -88.544941) (xy 156.003517 -88.518774) (xy 156.004696 -88.491294)
			(xy 155.998492 -88.464497) (xy 155.992322 -88.452198) (xy 155.977875 -88.424127) (xy 155.957384 -88.364418)
			(xy 155.946998 -88.302152) (xy 155.946348 -88.270588) (xy 155.946834 -88.243337) (xy 155.95459 -88.189389)
			(xy 155.969945 -88.137094) (xy 155.992587 -88.087517) (xy 156.022053 -88.041667) (xy 156.057744 -88.000476)
			(xy 156.098935 -87.964785) (xy 156.144785 -87.935319) (xy 156.194362 -87.912677) (xy 156.246657 -87.897322)
			(xy 156.300605 -87.889566) (xy 156.355107 -87.889566) (xy 156.409055 -87.897322) (xy 156.46135 -87.912677)
			(xy 156.510927 -87.935319) (xy 156.556777 -87.964785) (xy 156.597968 -88.000476) (xy 156.633659 -88.041667)
			(xy 156.663125 -88.087517) (xy 156.685767 -88.137094) (xy 156.701122 -88.189389) (xy 156.708878 -88.243337)
			(xy 156.709364 -88.270588) (xy 156.708945 -88.297328) (xy 156.701452 -88.35028) (xy 156.686639 -88.401667)
			(xy 156.664797 -88.450483) (xy 156.636352 -88.495771) (xy 156.601864 -88.536643) (xy 156.562006 -88.572301)
			(xy 156.51756 -88.602044) (xy 156.469397 -88.62529) (xy 156.41846 -88.641584) (xy 156.365747 -88.650606)
			(xy 156.339032 -88.651842) (xy 156.325274 -88.652627) (xy 156.298945 -88.660737) (xy 156.275742 -88.675588)
			(xy 156.257352 -88.696101) (xy 156.245113 -88.720782) (xy 156.239916 -88.747837) (xy 156.24214 -88.775297)
			(xy 156.251621 -88.801163) (xy 156.259276 -88.812624) (xy 156.277226 -88.838557) (xy 156.307253 -88.894021)
			(xy 156.330194 -88.952772) (xy 156.345698 -89.013908) (xy 156.353527 -89.076491) (xy 156.354018 -89.108026)
			(xy 156.353505 -89.139565) (xy 156.345699 -89.202159) (xy 156.330211 -89.263306) (xy 156.307279 -89.322068)
			(xy 156.277254 -89.377543) (xy 156.240599 -89.428877) (xy 156.197875 -89.475284) (xy 156.149739 -89.516049)
			(xy 156.09693 -89.550547) (xy 156.04026 -89.578249) (xy 155.980598 -89.598728) (xy 155.918862 -89.61167)
			(xy 155.855998 -89.616876) (xy 155.792974 -89.614267) (xy 155.730756 -89.603882) (xy 155.670301 -89.585881)
			(xy 155.612536 -89.560541) (xy 155.55835 -89.52825) (xy 155.508573 -89.489504) (xy 155.463972 -89.4449)
			(xy 155.42523 -89.395121) (xy 155.392943 -89.340932) (xy 155.367606 -89.283165) (xy 155.34961 -89.222709)
			(xy 155.339229 -89.16049) (xy 155.336625 -89.097466) (xy 135.94386 -89.097466) (xy 135.944102 -89.112852)
			(xy 135.9436 -89.144813) (xy 135.935589 -89.208231) (xy 135.919692 -89.270145) (xy 135.89616 -89.329578)
			(xy 135.865366 -89.385593) (xy 135.827793 -89.437308) (xy 135.784036 -89.483905) (xy 135.734783 -89.52465)
			(xy 135.680812 -89.558901) (xy 135.622973 -89.586118) (xy 135.56218 -89.605871) (xy 135.49939 -89.617849)
			(xy 135.435594 -89.621863) (xy 135.371798 -89.617849) (xy 135.309008 -89.605871) (xy 135.248215 -89.586118)
			(xy 135.190376 -89.558901) (xy 135.136405 -89.52465) (xy 135.087152 -89.483905) (xy 135.043395 -89.437308)
			(xy 135.005822 -89.385593) (xy 134.975028 -89.329578) (xy 134.951496 -89.270145) (xy 134.935599 -89.208231)
			(xy 134.927588 -89.144813) (xy 124.326938 -89.144813) (xy 124.308205 -89.186725) (xy 124.279756 -89.232056)
			(xy 124.245256 -89.27297) (xy 124.205379 -89.308664) (xy 124.183394 -89.323926) (xy 124.171654 -89.332253)
			(xy 124.153115 -89.354261) (xy 124.141463 -89.380571) (xy 124.137624 -89.409089) (xy 124.141903 -89.437544)
			(xy 124.153962 -89.46367) (xy 124.172838 -89.485389) (xy 124.184664 -89.493598) (xy 124.210975 -89.511207)
			(xy 124.259412 -89.551978) (xy 124.302414 -89.598447) (xy 124.339314 -89.649895) (xy 124.369544 -89.705524)
			(xy 124.392634 -89.764476) (xy 124.408228 -89.825838) (xy 124.416085 -89.888662) (xy 124.416566 -89.920318)
			(xy 124.416064 -89.952279) (xy 124.408053 -90.015697) (xy 124.392156 -90.077611) (xy 124.368624 -90.137044)
			(xy 124.33783 -90.193059) (xy 124.300257 -90.244774) (xy 124.2565 -90.291371) (xy 124.207247 -90.332116)
			(xy 124.153276 -90.366367) (xy 124.095437 -90.393584) (xy 124.034644 -90.413337) (xy 123.971854 -90.425315)
			(xy 123.908058 -90.429329) (xy 123.844262 -90.425315) (xy 123.781472 -90.413337) (xy 123.720679 -90.393584)
			(xy 123.66284 -90.366367) (xy 123.608869 -90.332116) (xy 123.559616 -90.291371) (xy 123.515859 -90.244774)
			(xy 123.478286 -90.193059) (xy 123.447492 -90.137044) (xy 123.42396 -90.077611) (xy 123.408063 -90.015697)
			(xy 123.400052 -89.952279) (xy 123.39955 -89.920318) (xy 119.130967 -89.920318) (xy 119.115998 -89.952744)
			(xy 119.08597 -89.998905) (xy 119.049619 -90.040271) (xy 119.028972 -90.058494) (xy 119.019828 -90.066368)
			(xy 119.01043 -90.087958) (xy 119.016526 -90.193114) (xy 119.02821 -90.213688) (xy 119.03837 -90.220292)
			(xy 119.064137 -90.237987) (xy 119.111518 -90.27876) (xy 119.153543 -90.325034) (xy 119.189579 -90.376111)
			(xy 119.21908 -90.43122) (xy 119.241603 -90.489531) (xy 119.256807 -90.550163) (xy 119.264464 -90.612201)
			(xy 119.264938 -90.643456) (xy 119.264436 -90.675417) (xy 119.256425 -90.738835) (xy 119.240528 -90.800749)
			(xy 119.216996 -90.860182) (xy 119.186202 -90.916197) (xy 119.148629 -90.967912) (xy 119.104872 -91.014509)
			(xy 119.055619 -91.055254) (xy 119.001648 -91.089505) (xy 118.943809 -91.116722) (xy 118.883016 -91.136475)
			(xy 118.820226 -91.148453) (xy 118.75643 -91.152467) (xy 118.692634 -91.148453) (xy 118.629844 -91.136475)
			(xy 118.569051 -91.116722) (xy 118.511212 -91.089505) (xy 118.457241 -91.055254) (xy 118.407988 -91.014509)
			(xy 118.364231 -90.967912) (xy 118.326658 -90.916197) (xy 118.295864 -90.860182) (xy 118.272332 -90.800749)
			(xy 118.256435 -90.738835) (xy 118.248424 -90.675417) (xy 118.247922 -90.643456) (xy 7.681976 -90.643456)
			(xy 7.681976 -91.658948) (xy 10.491468 -91.658948) (xy 10.495539 -91.603326) (xy 10.507665 -91.548889)
			(xy 10.527588 -91.496798) (xy 10.554884 -91.448163) (xy 10.58897 -91.40402) (xy 10.629119 -91.365311)
			(xy 10.674477 -91.33286) (xy 10.724077 -91.307359) (xy 10.776861 -91.289352) (xy 10.831704 -91.279222)
			(xy 10.887438 -91.277185) (xy 10.942875 -91.283285) (xy 10.996832 -91.297391) (xy 11.048161 -91.319203)
			(xy 11.095767 -91.348257) (xy 11.138635 -91.383932) (xy 11.175852 -91.425469) (xy 11.206625 -91.471982)
			(xy 11.230297 -91.522479) (xy 11.246365 -91.575886) (xy 11.254485 -91.631062) (xy 11.254994 -91.658948)
			(xy 11.513818 -91.658948) (xy 11.517889 -91.603326) (xy 11.530015 -91.548889) (xy 11.549938 -91.496798)
			(xy 11.577234 -91.448163) (xy 11.61132 -91.40402) (xy 11.651469 -91.365311) (xy 11.696827 -91.33286)
			(xy 11.746427 -91.307359) (xy 11.799211 -91.289352) (xy 11.854054 -91.279222) (xy 11.909788 -91.277185)
			(xy 11.965225 -91.283285) (xy 12.019182 -91.297391) (xy 12.070511 -91.319203) (xy 12.118117 -91.348257)
			(xy 12.160985 -91.383932) (xy 12.198202 -91.425469) (xy 12.228975 -91.471982) (xy 12.252647 -91.522479)
			(xy 12.268715 -91.575886) (xy 12.276835 -91.631062) (xy 12.277344 -91.658948) (xy 13.636242 -91.658948)
			(xy 13.640313 -91.603326) (xy 13.652439 -91.548889) (xy 13.672362 -91.496798) (xy 13.699658 -91.448163)
			(xy 13.733744 -91.40402) (xy 13.773893 -91.365311) (xy 13.819251 -91.33286) (xy 13.868851 -91.307359)
			(xy 13.921635 -91.289352) (xy 13.976478 -91.279222) (xy 14.032212 -91.277185) (xy 14.087649 -91.283285)
			(xy 14.141606 -91.297391) (xy 14.192935 -91.319203) (xy 14.240541 -91.348257) (xy 14.283409 -91.383932)
			(xy 14.320626 -91.425469) (xy 14.351399 -91.471982) (xy 14.375071 -91.522479) (xy 14.391139 -91.575886)
			(xy 14.399259 -91.631062) (xy 14.39961 -91.650269) (xy 16.682968 -91.650269) (xy 16.682968 -91.586347)
			(xy 16.690979 -91.522929) (xy 16.706876 -91.461015) (xy 16.730408 -91.401582) (xy 16.761202 -91.345567)
			(xy 16.798775 -91.293852) (xy 16.842532 -91.247255) (xy 16.891785 -91.20651) (xy 16.945756 -91.172259)
			(xy 17.003595 -91.145042) (xy 17.064388 -91.125289) (xy 17.127178 -91.113311) (xy 17.190974 -91.109298)
			(xy 17.25477 -91.113311) (xy 17.31756 -91.125289) (xy 17.378353 -91.145042) (xy 17.436192 -91.172259)
			(xy 17.490163 -91.20651) (xy 17.539416 -91.247255) (xy 17.583173 -91.293852) (xy 17.620746 -91.345567)
			(xy 17.65154 -91.401582) (xy 17.675072 -91.461015) (xy 17.690969 -91.522929) (xy 17.69898 -91.586347)
			(xy 17.699482 -91.618308) (xy 17.69898 -91.650269) (xy 17.697726 -91.6602) (xy 58.777886 -91.6602)
			(xy 58.7819 -91.596404) (xy 58.793878 -91.533613) (xy 58.813631 -91.472819) (xy 58.840848 -91.41498)
			(xy 58.8751 -91.361009) (xy 58.915846 -91.311756) (xy 58.962443 -91.267998) (xy 59.014158 -91.230425)
			(xy 59.070174 -91.19963) (xy 59.129608 -91.176099) (xy 59.191522 -91.160202) (xy 59.254941 -91.152191)
			(xy 59.286902 -91.15171) (xy 59.317623 -91.152179) (xy 59.378616 -91.159578) (xy 59.438275 -91.17427)
			(xy 59.49573 -91.196039) (xy 59.550146 -91.224569) (xy 59.5757 -91.241626) (xy 59.584385 -91.247019)
			(xy 59.604402 -91.25108) (xy 59.624419 -91.247019) (xy 59.633104 -91.241626) (xy 59.658662 -91.224574)
			(xy 59.713075 -91.196039) (xy 59.770529 -91.174267) (xy 59.830188 -91.159573) (xy 59.891181 -91.152173)
			(xy 59.921902 -91.15171) (xy 59.953864 -91.152176) (xy 60.017284 -91.160188) (xy 60.0792 -91.176086)
			(xy 60.138635 -91.199618) (xy 60.194652 -91.230414) (xy 60.246368 -91.267988) (xy 60.292966 -91.311747)
			(xy 60.333713 -91.361001) (xy 60.367965 -91.414974) (xy 60.395183 -91.472815) (xy 60.414937 -91.53361)
			(xy 60.426915 -91.596402) (xy 60.430929 -91.6602) (xy 60.428917 -91.692179) (xy 60.556896 -91.692179)
			(xy 60.556896 -91.628257) (xy 60.564907 -91.564839) (xy 60.580804 -91.502925) (xy 60.604336 -91.443492)
			(xy 60.63513 -91.387477) (xy 60.672703 -91.335762) (xy 60.71646 -91.289165) (xy 60.765713 -91.24842)
			(xy 60.819684 -91.214169) (xy 60.877523 -91.186952) (xy 60.938316 -91.167199) (xy 61.001106 -91.155221)
			(xy 61.064902 -91.151208) (xy 61.128698 -91.155221) (xy 61.191488 -91.167199) (xy 61.252281 -91.186952)
			(xy 61.31012 -91.214169) (xy 61.364091 -91.24842) (xy 61.401964 -91.279751) (xy 154.018203 -91.279751)
			(xy 154.018203 -91.225249) (xy 154.02596 -91.171302) (xy 154.041316 -91.119008) (xy 154.063958 -91.069432)
			(xy 154.093426 -91.023583) (xy 154.129118 -90.982394) (xy 154.17031 -90.946705) (xy 154.216162 -90.917242)
			(xy 154.26574 -90.894604) (xy 154.318035 -90.879253) (xy 154.371983 -90.871501) (xy 154.399234 -90.87104)
			(xy 154.425036 -90.871446) (xy 154.476169 -90.878411) (xy 154.525895 -90.892209) (xy 154.573306 -90.912588)
			(xy 154.617535 -90.939175) (xy 154.657773 -90.971485) (xy 154.67584 -90.989912) (xy 154.68346 -90.997786)
			(xy 154.703526 -91.005914) (xy 154.802078 -91.002104) (xy 154.821382 -90.992198) (xy 154.828494 -90.983562)
			(xy 154.849283 -90.958746) (xy 154.896055 -90.913987) (xy 154.948128 -90.875525) (xy 155.00466 -90.843981)
			(xy 155.064738 -90.819864) (xy 155.12739 -90.803566) (xy 155.191603 -90.795348) (xy 155.223972 -90.79484)
			(xy 155.255939 -90.795223) (xy 155.319368 -90.803233) (xy 155.381293 -90.81913) (xy 155.440737 -90.842663)
			(xy 155.496763 -90.87346) (xy 155.548487 -90.911037) (xy 155.595094 -90.954801) (xy 155.635847 -91.004062)
			(xy 155.670105 -91.058041) (xy 155.697328 -91.115889) (xy 155.717085 -91.176693) (xy 155.729065 -91.239493)
			(xy 155.73308 -91.3033) (xy 155.729065 -91.367107) (xy 155.717085 -91.429907) (xy 155.697328 -91.490711)
			(xy 155.682724 -91.521745) (xy 158.647378 -91.521745) (xy 158.647378 -91.457823) (xy 158.655389 -91.394405)
			(xy 158.671286 -91.332491) (xy 158.694818 -91.273058) (xy 158.725612 -91.217043) (xy 158.763185 -91.165328)
			(xy 158.806942 -91.118731) (xy 158.856195 -91.077986) (xy 158.910166 -91.043735) (xy 158.968005 -91.016518)
			(xy 159.028798 -90.996765) (xy 159.091588 -90.984787) (xy 159.155384 -90.980774) (xy 159.21918 -90.984787)
			(xy 159.28197 -90.996765) (xy 159.342763 -91.016518) (xy 159.400602 -91.043735) (xy 159.454573 -91.077986)
			(xy 159.503826 -91.118731) (xy 159.547583 -91.165328) (xy 159.585156 -91.217043) (xy 159.61595 -91.273058)
			(xy 159.639482 -91.332491) (xy 159.655379 -91.394405) (xy 159.66339 -91.457823) (xy 159.663892 -91.489784)
			(xy 159.66339 -91.521745) (xy 159.655379 -91.585163) (xy 159.639482 -91.647077) (xy 159.61595 -91.70651)
			(xy 159.585156 -91.762525) (xy 159.547583 -91.81424) (xy 159.503826 -91.860837) (xy 159.454573 -91.901582)
			(xy 159.400602 -91.935833) (xy 159.342763 -91.96305) (xy 159.28197 -91.982803) (xy 159.21918 -91.994781)
			(xy 159.155384 -91.998795) (xy 159.091588 -91.994781) (xy 159.028798 -91.982803) (xy 158.968005 -91.96305)
			(xy 158.910166 -91.935833) (xy 158.856195 -91.901582) (xy 158.806942 -91.860837) (xy 158.763185 -91.81424)
			(xy 158.725612 -91.762525) (xy 158.694818 -91.70651) (xy 158.671286 -91.647077) (xy 158.655389 -91.585163)
			(xy 158.647378 -91.521745) (xy 155.682724 -91.521745) (xy 155.670105 -91.548559) (xy 155.635847 -91.602538)
			(xy 155.595094 -91.651799) (xy 155.548487 -91.695563) (xy 155.496763 -91.73314) (xy 155.440737 -91.763937)
			(xy 155.381293 -91.78747) (xy 155.319368 -91.803367) (xy 155.255939 -91.811377) (xy 155.223972 -91.811856)
			(xy 155.191729 -91.811381) (xy 155.127761 -91.803218) (xy 155.065337 -91.787039) (xy 155.005457 -91.763103)
			(xy 154.949081 -91.731793) (xy 154.897112 -91.693613) (xy 154.850383 -91.649172) (xy 154.809643 -91.599184)
			(xy 154.792172 -91.57208) (xy 154.786036 -91.563106) (xy 154.768002 -91.551002) (xy 154.757374 -91.548712)
			(xy 154.671014 -91.534742) (xy 154.650186 -91.54033) (xy 154.64155 -91.547188) (xy 154.620992 -91.563547)
			(xy 154.576224 -91.591044) (xy 154.528105 -91.612134) (xy 154.477545 -91.626416) (xy 154.425503 -91.633621)
			(xy 154.399234 -91.634056) (xy 154.371983 -91.633499) (xy 154.318035 -91.625747) (xy 154.26574 -91.610396)
			(xy 154.216162 -91.587758) (xy 154.17031 -91.558295) (xy 154.129118 -91.522606) (xy 154.093426 -91.481417)
			(xy 154.063958 -91.435568) (xy 154.041316 -91.385992) (xy 154.02596 -91.333698) (xy 154.018203 -91.279751)
			(xy 61.401964 -91.279751) (xy 61.413344 -91.289165) (xy 61.457101 -91.335762) (xy 61.494674 -91.387477)
			(xy 61.525468 -91.443492) (xy 61.549 -91.502925) (xy 61.564897 -91.564839) (xy 61.572908 -91.628257)
			(xy 61.57341 -91.660218) (xy 61.572908 -91.692179) (xy 61.564897 -91.755597) (xy 61.549 -91.817511)
			(xy 61.525468 -91.876944) (xy 61.494674 -91.932959) (xy 61.457101 -91.984674) (xy 61.428611 -92.015013)
			(xy 124.05842 -92.015013) (xy 124.05842 -91.951091) (xy 124.066431 -91.887673) (xy 124.082328 -91.825759)
			(xy 124.10586 -91.766326) (xy 124.136654 -91.710311) (xy 124.174227 -91.658596) (xy 124.217984 -91.611999)
			(xy 124.267237 -91.571254) (xy 124.321208 -91.537003) (xy 124.379047 -91.509786) (xy 124.43984 -91.490033)
			(xy 124.50263 -91.478055) (xy 124.566426 -91.474042) (xy 124.630222 -91.478055) (xy 124.693012 -91.490033)
			(xy 124.753805 -91.509786) (xy 124.811644 -91.537003) (xy 124.865615 -91.571254) (xy 124.914868 -91.611999)
			(xy 124.958625 -91.658596) (xy 124.996198 -91.710311) (xy 125.026992 -91.766326) (xy 125.050524 -91.825759)
			(xy 125.066421 -91.887673) (xy 125.074432 -91.951091) (xy 125.074934 -91.983052) (xy 125.074432 -92.015013)
			(xy 125.066421 -92.078431) (xy 125.050524 -92.140345) (xy 125.026992 -92.199778) (xy 124.996198 -92.255793)
			(xy 124.958625 -92.307508) (xy 124.914868 -92.354105) (xy 124.865615 -92.39485) (xy 124.811644 -92.429101)
			(xy 124.753805 -92.456318) (xy 124.693012 -92.476071) (xy 124.630222 -92.488049) (xy 124.566426 -92.492063)
			(xy 124.50263 -92.488049) (xy 124.43984 -92.476071) (xy 124.379047 -92.456318) (xy 124.321208 -92.429101)
			(xy 124.267237 -92.39485) (xy 124.217984 -92.354105) (xy 124.174227 -92.307508) (xy 124.136654 -92.255793)
			(xy 124.10586 -92.199778) (xy 124.082328 -92.140345) (xy 124.066431 -92.078431) (xy 124.05842 -92.015013)
			(xy 61.428611 -92.015013) (xy 61.413344 -92.031271) (xy 61.364091 -92.072016) (xy 61.31012 -92.106267)
			(xy 61.252281 -92.133484) (xy 61.191488 -92.153237) (xy 61.128698 -92.165215) (xy 61.064902 -92.169229)
			(xy 61.001106 -92.165215) (xy 60.938316 -92.153237) (xy 60.877523 -92.133484) (xy 60.819684 -92.106267)
			(xy 60.765713 -92.072016) (xy 60.71646 -92.031271) (xy 60.672703 -91.984674) (xy 60.63513 -91.932959)
			(xy 60.604336 -91.876944) (xy 60.580804 -91.817511) (xy 60.564907 -91.755597) (xy 60.556896 -91.692179)
			(xy 60.428917 -91.692179) (xy 60.426915 -91.723998) (xy 60.414937 -91.78679) (xy 60.395183 -91.847585)
			(xy 60.367965 -91.905426) (xy 60.333713 -91.959399) (xy 60.292966 -92.008653) (xy 60.246368 -92.052412)
			(xy 60.194652 -92.089986) (xy 60.138635 -92.120782) (xy 60.0792 -92.144314) (xy 60.017284 -92.160212)
			(xy 59.953864 -92.168224) (xy 59.921902 -92.168726) (xy 59.891182 -92.168249) (xy 59.830189 -92.16085)
			(xy 59.77053 -92.14616) (xy 59.713075 -92.124393) (xy 59.658659 -92.095866) (xy 59.633104 -92.07881)
			(xy 59.624419 -92.073417) (xy 59.604402 -92.069356) (xy 59.584385 -92.073417) (xy 59.5757 -92.07881)
			(xy 59.550144 -92.095865) (xy 59.49573 -92.124398) (xy 59.438275 -92.14617) (xy 59.378617 -92.160863)
			(xy 59.317623 -92.168263) (xy 59.286902 -92.168726) (xy 59.254941 -92.168209) (xy 59.191522 -92.160198)
			(xy 59.129608 -92.144301) (xy 59.070174 -92.12077) (xy 59.014158 -92.089975) (xy 58.962443 -92.052402)
			(xy 58.915846 -92.008644) (xy 58.8751 -91.959391) (xy 58.840848 -91.90542) (xy 58.813631 -91.847581)
			(xy 58.793878 -91.786787) (xy 58.7819 -91.723996) (xy 58.777886 -91.6602) (xy 17.697726 -91.6602)
			(xy 17.690969 -91.713687) (xy 17.675072 -91.775601) (xy 17.65154 -91.835034) (xy 17.620746 -91.891049)
			(xy 17.583173 -91.942764) (xy 17.539416 -91.989361) (xy 17.490163 -92.030106) (xy 17.436192 -92.064357)
			(xy 17.378353 -92.091574) (xy 17.31756 -92.111327) (xy 17.25477 -92.123305) (xy 17.190974 -92.127319)
			(xy 17.127178 -92.123305) (xy 17.064388 -92.111327) (xy 17.003595 -92.091574) (xy 16.945756 -92.064357)
			(xy 16.891785 -92.030106) (xy 16.842532 -91.989361) (xy 16.798775 -91.942764) (xy 16.761202 -91.891049)
			(xy 16.730408 -91.835034) (xy 16.706876 -91.775601) (xy 16.690979 -91.713687) (xy 16.682968 -91.650269)
			(xy 14.39961 -91.650269) (xy 14.399768 -91.658948) (xy 14.399259 -91.686834) (xy 14.391139 -91.74201)
			(xy 14.375071 -91.795417) (xy 14.351399 -91.845914) (xy 14.320626 -91.892427) (xy 14.283409 -91.933964)
			(xy 14.240541 -91.969639) (xy 14.192935 -91.998693) (xy 14.141606 -92.020505) (xy 14.087649 -92.034611)
			(xy 14.032212 -92.040711) (xy 13.976478 -92.038674) (xy 13.921635 -92.028544) (xy 13.868851 -92.010537)
			(xy 13.819251 -91.985036) (xy 13.773893 -91.952585) (xy 13.733744 -91.913876) (xy 13.699658 -91.869733)
			(xy 13.672362 -91.821098) (xy 13.652439 -91.769007) (xy 13.640313 -91.71457) (xy 13.636242 -91.658948)
			(xy 12.277344 -91.658948) (xy 12.276835 -91.686834) (xy 12.268715 -91.74201) (xy 12.252647 -91.795417)
			(xy 12.228975 -91.845914) (xy 12.198202 -91.892427) (xy 12.160985 -91.933964) (xy 12.118117 -91.969639)
			(xy 12.070511 -91.998693) (xy 12.019182 -92.020505) (xy 11.965225 -92.034611) (xy 11.909788 -92.040711)
			(xy 11.854054 -92.038674) (xy 11.799211 -92.028544) (xy 11.746427 -92.010537) (xy 11.696827 -91.985036)
			(xy 11.651469 -91.952585) (xy 11.61132 -91.913876) (xy 11.577234 -91.869733) (xy 11.549938 -91.821098)
			(xy 11.530015 -91.769007) (xy 11.517889 -91.71457) (xy 11.513818 -91.658948) (xy 11.254994 -91.658948)
			(xy 11.254485 -91.686834) (xy 11.246365 -91.74201) (xy 11.230297 -91.795417) (xy 11.206625 -91.845914)
			(xy 11.175852 -91.892427) (xy 11.138635 -91.933964) (xy 11.095767 -91.969639) (xy 11.048161 -91.998693)
			(xy 10.996832 -92.020505) (xy 10.942875 -92.034611) (xy 10.887438 -92.040711) (xy 10.831704 -92.038674)
			(xy 10.776861 -92.028544) (xy 10.724077 -92.010537) (xy 10.674477 -91.985036) (xy 10.629119 -91.952585)
			(xy 10.58897 -91.913876) (xy 10.554884 -91.869733) (xy 10.527588 -91.821098) (xy 10.507665 -91.769007)
			(xy 10.495539 -91.71457) (xy 10.491468 -91.658948) (xy 7.681976 -91.658948) (xy 7.681976 -92.319559)
			(xy 8.569954 -92.319559) (xy 8.569954 -92.255637) (xy 8.577965 -92.192219) (xy 8.593862 -92.130305)
			(xy 8.617394 -92.070872) (xy 8.648188 -92.014857) (xy 8.685761 -91.963142) (xy 8.729518 -91.916545)
			(xy 8.778771 -91.8758) (xy 8.832742 -91.841549) (xy 8.890581 -91.814332) (xy 8.951374 -91.794579)
			(xy 9.014164 -91.782601) (xy 9.07796 -91.778588) (xy 9.141756 -91.782601) (xy 9.204546 -91.794579)
			(xy 9.265339 -91.814332) (xy 9.323178 -91.841549) (xy 9.377149 -91.8758) (xy 9.426402 -91.916545)
			(xy 9.470159 -91.963142) (xy 9.507732 -92.014857) (xy 9.538526 -92.070872) (xy 9.562058 -92.130305)
			(xy 9.577955 -92.192219) (xy 9.585966 -92.255637) (xy 9.586468 -92.287598) (xy 9.585966 -92.319559)
			(xy 9.577955 -92.382977) (xy 9.562058 -92.444891) (xy 9.538526 -92.504324) (xy 9.507732 -92.560339)
			(xy 9.470159 -92.612054) (xy 9.426402 -92.658651) (xy 9.377149 -92.699396) (xy 9.323178 -92.733647)
			(xy 9.265339 -92.760864) (xy 9.204546 -92.780617) (xy 9.141756 -92.792595) (xy 9.07796 -92.796609)
			(xy 9.014164 -92.792595) (xy 8.951374 -92.780617) (xy 8.890581 -92.760864) (xy 8.832742 -92.733647)
			(xy 8.778771 -92.699396) (xy 8.729518 -92.658651) (xy 8.685761 -92.612054) (xy 8.648188 -92.560339)
			(xy 8.617394 -92.504324) (xy 8.593862 -92.444891) (xy 8.577965 -92.382977) (xy 8.569954 -92.319559)
			(xy 7.681976 -92.319559) (xy 7.681976 -93.438937) (xy 81.891118 -93.438937) (xy 81.891118 -93.375015)
			(xy 81.899129 -93.311597) (xy 81.915026 -93.249683) (xy 81.938558 -93.19025) (xy 81.969352 -93.134235)
			(xy 82.006925 -93.08252) (xy 82.050682 -93.035923) (xy 82.099935 -92.995178) (xy 82.153906 -92.960927)
			(xy 82.211745 -92.93371) (xy 82.272538 -92.913957) (xy 82.335328 -92.901979) (xy 82.399124 -92.897966)
			(xy 82.46292 -92.901979) (xy 82.52571 -92.913957) (xy 82.586503 -92.93371) (xy 82.644342 -92.960927)
			(xy 82.698313 -92.995178) (xy 82.747566 -93.035923) (xy 82.791323 -93.08252) (xy 82.828896 -93.134235)
			(xy 82.85969 -93.19025) (xy 82.865934 -93.206019) (xy 148.375872 -93.206019) (xy 148.375872 -93.142097)
			(xy 148.383883 -93.078679) (xy 148.39978 -93.016765) (xy 148.423312 -92.957332) (xy 148.454106 -92.901317)
			(xy 148.491679 -92.849602) (xy 148.535436 -92.803005) (xy 148.584689 -92.76226) (xy 148.63866 -92.728009)
			(xy 148.696499 -92.700792) (xy 148.757292 -92.681039) (xy 148.820082 -92.669061) (xy 148.883878 -92.665048)
			(xy 148.947674 -92.669061) (xy 149.010464 -92.681039) (xy 149.071257 -92.700792) (xy 149.129096 -92.728009)
			(xy 149.183067 -92.76226) (xy 149.23232 -92.803005) (xy 149.276077 -92.849602) (xy 149.31365 -92.901317)
			(xy 149.344444 -92.957332) (xy 149.367976 -93.016765) (xy 149.383873 -93.078679) (xy 149.391884 -93.142097)
			(xy 149.392386 -93.174058) (xy 149.391884 -93.206019) (xy 149.383873 -93.269437) (xy 149.367976 -93.331351)
			(xy 149.344444 -93.390784) (xy 149.31365 -93.446799) (xy 149.276077 -93.498514) (xy 149.23232 -93.545111)
			(xy 149.183067 -93.585856) (xy 149.129096 -93.620107) (xy 149.071257 -93.647324) (xy 149.010464 -93.667077)
			(xy 148.947674 -93.679055) (xy 148.883878 -93.683069) (xy 148.820082 -93.679055) (xy 148.757292 -93.667077)
			(xy 148.696499 -93.647324) (xy 148.63866 -93.620107) (xy 148.584689 -93.585856) (xy 148.535436 -93.545111)
			(xy 148.491679 -93.498514) (xy 148.454106 -93.446799) (xy 148.423312 -93.390784) (xy 148.39978 -93.331351)
			(xy 148.383883 -93.269437) (xy 148.375872 -93.206019) (xy 82.865934 -93.206019) (xy 82.883222 -93.249683)
			(xy 82.899119 -93.311597) (xy 82.90713 -93.375015) (xy 82.907632 -93.406976) (xy 82.90713 -93.438937)
			(xy 82.899119 -93.502355) (xy 82.883222 -93.564269) (xy 82.85969 -93.623702) (xy 82.828896 -93.679717)
			(xy 82.791323 -93.731432) (xy 82.747566 -93.778029) (xy 82.698313 -93.818774) (xy 82.644342 -93.853025)
			(xy 82.586503 -93.880242) (xy 82.539147 -93.895629) (xy 156.726884 -93.895629) (xy 156.726884 -93.831707)
			(xy 156.734895 -93.768289) (xy 156.750792 -93.706375) (xy 156.774324 -93.646942) (xy 156.805118 -93.590927)
			(xy 156.842691 -93.539212) (xy 156.886448 -93.492615) (xy 156.935701 -93.45187) (xy 156.989672 -93.417619)
			(xy 157.047511 -93.390402) (xy 157.108304 -93.370649) (xy 157.171094 -93.358671) (xy 157.23489 -93.354658)
			(xy 157.298686 -93.358671) (xy 157.361476 -93.370649) (xy 157.422269 -93.390402) (xy 157.480108 -93.417619)
			(xy 157.534079 -93.45187) (xy 157.583332 -93.492615) (xy 157.627089 -93.539212) (xy 157.664662 -93.590927)
			(xy 157.695456 -93.646942) (xy 157.718988 -93.706375) (xy 157.734885 -93.768289) (xy 157.742896 -93.831707)
			(xy 157.743398 -93.863668) (xy 157.742896 -93.895629) (xy 157.734885 -93.959047) (xy 157.718988 -94.020961)
			(xy 157.695456 -94.080394) (xy 157.664662 -94.136409) (xy 157.627089 -94.188124) (xy 157.583332 -94.234721)
			(xy 157.534079 -94.275466) (xy 157.480108 -94.309717) (xy 157.422269 -94.336934) (xy 157.361476 -94.356687)
			(xy 157.298686 -94.368665) (xy 157.23489 -94.372679) (xy 157.171094 -94.368665) (xy 157.108304 -94.356687)
			(xy 157.047511 -94.336934) (xy 156.989672 -94.309717) (xy 156.935701 -94.275466) (xy 156.886448 -94.234721)
			(xy 156.842691 -94.188124) (xy 156.805118 -94.136409) (xy 156.774324 -94.080394) (xy 156.750792 -94.020961)
			(xy 156.734895 -93.959047) (xy 156.726884 -93.895629) (xy 82.539147 -93.895629) (xy 82.52571 -93.899995)
			(xy 82.46292 -93.911973) (xy 82.399124 -93.915987) (xy 82.335328 -93.911973) (xy 82.272538 -93.899995)
			(xy 82.211745 -93.880242) (xy 82.153906 -93.853025) (xy 82.099935 -93.818774) (xy 82.050682 -93.778029)
			(xy 82.006925 -93.731432) (xy 81.969352 -93.679717) (xy 81.938558 -93.623702) (xy 81.915026 -93.564269)
			(xy 81.899129 -93.502355) (xy 81.891118 -93.438937) (xy 7.681976 -93.438937) (xy 7.681976 -94.086426)
			(xy 7.682992 -94.095824) (xy 7.682992 -94.096332) (xy 7.684186 -94.101561) (xy 7.688419 -94.111414)
			(xy 7.691374 -94.11589) (xy 7.696708 -94.12224) (xy 8.370019 -94.795551) (xy 139.45717 -94.795551)
			(xy 139.45717 -94.731629) (xy 139.465181 -94.668211) (xy 139.481078 -94.606297) (xy 139.50461 -94.546864)
			(xy 139.535404 -94.490849) (xy 139.572977 -94.439134) (xy 139.616734 -94.392537) (xy 139.665987 -94.351792)
			(xy 139.719958 -94.317541) (xy 139.777797 -94.290324) (xy 139.83859 -94.270571) (xy 139.90138 -94.258593)
			(xy 139.965176 -94.25458) (xy 140.028972 -94.258593) (xy 140.091762 -94.270571) (xy 140.152555 -94.290324)
			(xy 140.210394 -94.317541) (xy 140.264365 -94.351792) (xy 140.313618 -94.392537) (xy 140.357375 -94.439134)
			(xy 140.394948 -94.490849) (xy 140.425742 -94.546864) (xy 140.449274 -94.606297) (xy 140.465171 -94.668211)
			(xy 140.470385 -94.709488) (xy 142.247112 -94.709488) (xy 142.247614 -94.677527) (xy 142.255625 -94.614109)
			(xy 142.271522 -94.552195) (xy 142.295054 -94.492762) (xy 142.325848 -94.436747) (xy 142.363421 -94.385032)
			(xy 142.407178 -94.338435) (xy 142.456431 -94.29769) (xy 142.510402 -94.263439) (xy 142.568241 -94.236222)
			(xy 142.629034 -94.216469) (xy 142.691824 -94.204491) (xy 142.75562 -94.200478) (xy 142.819416 -94.204491)
			(xy 142.882206 -94.216469) (xy 142.942999 -94.236222) (xy 143.000838 -94.263439) (xy 143.054809 -94.29769)
			(xy 143.104062 -94.338435) (xy 143.147819 -94.385032) (xy 143.185392 -94.436747) (xy 143.216186 -94.492762)
			(xy 143.232185 -94.533169) (xy 148.230584 -94.533169) (xy 148.230584 -94.469247) (xy 148.238595 -94.405829)
			(xy 148.254492 -94.343915) (xy 148.278024 -94.284482) (xy 148.308818 -94.228467) (xy 148.346391 -94.176752)
			(xy 148.390148 -94.130155) (xy 148.439401 -94.08941) (xy 148.493372 -94.055159) (xy 148.551211 -94.027942)
			(xy 148.612004 -94.008189) (xy 148.674794 -93.996211) (xy 148.73859 -93.992198) (xy 148.802386 -93.996211)
			(xy 148.865176 -94.008189) (xy 148.925969 -94.027942) (xy 148.983808 -94.055159) (xy 149.037779 -94.08941)
			(xy 149.087032 -94.130155) (xy 149.130789 -94.176752) (xy 149.168362 -94.228467) (xy 149.199156 -94.284482)
			(xy 149.222688 -94.343915) (xy 149.238585 -94.405829) (xy 149.246596 -94.469247) (xy 149.247098 -94.501208)
			(xy 149.246596 -94.533169) (xy 149.238585 -94.596587) (xy 149.234977 -94.610639) (xy 151.48915 -94.610639)
			(xy 151.48915 -94.546717) (xy 151.497161 -94.483299) (xy 151.513058 -94.421385) (xy 151.53659 -94.361952)
			(xy 151.567384 -94.305937) (xy 151.604957 -94.254222) (xy 151.648714 -94.207625) (xy 151.697967 -94.16688)
			(xy 151.751938 -94.132629) (xy 151.809777 -94.105412) (xy 151.87057 -94.085659) (xy 151.93336 -94.073681)
			(xy 151.997156 -94.069668) (xy 152.060952 -94.073681) (xy 152.123742 -94.085659) (xy 152.184535 -94.105412)
			(xy 152.242374 -94.132629) (xy 152.296345 -94.16688) (xy 152.345598 -94.207625) (xy 152.389355 -94.254222)
			(xy 152.426928 -94.305937) (xy 152.457722 -94.361952) (xy 152.481254 -94.421385) (xy 152.497151 -94.483299)
			(xy 152.505162 -94.546717) (xy 152.505664 -94.578678) (xy 152.505162 -94.610639) (xy 152.497151 -94.674057)
			(xy 152.481254 -94.735971) (xy 152.457722 -94.795404) (xy 152.426928 -94.851419) (xy 152.389355 -94.903134)
			(xy 152.345598 -94.949731) (xy 152.296345 -94.990476) (xy 152.242374 -95.024727) (xy 152.184535 -95.051944)
			(xy 152.123742 -95.071697) (xy 152.060952 -95.083675) (xy 151.997156 -95.087689) (xy 151.93336 -95.083675)
			(xy 151.87057 -95.071697) (xy 151.809777 -95.051944) (xy 151.751938 -95.024727) (xy 151.697967 -94.990476)
			(xy 151.648714 -94.949731) (xy 151.604957 -94.903134) (xy 151.567384 -94.851419) (xy 151.53659 -94.795404)
			(xy 151.513058 -94.735971) (xy 151.497161 -94.674057) (xy 151.48915 -94.610639) (xy 149.234977 -94.610639)
			(xy 149.222688 -94.658501) (xy 149.199156 -94.717934) (xy 149.168362 -94.773949) (xy 149.130789 -94.825664)
			(xy 149.087032 -94.872261) (xy 149.037779 -94.913006) (xy 148.983808 -94.947257) (xy 148.925969 -94.974474)
			(xy 148.865176 -94.994227) (xy 148.802386 -95.006205) (xy 148.73859 -95.010219) (xy 148.674794 -95.006205)
			(xy 148.612004 -94.994227) (xy 148.551211 -94.974474) (xy 148.493372 -94.947257) (xy 148.439401 -94.913006)
			(xy 148.390148 -94.872261) (xy 148.346391 -94.825664) (xy 148.308818 -94.773949) (xy 148.278024 -94.717934)
			(xy 148.254492 -94.658501) (xy 148.238595 -94.596587) (xy 148.230584 -94.533169) (xy 143.232185 -94.533169)
			(xy 143.239718 -94.552195) (xy 143.255615 -94.614109) (xy 143.263626 -94.677527) (xy 143.264128 -94.709488)
			(xy 143.263625 -94.741234) (xy 143.255711 -94.80423) (xy 143.240019 -94.865751) (xy 143.216791 -94.924841)
			(xy 143.186389 -94.980581) (xy 143.149286 -95.032103) (xy 143.106058 -95.078606) (xy 143.057379 -95.119367)
			(xy 143.030956 -95.13697) (xy 143.019327 -95.144956) (xy 143.000644 -95.166078) (xy 142.988463 -95.19151)
			(xy 142.983717 -95.219307) (xy 142.986768 -95.247341) (xy 142.997384 -95.273465) (xy 143.014751 -95.295682)
			(xy 143.025876 -95.304356) (xy 143.049667 -95.322474) (xy 143.091854 -95.364853) (xy 143.126915 -95.413293)
			(xy 143.153992 -95.466609) (xy 143.172423 -95.523495) (xy 143.181756 -95.582559) (xy 143.18234 -95.612458)
			(xy 151.562814 -95.612458) (xy 151.566885 -95.556836) (xy 151.579011 -95.502399) (xy 151.598934 -95.450308)
			(xy 151.62623 -95.401673) (xy 151.660316 -95.35753) (xy 151.700465 -95.318821) (xy 151.745823 -95.28637)
			(xy 151.795423 -95.260869) (xy 151.848207 -95.242862) (xy 151.90305 -95.232732) (xy 151.958784 -95.230695)
			(xy 152.014221 -95.236795) (xy 152.068178 -95.250901) (xy 152.119507 -95.272713) (xy 152.167113 -95.301767)
			(xy 152.209981 -95.337442) (xy 152.247198 -95.378979) (xy 152.277971 -95.425492) (xy 152.301643 -95.475989)
			(xy 152.317711 -95.529396) (xy 152.325831 -95.584572) (xy 152.32634 -95.612458) (xy 152.325831 -95.640344)
			(xy 152.317711 -95.69552) (xy 152.301643 -95.748927) (xy 152.277971 -95.799424) (xy 152.247198 -95.845937)
			(xy 152.209981 -95.887474) (xy 152.167113 -95.923149) (xy 152.119507 -95.952203) (xy 152.068178 -95.974015)
			(xy 152.014221 -95.988121) (xy 151.958784 -95.994221) (xy 151.90305 -95.992184) (xy 151.848207 -95.982054)
			(xy 151.795423 -95.964047) (xy 151.745823 -95.938546) (xy 151.700465 -95.906095) (xy 151.660316 -95.867386)
			(xy 151.62623 -95.823243) (xy 151.598934 -95.774608) (xy 151.579011 -95.722517) (xy 151.566885 -95.66808)
			(xy 151.562814 -95.612458) (xy 143.18234 -95.612458) (xy 143.181854 -95.639709) (xy 143.174098 -95.693657)
			(xy 143.158743 -95.745952) (xy 143.136101 -95.795529) (xy 143.106635 -95.841379) (xy 143.070944 -95.88257)
			(xy 143.029753 -95.918261) (xy 142.983903 -95.947727) (xy 142.934326 -95.970369) (xy 142.882031 -95.985724)
			(xy 142.828083 -95.99348) (xy 142.773581 -95.99348) (xy 142.719633 -95.985724) (xy 142.667338 -95.970369)
			(xy 142.617761 -95.947727) (xy 142.571911 -95.918261) (xy 142.53072 -95.88257) (xy 142.495029 -95.841379)
			(xy 142.465563 -95.795529) (xy 142.442921 -95.745952) (xy 142.427566 -95.693657) (xy 142.41981 -95.639709)
			(xy 142.419324 -95.612458) (xy 142.419771 -95.585754) (xy 142.427224 -95.53287) (xy 142.441979 -95.481541)
			(xy 142.463747 -95.432772) (xy 142.492103 -95.387514) (xy 142.526493 -95.346652) (xy 142.54607 -95.328486)
			(xy 142.556204 -95.318688) (xy 142.57124 -95.294863) (xy 142.579194 -95.267837) (xy 142.579459 -95.239666)
			(xy 142.572015 -95.212494) (xy 142.55743 -95.188391) (xy 142.536813 -95.169191) (xy 142.52448 -95.16237)
			(xy 142.497054 -95.147798) (xy 142.445577 -95.113056) (xy 142.398717 -95.072302) (xy 142.357171 -95.026141)
			(xy 142.321558 -94.975262) (xy 142.29241 -94.920423) (xy 142.270161 -94.862442) (xy 142.255142 -94.802181)
			(xy 142.247577 -94.74054) (xy 142.247112 -94.709488) (xy 140.470385 -94.709488) (xy 140.473182 -94.731629)
			(xy 140.473684 -94.76359) (xy 140.473182 -94.795551) (xy 140.465171 -94.858969) (xy 140.449274 -94.920883)
			(xy 140.425742 -94.980316) (xy 140.394948 -95.036331) (xy 140.357375 -95.088046) (xy 140.313618 -95.134643)
			(xy 140.264365 -95.175388) (xy 140.210394 -95.209639) (xy 140.152555 -95.236856) (xy 140.091762 -95.256609)
			(xy 140.028972 -95.268587) (xy 139.965176 -95.272601) (xy 139.90138 -95.268587) (xy 139.83859 -95.256609)
			(xy 139.777797 -95.236856) (xy 139.719958 -95.209639) (xy 139.665987 -95.175388) (xy 139.616734 -95.134643)
			(xy 139.572977 -95.088046) (xy 139.535404 -95.036331) (xy 139.50461 -94.980316) (xy 139.481078 -94.920883)
			(xy 139.465181 -94.858969) (xy 139.45717 -94.795551) (xy 8.370019 -94.795551) (xy 9.085072 -95.510604)
			(xy 21.882098 -95.510604) (xy 21.886169 -95.454982) (xy 21.898295 -95.400545) (xy 21.918218 -95.348454)
			(xy 21.945514 -95.299819) (xy 21.9796 -95.255676) (xy 22.019749 -95.216967) (xy 22.065107 -95.184516)
			(xy 22.114707 -95.159015) (xy 22.167491 -95.141008) (xy 22.222334 -95.130878) (xy 22.278068 -95.128841)
			(xy 22.333505 -95.134941) (xy 22.387462 -95.149047) (xy 22.438791 -95.170859) (xy 22.486397 -95.199913)
			(xy 22.529265 -95.235588) (xy 22.566482 -95.277125) (xy 22.597255 -95.323638) (xy 22.620927 -95.374135)
			(xy 22.636995 -95.427542) (xy 22.645115 -95.482718) (xy 22.645624 -95.510604) (xy 22.645115 -95.53849)
			(xy 22.636995 -95.593666) (xy 22.620927 -95.647073) (xy 22.597255 -95.69757) (xy 22.566482 -95.744083)
			(xy 22.529265 -95.78562) (xy 22.486397 -95.821295) (xy 22.438791 -95.850349) (xy 22.387462 -95.872161)
			(xy 22.333505 -95.886267) (xy 22.278068 -95.892367) (xy 22.222334 -95.89033) (xy 22.167491 -95.8802)
			(xy 22.114707 -95.862193) (xy 22.065107 -95.836692) (xy 22.019749 -95.804241) (xy 21.9796 -95.765532)
			(xy 21.945514 -95.721389) (xy 21.918218 -95.672754) (xy 21.898295 -95.620663) (xy 21.886169 -95.566226)
			(xy 21.882098 -95.510604) (xy 9.085072 -95.510604) (xy 9.497568 -95.9231) (xy 139.622782 -95.9231)
			(xy 139.626853 -95.867478) (xy 139.638979 -95.813041) (xy 139.658902 -95.76095) (xy 139.686198 -95.712315)
			(xy 139.720284 -95.668172) (xy 139.760433 -95.629463) (xy 139.805791 -95.597012) (xy 139.855391 -95.571511)
			(xy 139.908175 -95.553504) (xy 139.963018 -95.543374) (xy 140.018752 -95.541337) (xy 140.074189 -95.547437)
			(xy 140.128146 -95.561543) (xy 140.179475 -95.583355) (xy 140.227081 -95.612409) (xy 140.269949 -95.648084)
			(xy 140.307166 -95.689621) (xy 140.337939 -95.736134) (xy 140.361611 -95.786631) (xy 140.377679 -95.840038)
			(xy 140.385799 -95.895214) (xy 140.386308 -95.9231) (xy 140.385799 -95.950986) (xy 140.377679 -96.006162)
			(xy 140.361611 -96.059569) (xy 140.337939 -96.110066) (xy 140.307166 -96.156579) (xy 140.269949 -96.198116)
			(xy 140.227081 -96.233791) (xy 140.179475 -96.262845) (xy 140.128146 -96.284657) (xy 140.074189 -96.298763)
			(xy 140.018752 -96.304863) (xy 139.963018 -96.302826) (xy 139.908175 -96.292696) (xy 139.855391 -96.274689)
			(xy 139.805791 -96.249188) (xy 139.760433 -96.216737) (xy 139.720284 -96.178028) (xy 139.686198 -96.133885)
			(xy 139.658902 -96.08525) (xy 139.638979 -96.033159) (xy 139.626853 -95.978722) (xy 139.622782 -95.9231)
			(xy 9.497568 -95.9231) (xy 9.9441 -96.369632) (xy 9.948685 -96.373926) (xy 9.959472 -96.380358) (xy 9.965436 -96.382332)
			(xy 9.977882 -96.386142) (xy 9.990328 -96.383602) (xy 10.057508 -96.370415) (xy 10.193185 -96.35201)
			(xy 10.329792 -96.342781) (xy 10.398252 -96.3422) (xy 10.411968 -96.3422) (xy 10.476909 -96.343127)
			(xy 10.606478 -96.352245) (xy 10.735201 -96.369618) (xy 10.862552 -96.395177) (xy 10.927374 -96.412558)
			(xy 147.442172 -96.412558) (xy 147.446243 -96.356936) (xy 147.458369 -96.302499) (xy 147.478292 -96.250408)
			(xy 147.505588 -96.201773) (xy 147.539674 -96.15763) (xy 147.579823 -96.118921) (xy 147.625181 -96.08647)
			(xy 147.674781 -96.060969) (xy 147.727565 -96.042962) (xy 147.782408 -96.032832) (xy 147.838142 -96.030795)
			(xy 147.893579 -96.036895) (xy 147.947536 -96.051001) (xy 147.998865 -96.072813) (xy 148.046471 -96.101867)
			(xy 148.089339 -96.137542) (xy 148.126556 -96.179079) (xy 148.157329 -96.225592) (xy 148.181001 -96.276089)
			(xy 148.197069 -96.329496) (xy 148.205189 -96.384672) (xy 148.205698 -96.412558) (xy 156.586172 -96.412558)
			(xy 156.590243 -96.356936) (xy 156.602369 -96.302499) (xy 156.622292 -96.250408) (xy 156.649588 -96.201773)
			(xy 156.683674 -96.15763) (xy 156.723823 -96.118921) (xy 156.769181 -96.08647) (xy 156.818781 -96.060969)
			(xy 156.871565 -96.042962) (xy 156.926408 -96.032832) (xy 156.982142 -96.030795) (xy 157.037579 -96.036895)
			(xy 157.091536 -96.051001) (xy 157.142865 -96.072813) (xy 157.190471 -96.101867) (xy 157.233339 -96.137542)
			(xy 157.270556 -96.179079) (xy 157.301329 -96.225592) (xy 157.325001 -96.276089) (xy 157.341069 -96.329496)
			(xy 157.349189 -96.384672) (xy 157.349698 -96.412558) (xy 157.349189 -96.440444) (xy 157.341069 -96.49562)
			(xy 157.325001 -96.549027) (xy 157.301329 -96.599524) (xy 157.270556 -96.646037) (xy 157.233339 -96.687574)
			(xy 157.190471 -96.723249) (xy 157.142865 -96.752303) (xy 157.091536 -96.774115) (xy 157.037579 -96.788221)
			(xy 156.982142 -96.794321) (xy 156.926408 -96.792284) (xy 156.871565 -96.782154) (xy 156.818781 -96.764147)
			(xy 156.769181 -96.738646) (xy 156.723823 -96.706195) (xy 156.683674 -96.667486) (xy 156.649588 -96.623343)
			(xy 156.622292 -96.574708) (xy 156.602369 -96.522617) (xy 156.590243 -96.46818) (xy 156.586172 -96.412558)
			(xy 148.205698 -96.412558) (xy 148.205189 -96.440444) (xy 148.197069 -96.49562) (xy 148.181001 -96.549027)
			(xy 148.157329 -96.599524) (xy 148.126556 -96.646037) (xy 148.089339 -96.687574) (xy 148.046471 -96.723249)
			(xy 147.998865 -96.752303) (xy 147.947536 -96.774115) (xy 147.893579 -96.788221) (xy 147.838142 -96.794321)
			(xy 147.782408 -96.792284) (xy 147.727565 -96.782154) (xy 147.674781 -96.764147) (xy 147.625181 -96.738646)
			(xy 147.579823 -96.706195) (xy 147.539674 -96.667486) (xy 147.505588 -96.623343) (xy 147.478292 -96.574708)
			(xy 147.458369 -96.522617) (xy 147.446243 -96.46818) (xy 147.442172 -96.412558) (xy 10.927374 -96.412558)
			(xy 10.988011 -96.428817) (xy 11.111065 -96.470399) (xy 11.231213 -96.519756) (xy 11.347963 -96.576684)
			(xy 11.460839 -96.640953) (xy 11.569381 -96.712298) (xy 11.673144 -96.79043) (xy 11.771706 -96.875029)
			(xy 11.864665 -96.965749) (xy 11.95164 -97.062221) (xy 12.032276 -97.164051) (xy 12.106245 -97.270822)
			(xy 12.140184 -97.326196) (xy 12.144756 -97.333816) (xy 12.146026 -97.336102) (xy 12.155678 -97.342706)
			(xy 12.159723 -97.345265) (xy 12.168545 -97.348973) (xy 12.173204 -97.350072) (xy 12.18311 -97.351596)
			(xy 12.200128 -97.354136) (xy 12.200636 -97.354136) (xy 12.253214 -97.362264) (xy 12.258824 -97.363007)
			(xy 12.270112 -97.362246) (xy 12.275566 -97.36074) (xy 12.285726 -97.357692) (xy 12.293346 -97.351088)
			(xy 12.294616 -97.350072) (xy 12.29487 -97.349818) (xy 12.3159 -97.33188) (xy 12.362159 -97.301624)
			(xy 12.412298 -97.278358) (xy 12.465269 -97.262566) (xy 12.519963 -97.254579) (xy 12.5476 -97.25406)
			(xy 12.574851 -97.254546) (xy 12.628799 -97.262302) (xy 12.681094 -97.277658) (xy 12.730672 -97.300299)
			(xy 12.776523 -97.329765) (xy 12.817713 -97.365457) (xy 12.853405 -97.406647) (xy 12.882871 -97.452498)
			(xy 12.905512 -97.502076) (xy 12.920868 -97.554371) (xy 12.928624 -97.608319) (xy 12.928624 -97.627948)
			(xy 15.198342 -97.627948) (xy 15.202413 -97.572326) (xy 15.214539 -97.517889) (xy 15.234462 -97.465798)
			(xy 15.261758 -97.417163) (xy 15.295844 -97.37302) (xy 15.335993 -97.334311) (xy 15.381351 -97.30186)
			(xy 15.430951 -97.276359) (xy 15.483735 -97.258352) (xy 15.538578 -97.248222) (xy 15.594312 -97.246185)
			(xy 15.649749 -97.252285) (xy 15.703706 -97.266391) (xy 15.755035 -97.288203) (xy 15.802641 -97.317257)
			(xy 15.845509 -97.352932) (xy 15.882726 -97.394469) (xy 15.913499 -97.440982) (xy 15.91851 -97.451672)
			(xy 142.292324 -97.451672) (xy 142.292826 -97.419711) (xy 142.300837 -97.356293) (xy 142.316734 -97.294379)
			(xy 142.340266 -97.234946) (xy 142.37106 -97.178931) (xy 142.408633 -97.127216) (xy 142.45239 -97.080619)
			(xy 142.501643 -97.039874) (xy 142.555614 -97.005623) (xy 142.613453 -96.978406) (xy 142.674246 -96.958653)
			(xy 142.737036 -96.946675) (xy 142.800832 -96.942662) (xy 142.864628 -96.946675) (xy 142.927418 -96.958653)
			(xy 142.988211 -96.978406) (xy 143.04605 -97.005623) (xy 143.100021 -97.039874) (xy 143.149274 -97.080619)
			(xy 143.193031 -97.127216) (xy 143.230604 -97.178931) (xy 143.261398 -97.234946) (xy 143.28493 -97.294379)
			(xy 143.300827 -97.356293) (xy 143.308838 -97.419711) (xy 143.30934 -97.451672) (xy 143.308863 -97.483633)
			(xy 146.172422 -97.483633) (xy 146.172422 -97.419711) (xy 146.180433 -97.356293) (xy 146.19633 -97.294379)
			(xy 146.219862 -97.234946) (xy 146.250656 -97.178931) (xy 146.288229 -97.127216) (xy 146.331986 -97.080619)
			(xy 146.381239 -97.039874) (xy 146.43521 -97.005623) (xy 146.493049 -96.978406) (xy 146.553842 -96.958653)
			(xy 146.616632 -96.946675) (xy 146.680428 -96.942662) (xy 146.744224 -96.946675) (xy 146.807014 -96.958653)
			(xy 146.867807 -96.978406) (xy 146.925646 -97.005623) (xy 146.979617 -97.039874) (xy 147.02887 -97.080619)
			(xy 147.072627 -97.127216) (xy 147.1102 -97.178931) (xy 147.140994 -97.234946) (xy 147.164526 -97.294379)
			(xy 147.180423 -97.356293) (xy 147.188434 -97.419711) (xy 147.188936 -97.451672) (xy 151.436324 -97.451672)
			(xy 151.436826 -97.419711) (xy 151.444837 -97.356293) (xy 151.460734 -97.294379) (xy 151.484266 -97.234946)
			(xy 151.51506 -97.178931) (xy 151.552633 -97.127216) (xy 151.59639 -97.080619) (xy 151.645643 -97.039874)
			(xy 151.699614 -97.005623) (xy 151.757453 -96.978406) (xy 151.818246 -96.958653) (xy 151.881036 -96.946675)
			(xy 151.944832 -96.942662) (xy 152.008628 -96.946675) (xy 152.071418 -96.958653) (xy 152.132211 -96.978406)
			(xy 152.19005 -97.005623) (xy 152.244021 -97.039874) (xy 152.293274 -97.080619) (xy 152.337031 -97.127216)
			(xy 152.374604 -97.178931) (xy 152.405398 -97.234946) (xy 152.42893 -97.294379) (xy 152.444827 -97.356293)
			(xy 152.452838 -97.419711) (xy 152.45334 -97.451672) (xy 152.452863 -97.483633) (xy 155.316422 -97.483633)
			(xy 155.316422 -97.419711) (xy 155.324433 -97.356293) (xy 155.34033 -97.294379) (xy 155.363862 -97.234946)
			(xy 155.394656 -97.178931) (xy 155.432229 -97.127216) (xy 155.475986 -97.080619) (xy 155.525239 -97.039874)
			(xy 155.57921 -97.005623) (xy 155.637049 -96.978406) (xy 155.697842 -96.958653) (xy 155.760632 -96.946675)
			(xy 155.824428 -96.942662) (xy 155.888224 -96.946675) (xy 155.951014 -96.958653) (xy 156.011807 -96.978406)
			(xy 156.069646 -97.005623) (xy 156.123617 -97.039874) (xy 156.17287 -97.080619) (xy 156.216627 -97.127216)
			(xy 156.2542 -97.178931) (xy 156.284994 -97.234946) (xy 156.308526 -97.294379) (xy 156.324423 -97.356293)
			(xy 156.332434 -97.419711) (xy 156.332936 -97.451672) (xy 156.332434 -97.483633) (xy 156.324423 -97.547051)
			(xy 156.308526 -97.608965) (xy 156.284994 -97.668398) (xy 156.2542 -97.724413) (xy 156.216627 -97.776128)
			(xy 156.175455 -97.819972) (xy 164.463222 -97.819972) (xy 164.463661 -97.789586) (xy 164.470904 -97.729246)
			(xy 164.485283 -97.670199) (xy 164.506594 -97.613286) (xy 164.534533 -97.559316) (xy 164.568702 -97.509059)
			(xy 164.608615 -97.46323) (xy 164.630862 -97.442528) (xy 164.637141 -97.436387) (xy 164.645445 -97.420924)
			(xy 164.647118 -97.412302) (xy 164.651436 -97.382584) (xy 164.652315 -97.374016) (xy 164.648933 -97.357138)
			(xy 164.644832 -97.349564) (xy 164.632164 -97.327393) (xy 164.612214 -97.280387) (xy 164.598712 -97.23114)
			(xy 164.591901 -97.180532) (xy 164.591492 -97.155) (xy 164.591978 -97.127749) (xy 164.599734 -97.073801)
			(xy 164.615089 -97.021506) (xy 164.637731 -96.971929) (xy 164.667197 -96.926079) (xy 164.702888 -96.884888)
			(xy 164.744079 -96.849197) (xy 164.789929 -96.819731) (xy 164.839506 -96.797089) (xy 164.891801 -96.781734)
			(xy 164.945749 -96.773978) (xy 165.000251 -96.773978) (xy 165.054199 -96.781734) (xy 165.106494 -96.797089)
			(xy 165.156071 -96.819731) (xy 165.201921 -96.849197) (xy 165.243112 -96.884888) (xy 165.278803 -96.926079)
			(xy 165.308269 -96.971929) (xy 165.330911 -97.021506) (xy 165.346266 -97.073801) (xy 165.354022 -97.127749)
			(xy 165.354508 -97.155) (xy 165.354508 -97.155254) (xy 165.354071 -97.180929) (xy 165.3472 -97.231816)
			(xy 165.333575 -97.281325) (xy 165.313442 -97.328563) (xy 165.30066 -97.350834) (xy 165.296489 -97.358387)
			(xy 165.292975 -97.375266) (xy 165.293802 -97.383854) (xy 165.29812 -97.413572) (xy 165.299708 -97.422237)
			(xy 165.307892 -97.437823) (xy 165.314122 -97.444052) (xy 165.336203 -97.464705) (xy 165.375766 -97.510429)
			(xy 165.409625 -97.560522) (xy 165.437303 -97.614279) (xy 165.458409 -97.670939) (xy 165.472644 -97.729703)
			(xy 165.479808 -97.78974) (xy 165.480238 -97.819972) (xy 165.479736 -97.851933) (xy 165.471725 -97.915351)
			(xy 165.455828 -97.977265) (xy 165.432296 -98.036698) (xy 165.401502 -98.092713) (xy 165.363929 -98.144428)
			(xy 165.320172 -98.191025) (xy 165.270919 -98.23177) (xy 165.216948 -98.266021) (xy 165.159109 -98.293238)
			(xy 165.098316 -98.312991) (xy 165.035526 -98.324969) (xy 164.97173 -98.328983) (xy 164.907934 -98.324969)
			(xy 164.845144 -98.312991) (xy 164.784351 -98.293238) (xy 164.726512 -98.266021) (xy 164.672541 -98.23177)
			(xy 164.623288 -98.191025) (xy 164.579531 -98.144428) (xy 164.541958 -98.092713) (xy 164.511164 -98.036698)
			(xy 164.487632 -97.977265) (xy 164.471735 -97.915351) (xy 164.463724 -97.851933) (xy 164.463222 -97.819972)
			(xy 156.175455 -97.819972) (xy 156.17287 -97.822725) (xy 156.123617 -97.86347) (xy 156.069646 -97.897721)
			(xy 156.011807 -97.924938) (xy 155.951014 -97.944691) (xy 155.888224 -97.956669) (xy 155.824428 -97.960683)
			(xy 155.760632 -97.956669) (xy 155.697842 -97.944691) (xy 155.637049 -97.924938) (xy 155.57921 -97.897721)
			(xy 155.525239 -97.86347) (xy 155.475986 -97.822725) (xy 155.432229 -97.776128) (xy 155.394656 -97.724413)
			(xy 155.363862 -97.668398) (xy 155.34033 -97.608965) (xy 155.324433 -97.547051) (xy 155.316422 -97.483633)
			(xy 152.452863 -97.483633) (xy 152.452842 -97.485006) (xy 152.444133 -97.551103) (xy 152.42686 -97.615494)
			(xy 152.401321 -97.677076) (xy 152.367952 -97.734793) (xy 152.327327 -97.787653) (xy 152.280141 -97.83475)
			(xy 152.227206 -97.875278) (xy 152.198578 -97.892362) (xy 152.186572 -97.899734) (xy 152.166932 -97.919923)
			(xy 152.153551 -97.944708) (xy 152.147444 -97.972204) (xy 152.149076 -98.000322) (xy 152.158322 -98.026928)
			(xy 152.17448 -98.049998) (xy 152.185116 -98.05924) (xy 152.206786 -98.077448) (xy 152.244992 -98.119206)
			(xy 152.276612 -98.166148) (xy 152.300953 -98.217246) (xy 152.317479 -98.271379) (xy 152.32583 -98.327358)
			(xy 152.32634 -98.355658) (xy 152.325854 -98.382909) (xy 152.318098 -98.436857) (xy 152.302743 -98.489152)
			(xy 152.280101 -98.538729) (xy 152.250635 -98.584579) (xy 152.214944 -98.62577) (xy 152.173753 -98.661461)
			(xy 152.127903 -98.690927) (xy 152.078326 -98.713569) (xy 152.026031 -98.728924) (xy 151.972083 -98.73668)
			(xy 151.917581 -98.73668) (xy 151.863633 -98.728924) (xy 151.811338 -98.713569) (xy 151.761761 -98.690927)
			(xy 151.715911 -98.661461) (xy 151.67472 -98.62577) (xy 151.639029 -98.584579) (xy 151.609563 -98.538729)
			(xy 151.586921 -98.489152) (xy 151.571566 -98.436857) (xy 151.56381 -98.382909) (xy 151.563324 -98.355658)
			(xy 151.563876 -98.327362) (xy 151.572235 -98.271391) (xy 151.588763 -98.217266) (xy 151.613099 -98.166174)
			(xy 151.64471 -98.119233) (xy 151.682902 -98.077472) (xy 151.704548 -98.05924) (xy 151.715202 -98.050006)
			(xy 151.731411 -98.026952) (xy 151.740689 -98.000341) (xy 151.742329 -97.972207) (xy 151.736203 -97.944698)
			(xy 151.722782 -97.919918) (xy 151.703089 -97.899758) (xy 151.691086 -97.892362) (xy 151.66244 -97.875309)
			(xy 151.609513 -97.834772) (xy 151.562336 -97.787666) (xy 151.521718 -97.7348) (xy 151.488356 -97.67708)
			(xy 151.462822 -97.615496) (xy 151.445553 -97.551103) (xy 151.436846 -97.485006) (xy 151.436324 -97.451672)
			(xy 147.188936 -97.451672) (xy 147.188434 -97.483633) (xy 147.180423 -97.547051) (xy 147.164526 -97.608965)
			(xy 147.140994 -97.668398) (xy 147.1102 -97.724413) (xy 147.072627 -97.776128) (xy 147.02887 -97.822725)
			(xy 146.979617 -97.86347) (xy 146.925646 -97.897721) (xy 146.867807 -97.924938) (xy 146.807014 -97.944691)
			(xy 146.744224 -97.956669) (xy 146.680428 -97.960683) (xy 146.616632 -97.956669) (xy 146.553842 -97.944691)
			(xy 146.493049 -97.924938) (xy 146.43521 -97.897721) (xy 146.381239 -97.86347) (xy 146.331986 -97.822725)
			(xy 146.288229 -97.776128) (xy 146.250656 -97.724413) (xy 146.219862 -97.668398) (xy 146.19633 -97.608965)
			(xy 146.180433 -97.547051) (xy 146.172422 -97.483633) (xy 143.308863 -97.483633) (xy 143.308842 -97.485006)
			(xy 143.300133 -97.551103) (xy 143.28286 -97.615494) (xy 143.257321 -97.677076) (xy 143.223952 -97.734793)
			(xy 143.183327 -97.787653) (xy 143.136141 -97.83475) (xy 143.083206 -97.875278) (xy 143.054578 -97.892362)
			(xy 143.042572 -97.899734) (xy 143.022932 -97.919923) (xy 143.009551 -97.944708) (xy 143.003444 -97.972204)
			(xy 143.005076 -98.000322) (xy 143.014322 -98.026928) (xy 143.03048 -98.049998) (xy 143.041116 -98.05924)
			(xy 143.062786 -98.077448) (xy 143.100992 -98.119206) (xy 143.132612 -98.166148) (xy 143.156953 -98.217246)
			(xy 143.173479 -98.271379) (xy 143.18183 -98.327358) (xy 143.18234 -98.355658) (xy 143.181854 -98.382909)
			(xy 143.174098 -98.436857) (xy 143.158743 -98.489152) (xy 143.136101 -98.538729) (xy 143.106635 -98.584579)
			(xy 143.070944 -98.62577) (xy 143.029753 -98.661461) (xy 142.983903 -98.690927) (xy 142.934326 -98.713569)
			(xy 142.882031 -98.728924) (xy 142.828083 -98.73668) (xy 142.773581 -98.73668) (xy 142.719633 -98.728924)
			(xy 142.667338 -98.713569) (xy 142.617761 -98.690927) (xy 142.571911 -98.661461) (xy 142.53072 -98.62577)
			(xy 142.495029 -98.584579) (xy 142.465563 -98.538729) (xy 142.442921 -98.489152) (xy 142.427566 -98.436857)
			(xy 142.41981 -98.382909) (xy 142.419324 -98.355658) (xy 142.419876 -98.327362) (xy 142.428235 -98.271391)
			(xy 142.444763 -98.217266) (xy 142.469099 -98.166174) (xy 142.50071 -98.119233) (xy 142.538902 -98.077472)
			(xy 142.560548 -98.05924) (xy 142.571202 -98.050006) (xy 142.587411 -98.026952) (xy 142.596689 -98.000341)
			(xy 142.598329 -97.972207) (xy 142.592203 -97.944698) (xy 142.578782 -97.919918) (xy 142.559089 -97.899758)
			(xy 142.547086 -97.892362) (xy 142.51844 -97.875309) (xy 142.465513 -97.834772) (xy 142.418336 -97.787666)
			(xy 142.377718 -97.7348) (xy 142.344356 -97.67708) (xy 142.318822 -97.615496) (xy 142.301553 -97.551103)
			(xy 142.292846 -97.485006) (xy 142.292324 -97.451672) (xy 15.91851 -97.451672) (xy 15.937171 -97.491479)
			(xy 15.953239 -97.544886) (xy 15.961359 -97.600062) (xy 15.961868 -97.627948) (xy 15.961359 -97.655834)
			(xy 15.953239 -97.71101) (xy 15.937171 -97.764417) (xy 15.913499 -97.814914) (xy 15.882726 -97.861427)
			(xy 15.845509 -97.902964) (xy 15.802641 -97.938639) (xy 15.755035 -97.967693) (xy 15.703706 -97.989505)
			(xy 15.649749 -98.003611) (xy 15.594312 -98.009711) (xy 15.538578 -98.007674) (xy 15.483735 -97.997544)
			(xy 15.430951 -97.979537) (xy 15.381351 -97.954036) (xy 15.335993 -97.921585) (xy 15.295844 -97.882876)
			(xy 15.261758 -97.838733) (xy 15.234462 -97.790098) (xy 15.214539 -97.738007) (xy 15.202413 -97.68357)
			(xy 15.198342 -97.627948) (xy 12.928624 -97.627948) (xy 12.928624 -97.662821) (xy 12.920868 -97.716769)
			(xy 12.905512 -97.769064) (xy 12.882871 -97.818642) (xy 12.853405 -97.864493) (xy 12.817713 -97.905683)
			(xy 12.776523 -97.941375) (xy 12.730672 -97.970841) (xy 12.681094 -97.993482) (xy 12.628799 -98.008838)
			(xy 12.574851 -98.016594) (xy 12.5476 -98.017076) (xy 12.523724 -98.016314) (xy 12.512294 -98.015552)
			(xy 12.50188 -98.01987) (xy 12.496835 -98.022038) (xy 12.487742 -98.028191) (xy 12.483846 -98.032062)
			(xy 12.429998 -98.089212) (xy 12.426271 -98.093325) (xy 12.420503 -98.102806) (xy 12.418568 -98.108008)
			(xy 12.415266 -98.118168) (xy 12.416536 -98.129852) (xy 12.42127 -98.171508) (xy 21.848062 -98.171508)
			(xy 21.852133 -98.115886) (xy 21.864259 -98.061449) (xy 21.884182 -98.009358) (xy 21.911478 -97.960723)
			(xy 21.945564 -97.91658) (xy 21.985713 -97.877871) (xy 22.031071 -97.84542) (xy 22.080671 -97.819919)
			(xy 22.133455 -97.801912) (xy 22.188298 -97.791782) (xy 22.244032 -97.789745) (xy 22.299469 -97.795845)
			(xy 22.353426 -97.809951) (xy 22.404755 -97.831763) (xy 22.452361 -97.860817) (xy 22.495229 -97.896492)
			(xy 22.532446 -97.938029) (xy 22.563219 -97.984542) (xy 22.586891 -98.035039) (xy 22.602959 -98.088446)
			(xy 22.611079 -98.143622) (xy 22.611588 -98.171508) (xy 22.611079 -98.199394) (xy 22.602959 -98.25457)
			(xy 22.586891 -98.307977) (xy 22.563219 -98.358474) (xy 22.532446 -98.404987) (xy 22.495229 -98.446524)
			(xy 22.452361 -98.482199) (xy 22.404755 -98.511253) (xy 22.353426 -98.533065) (xy 22.299469 -98.547171)
			(xy 22.244032 -98.553271) (xy 22.188298 -98.551234) (xy 22.133455 -98.541104) (xy 22.080671 -98.523097)
			(xy 22.031071 -98.497596) (xy 21.985713 -98.465145) (xy 21.945564 -98.426436) (xy 21.911478 -98.382293)
			(xy 21.884182 -98.333658) (xy 21.864259 -98.281567) (xy 21.852133 -98.22713) (xy 21.848062 -98.171508)
			(xy 12.42127 -98.171508) (xy 12.423465 -98.190828) (xy 12.430838 -98.313341) (xy 12.431268 -98.374708)
			(xy 12.431268 -98.375216) (xy 12.431268 -98.382582) (xy 12.430472 -98.449812) (xy 12.421079 -98.583947)
			(xy 12.413394 -98.640068) (xy 45.819056 -98.640068) (xy 45.819056 -98.555372) (xy 45.827107 -98.471058)
			(xy 45.843136 -98.387892) (xy 45.866997 -98.306625) (xy 45.898476 -98.227995) (xy 45.937287 -98.152714)
			(xy 45.983077 -98.081462) (xy 46.035433 -98.014886) (xy 46.093881 -97.953588) (xy 46.157891 -97.898123)
			(xy 46.226883 -97.848994) (xy 46.300233 -97.806645) (xy 46.377276 -97.771461) (xy 46.457315 -97.743759)
			(xy 46.539624 -97.723791) (xy 46.623459 -97.711738) (xy 46.70806 -97.707708) (xy 46.792661 -97.711738)
			(xy 46.876496 -97.723791) (xy 46.958805 -97.743759) (xy 47.038844 -97.771461) (xy 47.115887 -97.806645)
			(xy 47.189237 -97.848994) (xy 47.258229 -97.898123) (xy 47.322239 -97.953588) (xy 47.380687 -98.014886)
			(xy 47.433043 -98.081462) (xy 47.478833 -98.152714) (xy 47.517644 -98.227995) (xy 47.549123 -98.306625)
			(xy 47.572984 -98.387892) (xy 47.589013 -98.471058) (xy 47.597064 -98.555372) (xy 47.597568 -98.59772)
			(xy 47.728122 -98.59772) (xy 47.732193 -98.542098) (xy 47.744319 -98.487661) (xy 47.764242 -98.43557)
			(xy 47.791538 -98.386935) (xy 47.825624 -98.342792) (xy 47.865773 -98.304083) (xy 47.911131 -98.271632)
			(xy 47.960731 -98.246131) (xy 48.013515 -98.228124) (xy 48.068358 -98.217994) (xy 48.124092 -98.215957)
			(xy 48.179529 -98.222057) (xy 48.233486 -98.236163) (xy 48.284815 -98.257975) (xy 48.332421 -98.287029)
			(xy 48.375289 -98.322704) (xy 48.412506 -98.364241) (xy 48.443279 -98.410754) (xy 48.466951 -98.461251)
			(xy 48.483019 -98.514658) (xy 48.491139 -98.569834) (xy 48.491648 -98.59772) (xy 48.491139 -98.625606)
			(xy 48.483019 -98.680782) (xy 48.466951 -98.734189) (xy 48.443279 -98.784686) (xy 48.412506 -98.831199)
			(xy 48.375289 -98.872736) (xy 48.332421 -98.908411) (xy 48.284815 -98.937465) (xy 48.233486 -98.959277)
			(xy 48.179529 -98.973383) (xy 48.124092 -98.979483) (xy 48.068358 -98.977446) (xy 48.013515 -98.967316)
			(xy 47.960731 -98.949309) (xy 47.911131 -98.923808) (xy 47.865773 -98.891357) (xy 47.825624 -98.852648)
			(xy 47.791538 -98.808505) (xy 47.764242 -98.75987) (xy 47.744319 -98.707779) (xy 47.732193 -98.653342)
			(xy 47.728122 -98.59772) (xy 47.597568 -98.59772) (xy 47.597064 -98.640068) (xy 47.589013 -98.724382)
			(xy 47.572984 -98.807548) (xy 47.549123 -98.888815) (xy 47.517644 -98.967445) (xy 47.478833 -99.042726)
			(xy 47.433043 -99.113978) (xy 47.400187 -99.155758) (xy 147.442172 -99.155758) (xy 147.446243 -99.100136)
			(xy 147.458369 -99.045699) (xy 147.478292 -98.993608) (xy 147.505588 -98.944973) (xy 147.539674 -98.90083)
			(xy 147.579823 -98.862121) (xy 147.625181 -98.82967) (xy 147.674781 -98.804169) (xy 147.727565 -98.786162)
			(xy 147.782408 -98.776032) (xy 147.838142 -98.773995) (xy 147.893579 -98.780095) (xy 147.947536 -98.794201)
			(xy 147.998865 -98.816013) (xy 148.046471 -98.845067) (xy 148.089339 -98.880742) (xy 148.126556 -98.922279)
			(xy 148.157329 -98.968792) (xy 148.181001 -99.019289) (xy 148.197069 -99.072696) (xy 148.205189 -99.127872)
			(xy 148.205698 -99.155758) (xy 156.586172 -99.155758) (xy 156.590243 -99.100136) (xy 156.602369 -99.045699)
			(xy 156.622292 -98.993608) (xy 156.649588 -98.944973) (xy 156.683674 -98.90083) (xy 156.723823 -98.862121)
			(xy 156.769181 -98.82967) (xy 156.818781 -98.804169) (xy 156.871565 -98.786162) (xy 156.926408 -98.776032)
			(xy 156.982142 -98.773995) (xy 157.037579 -98.780095) (xy 157.091536 -98.794201) (xy 157.142865 -98.816013)
			(xy 157.190471 -98.845067) (xy 157.233339 -98.880742) (xy 157.270556 -98.922279) (xy 157.301329 -98.968792)
			(xy 157.325001 -99.019289) (xy 157.341069 -99.072696) (xy 157.349189 -99.127872) (xy 157.349698 -99.155758)
			(xy 157.349189 -99.183644) (xy 157.341069 -99.23882) (xy 157.325001 -99.292227) (xy 157.304673 -99.33559)
			(xy 162.25901 -99.33559) (xy 162.259517 -99.306601) (xy 162.26829 -99.249291) (xy 162.285634 -99.193968)
			(xy 162.311149 -99.141906) (xy 162.344247 -99.094304) (xy 162.384167 -99.052258) (xy 162.429988 -99.016736)
			(xy 162.480657 -98.988556) (xy 162.535006 -98.968367) (xy 162.591784 -98.956633) (xy 162.620706 -98.95459)
			(xy 162.630358 -98.954082) (xy 162.647122 -98.946462) (xy 162.708844 -98.884486) (xy 162.716464 -98.867214)
			(xy 162.716718 -98.85807) (xy 162.718822 -98.825837) (xy 162.730006 -98.762221) (xy 162.749156 -98.700532)
			(xy 162.775962 -98.641765) (xy 162.809994 -98.586865) (xy 162.850704 -98.536717) (xy 162.897436 -98.492127)
			(xy 162.949438 -98.453813) (xy 163.005873 -98.422392) (xy 163.065833 -98.398371) (xy 163.128351 -98.382134)
			(xy 163.192422 -98.373945) (xy 163.224718 -98.373438) (xy 163.256681 -98.373849) (xy 163.320103 -98.381863)
			(xy 163.382021 -98.397763) (xy 163.441457 -98.421297) (xy 163.497476 -98.452096) (xy 163.549193 -98.489672)
			(xy 163.595792 -98.533433) (xy 163.63654 -98.58269) (xy 163.670792 -98.636665) (xy 163.69801 -98.694508)
			(xy 163.717764 -98.755306) (xy 163.729743 -98.8181) (xy 163.733757 -98.8819) (xy 163.729743 -98.9457)
			(xy 163.717764 -99.008494) (xy 163.69801 -99.069292) (xy 163.670792 -99.127135) (xy 163.63654 -99.18111)
			(xy 163.595792 -99.230367) (xy 163.549193 -99.274128) (xy 163.497476 -99.311704) (xy 163.441457 -99.342503)
			(xy 163.382021 -99.366037) (xy 163.320103 -99.381937) (xy 163.256681 -99.389951) (xy 163.224718 -99.390454)
			(xy 163.22421 -99.390454) (xy 163.198502 -99.390108) (xy 163.14735 -99.384896) (xy 163.122102 -99.38004)
			(xy 163.112958 -99.378008) (xy 163.094416 -99.381056) (xy 163.019232 -99.425506) (xy 163.007548 -99.439984)
			(xy 163.004754 -99.449128) (xy 162.996273 -99.474661) (xy 162.973208 -99.523264) (xy 162.943543 -99.568146)
			(xy 162.907867 -99.608414) (xy 162.866887 -99.643271) (xy 162.821416 -99.672025) (xy 162.772357 -99.694105)
			(xy 162.720683 -99.709075) (xy 162.667418 -99.716635) (xy 162.640518 -99.717098) (xy 162.613265 -99.716628)
			(xy 162.559314 -99.708873) (xy 162.507016 -99.693519) (xy 162.457435 -99.670878) (xy 162.411581 -99.641411)
			(xy 162.370388 -99.605718) (xy 162.334694 -99.564525) (xy 162.305226 -99.518672) (xy 162.282584 -99.469092)
			(xy 162.267229 -99.416794) (xy 162.259473 -99.362843) (xy 162.25901 -99.33559) (xy 157.304673 -99.33559)
			(xy 157.301329 -99.342724) (xy 157.270556 -99.389237) (xy 157.233339 -99.430774) (xy 157.190471 -99.466449)
			(xy 157.142865 -99.495503) (xy 157.091536 -99.517315) (xy 157.037579 -99.531421) (xy 156.982142 -99.537521)
			(xy 156.926408 -99.535484) (xy 156.871565 -99.525354) (xy 156.818781 -99.507347) (xy 156.769181 -99.481846)
			(xy 156.723823 -99.449395) (xy 156.683674 -99.410686) (xy 156.649588 -99.366543) (xy 156.622292 -99.317908)
			(xy 156.602369 -99.265817) (xy 156.590243 -99.21138) (xy 156.586172 -99.155758) (xy 148.205698 -99.155758)
			(xy 148.205189 -99.183644) (xy 148.197069 -99.23882) (xy 148.181001 -99.292227) (xy 148.157329 -99.342724)
			(xy 148.126556 -99.389237) (xy 148.089339 -99.430774) (xy 148.046471 -99.466449) (xy 147.998865 -99.495503)
			(xy 147.947536 -99.517315) (xy 147.893579 -99.531421) (xy 147.838142 -99.537521) (xy 147.782408 -99.535484)
			(xy 147.727565 -99.525354) (xy 147.674781 -99.507347) (xy 147.625181 -99.481846) (xy 147.579823 -99.449395)
			(xy 147.539674 -99.410686) (xy 147.505588 -99.366543) (xy 147.478292 -99.317908) (xy 147.458369 -99.265817)
			(xy 147.446243 -99.21138) (xy 147.442172 -99.155758) (xy 47.400187 -99.155758) (xy 47.380687 -99.180554)
			(xy 47.322239 -99.241852) (xy 47.258229 -99.297317) (xy 47.189237 -99.346446) (xy 47.115887 -99.388795)
			(xy 47.038844 -99.423979) (xy 46.958805 -99.451681) (xy 46.876496 -99.471649) (xy 46.792661 -99.483702)
			(xy 46.70806 -99.487733) (xy 46.623459 -99.483702) (xy 46.539624 -99.471649) (xy 46.457315 -99.451681)
			(xy 46.377276 -99.423979) (xy 46.300233 -99.388795) (xy 46.226883 -99.346446) (xy 46.157891 -99.297317)
			(xy 46.093881 -99.241852) (xy 46.035433 -99.180554) (xy 45.983077 -99.113978) (xy 45.937287 -99.042726)
			(xy 45.898476 -98.967445) (xy 45.866997 -98.888815) (xy 45.843136 -98.807548) (xy 45.827107 -98.724382)
			(xy 45.819056 -98.640068) (xy 12.413394 -98.640068) (xy 12.402836 -98.717168) (xy 12.389866 -98.78314)
			(xy 12.387326 -98.795586) (xy 12.391136 -98.808032) (xy 12.393101 -98.814001) (xy 12.399528 -98.824793)
			(xy 12.403836 -98.829368) (xy 14.194536 -100.620068) (xy 15.175482 -100.620068) (xy 15.179553 -100.564446)
			(xy 15.191679 -100.510009) (xy 15.211602 -100.457918) (xy 15.238898 -100.409283) (xy 15.272984 -100.36514)
			(xy 15.313133 -100.326431) (xy 15.358491 -100.29398) (xy 15.408091 -100.268479) (xy 15.460875 -100.250472)
			(xy 15.515718 -100.240342) (xy 15.571452 -100.238305) (xy 15.626889 -100.244405) (xy 15.680846 -100.258511)
			(xy 15.732175 -100.280323) (xy 15.779781 -100.309377) (xy 15.822649 -100.345052) (xy 15.859866 -100.386589)
			(xy 15.880878 -100.418349) (xy 16.769074 -100.418349) (xy 16.769074 -100.354427) (xy 16.777085 -100.291009)
			(xy 16.792982 -100.229095) (xy 16.816514 -100.169662) (xy 16.847308 -100.113647) (xy 16.884881 -100.061932)
			(xy 16.928638 -100.015335) (xy 16.977891 -99.97459) (xy 17.031862 -99.940339) (xy 17.089701 -99.913122)
			(xy 17.150494 -99.893369) (xy 17.213284 -99.881391) (xy 17.27708 -99.877378) (xy 17.340876 -99.881391)
			(xy 17.403666 -99.893369) (xy 17.464459 -99.913122) (xy 17.522298 -99.940339) (xy 17.576269 -99.97459)
			(xy 17.625522 -100.015335) (xy 17.669279 -100.061932) (xy 17.706852 -100.113647) (xy 17.737646 -100.169662)
			(xy 17.761178 -100.229095) (xy 17.777075 -100.291009) (xy 17.785086 -100.354427) (xy 17.785588 -100.386388)
			(xy 17.785086 -100.418349) (xy 17.777075 -100.481767) (xy 17.761178 -100.543681) (xy 17.737646 -100.603114)
			(xy 17.706852 -100.659129) (xy 17.669279 -100.710844) (xy 17.625522 -100.757441) (xy 17.576269 -100.798186)
			(xy 17.522298 -100.832437) (xy 17.48034 -100.852181) (xy 40.850814 -100.852181) (xy 40.850814 -100.788259)
			(xy 40.858825 -100.724841) (xy 40.874722 -100.662927) (xy 40.898254 -100.603494) (xy 40.929048 -100.547479)
			(xy 40.966621 -100.495764) (xy 41.010378 -100.449167) (xy 41.059631 -100.408422) (xy 41.113602 -100.374171)
			(xy 41.171441 -100.346954) (xy 41.232234 -100.327201) (xy 41.295024 -100.315223) (xy 41.35882 -100.31121)
			(xy 41.422616 -100.315223) (xy 41.485406 -100.327201) (xy 41.546199 -100.346954) (xy 41.604038 -100.374171)
			(xy 41.617175 -100.382508) (xy 43.388276 -100.382508) (xy 43.388276 -100.297812) (xy 43.396327 -100.213498)
			(xy 43.412356 -100.130332) (xy 43.436217 -100.049065) (xy 43.467696 -99.970435) (xy 43.506507 -99.895154)
			(xy 43.552297 -99.823902) (xy 43.604653 -99.757326) (xy 43.663101 -99.696028) (xy 43.727111 -99.640563)
			(xy 43.796103 -99.591434) (xy 43.869453 -99.549085) (xy 43.946496 -99.513901) (xy 44.026535 -99.486199)
			(xy 44.108844 -99.466231) (xy 44.192679 -99.454178) (xy 44.27728 -99.450148) (xy 44.361881 -99.454178)
			(xy 44.445716 -99.466231) (xy 44.528025 -99.486199) (xy 44.608064 -99.513901) (xy 44.685107 -99.549085)
			(xy 44.758457 -99.591434) (xy 44.827449 -99.640563) (xy 44.891459 -99.696028) (xy 44.949907 -99.757326)
			(xy 45.002263 -99.823902) (xy 45.048053 -99.895154) (xy 45.086864 -99.970435) (xy 45.100775 -100.005183)
			(xy 161.368941 -100.005183) (xy 161.371553 -99.942161) (xy 161.381939 -99.879946) (xy 161.399941 -99.819493)
			(xy 161.425282 -99.761732) (xy 161.457573 -99.707548) (xy 161.496318 -99.657775) (xy 161.540923 -99.613176)
			(xy 161.590701 -99.574437) (xy 161.644889 -99.542153) (xy 161.702653 -99.516819) (xy 161.763108 -99.498824)
			(xy 161.825324 -99.488446) (xy 161.888347 -99.485843) (xy 161.951207 -99.491055) (xy 162.01294 -99.504002)
			(xy 162.072597 -99.524486) (xy 162.129263 -99.552192) (xy 162.182066 -99.586694) (xy 162.230196 -99.627462)
			(xy 162.272914 -99.673871) (xy 162.309564 -99.725207) (xy 162.339582 -99.780682) (xy 162.362509 -99.839444)
			(xy 162.37799 -99.90059) (xy 162.38579 -99.963182) (xy 162.386264 -99.99472) (xy 162.385502 -100.021644)
			(xy 162.385195 -100.036834) (xy 162.392527 -100.066304) (xy 162.408207 -100.092312) (xy 162.430845 -100.112555)
			(xy 162.458437 -100.125241) (xy 162.488541 -100.129246) (xy 162.51849 -100.124217) (xy 162.532314 -100.11791)
			(xy 162.558782 -100.105189) (xy 162.61402 -100.085249) (xy 162.671185 -100.071794) (xy 162.729519 -100.065003)
			(xy 162.758882 -100.06457) (xy 162.759136 -100.06457) (xy 162.790675 -100.065106) (xy 162.853267 -100.072912)
			(xy 162.914413 -100.088401) (xy 162.973174 -100.111334) (xy 163.028646 -100.14136) (xy 163.079979 -100.178016)
			(xy 163.082239 -100.180097) (xy 165.34231 -100.180097) (xy 165.34231 -100.116175) (xy 165.350321 -100.052757)
			(xy 165.366218 -99.990843) (xy 165.38975 -99.93141) (xy 165.420544 -99.875395) (xy 165.458117 -99.82368)
			(xy 165.501874 -99.777083) (xy 165.551127 -99.736338) (xy 165.605098 -99.702087) (xy 165.662937 -99.67487)
			(xy 165.72373 -99.655117) (xy 165.78652 -99.643139) (xy 165.850316 -99.639126) (xy 165.914112 -99.643139)
			(xy 165.976902 -99.655117) (xy 166.037695 -99.67487) (xy 166.095534 -99.702087) (xy 166.149505 -99.736338)
			(xy 166.198758 -99.777083) (xy 166.242515 -99.82368) (xy 166.280088 -99.875395) (xy 166.310882 -99.93141)
			(xy 166.334414 -99.990843) (xy 166.350311 -100.052757) (xy 166.358322 -100.116175) (xy 166.358824 -100.148136)
			(xy 166.358322 -100.180097) (xy 166.350311 -100.243515) (xy 166.334414 -100.305429) (xy 166.310882 -100.364862)
			(xy 166.280088 -100.420877) (xy 166.242515 -100.472592) (xy 166.198758 -100.519189) (xy 166.149505 -100.559934)
			(xy 166.095534 -100.594185) (xy 166.037695 -100.621402) (xy 165.976902 -100.641155) (xy 165.914112 -100.653133)
			(xy 165.850316 -100.657147) (xy 165.78652 -100.653133) (xy 165.72373 -100.641155) (xy 165.662937 -100.621402)
			(xy 165.605098 -100.594185) (xy 165.551127 -100.559934) (xy 165.501874 -100.519189) (xy 165.458117 -100.472592)
			(xy 165.420544 -100.420877) (xy 165.38975 -100.364862) (xy 165.366218 -100.305429) (xy 165.350321 -100.243515)
			(xy 165.34231 -100.180097) (xy 163.082239 -100.180097) (xy 163.126384 -100.22074) (xy 163.167147 -100.268876)
			(xy 163.201644 -100.321684) (xy 163.229344 -100.378354) (xy 163.249821 -100.438015) (xy 163.262761 -100.49975)
			(xy 163.267966 -100.562612) (xy 163.265356 -100.625636) (xy 163.25497 -100.687852) (xy 163.236968 -100.748306)
			(xy 163.211627 -100.806069) (xy 163.179335 -100.860254) (xy 163.14059 -100.910028) (xy 163.095985 -100.954628)
			(xy 163.046206 -100.993368) (xy 162.992017 -101.025653) (xy 162.934251 -101.050988) (xy 162.873795 -101.068983)
			(xy 162.811578 -101.079362) (xy 162.748554 -101.081965) (xy 162.685693 -101.076753) (xy 162.623959 -101.063806)
			(xy 162.5643 -101.043321) (xy 162.507634 -101.015615) (xy 162.454829 -100.981113) (xy 162.406698 -100.940344)
			(xy 162.363979 -100.893934) (xy 162.327329 -100.842597) (xy 162.29731 -100.787121) (xy 162.274383 -100.728358)
			(xy 162.258902 -100.66721) (xy 162.251102 -100.604617) (xy 162.250628 -100.573078) (xy 162.25139 -100.546154)
			(xy 162.25171 -100.530963) (xy 162.244377 -100.501491) (xy 162.228695 -100.475482) (xy 162.206055 -100.455238)
			(xy 162.17846 -100.442553) (xy 162.148354 -100.438548) (xy 162.118403 -100.44358) (xy 162.104578 -100.449888)
			(xy 162.078111 -100.462611) (xy 162.022872 -100.482551) (xy 161.965707 -100.496005) (xy 161.907373 -100.502795)
			(xy 161.87801 -100.503228) (xy 161.877756 -100.503228) (xy 161.846218 -100.502686) (xy 161.783627 -100.494878)
			(xy 161.722483 -100.479389) (xy 161.663723 -100.456455) (xy 161.608252 -100.42643) (xy 161.556921 -100.389774)
			(xy 161.510518 -100.34705) (xy 161.469755 -100.298915) (xy 161.43526 -100.246107) (xy 161.407562 -100.189438)
			(xy 161.387085 -100.129778) (xy 161.374146 -100.068044) (xy 161.368941 -100.005183) (xy 45.100775 -100.005183)
			(xy 45.118343 -100.049065) (xy 45.142204 -100.130332) (xy 45.158233 -100.213498) (xy 45.166284 -100.297812)
			(xy 45.166788 -100.34016) (xy 45.166284 -100.382508) (xy 45.158233 -100.466822) (xy 45.142204 -100.549988)
			(xy 45.118343 -100.631255) (xy 45.086864 -100.709885) (xy 45.048053 -100.785166) (xy 45.037632 -100.801381)
			(xy 47.571654 -100.801381) (xy 47.571654 -100.737459) (xy 47.579665 -100.674041) (xy 47.595562 -100.612127)
			(xy 47.619094 -100.552694) (xy 47.649888 -100.496679) (xy 47.687461 -100.444964) (xy 47.731218 -100.398367)
			(xy 47.780471 -100.357622) (xy 47.834442 -100.323371) (xy 47.892281 -100.296154) (xy 47.953074 -100.276401)
			(xy 48.015864 -100.264423) (xy 48.07966 -100.26041) (xy 48.143456 -100.264423) (xy 48.206246 -100.276401)
			(xy 48.267039 -100.296154) (xy 48.324878 -100.323371) (xy 48.378849 -100.357622) (xy 48.428102 -100.398367)
			(xy 48.471859 -100.444964) (xy 48.509432 -100.496679) (xy 48.540226 -100.552694) (xy 48.563758 -100.612127)
			(xy 48.579655 -100.674041) (xy 48.587666 -100.737459) (xy 48.588168 -100.76942) (xy 48.587666 -100.801381)
			(xy 48.579655 -100.864799) (xy 48.563758 -100.926713) (xy 48.540226 -100.986146) (xy 48.509432 -101.042161)
			(xy 48.471859 -101.093876) (xy 48.428102 -101.140473) (xy 48.378849 -101.181218) (xy 48.324878 -101.215469)
			(xy 48.267039 -101.242686) (xy 48.206246 -101.262439) (xy 48.143456 -101.274417) (xy 48.07966 -101.278431)
			(xy 48.015864 -101.274417) (xy 47.953074 -101.262439) (xy 47.892281 -101.242686) (xy 47.834442 -101.215469)
			(xy 47.780471 -101.181218) (xy 47.731218 -101.140473) (xy 47.687461 -101.093876) (xy 47.649888 -101.042161)
			(xy 47.619094 -100.986146) (xy 47.595562 -100.926713) (xy 47.579665 -100.864799) (xy 47.571654 -100.801381)
			(xy 45.037632 -100.801381) (xy 45.002263 -100.856418) (xy 44.949907 -100.922994) (xy 44.891459 -100.984292)
			(xy 44.827449 -101.039757) (xy 44.758457 -101.088886) (xy 44.685107 -101.131235) (xy 44.608064 -101.166419)
			(xy 44.528025 -101.194121) (xy 44.445716 -101.214089) (xy 44.361881 -101.226142) (xy 44.27728 -101.230173)
			(xy 44.192679 -101.226142) (xy 44.108844 -101.214089) (xy 44.026535 -101.194121) (xy 43.946496 -101.166419)
			(xy 43.869453 -101.131235) (xy 43.796103 -101.088886) (xy 43.727111 -101.039757) (xy 43.663101 -100.984292)
			(xy 43.604653 -100.922994) (xy 43.552297 -100.856418) (xy 43.506507 -100.785166) (xy 43.467696 -100.709885)
			(xy 43.436217 -100.631255) (xy 43.412356 -100.549988) (xy 43.396327 -100.466822) (xy 43.388276 -100.382508)
			(xy 41.617175 -100.382508) (xy 41.658009 -100.408422) (xy 41.707262 -100.449167) (xy 41.751019 -100.495764)
			(xy 41.788592 -100.547479) (xy 41.819386 -100.603494) (xy 41.842918 -100.662927) (xy 41.858815 -100.724841)
			(xy 41.866826 -100.788259) (xy 41.867328 -100.82022) (xy 41.866826 -100.852181) (xy 41.858815 -100.915599)
			(xy 41.842918 -100.977513) (xy 41.819386 -101.036946) (xy 41.788592 -101.092961) (xy 41.751019 -101.144676)
			(xy 41.707262 -101.191273) (xy 41.658009 -101.232018) (xy 41.604038 -101.266269) (xy 41.564239 -101.284997)
			(xy 134.29716 -101.284997) (xy 134.29716 -101.221075) (xy 134.305171 -101.157657) (xy 134.321068 -101.095743)
			(xy 134.3446 -101.03631) (xy 134.375394 -100.980295) (xy 134.412967 -100.92858) (xy 134.456724 -100.881983)
			(xy 134.505977 -100.841238) (xy 134.559948 -100.806987) (xy 134.617787 -100.77977) (xy 134.67858 -100.760017)
			(xy 134.74137 -100.748039) (xy 134.805166 -100.744026) (xy 134.868962 -100.748039) (xy 134.931752 -100.760017)
			(xy 134.992545 -100.77977) (xy 135.050384 -100.806987) (xy 135.104355 -100.841238) (xy 135.153608 -100.881983)
			(xy 135.197365 -100.92858) (xy 135.234938 -100.980295) (xy 135.265732 -101.03631) (xy 135.289264 -101.095743)
			(xy 135.305161 -101.157657) (xy 135.313172 -101.221075) (xy 135.313674 -101.253036) (xy 135.313172 -101.284997)
			(xy 135.305161 -101.348415) (xy 135.289264 -101.410329) (xy 135.265732 -101.469762) (xy 135.234938 -101.525777)
			(xy 135.197365 -101.577492) (xy 135.153608 -101.624089) (xy 135.104355 -101.664834) (xy 135.050384 -101.699085)
			(xy 134.992545 -101.726302) (xy 134.931752 -101.746055) (xy 134.868962 -101.758033) (xy 134.805166 -101.762047)
			(xy 134.74137 -101.758033) (xy 134.67858 -101.746055) (xy 134.617787 -101.726302) (xy 134.559948 -101.699085)
			(xy 134.505977 -101.664834) (xy 134.456724 -101.624089) (xy 134.412967 -101.577492) (xy 134.375394 -101.525777)
			(xy 134.3446 -101.469762) (xy 134.321068 -101.410329) (xy 134.305171 -101.348415) (xy 134.29716 -101.284997)
			(xy 41.564239 -101.284997) (xy 41.546199 -101.293486) (xy 41.485406 -101.313239) (xy 41.422616 -101.325217)
			(xy 41.35882 -101.329231) (xy 41.295024 -101.325217) (xy 41.232234 -101.313239) (xy 41.171441 -101.293486)
			(xy 41.113602 -101.266269) (xy 41.059631 -101.232018) (xy 41.010378 -101.191273) (xy 40.966621 -101.144676)
			(xy 40.929048 -101.092961) (xy 40.898254 -101.036946) (xy 40.874722 -100.977513) (xy 40.858825 -100.915599)
			(xy 40.850814 -100.852181) (xy 17.48034 -100.852181) (xy 17.464459 -100.859654) (xy 17.403666 -100.879407)
			(xy 17.340876 -100.891385) (xy 17.27708 -100.895399) (xy 17.213284 -100.891385) (xy 17.150494 -100.879407)
			(xy 17.089701 -100.859654) (xy 17.031862 -100.832437) (xy 16.977891 -100.798186) (xy 16.928638 -100.757441)
			(xy 16.884881 -100.710844) (xy 16.847308 -100.659129) (xy 16.816514 -100.603114) (xy 16.792982 -100.543681)
			(xy 16.777085 -100.481767) (xy 16.769074 -100.418349) (xy 15.880878 -100.418349) (xy 15.890639 -100.433102)
			(xy 15.914311 -100.483599) (xy 15.930379 -100.537006) (xy 15.938499 -100.592182) (xy 15.939008 -100.620068)
			(xy 15.938499 -100.647954) (xy 15.930379 -100.70313) (xy 15.914311 -100.756537) (xy 15.890639 -100.807034)
			(xy 15.859866 -100.853547) (xy 15.822649 -100.895084) (xy 15.779781 -100.930759) (xy 15.732175 -100.959813)
			(xy 15.680846 -100.981625) (xy 15.626889 -100.995731) (xy 15.571452 -101.001831) (xy 15.515718 -100.999794)
			(xy 15.460875 -100.989664) (xy 15.408091 -100.971657) (xy 15.358491 -100.946156) (xy 15.313133 -100.913705)
			(xy 15.272984 -100.874996) (xy 15.238898 -100.830853) (xy 15.211602 -100.782218) (xy 15.191679 -100.730127)
			(xy 15.179553 -100.67569) (xy 15.175482 -100.620068) (xy 14.194536 -100.620068) (xy 15.316708 -101.74224)
			(xy 43.803822 -101.74224) (xy 43.807893 -101.686618) (xy 43.820019 -101.632181) (xy 43.839942 -101.58009)
			(xy 43.867238 -101.531455) (xy 43.901324 -101.487312) (xy 43.941473 -101.448603) (xy 43.986831 -101.416152)
			(xy 44.036431 -101.390651) (xy 44.089215 -101.372644) (xy 44.144058 -101.362514) (xy 44.199792 -101.360477)
			(xy 44.255229 -101.366577) (xy 44.309186 -101.380683) (xy 44.360515 -101.402495) (xy 44.408121 -101.431549)
			(xy 44.450989 -101.467224) (xy 44.488206 -101.508761) (xy 44.518979 -101.555274) (xy 44.542651 -101.605771)
			(xy 44.558719 -101.659178) (xy 44.566839 -101.714354) (xy 44.567348 -101.74224) (xy 44.566839 -101.770126)
			(xy 44.558719 -101.825302) (xy 44.542651 -101.878709) (xy 44.518979 -101.929206) (xy 44.488206 -101.975719)
			(xy 44.450989 -102.017256) (xy 44.408121 -102.052931) (xy 44.360515 -102.081985) (xy 44.309186 -102.103797)
			(xy 44.255229 -102.117903) (xy 44.199792 -102.124003) (xy 44.144058 -102.121966) (xy 44.089215 -102.111836)
			(xy 44.036431 -102.093829) (xy 43.986831 -102.068328) (xy 43.941473 -102.035877) (xy 43.901324 -101.997168)
			(xy 43.867238 -101.953025) (xy 43.839942 -101.90439) (xy 43.820019 -101.852299) (xy 43.807893 -101.797862)
			(xy 43.803822 -101.74224) (xy 15.316708 -101.74224) (xy 16.135568 -102.5611) (xy 133.937504 -102.5611)
			(xy 133.941518 -102.497305) (xy 133.953496 -102.434515) (xy 133.97325 -102.373722) (xy 134.000467 -102.315884)
			(xy 134.034718 -102.261914) (xy 134.075464 -102.212662) (xy 134.122062 -102.168906) (xy 134.173776 -102.131335)
			(xy 134.229792 -102.100542) (xy 134.289225 -102.077012) (xy 134.351139 -102.061117) (xy 134.414557 -102.053108)
			(xy 134.446518 -102.052628) (xy 134.47939 -102.05309) (xy 134.544588 -102.061554) (xy 134.60815 -102.078352)
			(xy 134.669017 -102.103203) (xy 134.726173 -102.135692) (xy 134.778664 -102.175278) (xy 134.825614 -102.2213)
			(xy 134.86624 -102.27299) (xy 134.899865 -102.329486) (xy 134.91337 -102.35946) (xy 134.919249 -102.371925)
			(xy 134.936473 -102.393421) (xy 134.958824 -102.409522) (xy 134.984668 -102.419053) (xy 135.01212 -102.421317)
			(xy 135.039177 -102.416151) (xy 135.063864 -102.40393) (xy 135.084378 -102.385547) (xy 135.092186 -102.374192)
			(xy 135.109729 -102.347687) (xy 135.15048 -102.298903) (xy 135.196994 -102.255579) (xy 135.248546 -102.218393)
			(xy 135.304332 -102.187923) (xy 135.363481 -102.164645) (xy 135.425071 -102.148923) (xy 135.48814 -102.141002)
			(xy 135.519922 -102.140512) (xy 135.551883 -102.140975) (xy 135.615302 -102.148989) (xy 135.677216 -102.164889)
			(xy 135.736649 -102.188422) (xy 135.792664 -102.219219) (xy 135.844378 -102.256793) (xy 135.890975 -102.300552)
			(xy 135.93172 -102.349807) (xy 135.96597 -102.403779) (xy 135.993187 -102.461618) (xy 136.012939 -102.522413)
			(xy 136.016829 -102.542805) (xy 139.337536 -102.542805) (xy 139.337536 -102.478883) (xy 139.345547 -102.415465)
			(xy 139.361444 -102.353551) (xy 139.384976 -102.294118) (xy 139.41577 -102.238103) (xy 139.453343 -102.186388)
			(xy 139.4971 -102.139791) (xy 139.546353 -102.099046) (xy 139.600324 -102.064795) (xy 139.658163 -102.037578)
			(xy 139.718956 -102.017825) (xy 139.781746 -102.005847) (xy 139.845542 -102.001834) (xy 139.909338 -102.005847)
			(xy 139.972128 -102.017825) (xy 140.032921 -102.037578) (xy 140.09076 -102.064795) (xy 140.144731 -102.099046)
			(xy 140.193984 -102.139791) (xy 140.237741 -102.186388) (xy 140.275314 -102.238103) (xy 140.306108 -102.294118)
			(xy 140.32964 -102.353551) (xy 140.345537 -102.415465) (xy 140.353548 -102.478883) (xy 140.35405 -102.510844)
			(xy 140.353548 -102.542805) (xy 140.345537 -102.606223) (xy 140.32964 -102.668137) (xy 140.306108 -102.72757)
			(xy 140.275314 -102.783585) (xy 140.264755 -102.798118) (xy 142.292324 -102.798118) (xy 142.292832 -102.764784)
			(xy 142.301542 -102.698689) (xy 142.318814 -102.634298) (xy 142.344353 -102.572717) (xy 142.37772 -102.515001)
			(xy 142.418343 -102.462141) (xy 142.465526 -102.415042) (xy 142.518459 -102.374514) (xy 142.547086 -102.357428)
			(xy 142.54734 -102.357428) (xy 142.557749 -102.350646) (xy 142.57093 -102.329621) (xy 142.572486 -102.317296)
			(xy 142.58036 -102.221538) (xy 142.5702 -102.198424) (xy 142.560548 -102.19055) (xy 142.538932 -102.172284)
			(xy 142.500735 -102.13053) (xy 142.46912 -102.083595) (xy 142.444782 -102.032506) (xy 142.428253 -101.978384)
			(xy 142.419895 -101.922415) (xy 142.419892 -101.865825) (xy 142.428244 -101.809855) (xy 142.444768 -101.755732)
			(xy 142.4691 -101.70464) (xy 142.50071 -101.657702) (xy 142.538902 -101.615944) (xy 142.560548 -101.597714)
			(xy 142.5702 -101.58984) (xy 142.58036 -101.566726) (xy 142.572486 -101.470968) (xy 142.570968 -101.458629)
			(xy 142.557781 -101.437586) (xy 142.54734 -101.430836) (xy 142.547086 -101.430836) (xy 142.518473 -101.413731)
			(xy 142.465546 -101.373201) (xy 142.418368 -101.326102) (xy 142.377747 -101.273244) (xy 142.344381 -101.215532)
			(xy 142.318842 -101.153955) (xy 142.301566 -101.089569) (xy 142.29285 -101.023478) (xy 142.292324 -100.990146)
			(xy 142.292826 -100.958185) (xy 142.300837 -100.894767) (xy 142.316734 -100.832853) (xy 142.340266 -100.77342)
			(xy 142.37106 -100.717405) (xy 142.408633 -100.66569) (xy 142.45239 -100.619093) (xy 142.501643 -100.578348)
			(xy 142.555614 -100.544097) (xy 142.613453 -100.51688) (xy 142.674246 -100.497127) (xy 142.737036 -100.485149)
			(xy 142.800832 -100.481136) (xy 142.864628 -100.485149) (xy 142.927418 -100.497127) (xy 142.988211 -100.51688)
			(xy 143.04605 -100.544097) (xy 143.100021 -100.578348) (xy 143.149274 -100.619093) (xy 143.193031 -100.66569)
			(xy 143.230604 -100.717405) (xy 143.261398 -100.77342) (xy 143.28493 -100.832853) (xy 143.300827 -100.894767)
			(xy 143.308838 -100.958185) (xy 143.30934 -100.990146) (xy 143.308821 -101.023479) (xy 143.300115 -101.089575)
			(xy 143.282846 -101.153966) (xy 143.25731 -101.215548) (xy 143.223944 -101.273265) (xy 143.183321 -101.326125)
			(xy 143.136138 -101.373223) (xy 143.083205 -101.413751) (xy 143.054578 -101.430836) (xy 143.054324 -101.430836)
			(xy 143.044018 -101.437725) (xy 143.03578 -101.450859) (xy 148.770334 -101.450859) (xy 148.770334 -101.386937)
			(xy 148.778345 -101.323519) (xy 148.794242 -101.261605) (xy 148.817774 -101.202172) (xy 148.848568 -101.146157)
			(xy 148.886141 -101.094442) (xy 148.929898 -101.047845) (xy 148.979151 -101.0071) (xy 149.033122 -100.972849)
			(xy 149.090961 -100.945632) (xy 149.151754 -100.925879) (xy 149.214544 -100.913901) (xy 149.27834 -100.909888)
			(xy 149.342136 -100.913901) (xy 149.404926 -100.925879) (xy 149.465719 -100.945632) (xy 149.523558 -100.972849)
			(xy 149.577529 -101.0071) (xy 149.626782 -101.047845) (xy 149.670539 -101.094442) (xy 149.708112 -101.146157)
			(xy 149.738906 -101.202172) (xy 149.762438 -101.261605) (xy 149.778335 -101.323519) (xy 149.786346 -101.386937)
			(xy 149.786848 -101.418898) (xy 149.786346 -101.450859) (xy 149.778335 -101.514277) (xy 149.762438 -101.576191)
			(xy 149.738906 -101.635624) (xy 149.708112 -101.691639) (xy 149.670539 -101.743354) (xy 149.626782 -101.789951)
			(xy 149.577529 -101.830696) (xy 149.523558 -101.864947) (xy 149.465719 -101.892164) (xy 149.404926 -101.911917)
			(xy 149.342136 -101.923895) (xy 149.27834 -101.927909) (xy 149.214544 -101.923895) (xy 149.151754 -101.911917)
			(xy 149.090961 -101.892164) (xy 149.033122 -101.864947) (xy 148.979151 -101.830696) (xy 148.929898 -101.789951)
			(xy 148.886141 -101.743354) (xy 148.848568 -101.691639) (xy 148.817774 -101.635624) (xy 148.794242 -101.576191)
			(xy 148.778345 -101.514277) (xy 148.770334 -101.450859) (xy 143.03578 -101.450859) (xy 143.030869 -101.458689)
			(xy 143.029178 -101.470968) (xy 143.021304 -101.566726) (xy 143.031464 -101.58984) (xy 143.041116 -101.597714)
			(xy 143.062798 -101.615906) (xy 143.100999 -101.657668) (xy 143.132615 -101.704613) (xy 143.156953 -101.755711)
			(xy 143.173481 -101.809842) (xy 143.181834 -101.865821) (xy 143.181831 -101.922419) (xy 143.173472 -101.978397)
			(xy 143.156939 -102.032527) (xy 143.153897 -102.038912) (xy 152.150062 -102.038912) (xy 152.154133 -101.98329)
			(xy 152.166259 -101.928853) (xy 152.186182 -101.876762) (xy 152.213478 -101.828127) (xy 152.247564 -101.783984)
			(xy 152.287713 -101.745275) (xy 152.333071 -101.712824) (xy 152.382671 -101.687323) (xy 152.435455 -101.669316)
			(xy 152.490298 -101.659186) (xy 152.546032 -101.657149) (xy 152.601469 -101.663249) (xy 152.655426 -101.677355)
			(xy 152.706755 -101.699167) (xy 152.754361 -101.728221) (xy 152.797229 -101.763896) (xy 152.834446 -101.805433)
			(xy 152.865219 -101.851946) (xy 152.888891 -101.902443) (xy 152.904959 -101.95585) (xy 152.913079 -102.011026)
			(xy 152.913588 -102.038912) (xy 156.459682 -102.038912) (xy 156.460212 -102.005354) (xy 156.469062 -101.938824)
			(xy 156.486583 -101.874036) (xy 156.512472 -101.812113) (xy 156.546278 -101.754133) (xy 156.587414 -101.701101)
			(xy 156.635166 -101.653939) (xy 156.661612 -101.633274) (xy 156.669606 -101.626607) (xy 156.679841 -101.608509)
			(xy 156.681424 -101.598222) (xy 156.689806 -101.524816) (xy 156.69044 -101.514392) (xy 156.684268 -101.494461)
			(xy 156.677868 -101.486208) (xy 156.660759 -101.465401) (xy 156.63191 -101.419909) (xy 156.609755 -101.370808)
			(xy 156.594734 -101.319077) (xy 156.587148 -101.265746) (xy 156.586682 -101.238812) (xy 156.587168 -101.211561)
			(xy 156.594924 -101.157613) (xy 156.610279 -101.105318) (xy 156.632921 -101.055741) (xy 156.662387 -101.009891)
			(xy 156.698078 -100.9687) (xy 156.739269 -100.933009) (xy 156.785119 -100.903543) (xy 156.834696 -100.880901)
			(xy 156.886991 -100.865546) (xy 156.940939 -100.85779) (xy 156.995441 -100.85779) (xy 157.049389 -100.865546)
			(xy 157.101684 -100.880901) (xy 157.151261 -100.903543) (xy 157.197111 -100.933009) (xy 157.238302 -100.9687)
			(xy 157.273993 -101.009891) (xy 157.303459 -101.055741) (xy 157.326101 -101.105318) (xy 157.341456 -101.157613)
			(xy 157.349212 -101.211561) (xy 157.349698 -101.238812) (xy 157.349217 -101.265746) (xy 157.341633 -101.319077)
			(xy 157.326619 -101.37081) (xy 157.304473 -101.419914) (xy 157.275636 -101.465413) (xy 157.258512 -101.486208)
			(xy 157.25209 -101.494449) (xy 157.245924 -101.514388) (xy 157.246574 -101.524816) (xy 157.250108 -101.555761)
			(xy 160.796726 -101.555761) (xy 160.796726 -101.491839) (xy 160.804737 -101.428421) (xy 160.820634 -101.366507)
			(xy 160.844166 -101.307074) (xy 160.87496 -101.251059) (xy 160.912533 -101.199344) (xy 160.95629 -101.152747)
			(xy 161.005543 -101.112002) (xy 161.059514 -101.077751) (xy 161.117353 -101.050534) (xy 161.178146 -101.030781)
			(xy 161.240936 -101.018803) (xy 161.304732 -101.01479) (xy 161.368528 -101.018803) (xy 161.431318 -101.030781)
			(xy 161.492111 -101.050534) (xy 161.54995 -101.077751) (xy 161.603921 -101.112002) (xy 161.653174 -101.152747)
			(xy 161.696931 -101.199344) (xy 161.734504 -101.251059) (xy 161.765298 -101.307074) (xy 161.78883 -101.366507)
			(xy 161.804727 -101.428421) (xy 161.812738 -101.491839) (xy 161.81324 -101.5238) (xy 161.812738 -101.555761)
			(xy 161.804727 -101.619179) (xy 161.802293 -101.628659) (xy 165.486836 -101.628659) (xy 165.486836 -101.564737)
			(xy 165.494847 -101.501319) (xy 165.510744 -101.439405) (xy 165.534276 -101.379972) (xy 165.56507 -101.323957)
			(xy 165.602643 -101.272242) (xy 165.6464 -101.225645) (xy 165.695653 -101.1849) (xy 165.749624 -101.150649)
			(xy 165.807463 -101.123432) (xy 165.868256 -101.103679) (xy 165.931046 -101.091701) (xy 165.994842 -101.087688)
			(xy 166.058638 -101.091701) (xy 166.121428 -101.103679) (xy 166.182221 -101.123432) (xy 166.24006 -101.150649)
			(xy 166.294031 -101.1849) (xy 166.343284 -101.225645) (xy 166.387041 -101.272242) (xy 166.424614 -101.323957)
			(xy 166.455408 -101.379972) (xy 166.47894 -101.439405) (xy 166.494837 -101.501319) (xy 166.502848 -101.564737)
			(xy 166.50335 -101.596698) (xy 166.502848 -101.628659) (xy 166.494837 -101.692077) (xy 166.47894 -101.753991)
			(xy 166.455408 -101.813424) (xy 166.424614 -101.869439) (xy 166.387041 -101.921154) (xy 166.343284 -101.967751)
			(xy 166.294031 -102.008496) (xy 166.24006 -102.042747) (xy 166.182221 -102.069964) (xy 166.121428 -102.089717)
			(xy 166.058638 -102.101695) (xy 165.994842 -102.105709) (xy 165.931046 -102.101695) (xy 165.868256 -102.089717)
			(xy 165.807463 -102.069964) (xy 165.749624 -102.042747) (xy 165.695653 -102.008496) (xy 165.6464 -101.967751)
			(xy 165.602643 -101.921154) (xy 165.56507 -101.869439) (xy 165.534276 -101.813424) (xy 165.510744 -101.753991)
			(xy 165.494847 -101.692077) (xy 165.486836 -101.628659) (xy 161.802293 -101.628659) (xy 161.78883 -101.681093)
			(xy 161.765298 -101.740526) (xy 161.734504 -101.796541) (xy 161.696931 -101.848256) (xy 161.653174 -101.894853)
			(xy 161.603921 -101.935598) (xy 161.54995 -101.969849) (xy 161.492111 -101.997066) (xy 161.431318 -102.016819)
			(xy 161.368528 -102.028797) (xy 161.304732 -102.032811) (xy 161.240936 -102.028797) (xy 161.178146 -102.016819)
			(xy 161.117353 -101.997066) (xy 161.059514 -101.969849) (xy 161.005543 -101.935598) (xy 160.95629 -101.894853)
			(xy 160.912533 -101.848256) (xy 160.87496 -101.796541) (xy 160.844166 -101.740526) (xy 160.820634 -101.681093)
			(xy 160.804737 -101.619179) (xy 160.796726 -101.555761) (xy 157.250108 -101.555761) (xy 157.254956 -101.598222)
			(xy 157.256605 -101.608489) (xy 157.266812 -101.62658) (xy 157.274768 -101.633274) (xy 157.301206 -101.653951)
			(xy 157.348974 -101.701099) (xy 157.390121 -101.754124) (xy 157.423931 -101.812103) (xy 157.449817 -101.874027)
			(xy 157.467328 -101.93882) (xy 157.47616 -102.005353) (xy 157.476698 -102.038912) (xy 157.476196 -102.070873)
			(xy 157.468185 -102.134291) (xy 157.452288 -102.196205) (xy 157.428756 -102.255638) (xy 157.397962 -102.311653)
			(xy 157.360389 -102.363368) (xy 157.316632 -102.409965) (xy 157.267379 -102.45071) (xy 157.213408 -102.484961)
			(xy 157.155569 -102.512178) (xy 157.094776 -102.531931) (xy 157.031986 -102.543909) (xy 156.96819 -102.547923)
			(xy 156.904394 -102.543909) (xy 156.841604 -102.531931) (xy 156.780811 -102.512178) (xy 156.722972 -102.484961)
			(xy 156.669001 -102.45071) (xy 156.619748 -102.409965) (xy 156.575991 -102.363368) (xy 156.538418 -102.311653)
			(xy 156.507624 -102.255638) (xy 156.484092 -102.196205) (xy 156.468195 -102.134291) (xy 156.460184 -102.070873)
			(xy 156.459682 -102.038912) (xy 152.913588 -102.038912) (xy 152.913079 -102.066798) (xy 152.904959 -102.121974)
			(xy 152.888891 -102.175381) (xy 152.865219 -102.225878) (xy 152.834446 -102.272391) (xy 152.797229 -102.313928)
			(xy 152.754361 -102.349603) (xy 152.706755 -102.378657) (xy 152.655426 -102.400469) (xy 152.601469 -102.414575)
			(xy 152.546032 -102.420675) (xy 152.490298 -102.418638) (xy 152.435455 -102.408508) (xy 152.382671 -102.390501)
			(xy 152.333071 -102.365) (xy 152.287713 -102.332549) (xy 152.247564 -102.29384) (xy 152.213478 -102.249697)
			(xy 152.186182 -102.201062) (xy 152.166259 -102.148971) (xy 152.154133 -102.094534) (xy 152.150062 -102.038912)
			(xy 143.153897 -102.038912) (xy 143.132595 -102.083622) (xy 143.100974 -102.130563) (xy 143.062768 -102.172321)
			(xy 143.041116 -102.19055) (xy 143.031464 -102.198424) (xy 143.021304 -102.221538) (xy 143.029178 -102.317296)
			(xy 143.030689 -102.329638) (xy 143.043879 -102.350682) (xy 143.054324 -102.357428) (xy 143.054578 -102.357428)
			(xy 143.083211 -102.374501) (xy 143.13614 -102.415035) (xy 143.183319 -102.462137) (xy 143.223938 -102.515)
			(xy 143.257302 -102.572717) (xy 143.282839 -102.634299) (xy 143.298914 -102.694232) (xy 147.442172 -102.694232)
			(xy 147.446243 -102.63861) (xy 147.458369 -102.584173) (xy 147.478292 -102.532082) (xy 147.505588 -102.483447)
			(xy 147.539674 -102.439304) (xy 147.579823 -102.400595) (xy 147.625181 -102.368144) (xy 147.674781 -102.342643)
			(xy 147.727565 -102.324636) (xy 147.782408 -102.314506) (xy 147.838142 -102.312469) (xy 147.893579 -102.318569)
			(xy 147.947536 -102.332675) (xy 147.998865 -102.354487) (xy 148.046471 -102.383541) (xy 148.089339 -102.419216)
			(xy 148.126556 -102.460753) (xy 148.157329 -102.507266) (xy 148.181001 -102.557763) (xy 148.197069 -102.61117)
			(xy 148.205189 -102.666346) (xy 148.205698 -102.694232) (xy 148.205212 -102.720859) (xy 148.770334 -102.720859)
			(xy 148.770334 -102.656937) (xy 148.778345 -102.593519) (xy 148.794242 -102.531605) (xy 148.817774 -102.472172)
			(xy 148.848568 -102.416157) (xy 148.886141 -102.364442) (xy 148.929898 -102.317845) (xy 148.979151 -102.2771)
			(xy 149.033122 -102.242849) (xy 149.090961 -102.215632) (xy 149.151754 -102.195879) (xy 149.214544 -102.183901)
			(xy 149.27834 -102.179888) (xy 149.342136 -102.183901) (xy 149.404926 -102.195879) (xy 149.465719 -102.215632)
			(xy 149.523558 -102.242849) (xy 149.577529 -102.2771) (xy 149.626782 -102.317845) (xy 149.670539 -102.364442)
			(xy 149.708112 -102.416157) (xy 149.738906 -102.472172) (xy 149.762438 -102.531605) (xy 149.778335 -102.593519)
			(xy 149.786346 -102.656937) (xy 149.786848 -102.688898) (xy 149.786346 -102.720859) (xy 149.778672 -102.781608)
			(xy 160.554162 -102.781608) (xy 160.554664 -102.749647) (xy 160.562675 -102.686229) (xy 160.578572 -102.624315)
			(xy 160.602104 -102.564882) (xy 160.632898 -102.508867) (xy 160.670471 -102.457152) (xy 160.714228 -102.410555)
			(xy 160.763481 -102.36981) (xy 160.817452 -102.335559) (xy 160.875291 -102.308342) (xy 160.936084 -102.288589)
			(xy 160.998874 -102.276611) (xy 161.06267 -102.272598) (xy 161.126466 -102.276611) (xy 161.189256 -102.288589)
			(xy 161.250049 -102.308342) (xy 161.307888 -102.335559) (xy 161.361859 -102.36981) (xy 161.411112 -102.410555)
			(xy 161.454869 -102.457152) (xy 161.492442 -102.508867) (xy 161.523236 -102.564882) (xy 161.546768 -102.624315)
			(xy 161.562665 -102.686229) (xy 161.570676 -102.749647) (xy 161.570906 -102.764293) (xy 164.91686 -102.764293)
			(xy 164.91686 -102.700371) (xy 164.924871 -102.636953) (xy 164.940768 -102.575039) (xy 164.9643 -102.515606)
			(xy 164.995094 -102.459591) (xy 165.032667 -102.407876) (xy 165.076424 -102.361279) (xy 165.125677 -102.320534)
			(xy 165.179648 -102.286283) (xy 165.237487 -102.259066) (xy 165.29828 -102.239313) (xy 165.36107 -102.227335)
			(xy 165.424866 -102.223322) (xy 165.488662 -102.227335) (xy 165.551452 -102.239313) (xy 165.612245 -102.259066)
			(xy 165.670084 -102.286283) (xy 165.724055 -102.320534) (xy 165.773308 -102.361279) (xy 165.817065 -102.407876)
			(xy 165.854638 -102.459591) (xy 165.885432 -102.515606) (xy 165.908964 -102.575039) (xy 165.924861 -102.636953)
			(xy 165.932872 -102.700371) (xy 165.933374 -102.732332) (xy 165.932872 -102.764293) (xy 165.924861 -102.827711)
			(xy 165.908964 -102.889625) (xy 165.885432 -102.949058) (xy 165.854638 -103.005073) (xy 165.817065 -103.056788)
			(xy 165.773308 -103.103385) (xy 165.724055 -103.14413) (xy 165.670084 -103.178381) (xy 165.612245 -103.205598)
			(xy 165.551452 -103.225351) (xy 165.488662 -103.237329) (xy 165.424866 -103.241343) (xy 165.36107 -103.237329)
			(xy 165.29828 -103.225351) (xy 165.237487 -103.205598) (xy 165.179648 -103.178381) (xy 165.125677 -103.14413)
			(xy 165.076424 -103.103385) (xy 165.032667 -103.056788) (xy 164.995094 -103.005073) (xy 164.9643 -102.949058)
			(xy 164.940768 -102.889625) (xy 164.924871 -102.827711) (xy 164.91686 -102.764293) (xy 161.570906 -102.764293)
			(xy 161.571178 -102.781608) (xy 161.570643 -102.815639) (xy 161.561574 -102.883095) (xy 161.543586 -102.948737)
			(xy 161.517 -103.011392) (xy 161.482292 -103.06994) (xy 161.440083 -103.123334) (xy 161.415984 -103.147368)
			(xy 161.40811 -103.154988) (xy 161.400236 -103.1748) (xy 161.404046 -103.27259) (xy 161.413444 -103.29164)
			(xy 161.42208 -103.298752) (xy 161.443429 -103.316985) (xy 161.481105 -103.358606) (xy 161.512272 -103.405301)
			(xy 161.536257 -103.45606) (xy 161.552541 -103.509788) (xy 161.560773 -103.565322) (xy 161.561272 -103.593392)
			(xy 161.560786 -103.620643) (xy 161.55303 -103.674591) (xy 161.537675 -103.726886) (xy 161.515033 -103.776463)
			(xy 161.485567 -103.822313) (xy 161.449876 -103.863504) (xy 161.408685 -103.899195) (xy 161.362835 -103.928661)
			(xy 161.313258 -103.951303) (xy 161.260963 -103.966658) (xy 161.207015 -103.974414) (xy 161.152513 -103.974414)
			(xy 161.098565 -103.966658) (xy 161.04627 -103.951303) (xy 160.996693 -103.928661) (xy 160.950843 -103.899195)
			(xy 160.909652 -103.863504) (xy 160.873961 -103.822313) (xy 160.844495 -103.776463) (xy 160.821853 -103.726886)
			(xy 160.806498 -103.674591) (xy 160.798742 -103.620643) (xy 160.798256 -103.593392) (xy 160.798773 -103.564959)
			(xy 160.807211 -103.508722) (xy 160.823913 -103.454363) (xy 160.848507 -103.40309) (xy 160.864042 -103.37927)
			(xy 160.86954 -103.370044) (xy 160.873224 -103.348914) (xy 160.871154 -103.338376) (xy 160.852866 -103.26497)
			(xy 160.849843 -103.254611) (xy 160.836534 -103.237643) (xy 160.827212 -103.232204) (xy 160.826958 -103.232204)
			(xy 160.799904 -103.217537) (xy 160.749216 -103.182637) (xy 160.70311 -103.141875) (xy 160.662261 -103.095846)
			(xy 160.627264 -103.045225) (xy 160.598632 -102.99075) (xy 160.576784 -102.933218) (xy 160.562038 -102.87347)
			(xy 160.55461 -102.812378) (xy 160.554162 -102.781608) (xy 149.778672 -102.781608) (xy 149.778335 -102.784277)
			(xy 149.762438 -102.846191) (xy 149.738906 -102.905624) (xy 149.708112 -102.961639) (xy 149.670539 -103.013354)
			(xy 149.626782 -103.059951) (xy 149.577529 -103.100696) (xy 149.523558 -103.134947) (xy 149.465719 -103.162164)
			(xy 149.404926 -103.181917) (xy 149.342136 -103.193895) (xy 149.27834 -103.197909) (xy 149.214544 -103.193895)
			(xy 149.151754 -103.181917) (xy 149.090961 -103.162164) (xy 149.033122 -103.134947) (xy 148.979151 -103.100696)
			(xy 148.929898 -103.059951) (xy 148.886141 -103.013354) (xy 148.848568 -102.961639) (xy 148.817774 -102.905624)
			(xy 148.794242 -102.846191) (xy 148.778345 -102.784277) (xy 148.770334 -102.720859) (xy 148.205212 -102.720859)
			(xy 148.205189 -102.722118) (xy 148.197069 -102.777294) (xy 148.181001 -102.830701) (xy 148.157329 -102.881198)
			(xy 148.126556 -102.927711) (xy 148.089339 -102.969248) (xy 148.046471 -103.004923) (xy 147.998865 -103.033977)
			(xy 147.947536 -103.055789) (xy 147.893579 -103.069895) (xy 147.838142 -103.075995) (xy 147.782408 -103.073958)
			(xy 147.727565 -103.063828) (xy 147.674781 -103.045821) (xy 147.625181 -103.02032) (xy 147.579823 -102.987869)
			(xy 147.539674 -102.94916) (xy 147.505588 -102.905017) (xy 147.478292 -102.856382) (xy 147.458369 -102.804291)
			(xy 147.446243 -102.749854) (xy 147.442172 -102.694232) (xy 143.298914 -102.694232) (xy 143.300109 -102.698689)
			(xy 143.308818 -102.764785) (xy 143.30934 -102.798118) (xy 143.308838 -102.830079) (xy 143.300827 -102.893497)
			(xy 143.28493 -102.955411) (xy 143.261398 -103.014844) (xy 143.230604 -103.070859) (xy 143.193031 -103.122574)
			(xy 143.149274 -103.169171) (xy 143.100021 -103.209916) (xy 143.04605 -103.244167) (xy 142.988211 -103.271384)
			(xy 142.927418 -103.291137) (xy 142.864628 -103.303115) (xy 142.800832 -103.307129) (xy 142.737036 -103.303115)
			(xy 142.674246 -103.291137) (xy 142.613453 -103.271384) (xy 142.555614 -103.244167) (xy 142.501643 -103.209916)
			(xy 142.45239 -103.169171) (xy 142.408633 -103.122574) (xy 142.37106 -103.070859) (xy 142.340266 -103.014844)
			(xy 142.316734 -102.955411) (xy 142.300837 -102.893497) (xy 142.292826 -102.830079) (xy 142.292324 -102.798118)
			(xy 140.264755 -102.798118) (xy 140.237741 -102.8353) (xy 140.193984 -102.881897) (xy 140.144731 -102.922642)
			(xy 140.09076 -102.956893) (xy 140.032921 -102.98411) (xy 139.972128 -103.003863) (xy 139.909338 -103.015841)
			(xy 139.845542 -103.019855) (xy 139.781746 -103.015841) (xy 139.718956 -103.003863) (xy 139.658163 -102.98411)
			(xy 139.600324 -102.956893) (xy 139.546353 -102.922642) (xy 139.4971 -102.881897) (xy 139.453343 -102.8353)
			(xy 139.41577 -102.783585) (xy 139.384976 -102.72757) (xy 139.361444 -102.668137) (xy 139.345547 -102.606223)
			(xy 139.337536 -102.542805) (xy 136.016829 -102.542805) (xy 136.024917 -102.585203) (xy 136.028931 -102.649)
			(xy 136.024917 -102.712797) (xy 136.012939 -102.775587) (xy 135.993187 -102.836382) (xy 135.96597 -102.894221)
			(xy 135.93172 -102.948193) (xy 135.890975 -102.997448) (xy 135.844378 -103.041207) (xy 135.792664 -103.078781)
			(xy 135.736649 -103.109578) (xy 135.677216 -103.133111) (xy 135.615302 -103.149011) (xy 135.551883 -103.157025)
			(xy 135.519922 -103.157528) (xy 135.487052 -103.156998) (xy 135.421859 -103.14854) (xy 135.3583 -103.131749)
			(xy 135.297435 -103.106906) (xy 135.24028 -103.074425) (xy 135.187789 -103.034848) (xy 135.140837 -102.988835)
			(xy 135.100207 -102.937153) (xy 135.066578 -102.880666) (xy 135.05307 -102.850696) (xy 135.04728 -102.838183)
			(xy 135.030046 -102.816669) (xy 135.007681 -102.800557) (xy 134.981818 -102.791023) (xy 134.954346 -102.788764)
			(xy 134.927272 -102.793945) (xy 134.902575 -102.806187) (xy 134.882059 -102.824595) (xy 134.874254 -102.835964)
			(xy 134.856669 -102.862441) (xy 134.815926 -102.911227) (xy 134.769419 -102.954553) (xy 134.717873 -102.991743)
			(xy 134.662093 -103.022217) (xy 134.602949 -103.045499) (xy 134.541364 -103.061226) (xy 134.478299 -103.069152)
			(xy 134.446518 -103.069644) (xy 134.414557 -103.069092) (xy 134.351139 -103.061083) (xy 134.289225 -103.045188)
			(xy 134.229792 -103.021658) (xy 134.173776 -102.990865) (xy 134.122062 -102.953294) (xy 134.075464 -102.909538)
			(xy 134.034718 -102.860286) (xy 134.000467 -102.806316) (xy 133.97325 -102.748478) (xy 133.953496 -102.687685)
			(xy 133.941518 -102.624895) (xy 133.937504 -102.5611) (xy 16.135568 -102.5611) (xy 17.221708 -103.64724)
			(xy 17.228547 -103.654641) (xy 17.236266 -103.673239) (xy 17.236694 -103.683308) (xy 17.236694 -105.64622)
			(xy 42.521632 -105.64622) (xy 42.522172 -105.617167) (xy 42.530968 -105.55973) (xy 42.548376 -105.504292)
			(xy 42.573993 -105.452137) (xy 42.607225 -105.404471) (xy 42.647303 -105.362399) (xy 42.669968 -105.344214)
			(xy 42.678796 -105.336762) (xy 42.689122 -105.316124) (xy 42.68978 -105.30459) (xy 42.69105 -105.21315)
			(xy 42.681398 -105.192322) (xy 42.672254 -105.184956) (xy 42.650727 -105.166724) (xy 42.612717 -105.125041)
			(xy 42.581264 -105.078213) (xy 42.557052 -105.027262) (xy 42.540612 -104.973301) (xy 42.532301 -104.917505)
			(xy 42.531792 -104.8893) (xy 42.532278 -104.862049) (xy 42.540034 -104.808101) (xy 42.555389 -104.755806)
			(xy 42.578031 -104.706229) (xy 42.607497 -104.660379) (xy 42.643188 -104.619188) (xy 42.684379 -104.583497)
			(xy 42.730229 -104.554031) (xy 42.779806 -104.531389) (xy 42.832101 -104.516034) (xy 42.886049 -104.508278)
			(xy 42.940551 -104.508278) (xy 42.994499 -104.516034) (xy 43.046794 -104.531389) (xy 43.096371 -104.554031)
			(xy 43.142221 -104.583497) (xy 43.183412 -104.619188) (xy 43.219103 -104.660379) (xy 43.248569 -104.706229)
			(xy 43.271211 -104.755806) (xy 43.286566 -104.808101) (xy 43.294322 -104.862049) (xy 43.294808 -104.8893)
			(xy 43.294267 -104.918353) (xy 43.285468 -104.975789) (xy 43.26806 -105.031226) (xy 43.242443 -105.083381)
			(xy 43.209212 -105.131047) (xy 43.169136 -105.17312) (xy 43.146472 -105.191306) (xy 43.137624 -105.198738)
			(xy 43.127312 -105.219392) (xy 43.12666 -105.23093) (xy 43.12539 -105.32237) (xy 43.135042 -105.343198)
			(xy 43.144186 -105.350564) (xy 43.164665 -105.367794) (xy 43.201033 -105.407057) (xy 43.231542 -105.451028)
			(xy 43.255593 -105.498838) (xy 43.264582 -105.524046) (xy 43.264582 -105.5243) (xy 43.267757 -105.532533)
			(xy 43.2788 -105.546281) (xy 43.293861 -105.555454) (xy 43.302428 -105.557574) (xy 43.388026 -105.575608)
			(xy 43.39676 -105.57702) (xy 43.414257 -105.574515) (xy 43.429846 -105.566183) (xy 43.436032 -105.55986)
			(xy 43.454171 -105.540522) (xy 43.494921 -105.5066) (xy 43.539975 -105.478646) (xy 43.588465 -105.457199)
			(xy 43.639457 -105.44267) (xy 43.691969 -105.435341) (xy 43.71848 -105.434892) (xy 43.745734 -105.435354)
			(xy 43.799687 -105.443109) (xy 43.851987 -105.458463) (xy 43.90157 -105.481104) (xy 43.945072 -105.50906)
			(xy 49.323752 -105.50906) (xy 49.324313 -105.480007) (xy 49.333104 -105.422571) (xy 49.350507 -105.367134)
			(xy 49.37612 -105.314978) (xy 49.409348 -105.267312) (xy 49.449424 -105.225239) (xy 49.472088 -105.207054)
			(xy 49.480901 -105.199587) (xy 49.491234 -105.17896) (xy 49.4919 -105.16743) (xy 49.49317 -105.07599)
			(xy 49.483518 -105.055162) (xy 49.474374 -105.047796) (xy 49.452822 -105.029592) (xy 49.414813 -104.987904)
			(xy 49.383362 -104.94107) (xy 49.359155 -104.890114) (xy 49.34272 -104.836147) (xy 49.334416 -104.780347)
			(xy 49.333912 -104.75214) (xy 49.334398 -104.724889) (xy 49.342154 -104.670941) (xy 49.357509 -104.618646)
			(xy 49.380151 -104.569069) (xy 49.409617 -104.523219) (xy 49.445308 -104.482028) (xy 49.486499 -104.446337)
			(xy 49.532349 -104.416871) (xy 49.581926 -104.394229) (xy 49.634221 -104.378874) (xy 49.688169 -104.371118)
			(xy 49.742671 -104.371118) (xy 49.796619 -104.378874) (xy 49.848914 -104.394229) (xy 49.898491 -104.416871)
			(xy 49.944341 -104.446337) (xy 49.985532 -104.482028) (xy 50.021223 -104.523219) (xy 50.039385 -104.55148)
			(xy 87.728552 -104.55148) (xy 87.728995 -104.513192) (xy 87.735614 -104.436902) (xy 87.748759 -104.361462)
			(xy 87.768333 -104.28743) (xy 87.780876 -104.251252) (xy 87.783536 -104.242818) (xy 87.78353 -104.225145)
			(xy 87.780876 -104.216708) (xy 87.768312 -104.180536) (xy 87.748718 -104.106506) (xy 87.735569 -104.031064)
			(xy 87.728962 -103.95477) (xy 87.728552 -103.91648) (xy 87.729047 -103.875378) (xy 87.736634 -103.793526)
			(xy 87.75174 -103.712722) (xy 87.774237 -103.633657) (xy 87.803932 -103.557005) (xy 87.840574 -103.48342)
			(xy 87.883848 -103.413529) (xy 87.933386 -103.347929) (xy 87.988766 -103.28718) (xy 88.049514 -103.231799)
			(xy 88.115113 -103.182259) (xy 88.185003 -103.138983) (xy 88.258587 -103.10234) (xy 88.335238 -103.072643)
			(xy 88.414303 -103.050144) (xy 88.495106 -103.035037) (xy 88.576958 -103.027448) (xy 88.61806 -103.026972)
			(xy 88.656348 -103.027402) (xy 88.732638 -103.034025) (xy 88.808078 -103.047174) (xy 88.88211 -103.066751)
			(xy 88.918288 -103.079296) (xy 88.926725 -103.081947) (xy 88.944395 -103.081947) (xy 88.952832 -103.079296)
			(xy 88.989001 -103.066722) (xy 89.063032 -103.04713) (xy 89.138475 -103.033984) (xy 89.21477 -103.02738)
			(xy 89.25306 -103.026972) (xy 89.291348 -103.027402) (xy 89.367638 -103.034025) (xy 89.443078 -103.047174)
			(xy 89.51711 -103.066751) (xy 89.553288 -103.079296) (xy 89.561725 -103.081947) (xy 89.579395 -103.081947)
			(xy 89.587832 -103.079296) (xy 89.624001 -103.066722) (xy 89.698032 -103.04713) (xy 89.773475 -103.033984)
			(xy 89.84977 -103.02738) (xy 89.88806 -103.026972) (xy 89.929162 -103.02749) (xy 90.011015 -103.035072)
			(xy 90.09182 -103.050173) (xy 90.170887 -103.072666) (xy 90.247541 -103.102358) (xy 90.321128 -103.138997)
			(xy 90.391021 -103.182269) (xy 90.456623 -103.231806) (xy 90.517374 -103.287184) (xy 90.572756 -103.347931)
			(xy 90.622297 -103.41353) (xy 90.665574 -103.48342) (xy 90.702217 -103.557004) (xy 90.731915 -103.633656)
			(xy 90.754413 -103.712721) (xy 90.76952 -103.793525) (xy 90.777107 -103.875378) (xy 90.777568 -103.91648)
			(xy 90.777148 -103.954769) (xy 90.770522 -104.031059) (xy 90.757371 -104.106499) (xy 90.73779 -104.180531)
			(xy 90.725244 -104.216708) (xy 90.722603 -104.225147) (xy 90.722597 -104.242815) (xy 90.725244 -104.251252)
			(xy 90.737826 -104.287418) (xy 90.756204 -104.356873) (xy 144.491196 -104.356873) (xy 144.491196 -104.292951)
			(xy 144.499207 -104.229533) (xy 144.515104 -104.167619) (xy 144.538636 -104.108186) (xy 144.56943 -104.052171)
			(xy 144.607003 -104.000456) (xy 144.65076 -103.953859) (xy 144.700013 -103.913114) (xy 144.753984 -103.878863)
			(xy 144.811823 -103.851646) (xy 144.872616 -103.831893) (xy 144.935406 -103.819915) (xy 144.999202 -103.815902)
			(xy 145.062998 -103.819915) (xy 145.125788 -103.831893) (xy 145.186581 -103.851646) (xy 145.24442 -103.878863)
			(xy 145.298391 -103.913114) (xy 145.347644 -103.953859) (xy 145.391401 -104.000456) (xy 145.428974 -104.052171)
			(xy 145.459768 -104.108186) (xy 145.471962 -104.138984) (xy 154.795472 -104.138984) (xy 154.799543 -104.083362)
			(xy 154.811669 -104.028925) (xy 154.831592 -103.976834) (xy 154.858888 -103.928199) (xy 154.892974 -103.884056)
			(xy 154.933123 -103.845347) (xy 154.978481 -103.812896) (xy 155.028081 -103.787395) (xy 155.080865 -103.769388)
			(xy 155.135708 -103.759258) (xy 155.191442 -103.757221) (xy 155.246879 -103.763321) (xy 155.300836 -103.777427)
			(xy 155.352165 -103.799239) (xy 155.399771 -103.828293) (xy 155.442639 -103.863968) (xy 155.479856 -103.905505)
			(xy 155.510629 -103.952018) (xy 155.534301 -104.002515) (xy 155.550369 -104.055922) (xy 155.558489 -104.111098)
			(xy 155.558998 -104.138984) (xy 155.558489 -104.16687) (xy 155.550369 -104.222046) (xy 155.534301 -104.275453)
			(xy 155.510629 -104.32595) (xy 155.479856 -104.372463) (xy 155.442639 -104.414) (xy 155.399771 -104.449675)
			(xy 155.352165 -104.478729) (xy 155.300836 -104.500541) (xy 155.246879 -104.514647) (xy 155.191442 -104.520747)
			(xy 155.135708 -104.51871) (xy 155.080865 -104.50858) (xy 155.028081 -104.490573) (xy 154.978481 -104.465072)
			(xy 154.933123 -104.432621) (xy 154.892974 -104.393912) (xy 154.858888 -104.349769) (xy 154.831592 -104.301134)
			(xy 154.811669 -104.249043) (xy 154.799543 -104.194606) (xy 154.795472 -104.138984) (xy 145.471962 -104.138984)
			(xy 145.4833 -104.167619) (xy 145.499197 -104.229533) (xy 145.507208 -104.292951) (xy 145.50771 -104.324912)
			(xy 145.507208 -104.356873) (xy 145.499197 -104.420291) (xy 145.4833 -104.482205) (xy 145.459768 -104.541638)
			(xy 145.428974 -104.597653) (xy 145.391401 -104.649368) (xy 145.347644 -104.695965) (xy 145.298391 -104.73671)
			(xy 145.24442 -104.770961) (xy 145.186581 -104.798178) (xy 145.125788 -104.817931) (xy 145.062998 -104.829909)
			(xy 144.999202 -104.833923) (xy 144.935406 -104.829909) (xy 144.872616 -104.817931) (xy 144.811823 -104.798178)
			(xy 144.753984 -104.770961) (xy 144.700013 -104.73671) (xy 144.65076 -104.695965) (xy 144.607003 -104.649368)
			(xy 144.56943 -104.597653) (xy 144.538636 -104.541638) (xy 144.515104 -104.482205) (xy 144.499207 -104.420291)
			(xy 144.491196 -104.356873) (xy 90.756204 -104.356873) (xy 90.757415 -104.361451) (xy 90.770559 -104.436895)
			(xy 90.777161 -104.51319) (xy 90.777568 -104.55148) (xy 90.777129 -104.592584) (xy 90.769545 -104.674441)
			(xy 90.754441 -104.75525) (xy 90.731944 -104.83432) (xy 90.702248 -104.910977) (xy 90.665605 -104.984567)
			(xy 90.651802 -105.006859) (xy 145.773896 -105.006859) (xy 145.773896 -104.942937) (xy 145.781907 -104.879519)
			(xy 145.797804 -104.817605) (xy 145.821336 -104.758172) (xy 145.85213 -104.702157) (xy 145.889703 -104.650442)
			(xy 145.93346 -104.603845) (xy 145.982713 -104.5631) (xy 146.036684 -104.528849) (xy 146.094523 -104.501632)
			(xy 146.155316 -104.481879) (xy 146.218106 -104.469901) (xy 146.281902 -104.465888) (xy 146.345698 -104.469901)
			(xy 146.408488 -104.481879) (xy 146.469281 -104.501632) (xy 146.52712 -104.528849) (xy 146.581091 -104.5631)
			(xy 146.630344 -104.603845) (xy 146.674101 -104.650442) (xy 146.711674 -104.702157) (xy 146.742468 -104.758172)
			(xy 146.766 -104.817605) (xy 146.781897 -104.879519) (xy 146.789908 -104.942937) (xy 146.79041 -104.974898)
			(xy 146.789908 -105.006859) (xy 146.781897 -105.070277) (xy 146.766 -105.132191) (xy 146.742468 -105.191624)
			(xy 146.711674 -105.247639) (xy 146.674101 -105.299354) (xy 146.630344 -105.345951) (xy 146.581091 -105.386696)
			(xy 146.52712 -105.420947) (xy 146.469281 -105.448164) (xy 146.408488 -105.467917) (xy 146.345698 -105.479895)
			(xy 146.281902 -105.483909) (xy 146.218106 -105.479895) (xy 146.155316 -105.467917) (xy 146.094523 -105.448164)
			(xy 146.036684 -105.420947) (xy 145.982713 -105.386696) (xy 145.93346 -105.345951) (xy 145.889703 -105.299354)
			(xy 145.85213 -105.247639) (xy 145.821336 -105.191624) (xy 145.797804 -105.132191) (xy 145.781907 -105.070277)
			(xy 145.773896 -105.006859) (xy 90.651802 -105.006859) (xy 90.622328 -105.054461) (xy 90.572786 -105.120064)
			(xy 90.517402 -105.180816) (xy 90.456649 -105.236199) (xy 90.391045 -105.285739) (xy 90.321149 -105.329014)
			(xy 90.247559 -105.365656) (xy 90.170901 -105.39535) (xy 90.09183 -105.417845) (xy 90.011022 -105.432948)
			(xy 89.929164 -105.44053) (xy 89.88806 -105.440988) (xy 89.849772 -105.440555) (xy 89.773482 -105.433933)
			(xy 89.698042 -105.420785) (xy 89.62401 -105.401208) (xy 89.587832 -105.388664) (xy 89.579395 -105.386013)
			(xy 89.561725 -105.386013) (xy 89.553288 -105.388664) (xy 89.517117 -105.401231) (xy 89.443086 -105.420825)
			(xy 89.367644 -105.433973) (xy 89.29135 -105.440579) (xy 89.25306 -105.440988) (xy 89.214772 -105.440555)
			(xy 89.138482 -105.433933) (xy 89.063042 -105.420785) (xy 88.98901 -105.401208) (xy 88.952832 -105.388664)
			(xy 88.944395 -105.386013) (xy 88.926725 -105.386013) (xy 88.918288 -105.388664) (xy 88.882117 -105.401231)
			(xy 88.808086 -105.420825) (xy 88.732644 -105.433973) (xy 88.65635 -105.440579) (xy 88.61806 -105.440988)
			(xy 88.576956 -105.440572) (xy 88.4951 -105.432983) (xy 88.414293 -105.417874) (xy 88.335224 -105.395373)
			(xy 88.258569 -105.365674) (xy 88.184982 -105.329028) (xy 88.115089 -105.285748) (xy 88.049488 -105.236205)
			(xy 87.988737 -105.18082) (xy 87.933357 -105.120066) (xy 87.883818 -105.054462) (xy 87.840543 -104.984566)
			(xy 87.803902 -104.910976) (xy 87.774208 -104.834319) (xy 87.751712 -104.755249) (xy 87.736609 -104.674441)
			(xy 87.729026 -104.592584) (xy 87.728552 -104.55148) (xy 50.039385 -104.55148) (xy 50.050689 -104.569069)
			(xy 50.073331 -104.618646) (xy 50.088686 -104.670941) (xy 50.096442 -104.724889) (xy 50.096928 -104.75214)
			(xy 50.096375 -104.781193) (xy 50.087583 -104.83863) (xy 50.070179 -104.894068) (xy 50.044565 -104.946224)
			(xy 50.011335 -104.993889) (xy 49.971257 -105.035962) (xy 49.948592 -105.054146) (xy 49.939775 -105.061609)
			(xy 49.929445 -105.082239) (xy 49.92878 -105.09377) (xy 49.92751 -105.18521) (xy 49.937162 -105.206038)
			(xy 49.946306 -105.213404) (xy 49.967854 -105.231613) (xy 50.005864 -105.273299) (xy 50.037316 -105.320132)
			(xy 50.061524 -105.371087) (xy 50.07796 -105.425054) (xy 50.086264 -105.480853) (xy 50.086768 -105.50906)
			(xy 50.086282 -105.536311) (xy 50.078526 -105.590259) (xy 50.063171 -105.642554) (xy 50.040529 -105.692131)
			(xy 50.011063 -105.737981) (xy 49.975372 -105.779172) (xy 49.934181 -105.814863) (xy 49.888331 -105.844329)
			(xy 49.838754 -105.866971) (xy 49.786459 -105.882326) (xy 49.732511 -105.890082) (xy 49.678009 -105.890082)
			(xy 49.624061 -105.882326) (xy 49.571766 -105.866971) (xy 49.522189 -105.844329) (xy 49.476339 -105.814863)
			(xy 49.435148 -105.779172) (xy 49.399457 -105.737981) (xy 49.369991 -105.692131) (xy 49.347349 -105.642554)
			(xy 49.331994 -105.590259) (xy 49.324238 -105.536311) (xy 49.323752 -105.50906) (xy 43.945072 -105.50906)
			(xy 43.947425 -105.510572) (xy 43.98862 -105.546265) (xy 44.024316 -105.587459) (xy 44.053786 -105.633313)
			(xy 44.07643 -105.682894) (xy 44.091787 -105.735194) (xy 44.099545 -105.789146) (xy 44.099545 -105.843654)
			(xy 44.091787 -105.897606) (xy 44.07643 -105.949906) (xy 44.053786 -105.999487) (xy 44.024316 -106.045341)
			(xy 43.98862 -106.086535) (xy 43.947425 -106.122228) (xy 43.90157 -106.151696) (xy 43.851987 -106.174337)
			(xy 43.799687 -106.189691) (xy 43.745734 -106.197446) (xy 43.71848 -106.197908) (xy 43.692085 -106.197414)
			(xy 43.639798 -106.190146) (xy 43.589013 -106.175737) (xy 43.5407 -106.154464) (xy 43.495782 -106.126731)
			(xy 43.455117 -106.09307) (xy 43.419482 -106.054123) (xy 43.389558 -106.010634) (xy 43.365916 -105.963435)
			(xy 43.357038 -105.938574) (xy 43.357038 -105.93832) (xy 43.353842 -105.930097) (xy 43.342808 -105.916347)
			(xy 43.327755 -105.90717) (xy 43.319192 -105.905046) (xy 43.233594 -105.887012) (xy 43.224859 -105.88561)
			(xy 43.207362 -105.888109) (xy 43.191774 -105.896438) (xy 43.185588 -105.90276) (xy 43.167443 -105.922092)
			(xy 43.126694 -105.956014) (xy 43.081641 -105.983968) (xy 43.033152 -106.005416) (xy 42.982162 -106.019946)
			(xy 42.92965 -106.027277) (xy 42.90314 -106.027728) (xy 42.875889 -106.027208) (xy 42.821941 -106.019457)
			(xy 42.769646 -106.004107) (xy 42.720067 -105.98147) (xy 42.674215 -105.952008) (xy 42.633022 -105.91632)
			(xy 42.597328 -105.875133) (xy 42.567859 -105.829286) (xy 42.545214 -105.779711) (xy 42.529856 -105.727418)
			(xy 42.522097 -105.673471) (xy 42.521632 -105.64622) (xy 17.236694 -105.64622) (xy 17.236694 -106.651001)
			(xy 39.720514 -106.651001) (xy 39.720514 -106.587079) (xy 39.728525 -106.523661) (xy 39.744422 -106.461747)
			(xy 39.767954 -106.402314) (xy 39.798748 -106.346299) (xy 39.836321 -106.294584) (xy 39.880078 -106.247987)
			(xy 39.929331 -106.207242) (xy 39.983302 -106.172991) (xy 40.041141 -106.145774) (xy 40.101934 -106.126021)
			(xy 40.164724 -106.114043) (xy 40.22852 -106.11003) (xy 40.292316 -106.114043) (xy 40.355106 -106.126021)
			(xy 40.415899 -106.145774) (xy 40.473738 -106.172991) (xy 40.527709 -106.207242) (xy 40.576962 -106.247987)
			(xy 40.620719 -106.294584) (xy 40.658292 -106.346299) (xy 40.689086 -106.402314) (xy 40.712618 -106.461747)
			(xy 40.728515 -106.523661) (xy 40.728558 -106.524001) (xy 44.621444 -106.524001) (xy 44.621444 -106.460079)
			(xy 44.629455 -106.396661) (xy 44.645352 -106.334747) (xy 44.668884 -106.275314) (xy 44.699678 -106.219299)
			(xy 44.737251 -106.167584) (xy 44.781008 -106.120987) (xy 44.830261 -106.080242) (xy 44.884232 -106.045991)
			(xy 44.942071 -106.018774) (xy 45.002864 -105.999021) (xy 45.065654 -105.987043) (xy 45.12945 -105.98303)
			(xy 45.193246 -105.987043) (xy 45.256036 -105.999021) (xy 45.316829 -106.018774) (xy 45.374668 -106.045991)
			(xy 45.428639 -106.080242) (xy 45.477892 -106.120987) (xy 45.521649 -106.167584) (xy 45.559222 -106.219299)
			(xy 45.590016 -106.275314) (xy 45.613548 -106.334747) (xy 45.629445 -106.396661) (xy 45.637456 -106.460079)
			(xy 45.637958 -106.49204) (xy 45.637616 -106.513841) (xy 46.522634 -106.513841) (xy 46.522634 -106.449919)
			(xy 46.530645 -106.386501) (xy 46.546542 -106.324587) (xy 46.570074 -106.265154) (xy 46.600868 -106.209139)
			(xy 46.638441 -106.157424) (xy 46.682198 -106.110827) (xy 46.731451 -106.070082) (xy 46.785422 -106.035831)
			(xy 46.843261 -106.008614) (xy 46.904054 -105.988861) (xy 46.966844 -105.976883) (xy 47.03064 -105.97287)
			(xy 47.094436 -105.976883) (xy 47.157226 -105.988861) (xy 47.218019 -106.008614) (xy 47.275858 -106.035831)
			(xy 47.329829 -106.070082) (xy 47.379082 -106.110827) (xy 47.422839 -106.157424) (xy 47.460412 -106.209139)
			(xy 47.491206 -106.265154) (xy 47.514738 -106.324587) (xy 47.530635 -106.386501) (xy 47.534983 -106.42092)
			(xy 123.636022 -106.42092) (xy 123.640093 -106.365298) (xy 123.652219 -106.310861) (xy 123.672142 -106.25877)
			(xy 123.699438 -106.210135) (xy 123.733524 -106.165992) (xy 123.773673 -106.127283) (xy 123.819031 -106.094832)
			(xy 123.868631 -106.069331) (xy 123.921415 -106.051324) (xy 123.976258 -106.041194) (xy 124.031992 -106.039157)
			(xy 124.087429 -106.045257) (xy 124.141386 -106.059363) (xy 124.192715 -106.081175) (xy 124.228261 -106.102869)
			(xy 132.760714 -106.102869) (xy 132.760714 -106.038947) (xy 132.768725 -105.975529) (xy 132.784622 -105.913615)
			(xy 132.808154 -105.854182) (xy 132.838948 -105.798167) (xy 132.876521 -105.746452) (xy 132.920278 -105.699855)
			(xy 132.969531 -105.65911) (xy 133.023502 -105.624859) (xy 133.081341 -105.597642) (xy 133.142134 -105.577889)
			(xy 133.204924 -105.565911) (xy 133.26872 -105.561898) (xy 133.332516 -105.565911) (xy 133.395306 -105.577889)
			(xy 133.456099 -105.597642) (xy 133.513938 -105.624859) (xy 133.513977 -105.624884) (xy 143.999964 -105.624884)
			(xy 144.004035 -105.569262) (xy 144.016161 -105.514825) (xy 144.036084 -105.462734) (xy 144.06338 -105.414099)
			(xy 144.097466 -105.369956) (xy 144.137615 -105.331247) (xy 144.182973 -105.298796) (xy 144.232573 -105.273295)
			(xy 144.285357 -105.255288) (xy 144.3402 -105.245158) (xy 144.395934 -105.243121) (xy 144.451371 -105.249221)
			(xy 144.505328 -105.263327) (xy 144.556657 -105.285139) (xy 144.604263 -105.314193) (xy 144.647131 -105.349868)
			(xy 144.684348 -105.391405) (xy 144.715121 -105.437918) (xy 144.738793 -105.488415) (xy 144.754861 -105.541822)
			(xy 144.762981 -105.596998) (xy 144.76349 -105.624884) (xy 144.762981 -105.65277) (xy 144.762232 -105.657861)
			(xy 150.306526 -105.657861) (xy 150.306526 -105.593939) (xy 150.314537 -105.530521) (xy 150.330434 -105.468607)
			(xy 150.353966 -105.409174) (xy 150.38476 -105.353159) (xy 150.422333 -105.301444) (xy 150.46609 -105.254847)
			(xy 150.515343 -105.214102) (xy 150.569314 -105.179851) (xy 150.627153 -105.152634) (xy 150.687946 -105.132881)
			(xy 150.750736 -105.120903) (xy 150.814532 -105.11689) (xy 150.878328 -105.120903) (xy 150.941118 -105.132881)
			(xy 151.001911 -105.152634) (xy 151.05975 -105.179851) (xy 151.113721 -105.214102) (xy 151.162974 -105.254847)
			(xy 151.206731 -105.301444) (xy 151.244304 -105.353159) (xy 151.275098 -105.409174) (xy 151.29863 -105.468607)
			(xy 151.311299 -105.51795) (xy 160.958782 -105.51795) (xy 160.962853 -105.462328) (xy 160.974979 -105.407891)
			(xy 160.994902 -105.3558) (xy 161.022198 -105.307165) (xy 161.056284 -105.263022) (xy 161.096433 -105.224313)
			(xy 161.141791 -105.191862) (xy 161.191391 -105.166361) (xy 161.244175 -105.148354) (xy 161.299018 -105.138224)
			(xy 161.354752 -105.136187) (xy 161.410189 -105.142287) (xy 161.464146 -105.156393) (xy 161.515475 -105.178205)
			(xy 161.563081 -105.207259) (xy 161.605949 -105.242934) (xy 161.643166 -105.284471) (xy 161.673939 -105.330984)
			(xy 161.697611 -105.381481) (xy 161.713679 -105.434888) (xy 161.721799 -105.490064) (xy 161.722308 -105.51795)
			(xy 161.721799 -105.545836) (xy 161.713679 -105.601012) (xy 161.697611 -105.654419) (xy 161.696549 -105.656684)
			(xy 165.106039 -105.656684) (xy 165.10865 -105.593662) (xy 165.119037 -105.531446) (xy 165.137038 -105.470994)
			(xy 165.16238 -105.413232) (xy 165.194671 -105.359048) (xy 165.233416 -105.309274) (xy 165.278021 -105.264675)
			(xy 165.327799 -105.225936) (xy 165.381987 -105.193651) (xy 165.439752 -105.168317) (xy 165.500207 -105.150323)
			(xy 165.562424 -105.139944) (xy 165.625446 -105.137341) (xy 165.688307 -105.142553) (xy 165.75004 -105.1555)
			(xy 165.809697 -105.175984) (xy 165.866363 -105.20369) (xy 165.919167 -105.238192) (xy 165.967297 -105.27896)
			(xy 166.010016 -105.325369) (xy 166.046666 -105.376705) (xy 166.076684 -105.432181) (xy 166.09961 -105.490943)
			(xy 166.115092 -105.55209) (xy 166.122892 -105.614682) (xy 166.123366 -105.64622) (xy 166.123366 -105.646728)
			(xy 166.122815 -105.679928) (xy 166.114125 -105.745757) (xy 166.096948 -105.809898) (xy 166.084758 -105.840784)
			(xy 166.079681 -105.854232) (xy 166.076467 -105.882785) (xy 166.081346 -105.911101) (xy 166.09393 -105.936932)
			(xy 166.11322 -105.958227) (xy 166.137685 -105.973296) (xy 166.165382 -105.980942) (xy 166.179754 -105.981246)
			(xy 166.185342 -105.981246) (xy 166.21688 -105.981812) (xy 166.279472 -105.98962) (xy 166.340618 -106.005109)
			(xy 166.399378 -106.028043) (xy 166.45485 -106.058069) (xy 166.506182 -106.094726) (xy 166.552586 -106.137451)
			(xy 166.593348 -106.185587) (xy 166.627844 -106.238396) (xy 166.655542 -106.295066) (xy 166.676018 -106.354727)
			(xy 166.688957 -106.416463) (xy 166.694161 -106.479325) (xy 166.691549 -106.542347) (xy 166.681161 -106.604563)
			(xy 166.663158 -106.665016) (xy 166.637815 -106.722778) (xy 166.605522 -106.776962) (xy 166.566775 -106.826735)
			(xy 166.522169 -106.871334) (xy 166.472389 -106.910072) (xy 166.4182 -106.942356) (xy 166.360434 -106.967688)
			(xy 166.299977 -106.985681) (xy 166.23776 -106.996058) (xy 166.174736 -106.998659) (xy 166.111875 -106.993444)
			(xy 166.050142 -106.980495) (xy 165.990485 -106.960008) (xy 165.933819 -106.9323) (xy 165.881016 -106.897796)
			(xy 165.832887 -106.857025) (xy 165.79017 -106.810614) (xy 165.753522 -106.759275) (xy 165.723506 -106.703798)
			(xy 165.700582 -106.645034) (xy 165.685103 -106.583886) (xy 165.677307 -106.521293) (xy 165.676834 -106.489754)
			(xy 165.676834 -106.489246) (xy 165.677408 -106.456047) (xy 165.686089 -106.390218) (xy 165.703257 -106.326077)
			(xy 165.715442 -106.29519) (xy 165.720551 -106.281753) (xy 165.723759 -106.253195) (xy 165.718874 -106.224876)
			(xy 165.706285 -106.199043) (xy 165.68699 -106.177747) (xy 165.662521 -106.162678) (xy 165.63482 -106.155031)
			(xy 165.620446 -106.154728) (xy 165.614858 -106.154728) (xy 165.58332 -106.154188) (xy 165.520729 -106.146381)
			(xy 165.459584 -106.130891) (xy 165.400824 -106.107958) (xy 165.345353 -106.077933) (xy 165.294021 -106.041277)
			(xy 165.247617 -105.998553) (xy 165.206855 -105.950417) (xy 165.172359 -105.897609) (xy 165.14466 -105.84094)
			(xy 165.124184 -105.78128) (xy 165.111244 -105.719545) (xy 165.106039 -105.656684) (xy 161.696549 -105.656684)
			(xy 161.673939 -105.704916) (xy 161.643166 -105.751429) (xy 161.605949 -105.792966) (xy 161.563081 -105.828641)
			(xy 161.515475 -105.857695) (xy 161.464146 -105.879507) (xy 161.410189 -105.893613) (xy 161.354752 -105.899713)
			(xy 161.299018 -105.897676) (xy 161.244175 -105.887546) (xy 161.191391 -105.869539) (xy 161.141791 -105.844038)
			(xy 161.096433 -105.811587) (xy 161.056284 -105.772878) (xy 161.022198 -105.728735) (xy 160.994902 -105.6801)
			(xy 160.974979 -105.628009) (xy 160.962853 -105.573572) (xy 160.958782 -105.51795) (xy 151.311299 -105.51795)
			(xy 151.314527 -105.530521) (xy 151.322538 -105.593939) (xy 151.32304 -105.6259) (xy 151.322538 -105.657861)
			(xy 151.314527 -105.721279) (xy 151.29863 -105.783193) (xy 151.275098 -105.842626) (xy 151.244304 -105.898641)
			(xy 151.206731 -105.950356) (xy 151.162974 -105.996953) (xy 151.113721 -106.037698) (xy 151.05975 -106.071949)
			(xy 151.001911 -106.099166) (xy 150.941118 -106.118919) (xy 150.878328 -106.130897) (xy 150.814532 -106.134911)
			(xy 150.750736 -106.130897) (xy 150.687946 -106.118919) (xy 150.627153 -106.099166) (xy 150.569314 -106.071949)
			(xy 150.515343 -106.037698) (xy 150.46609 -105.996953) (xy 150.422333 -105.950356) (xy 150.38476 -105.898641)
			(xy 150.353966 -105.842626) (xy 150.330434 -105.783193) (xy 150.314537 -105.721279) (xy 150.306526 -105.657861)
			(xy 144.762232 -105.657861) (xy 144.754861 -105.707946) (xy 144.738793 -105.761353) (xy 144.715121 -105.81185)
			(xy 144.684348 -105.858363) (xy 144.647131 -105.8999) (xy 144.604263 -105.935575) (xy 144.556657 -105.964629)
			(xy 144.505328 -105.986441) (xy 144.451371 -106.000547) (xy 144.395934 -106.006647) (xy 144.3402 -106.00461)
			(xy 144.285357 -105.99448) (xy 144.232573 -105.976473) (xy 144.182973 -105.950972) (xy 144.137615 -105.918521)
			(xy 144.097466 -105.879812) (xy 144.06338 -105.835669) (xy 144.036084 -105.787034) (xy 144.016161 -105.734943)
			(xy 144.004035 -105.680506) (xy 143.999964 -105.624884) (xy 133.513977 -105.624884) (xy 133.567909 -105.65911)
			(xy 133.617162 -105.699855) (xy 133.660919 -105.746452) (xy 133.698492 -105.798167) (xy 133.729286 -105.854182)
			(xy 133.752818 -105.913615) (xy 133.768715 -105.975529) (xy 133.776726 -106.038947) (xy 133.777228 -106.070908)
			(xy 133.776726 -106.102869) (xy 133.768715 -106.166287) (xy 133.752818 -106.228201) (xy 133.729286 -106.287634)
			(xy 133.698492 -106.343649) (xy 133.660919 -106.395364) (xy 133.617162 -106.441961) (xy 133.567909 -106.482706)
			(xy 133.513938 -106.516957) (xy 133.456099 -106.544174) (xy 133.395306 -106.563927) (xy 133.332516 -106.575905)
			(xy 133.26872 -106.579919) (xy 133.204924 -106.575905) (xy 133.142134 -106.563927) (xy 133.081341 -106.544174)
			(xy 133.023502 -106.516957) (xy 132.969531 -106.482706) (xy 132.920278 -106.441961) (xy 132.876521 -106.395364)
			(xy 132.838948 -106.343649) (xy 132.808154 -106.287634) (xy 132.784622 -106.228201) (xy 132.768725 -106.166287)
			(xy 132.760714 -106.102869) (xy 124.228261 -106.102869) (xy 124.240321 -106.110229) (xy 124.283189 -106.145904)
			(xy 124.320406 -106.187441) (xy 124.351179 -106.233954) (xy 124.374851 -106.284451) (xy 124.390919 -106.337858)
			(xy 124.399039 -106.393034) (xy 124.399548 -106.42092) (xy 124.399039 -106.448806) (xy 124.390919 -106.503982)
			(xy 124.374851 -106.557389) (xy 124.351179 -106.607886) (xy 124.328442 -106.642252) (xy 152.852854 -106.642252)
			(xy 152.852854 -106.587748) (xy 152.86061 -106.533798) (xy 152.875966 -106.481502) (xy 152.898607 -106.431923)
			(xy 152.928073 -106.38607) (xy 152.963765 -106.344878) (xy 153.004956 -106.309184) (xy 153.050807 -106.279715)
			(xy 153.100385 -106.257072) (xy 153.152681 -106.241714) (xy 153.20663 -106.233955) (xy 153.233882 -106.233468)
			(xy 153.263519 -106.23404) (xy 153.322077 -106.243232) (xy 153.350468 -106.251756) (xy 153.350722 -106.251756)
			(xy 153.359532 -106.254153) (xy 153.377754 -106.253239) (xy 153.386282 -106.249978) (xy 153.455878 -106.219752)
			(xy 153.46934 -106.207052) (xy 153.47315 -106.19867) (xy 153.487287 -106.170178) (xy 153.521662 -106.116661)
			(xy 153.562441 -106.067848) (xy 153.608987 -106.024498) (xy 153.660574 -105.987289) (xy 153.716397 -105.956801)
			(xy 153.775585 -105.93351) (xy 153.837215 -105.917779) (xy 153.900325 -105.909853) (xy 153.932128 -105.909364)
			(xy 153.964086 -105.909924) (xy 154.027498 -105.917938) (xy 154.089406 -105.933836) (xy 154.148832 -105.957367)
			(xy 154.204842 -105.988161) (xy 154.25655 -106.025732) (xy 154.303141 -106.069487) (xy 154.343882 -106.118737)
			(xy 154.378129 -106.172704) (xy 154.405342 -106.230537) (xy 154.425093 -106.291326) (xy 154.437069 -106.35411)
			(xy 154.441083 -106.4179) (xy 154.437069 -106.48169) (xy 154.425093 -106.544474) (xy 154.405342 -106.605263)
			(xy 154.378129 -106.663096) (xy 154.343882 -106.717063) (xy 154.303141 -106.766313) (xy 154.25655 -106.810068)
			(xy 154.204842 -106.847639) (xy 154.148832 -106.878433) (xy 154.089406 -106.901964) (xy 154.027498 -106.917862)
			(xy 153.964086 -106.925876) (xy 153.932128 -106.92638) (xy 153.902873 -106.925963) (xy 153.84475 -106.919259)
			(xy 153.78778 -106.905926) (xy 153.732719 -106.886139) (xy 153.680294 -106.86016) (xy 153.655522 -106.844592)
			(xy 153.647648 -106.839512) (xy 153.629868 -106.835448) (xy 153.55443 -106.84637) (xy 153.545438 -106.848094)
			(xy 153.529426 -106.856941) (xy 153.523188 -106.863642) (xy 153.50498 -106.884095) (xy 153.463722 -106.920099)
			(xy 153.417739 -106.949833) (xy 153.367977 -106.972684) (xy 153.315457 -106.988184) (xy 153.261261 -106.996013)
			(xy 153.233882 -106.996484) (xy 153.20663 -106.996045) (xy 153.152681 -106.988286) (xy 153.100385 -106.972928)
			(xy 153.050807 -106.950285) (xy 153.004956 -106.920816) (xy 152.963765 -106.885122) (xy 152.928073 -106.84393)
			(xy 152.898607 -106.798077) (xy 152.875966 -106.748498) (xy 152.86061 -106.696202) (xy 152.852854 -106.642252)
			(xy 124.328442 -106.642252) (xy 124.320406 -106.654399) (xy 124.283189 -106.695936) (xy 124.240321 -106.731611)
			(xy 124.192715 -106.760665) (xy 124.141386 -106.782477) (xy 124.087429 -106.796583) (xy 124.031992 -106.802683)
			(xy 123.976258 -106.800646) (xy 123.921415 -106.790516) (xy 123.868631 -106.772509) (xy 123.819031 -106.747008)
			(xy 123.773673 -106.714557) (xy 123.733524 -106.675848) (xy 123.699438 -106.631705) (xy 123.672142 -106.58307)
			(xy 123.652219 -106.530979) (xy 123.640093 -106.476542) (xy 123.636022 -106.42092) (xy 47.534983 -106.42092)
			(xy 47.538646 -106.449919) (xy 47.539148 -106.48188) (xy 47.538646 -106.513841) (xy 47.530635 -106.577259)
			(xy 47.514738 -106.639173) (xy 47.491206 -106.698606) (xy 47.460412 -106.754621) (xy 47.422839 -106.806336)
			(xy 47.379082 -106.852933) (xy 47.329829 -106.893678) (xy 47.275858 -106.927929) (xy 47.218019 -106.955146)
			(xy 47.157226 -106.974899) (xy 47.094436 -106.986877) (xy 47.03064 -106.990891) (xy 46.966844 -106.986877)
			(xy 46.904054 -106.974899) (xy 46.843261 -106.955146) (xy 46.785422 -106.927929) (xy 46.731451 -106.893678)
			(xy 46.682198 -106.852933) (xy 46.638441 -106.806336) (xy 46.600868 -106.754621) (xy 46.570074 -106.698606)
			(xy 46.546542 -106.639173) (xy 46.530645 -106.577259) (xy 46.522634 -106.513841) (xy 45.637616 -106.513841)
			(xy 45.637456 -106.524001) (xy 45.629445 -106.587419) (xy 45.613548 -106.649333) (xy 45.590016 -106.708766)
			(xy 45.559222 -106.764781) (xy 45.521649 -106.816496) (xy 45.477892 -106.863093) (xy 45.428639 -106.903838)
			(xy 45.374668 -106.938089) (xy 45.316829 -106.965306) (xy 45.256036 -106.985059) (xy 45.193246 -106.997037)
			(xy 45.12945 -107.001051) (xy 45.065654 -106.997037) (xy 45.002864 -106.985059) (xy 44.942071 -106.965306)
			(xy 44.884232 -106.938089) (xy 44.830261 -106.903838) (xy 44.781008 -106.863093) (xy 44.737251 -106.816496)
			(xy 44.699678 -106.764781) (xy 44.668884 -106.708766) (xy 44.645352 -106.649333) (xy 44.629455 -106.587419)
			(xy 44.621444 -106.524001) (xy 40.728558 -106.524001) (xy 40.736526 -106.587079) (xy 40.737028 -106.61904)
			(xy 40.736526 -106.651001) (xy 40.728515 -106.714419) (xy 40.712618 -106.776333) (xy 40.689086 -106.835766)
			(xy 40.658292 -106.891781) (xy 40.620719 -106.943496) (xy 40.576962 -106.990093) (xy 40.527709 -107.030838)
			(xy 40.524208 -107.03306) (xy 145.9009 -107.03306) (xy 145.904971 -106.977438) (xy 145.917097 -106.923001)
			(xy 145.93702 -106.87091) (xy 145.964316 -106.822275) (xy 145.998402 -106.778132) (xy 146.038551 -106.739423)
			(xy 146.083909 -106.706972) (xy 146.133509 -106.681471) (xy 146.186293 -106.663464) (xy 146.241136 -106.653334)
			(xy 146.29687 -106.651297) (xy 146.352307 -106.657397) (xy 146.406264 -106.671503) (xy 146.457593 -106.693315)
			(xy 146.505199 -106.722369) (xy 146.548067 -106.758044) (xy 146.585284 -106.799581) (xy 146.616057 -106.846094)
			(xy 146.639729 -106.896591) (xy 146.655797 -106.949998) (xy 146.663917 -107.005174) (xy 146.664426 -107.03306)
			(xy 146.663917 -107.060946) (xy 146.655797 -107.116122) (xy 146.639729 -107.169529) (xy 146.620136 -107.211325)
			(xy 158.984944 -107.211325) (xy 158.984944 -107.147403) (xy 158.992955 -107.083985) (xy 159.008852 -107.022071)
			(xy 159.032384 -106.962638) (xy 159.063178 -106.906623) (xy 159.100751 -106.854908) (xy 159.144508 -106.808311)
			(xy 159.193761 -106.767566) (xy 159.247732 -106.733315) (xy 159.305571 -106.706098) (xy 159.366364 -106.686345)
			(xy 159.429154 -106.674367) (xy 159.49295 -106.670354) (xy 159.556746 -106.674367) (xy 159.619536 -106.686345)
			(xy 159.680329 -106.706098) (xy 159.738168 -106.733315) (xy 159.792139 -106.767566) (xy 159.841392 -106.808311)
			(xy 159.885149 -106.854908) (xy 159.922722 -106.906623) (xy 159.953516 -106.962638) (xy 159.977048 -107.022071)
			(xy 159.992945 -107.083985) (xy 160.000956 -107.147403) (xy 160.001458 -107.179364) (xy 160.000956 -107.211325)
			(xy 159.992945 -107.274743) (xy 159.977048 -107.336657) (xy 159.953516 -107.39609) (xy 159.953435 -107.396237)
			(xy 166.505884 -107.396237) (xy 166.505884 -107.332315) (xy 166.513895 -107.268897) (xy 166.529792 -107.206983)
			(xy 166.553324 -107.14755) (xy 166.584118 -107.091535) (xy 166.621691 -107.03982) (xy 166.665448 -106.993223)
			(xy 166.714701 -106.952478) (xy 166.768672 -106.918227) (xy 166.826511 -106.89101) (xy 166.887304 -106.871257)
			(xy 166.950094 -106.859279) (xy 167.01389 -106.855266) (xy 167.077686 -106.859279) (xy 167.140476 -106.871257)
			(xy 167.201269 -106.89101) (xy 167.259108 -106.918227) (xy 167.313079 -106.952478) (xy 167.362332 -106.993223)
			(xy 167.406089 -107.03982) (xy 167.443662 -107.091535) (xy 167.474456 -107.14755) (xy 167.497988 -107.206983)
			(xy 167.513885 -107.268897) (xy 167.521896 -107.332315) (xy 167.522398 -107.364276) (xy 167.521896 -107.396237)
			(xy 167.513885 -107.459655) (xy 167.497988 -107.521569) (xy 167.474456 -107.581002) (xy 167.443662 -107.637017)
			(xy 167.406089 -107.688732) (xy 167.362332 -107.735329) (xy 167.313079 -107.776074) (xy 167.259108 -107.810325)
			(xy 167.201269 -107.837542) (xy 167.140476 -107.857295) (xy 167.077686 -107.869273) (xy 167.01389 -107.873287)
			(xy 166.950094 -107.869273) (xy 166.887304 -107.857295) (xy 166.826511 -107.837542) (xy 166.768672 -107.810325)
			(xy 166.714701 -107.776074) (xy 166.665448 -107.735329) (xy 166.621691 -107.688732) (xy 166.584118 -107.637017)
			(xy 166.553324 -107.581002) (xy 166.529792 -107.521569) (xy 166.513895 -107.459655) (xy 166.505884 -107.396237)
			(xy 159.953435 -107.396237) (xy 159.922722 -107.452105) (xy 159.885149 -107.50382) (xy 159.841392 -107.550417)
			(xy 159.792139 -107.591162) (xy 159.738168 -107.625413) (xy 159.680329 -107.65263) (xy 159.619536 -107.672383)
			(xy 159.556746 -107.684361) (xy 159.49295 -107.688375) (xy 159.429154 -107.684361) (xy 159.366364 -107.672383)
			(xy 159.305571 -107.65263) (xy 159.247732 -107.625413) (xy 159.193761 -107.591162) (xy 159.144508 -107.550417)
			(xy 159.100751 -107.50382) (xy 159.063178 -107.452105) (xy 159.032384 -107.39609) (xy 159.008852 -107.336657)
			(xy 158.992955 -107.274743) (xy 158.984944 -107.211325) (xy 146.620136 -107.211325) (xy 146.616057 -107.220026)
			(xy 146.585284 -107.266539) (xy 146.548067 -107.308076) (xy 146.505199 -107.343751) (xy 146.457593 -107.372805)
			(xy 146.406264 -107.394617) (xy 146.352307 -107.408723) (xy 146.29687 -107.414823) (xy 146.241136 -107.412786)
			(xy 146.186293 -107.402656) (xy 146.133509 -107.384649) (xy 146.083909 -107.359148) (xy 146.038551 -107.326697)
			(xy 145.998402 -107.287988) (xy 145.964316 -107.243845) (xy 145.93702 -107.19521) (xy 145.917097 -107.143119)
			(xy 145.904971 -107.088682) (xy 145.9009 -107.03306) (xy 40.524208 -107.03306) (xy 40.473738 -107.065089)
			(xy 40.415899 -107.092306) (xy 40.355106 -107.112059) (xy 40.292316 -107.124037) (xy 40.22852 -107.128051)
			(xy 40.164724 -107.124037) (xy 40.101934 -107.112059) (xy 40.041141 -107.092306) (xy 39.983302 -107.065089)
			(xy 39.929331 -107.030838) (xy 39.880078 -106.990093) (xy 39.836321 -106.943496) (xy 39.798748 -106.891781)
			(xy 39.767954 -106.835766) (xy 39.744422 -106.776333) (xy 39.728525 -106.714419) (xy 39.720514 -106.651001)
			(xy 17.236694 -106.651001) (xy 17.236694 -107.123484) (xy 17.84807 -107.123484) (xy 17.852141 -107.067862)
			(xy 17.864267 -107.013425) (xy 17.88419 -106.961334) (xy 17.911486 -106.912699) (xy 17.945572 -106.868556)
			(xy 17.985721 -106.829847) (xy 18.031079 -106.797396) (xy 18.080679 -106.771895) (xy 18.133463 -106.753888)
			(xy 18.188306 -106.743758) (xy 18.24404 -106.741721) (xy 18.299477 -106.747821) (xy 18.353434 -106.761927)
			(xy 18.404763 -106.783739) (xy 18.452369 -106.812793) (xy 18.495237 -106.848468) (xy 18.532454 -106.890005)
			(xy 18.563227 -106.936518) (xy 18.586899 -106.987015) (xy 18.602967 -107.040422) (xy 18.611087 -107.095598)
			(xy 18.611596 -107.123484) (xy 18.611087 -107.15137) (xy 18.602967 -107.206546) (xy 18.586899 -107.259953)
			(xy 18.563227 -107.31045) (xy 18.532454 -107.356963) (xy 18.495237 -107.3985) (xy 18.452369 -107.434175)
			(xy 18.404763 -107.463229) (xy 18.353434 -107.485041) (xy 18.299477 -107.499147) (xy 18.24404 -107.505247)
			(xy 18.188306 -107.50321) (xy 18.133463 -107.49308) (xy 18.080679 -107.475073) (xy 18.031079 -107.449572)
			(xy 17.985721 -107.417121) (xy 17.945572 -107.378412) (xy 17.911486 -107.334269) (xy 17.88419 -107.285634)
			(xy 17.864267 -107.233543) (xy 17.852141 -107.179106) (xy 17.84807 -107.123484) (xy 17.236694 -107.123484)
			(xy 17.236694 -107.692401) (xy 36.944294 -107.692401) (xy 36.944294 -107.628479) (xy 36.952305 -107.565061)
			(xy 36.968202 -107.503147) (xy 36.991734 -107.443714) (xy 37.022528 -107.387699) (xy 37.060101 -107.335984)
			(xy 37.103858 -107.289387) (xy 37.153111 -107.248642) (xy 37.207082 -107.214391) (xy 37.264921 -107.187174)
			(xy 37.325714 -107.167421) (xy 37.388504 -107.155443) (xy 37.4523 -107.15143) (xy 37.516096 -107.155443)
			(xy 37.578886 -107.167421) (xy 37.639679 -107.187174) (xy 37.697518 -107.214391) (xy 37.751489 -107.248642)
			(xy 37.800742 -107.289387) (xy 37.844499 -107.335984) (xy 37.882072 -107.387699) (xy 37.912866 -107.443714)
			(xy 37.936398 -107.503147) (xy 37.952295 -107.565061) (xy 37.960306 -107.628479) (xy 37.960808 -107.66044)
			(xy 37.960306 -107.692401) (xy 37.952295 -107.755819) (xy 37.936398 -107.817733) (xy 37.912866 -107.877166)
			(xy 37.882072 -107.933181) (xy 37.844499 -107.984896) (xy 37.800742 -108.031493) (xy 37.751489 -108.072238)
			(xy 37.697518 -108.106489) (xy 37.639679 -108.133706) (xy 37.578886 -108.153459) (xy 37.516096 -108.165437)
			(xy 37.4523 -108.169451) (xy 37.388504 -108.165437) (xy 37.325714 -108.153459) (xy 37.264921 -108.133706)
			(xy 37.207082 -108.106489) (xy 37.153111 -108.072238) (xy 37.103858 -108.031493) (xy 37.060101 -107.984896)
			(xy 37.022528 -107.933181) (xy 36.991734 -107.877166) (xy 36.968202 -107.817733) (xy 36.952305 -107.755819)
			(xy 36.944294 -107.692401) (xy 17.236694 -107.692401) (xy 17.236694 -108.331) (xy 134.746492 -108.331)
			(xy 134.746978 -108.303749) (xy 134.754734 -108.249801) (xy 134.770089 -108.197506) (xy 134.792731 -108.147929)
			(xy 134.822197 -108.102079) (xy 134.857888 -108.060888) (xy 134.899079 -108.025197) (xy 134.944929 -107.995731)
			(xy 134.994506 -107.973089) (xy 135.046801 -107.957734) (xy 135.100749 -107.949978) (xy 135.128 -107.949492)
			(xy 135.155234 -107.950017) (xy 135.209146 -107.957785) (xy 135.261408 -107.973134) (xy 135.310958 -107.995753)
			(xy 135.356791 -108.025184) (xy 135.397978 -108.060828) (xy 135.42915 -108.096742) (xy 138.183362 -108.096742)
			(xy 138.183362 -108.012046) (xy 138.191413 -107.927732) (xy 138.207442 -107.844566) (xy 138.231303 -107.763299)
			(xy 138.262782 -107.684669) (xy 138.301593 -107.609388) (xy 138.347383 -107.538136) (xy 138.399739 -107.47156)
			(xy 138.458187 -107.410262) (xy 138.522197 -107.354797) (xy 138.591189 -107.305668) (xy 138.664539 -107.263319)
			(xy 138.741582 -107.228135) (xy 138.821621 -107.200433) (xy 138.90393 -107.180465) (xy 138.987765 -107.168412)
			(xy 139.072366 -107.164382) (xy 139.156967 -107.168412) (xy 139.240802 -107.180465) (xy 139.323111 -107.200433)
			(xy 139.40315 -107.228135) (xy 139.480193 -107.263319) (xy 139.553543 -107.305668) (xy 139.622535 -107.354797)
			(xy 139.686545 -107.410262) (xy 139.744993 -107.47156) (xy 139.797349 -107.538136) (xy 139.843139 -107.609388)
			(xy 139.881113 -107.683046) (xy 149.153624 -107.683046) (xy 149.157695 -107.627424) (xy 149.169821 -107.572987)
			(xy 149.189744 -107.520896) (xy 149.21704 -107.472261) (xy 149.251126 -107.428118) (xy 149.291275 -107.389409)
			(xy 149.336633 -107.356958) (xy 149.386233 -107.331457) (xy 149.439017 -107.31345) (xy 149.49386 -107.30332)
			(xy 149.549594 -107.301283) (xy 149.605031 -107.307383) (xy 149.658988 -107.321489) (xy 149.710317 -107.343301)
			(xy 149.757923 -107.372355) (xy 149.800791 -107.40803) (xy 149.838008 -107.449567) (xy 149.868781 -107.49608)
			(xy 149.892453 -107.546577) (xy 149.908521 -107.599984) (xy 149.916641 -107.65516) (xy 149.91715 -107.683046)
			(xy 149.916641 -107.710932) (xy 149.908521 -107.766108) (xy 149.892453 -107.819515) (xy 149.868781 -107.870012)
			(xy 149.838008 -107.916525) (xy 149.800791 -107.958062) (xy 149.757923 -107.993737) (xy 149.710317 -108.022791)
			(xy 149.658988 -108.044603) (xy 149.605031 -108.058709) (xy 149.549594 -108.064809) (xy 149.49386 -108.062772)
			(xy 149.439017 -108.052642) (xy 149.386233 -108.034635) (xy 149.336633 -108.009134) (xy 149.291275 -107.976683)
			(xy 149.251126 -107.937974) (xy 149.21704 -107.893831) (xy 149.189744 -107.845196) (xy 149.169821 -107.793105)
			(xy 149.157695 -107.738668) (xy 149.153624 -107.683046) (xy 139.881113 -107.683046) (xy 139.88195 -107.684669)
			(xy 139.913429 -107.763299) (xy 139.93729 -107.844566) (xy 139.953319 -107.927732) (xy 139.96137 -108.012046)
			(xy 139.961874 -108.054394) (xy 139.96137 -108.096742) (xy 139.953319 -108.181056) (xy 139.93729 -108.264222)
			(xy 139.917087 -108.333032) (xy 142.678402 -108.333032) (xy 142.682473 -108.27741) (xy 142.694599 -108.222973)
			(xy 142.714522 -108.170882) (xy 142.741818 -108.122247) (xy 142.775904 -108.078104) (xy 142.816053 -108.039395)
			(xy 142.861411 -108.006944) (xy 142.911011 -107.981443) (xy 142.963795 -107.963436) (xy 143.018638 -107.953306)
			(xy 143.074372 -107.951269) (xy 143.129809 -107.957369) (xy 143.183766 -107.971475) (xy 143.235095 -107.993287)
			(xy 143.282701 -108.022341) (xy 143.325569 -108.058016) (xy 143.361923 -108.09859) (xy 153.490166 -108.09859)
			(xy 153.494237 -108.042968) (xy 153.506363 -107.988531) (xy 153.526286 -107.93644) (xy 153.553582 -107.887805)
			(xy 153.587668 -107.843662) (xy 153.627817 -107.804953) (xy 153.673175 -107.772502) (xy 153.722775 -107.747001)
			(xy 153.775559 -107.728994) (xy 153.830402 -107.718864) (xy 153.886136 -107.716827) (xy 153.941573 -107.722927)
			(xy 153.99553 -107.737033) (xy 154.046859 -107.758845) (xy 154.094465 -107.787899) (xy 154.137333 -107.823574)
			(xy 154.152522 -107.840526) (xy 158.307022 -107.840526) (xy 158.311093 -107.784904) (xy 158.323219 -107.730467)
			(xy 158.343142 -107.678376) (xy 158.370438 -107.629741) (xy 158.404524 -107.585598) (xy 158.444673 -107.546889)
			(xy 158.490031 -107.514438) (xy 158.539631 -107.488937) (xy 158.592415 -107.47093) (xy 158.647258 -107.4608)
			(xy 158.702992 -107.458763) (xy 158.758429 -107.464863) (xy 158.812386 -107.478969) (xy 158.863715 -107.500781)
			(xy 158.911321 -107.529835) (xy 158.954189 -107.56551) (xy 158.991406 -107.607047) (xy 159.022179 -107.65356)
			(xy 159.045851 -107.704057) (xy 159.061919 -107.757464) (xy 159.070039 -107.81264) (xy 159.070548 -107.840526)
			(xy 159.070039 -107.868412) (xy 159.061919 -107.923588) (xy 159.045851 -107.976995) (xy 159.022179 -108.027492)
			(xy 158.991406 -108.074005) (xy 158.954189 -108.115542) (xy 158.911321 -108.151217) (xy 158.863715 -108.180271)
			(xy 158.812386 -108.202083) (xy 158.758429 -108.216189) (xy 158.702992 -108.222289) (xy 158.647258 -108.220252)
			(xy 158.592415 -108.210122) (xy 158.539631 -108.192115) (xy 158.490031 -108.166614) (xy 158.444673 -108.134163)
			(xy 158.404524 -108.095454) (xy 158.370438 -108.051311) (xy 158.343142 -108.002676) (xy 158.323219 -107.950585)
			(xy 158.311093 -107.896148) (xy 158.307022 -107.840526) (xy 154.152522 -107.840526) (xy 154.17455 -107.865111)
			(xy 154.205323 -107.911624) (xy 154.228995 -107.962121) (xy 154.245063 -108.015528) (xy 154.253183 -108.070704)
			(xy 154.253692 -108.09859) (xy 154.253183 -108.126476) (xy 154.245063 -108.181652) (xy 154.228995 -108.235059)
			(xy 154.205323 -108.285556) (xy 154.17455 -108.332069) (xy 154.137333 -108.373606) (xy 154.094465 -108.409281)
			(xy 154.046859 -108.438335) (xy 153.99553 -108.460147) (xy 153.941573 -108.474253) (xy 153.886136 -108.480353)
			(xy 153.830402 -108.478316) (xy 153.775559 -108.468186) (xy 153.722775 -108.450179) (xy 153.673175 -108.424678)
			(xy 153.627817 -108.392227) (xy 153.587668 -108.353518) (xy 153.553582 -108.309375) (xy 153.526286 -108.26074)
			(xy 153.506363 -108.208649) (xy 153.494237 -108.154212) (xy 153.490166 -108.09859) (xy 143.361923 -108.09859)
			(xy 143.362786 -108.099553) (xy 143.393559 -108.146066) (xy 143.417231 -108.196563) (xy 143.433299 -108.24997)
			(xy 143.441419 -108.305146) (xy 143.441928 -108.333032) (xy 143.441419 -108.360918) (xy 143.433299 -108.416094)
			(xy 143.417231 -108.469501) (xy 143.393559 -108.519998) (xy 143.362786 -108.566511) (xy 143.325569 -108.608048)
			(xy 143.282701 -108.643723) (xy 143.235095 -108.672777) (xy 143.183766 -108.694589) (xy 143.166717 -108.699046)
			(xy 149.027134 -108.699046) (xy 149.027636 -108.667085) (xy 149.035647 -108.603667) (xy 149.051544 -108.541753)
			(xy 149.075076 -108.48232) (xy 149.10587 -108.426305) (xy 149.143443 -108.37459) (xy 149.1872 -108.327993)
			(xy 149.236453 -108.287248) (xy 149.290424 -108.252997) (xy 149.348263 -108.22578) (xy 149.409056 -108.206027)
			(xy 149.471846 -108.194049) (xy 149.535642 -108.190036) (xy 149.599438 -108.194049) (xy 149.662228 -108.206027)
			(xy 149.723021 -108.22578) (xy 149.78086 -108.252997) (xy 149.834831 -108.287248) (xy 149.884084 -108.327993)
			(xy 149.927841 -108.37459) (xy 149.965414 -108.426305) (xy 149.996208 -108.48232) (xy 150.01974 -108.541753)
			(xy 150.035637 -108.603667) (xy 150.043648 -108.667085) (xy 150.04415 -108.699046) (xy 150.043718 -108.730508)
			(xy 150.035955 -108.792951) (xy 150.020543 -108.853959) (xy 149.997717 -108.912596) (xy 149.967826 -108.967967)
			(xy 149.931328 -109.019224) (xy 149.88878 -109.065583) (xy 149.84758 -109.1006) (xy 152.735788 -109.1006)
			(xy 152.739802 -109.036804) (xy 152.75178 -108.974013) (xy 152.771533 -108.913219) (xy 152.79875 -108.855381)
			(xy 152.833002 -108.801409) (xy 152.873748 -108.752156) (xy 152.920346 -108.708398) (xy 152.97206 -108.670826)
			(xy 153.028076 -108.640031) (xy 153.08751 -108.6165) (xy 153.149424 -108.600604) (xy 153.212843 -108.592593)
			(xy 153.244804 -108.592112) (xy 153.245058 -108.592112) (xy 153.279429 -108.592657) (xy 153.347542 -108.601947)
			(xy 153.413784 -108.620323) (xy 153.476948 -108.647449) (xy 153.535885 -108.682834) (xy 153.589522 -108.725831)
			(xy 153.613612 -108.750354) (xy 153.620724 -108.757974) (xy 153.640028 -108.766356) (xy 153.73477 -108.766102)
			(xy 153.753566 -108.757974) (xy 153.760932 -108.750354) (xy 153.785007 -108.72573) (xy 153.83869 -108.682594)
			(xy 153.897703 -108.647098) (xy 153.960967 -108.619891) (xy 154.027325 -108.601471) (xy 154.095561 -108.592176)
			(xy 154.129994 -108.591604) (xy 154.161957 -108.592061) (xy 154.22538 -108.600072) (xy 154.287299 -108.615969)
			(xy 154.346736 -108.639502) (xy 154.402756 -108.670298) (xy 154.454474 -108.707873) (xy 154.501075 -108.751634)
			(xy 154.541823 -108.80089) (xy 154.576077 -108.854865) (xy 154.603296 -108.912707) (xy 154.623051 -108.973505)
			(xy 154.624567 -108.981451) (xy 161.399722 -108.981451) (xy 161.399722 -108.917529) (xy 161.407733 -108.854111)
			(xy 161.42363 -108.792197) (xy 161.447162 -108.732764) (xy 161.477956 -108.676749) (xy 161.515529 -108.625034)
			(xy 161.559286 -108.578437) (xy 161.608539 -108.537692) (xy 161.66251 -108.503441) (xy 161.720349 -108.476224)
			(xy 161.781142 -108.456471) (xy 161.843932 -108.444493) (xy 161.907728 -108.44048) (xy 161.971524 -108.444493)
			(xy 162.034314 -108.456471) (xy 162.095107 -108.476224) (xy 162.152946 -108.503441) (xy 162.206917 -108.537692)
			(xy 162.25617 -108.578437) (xy 162.289566 -108.614) (xy 162.662024 -108.614) (xy 162.666039 -108.550194)
			(xy 162.678019 -108.487394) (xy 162.697776 -108.426591) (xy 162.724997 -108.368744) (xy 162.759255 -108.314765)
			(xy 162.800008 -108.265505) (xy 162.846613 -108.221742) (xy 162.898337 -108.184165) (xy 162.954362 -108.153367)
			(xy 163.013805 -108.129834) (xy 163.07573 -108.113938) (xy 163.139158 -108.105928) (xy 163.171124 -108.105448)
			(xy 163.195081 -108.105689) (xy 163.242786 -108.110144) (xy 163.266374 -108.114338) (xy 163.275518 -108.116116)
			(xy 163.29406 -108.112814) (xy 163.3601 -108.07319) (xy 163.367802 -108.068103) (xy 163.379267 -108.053658)
			(xy 163.382452 -108.044996) (xy 163.382452 -108.044488) (xy 163.390918 -108.018904) (xy 163.413933 -107.970179)
			(xy 163.443574 -107.925177) (xy 163.479253 -107.884794) (xy 163.520259 -107.849832) (xy 163.565776 -107.820988)
			(xy 163.614898 -107.798835) (xy 163.666649 -107.783814) (xy 163.719999 -107.776224) (xy 163.746942 -107.775756)
			(xy 163.774193 -107.776239) (xy 163.828139 -107.784) (xy 163.880431 -107.799359) (xy 163.930006 -107.822002)
			(xy 163.975855 -107.851469) (xy 164.017043 -107.887161) (xy 164.052734 -107.92835) (xy 164.082201 -107.974199)
			(xy 164.104844 -108.023774) (xy 164.120201 -108.076067) (xy 164.127962 -108.130013) (xy 164.12845 -108.157264)
			(xy 164.127966 -108.185904) (xy 164.11938 -108.242538) (xy 164.102426 -108.297253) (xy 164.077484 -108.348818)
			(xy 164.045114 -108.396076) (xy 164.006045 -108.437965) (xy 163.961153 -108.473544) (xy 163.911448 -108.502014)
			(xy 163.858046 -108.522734) (xy 163.802146 -108.535239) (xy 163.773612 -108.537756) (xy 163.773358 -108.537756)
			(xy 163.764281 -108.538903) (xy 163.747751 -108.546713) (xy 163.7411 -108.552996) (xy 163.693602 -108.60151)
			(xy 163.687373 -108.608516) (xy 163.679929 -108.6257) (xy 163.679124 -108.635038) (xy 163.677288 -108.667404)
			(xy 163.670047 -108.709925) (xy 165.293796 -108.709925) (xy 165.293796 -108.646003) (xy 165.301807 -108.582585)
			(xy 165.317704 -108.520671) (xy 165.341236 -108.461238) (xy 165.37203 -108.405223) (xy 165.409603 -108.353508)
			(xy 165.45336 -108.306911) (xy 165.502613 -108.266166) (xy 165.556584 -108.231915) (xy 165.614423 -108.204698)
			(xy 165.675216 -108.184945) (xy 165.738006 -108.172967) (xy 165.801802 -108.168954) (xy 165.865598 -108.172967)
			(xy 165.928388 -108.184945) (xy 165.989181 -108.204698) (xy 166.04702 -108.231915) (xy 166.100991 -108.266166)
			(xy 166.150244 -108.306911) (xy 166.194001 -108.353508) (xy 166.231574 -108.405223) (xy 166.262368 -108.461238)
			(xy 166.2859 -108.520671) (xy 166.301797 -108.582585) (xy 166.309808 -108.646003) (xy 166.31031 -108.677964)
			(xy 166.309808 -108.709925) (xy 166.301797 -108.773343) (xy 166.2859 -108.835257) (xy 166.262368 -108.89469)
			(xy 166.231574 -108.950705) (xy 166.194001 -109.00242) (xy 166.150244 -109.049017) (xy 166.100991 -109.089762)
			(xy 166.04702 -109.124013) (xy 165.989181 -109.15123) (xy 165.928388 -109.170983) (xy 165.865598 -109.182961)
			(xy 165.801802 -109.186975) (xy 165.738006 -109.182961) (xy 165.675216 -109.170983) (xy 165.614423 -109.15123)
			(xy 165.556584 -109.124013) (xy 165.502613 -109.089762) (xy 165.45336 -109.049017) (xy 165.409603 -109.00242)
			(xy 165.37203 -108.950705) (xy 165.341236 -108.89469) (xy 165.317704 -108.835257) (xy 165.301807 -108.773343)
			(xy 165.293796 -108.709925) (xy 163.670047 -108.709925) (xy 163.666405 -108.731313) (xy 163.647485 -108.793319)
			(xy 163.620835 -108.852416) (xy 163.586889 -108.907646) (xy 163.546196 -108.958113) (xy 163.499417 -109.002996)
			(xy 163.447312 -109.041568) (xy 163.390726 -109.073202) (xy 163.330577 -109.097386) (xy 163.267842 -109.113727)
			(xy 163.203538 -109.121959) (xy 163.171124 -109.122464) (xy 163.139158 -109.122072) (xy 163.07573 -109.114062)
			(xy 163.013805 -109.098166) (xy 162.954362 -109.074633) (xy 162.898337 -109.043835) (xy 162.846613 -109.006258)
			(xy 162.800008 -108.962495) (xy 162.759255 -108.913235) (xy 162.724997 -108.859256) (xy 162.697776 -108.801409)
			(xy 162.678019 -108.740606) (xy 162.666039 -108.677806) (xy 162.662024 -108.614) (xy 162.289566 -108.614)
			(xy 162.299927 -108.625034) (xy 162.3375 -108.676749) (xy 162.368294 -108.732764) (xy 162.391826 -108.792197)
			(xy 162.407723 -108.854111) (xy 162.415734 -108.917529) (xy 162.416236 -108.94949) (xy 162.415734 -108.981451)
			(xy 162.407723 -109.044869) (xy 162.391826 -109.106783) (xy 162.368294 -109.166216) (xy 162.3375 -109.222231)
			(xy 162.299927 -109.273946) (xy 162.25617 -109.320543) (xy 162.206917 -109.361288) (xy 162.152946 -109.395539)
			(xy 162.095107 -109.422756) (xy 162.034314 -109.442509) (xy 161.971524 -109.454487) (xy 161.907728 -109.458501)
			(xy 161.843932 -109.454487) (xy 161.781142 -109.442509) (xy 161.720349 -109.422756) (xy 161.66251 -109.395539)
			(xy 161.608539 -109.361288) (xy 161.559286 -109.320543) (xy 161.515529 -109.273946) (xy 161.477956 -109.222231)
			(xy 161.447162 -109.166216) (xy 161.42363 -109.106783) (xy 161.407733 -109.044869) (xy 161.399722 -108.981451)
			(xy 154.624567 -108.981451) (xy 154.635029 -109.036299) (xy 154.639044 -109.1001) (xy 154.635029 -109.163901)
			(xy 154.623051 -109.226695) (xy 154.603296 -109.287493) (xy 154.576077 -109.345335) (xy 154.541823 -109.39931)
			(xy 154.501075 -109.448566) (xy 154.454474 -109.492327) (xy 154.402756 -109.529902) (xy 154.346736 -109.560698)
			(xy 154.287299 -109.584231) (xy 154.22538 -109.600128) (xy 154.161957 -109.608139) (xy 154.129994 -109.60862)
			(xy 154.12974 -109.60862) (xy 154.095369 -109.608066) (xy 154.027257 -109.598777) (xy 153.961016 -109.580402)
			(xy 153.897852 -109.553277) (xy 153.838914 -109.517895) (xy 153.785277 -109.4749) (xy 153.761186 -109.450378)
			(xy 153.754074 -109.442758) (xy 153.73477 -109.434376) (xy 153.640028 -109.43463) (xy 153.621232 -109.442758)
			(xy 153.613866 -109.450378) (xy 153.589798 -109.475008) (xy 153.536113 -109.518143) (xy 153.477098 -109.553637)
			(xy 153.413832 -109.580843) (xy 153.347474 -109.599261) (xy 153.279237 -109.608556) (xy 153.244804 -109.609128)
			(xy 153.212843 -109.608607) (xy 153.149424 -109.600596) (xy 153.08751 -109.5847) (xy 153.028076 -109.561169)
			(xy 152.97206 -109.530374) (xy 152.920346 -109.492802) (xy 152.873748 -109.449044) (xy 152.833002 -109.399791)
			(xy 152.79875 -109.345819) (xy 152.771533 -109.287981) (xy 152.75178 -109.227187) (xy 152.739802 -109.164396)
			(xy 152.735788 -109.1006) (xy 149.84758 -109.1006) (xy 149.840834 -109.106334) (xy 149.814788 -109.123988)
			(xy 149.814534 -109.123988) (xy 149.804384 -109.131592) (xy 149.792541 -109.15399) (xy 149.791928 -109.16666)
			(xy 149.792436 -109.25175) (xy 149.792769 -109.260228) (xy 149.798358 -109.276239) (xy 149.808847 -109.289565)
			(xy 149.815804 -109.294422) (xy 149.842217 -109.312041) (xy 149.890908 -109.352791) (xy 149.934146 -109.399287)
			(xy 149.971256 -109.450805) (xy 150.001663 -109.506544) (xy 150.024892 -109.565635) (xy 150.040581 -109.627159)
			(xy 150.048488 -109.690158) (xy 150.048976 -109.721904) (xy 150.048543 -109.752426) (xy 150.045082 -109.781086)
			(xy 151.805638 -109.781086) (xy 151.809709 -109.725464) (xy 151.821835 -109.671027) (xy 151.841758 -109.618936)
			(xy 151.869054 -109.570301) (xy 151.90314 -109.526158) (xy 151.943289 -109.487449) (xy 151.988647 -109.454998)
			(xy 152.038247 -109.429497) (xy 152.091031 -109.41149) (xy 152.145874 -109.40136) (xy 152.201608 -109.399323)
			(xy 152.257045 -109.405423) (xy 152.311002 -109.419529) (xy 152.362331 -109.441341) (xy 152.409937 -109.470395)
			(xy 152.452805 -109.50607) (xy 152.490022 -109.547607) (xy 152.520795 -109.59412) (xy 152.544467 -109.644617)
			(xy 152.560535 -109.698024) (xy 152.568655 -109.7532) (xy 152.569164 -109.781086) (xy 152.568655 -109.808972)
			(xy 152.560535 -109.864148) (xy 152.544467 -109.917555) (xy 152.520795 -109.968052) (xy 152.490022 -110.014565)
			(xy 152.452805 -110.056102) (xy 152.409937 -110.091777) (xy 152.362331 -110.120831) (xy 152.311002 -110.142643)
			(xy 152.299947 -110.145533) (xy 160.843716 -110.145533) (xy 160.843716 -110.081611) (xy 160.851727 -110.018193)
			(xy 160.867624 -109.956279) (xy 160.891156 -109.896846) (xy 160.92195 -109.840831) (xy 160.959523 -109.789116)
			(xy 161.00328 -109.742519) (xy 161.052533 -109.701774) (xy 161.106504 -109.667523) (xy 161.164343 -109.640306)
			(xy 161.225136 -109.620553) (xy 161.287926 -109.608575) (xy 161.351722 -109.604562) (xy 161.415518 -109.608575)
			(xy 161.478308 -109.620553) (xy 161.539101 -109.640306) (xy 161.59694 -109.667523) (xy 161.650911 -109.701774)
			(xy 161.700164 -109.742519) (xy 161.743921 -109.789116) (xy 161.781494 -109.840831) (xy 161.812288 -109.896846)
			(xy 161.83582 -109.956279) (xy 161.851717 -110.018193) (xy 161.859728 -110.081611) (xy 161.86023 -110.113572)
			(xy 161.859728 -110.145533) (xy 161.859279 -110.149089) (xy 164.955722 -110.149089) (xy 164.955722 -110.085167)
			(xy 164.963733 -110.021749) (xy 164.97963 -109.959835) (xy 165.003162 -109.900402) (xy 165.033956 -109.844387)
			(xy 165.071529 -109.792672) (xy 165.115286 -109.746075) (xy 165.164539 -109.70533) (xy 165.21851 -109.671079)
			(xy 165.276349 -109.643862) (xy 165.337142 -109.624109) (xy 165.399932 -109.612131) (xy 165.463728 -109.608118)
			(xy 165.527524 -109.612131) (xy 165.590314 -109.624109) (xy 165.651107 -109.643862) (xy 165.708946 -109.671079)
			(xy 165.762917 -109.70533) (xy 165.81217 -109.746075) (xy 165.855927 -109.792672) (xy 165.8935 -109.844387)
			(xy 165.924294 -109.900402) (xy 165.947826 -109.959835) (xy 165.963723 -110.021749) (xy 165.971734 -110.085167)
			(xy 165.972236 -110.117128) (xy 165.971734 -110.149089) (xy 165.963723 -110.212507) (xy 165.947826 -110.274421)
			(xy 165.924294 -110.333854) (xy 165.8935 -110.389869) (xy 165.855927 -110.441584) (xy 165.81217 -110.488181)
			(xy 165.762917 -110.528926) (xy 165.708946 -110.563177) (xy 165.651107 -110.590394) (xy 165.590314 -110.610147)
			(xy 165.527524 -110.622125) (xy 165.463728 -110.626139) (xy 165.399932 -110.622125) (xy 165.337142 -110.610147)
			(xy 165.276349 -110.590394) (xy 165.21851 -110.563177) (xy 165.164539 -110.528926) (xy 165.115286 -110.488181)
			(xy 165.071529 -110.441584) (xy 165.033956 -110.389869) (xy 165.003162 -110.333854) (xy 164.97963 -110.274421)
			(xy 164.963733 -110.212507) (xy 164.955722 -110.149089) (xy 161.859279 -110.149089) (xy 161.851717 -110.208951)
			(xy 161.83582 -110.270865) (xy 161.812288 -110.330298) (xy 161.781494 -110.386313) (xy 161.743921 -110.438028)
			(xy 161.700164 -110.484625) (xy 161.650911 -110.52537) (xy 161.59694 -110.559621) (xy 161.539101 -110.586838)
			(xy 161.478308 -110.606591) (xy 161.415518 -110.618569) (xy 161.351722 -110.622583) (xy 161.287926 -110.618569)
			(xy 161.225136 -110.606591) (xy 161.164343 -110.586838) (xy 161.106504 -110.559621) (xy 161.052533 -110.52537)
			(xy 161.00328 -110.484625) (xy 160.959523 -110.438028) (xy 160.92195 -110.386313) (xy 160.891156 -110.330298)
			(xy 160.867624 -110.270865) (xy 160.851727 -110.208951) (xy 160.843716 -110.145533) (xy 152.299947 -110.145533)
			(xy 152.257045 -110.156749) (xy 152.201608 -110.162849) (xy 152.145874 -110.160812) (xy 152.091031 -110.150682)
			(xy 152.038247 -110.132675) (xy 151.988647 -110.107174) (xy 151.943289 -110.074723) (xy 151.90314 -110.036014)
			(xy 151.869054 -109.991871) (xy 151.841758 -109.943236) (xy 151.821835 -109.891145) (xy 151.809709 -109.836708)
			(xy 151.805638 -109.781086) (xy 150.045082 -109.781086) (xy 150.041224 -109.813028) (xy 150.026704 -109.872319)
			(xy 150.005191 -109.929446) (xy 149.976995 -109.983587) (xy 149.942521 -110.033964) (xy 149.902265 -110.079852)
			(xy 149.856806 -110.120592) (xy 149.83206 -110.138464) (xy 149.822381 -110.146213) (xy 149.811099 -110.168246)
			(xy 149.81047 -110.180628) (xy 149.81174 -110.277402) (xy 149.823932 -110.2995) (xy 149.8346 -110.306358)
			(xy 149.860544 -110.32408) (xy 149.90833 -110.364872) (xy 149.95073 -110.411237) (xy 149.987098 -110.46247)
			(xy 150.016881 -110.517791) (xy 150.039626 -110.576359) (xy 150.054987 -110.637281) (xy 150.06273 -110.699632)
			(xy 150.0632 -110.731046) (xy 150.062698 -110.763007) (xy 150.054687 -110.826425) (xy 150.03879 -110.888339)
			(xy 150.015258 -110.947772) (xy 149.984464 -111.003787) (xy 149.965448 -111.029961) (xy 154.920944 -111.029961)
			(xy 154.920944 -110.966039) (xy 154.928955 -110.902621) (xy 154.944852 -110.840707) (xy 154.968384 -110.781274)
			(xy 154.999178 -110.725259) (xy 155.036751 -110.673544) (xy 155.080508 -110.626947) (xy 155.129761 -110.586202)
			(xy 155.183732 -110.551951) (xy 155.241571 -110.524734) (xy 155.302364 -110.504981) (xy 155.365154 -110.493003)
			(xy 155.42895 -110.48899) (xy 155.492746 -110.493003) (xy 155.555536 -110.504981) (xy 155.616329 -110.524734)
			(xy 155.674168 -110.551951) (xy 155.728139 -110.586202) (xy 155.777392 -110.626947) (xy 155.821149 -110.673544)
			(xy 155.858722 -110.725259) (xy 155.889516 -110.781274) (xy 155.899078 -110.805425) (xy 157.530032 -110.805425)
			(xy 157.530032 -110.741503) (xy 157.538043 -110.678085) (xy 157.55394 -110.616171) (xy 157.577472 -110.556738)
			(xy 157.608266 -110.500723) (xy 157.645839 -110.449008) (xy 157.689596 -110.402411) (xy 157.738849 -110.361666)
			(xy 157.79282 -110.327415) (xy 157.850659 -110.300198) (xy 157.911452 -110.280445) (xy 157.974242 -110.268467)
			(xy 158.038038 -110.264454) (xy 158.101834 -110.268467) (xy 158.164624 -110.280445) (xy 158.225417 -110.300198)
			(xy 158.283256 -110.327415) (xy 158.337227 -110.361666) (xy 158.38648 -110.402411) (xy 158.430237 -110.449008)
			(xy 158.46781 -110.500723) (xy 158.498604 -110.556738) (xy 158.522136 -110.616171) (xy 158.538033 -110.678085)
			(xy 158.546044 -110.741503) (xy 158.546546 -110.773464) (xy 158.546044 -110.805425) (xy 158.538033 -110.868843)
			(xy 158.522136 -110.930757) (xy 158.498604 -110.99019) (xy 158.46781 -111.046205) (xy 158.430237 -111.09792)
			(xy 158.38648 -111.144517) (xy 158.337227 -111.185262) (xy 158.283256 -111.219513) (xy 158.225417 -111.24673)
			(xy 158.164624 -111.266483) (xy 158.101834 -111.278461) (xy 158.038038 -111.282475) (xy 157.974242 -111.278461)
			(xy 157.911452 -111.266483) (xy 157.850659 -111.24673) (xy 157.79282 -111.219513) (xy 157.738849 -111.185262)
			(xy 157.689596 -111.144517) (xy 157.645839 -111.09792) (xy 157.608266 -111.046205) (xy 157.577472 -110.99019)
			(xy 157.55394 -110.930757) (xy 157.538043 -110.868843) (xy 157.530032 -110.805425) (xy 155.899078 -110.805425)
			(xy 155.913048 -110.840707) (xy 155.928945 -110.902621) (xy 155.936956 -110.966039) (xy 155.937458 -110.998)
			(xy 155.936956 -111.029961) (xy 155.928945 -111.093379) (xy 155.913048 -111.155293) (xy 155.889516 -111.214726)
			(xy 155.858722 -111.270741) (xy 155.821149 -111.322456) (xy 155.811741 -111.332475) (xy 161.851588 -111.332475)
			(xy 161.851588 -111.268553) (xy 161.859599 -111.205135) (xy 161.875496 -111.143221) (xy 161.899028 -111.083788)
			(xy 161.929822 -111.027773) (xy 161.967395 -110.976058) (xy 162.011152 -110.929461) (xy 162.060405 -110.888716)
			(xy 162.114376 -110.854465) (xy 162.172215 -110.827248) (xy 162.233008 -110.807495) (xy 162.295798 -110.795517)
			(xy 162.359594 -110.791504) (xy 162.42339 -110.795517) (xy 162.48618 -110.807495) (xy 162.546973 -110.827248)
			(xy 162.604812 -110.854465) (xy 162.658783 -110.888716) (xy 162.708036 -110.929461) (xy 162.751793 -110.976058)
			(xy 162.789366 -111.027773) (xy 162.82016 -111.083788) (xy 162.843692 -111.143221) (xy 162.859589 -111.205135)
			(xy 162.8676 -111.268553) (xy 162.868102 -111.300514) (xy 162.8676 -111.332475) (xy 162.859589 -111.395893)
			(xy 162.843692 -111.457807) (xy 162.82016 -111.51724) (xy 162.789366 -111.573255) (xy 162.751793 -111.62497)
			(xy 162.708036 -111.671567) (xy 162.658783 -111.712312) (xy 162.604812 -111.746563) (xy 162.546973 -111.77378)
			(xy 162.48618 -111.793533) (xy 162.42339 -111.805511) (xy 162.359594 -111.809525) (xy 162.295798 -111.805511)
			(xy 162.233008 -111.793533) (xy 162.172215 -111.77378) (xy 162.114376 -111.746563) (xy 162.060405 -111.712312)
			(xy 162.011152 -111.671567) (xy 161.967395 -111.62497) (xy 161.929822 -111.573255) (xy 161.899028 -111.51724)
			(xy 161.875496 -111.457807) (xy 161.859599 -111.395893) (xy 161.851588 -111.332475) (xy 155.811741 -111.332475)
			(xy 155.777392 -111.369053) (xy 155.728139 -111.409798) (xy 155.674168 -111.444049) (xy 155.616329 -111.471266)
			(xy 155.555536 -111.491019) (xy 155.492746 -111.502997) (xy 155.42895 -111.507011) (xy 155.365154 -111.502997)
			(xy 155.302364 -111.491019) (xy 155.241571 -111.471266) (xy 155.183732 -111.444049) (xy 155.129761 -111.409798)
			(xy 155.080508 -111.369053) (xy 155.036751 -111.322456) (xy 154.999178 -111.270741) (xy 154.968384 -111.214726)
			(xy 154.944852 -111.155293) (xy 154.928955 -111.093379) (xy 154.920944 -111.029961) (xy 149.965448 -111.029961)
			(xy 149.946891 -111.055502) (xy 149.903134 -111.102099) (xy 149.853881 -111.142844) (xy 149.79991 -111.177095)
			(xy 149.742071 -111.204312) (xy 149.681278 -111.224065) (xy 149.618488 -111.236043) (xy 149.554692 -111.240057)
			(xy 149.490896 -111.236043) (xy 149.428106 -111.224065) (xy 149.367313 -111.204312) (xy 149.309474 -111.177095)
			(xy 149.255503 -111.142844) (xy 149.20625 -111.102099) (xy 149.162493 -111.055502) (xy 149.12492 -111.003787)
			(xy 149.094126 -110.947772) (xy 149.070594 -110.888339) (xy 149.054697 -110.826425) (xy 149.046686 -110.763007)
			(xy 149.046184 -110.731046) (xy 149.046672 -110.700526) (xy 149.053984 -110.639926) (xy 149.068497 -110.580637)
			(xy 149.090003 -110.523512) (xy 149.118191 -110.469371) (xy 149.152658 -110.418993) (xy 149.192906 -110.373103)
			(xy 149.238358 -110.33236) (xy 149.2631 -110.314486) (xy 149.272795 -110.306754) (xy 149.284071 -110.284709)
			(xy 149.28469 -110.272322) (xy 149.28342 -110.175548) (xy 149.271228 -110.15345) (xy 149.26056 -110.146592)
			(xy 149.234584 -110.128916) (xy 149.1868 -110.088116) (xy 149.144403 -110.041743) (xy 149.108038 -109.990503)
			(xy 149.078259 -109.935176) (xy 149.055519 -109.876602) (xy 149.040164 -109.815675) (xy 149.032427 -109.75332)
			(xy 149.03196 -109.721904) (xy 149.032427 -109.690443) (xy 149.040183 -109.628001) (xy 149.055589 -109.566994)
			(xy 149.07841 -109.508357) (xy 149.108297 -109.452985) (xy 149.144791 -109.401728) (xy 149.187335 -109.355368)
			(xy 149.235277 -109.314616) (xy 149.261322 -109.296962) (xy 149.261576 -109.296962) (xy 149.271705 -109.289335)
			(xy 149.283559 -109.266954) (xy 149.284182 -109.25429) (xy 149.283674 -109.1692) (xy 149.283346 -109.160721)
			(xy 149.277762 -109.144706) (xy 149.267268 -109.131381) (xy 149.260306 -109.126528) (xy 149.233872 -109.108939)
			(xy 149.185181 -109.068185) (xy 149.141944 -109.021685) (xy 149.104835 -108.970162) (xy 149.074431 -108.914419)
			(xy 149.051205 -108.855324) (xy 149.03552 -108.793796) (xy 149.027619 -108.730794) (xy 149.027134 -108.699046)
			(xy 143.166717 -108.699046) (xy 143.129809 -108.708695) (xy 143.074372 -108.714795) (xy 143.018638 -108.712758)
			(xy 142.963795 -108.702628) (xy 142.911011 -108.684621) (xy 142.861411 -108.65912) (xy 142.816053 -108.626669)
			(xy 142.775904 -108.58796) (xy 142.741818 -108.543817) (xy 142.714522 -108.495182) (xy 142.694599 -108.443091)
			(xy 142.682473 -108.388654) (xy 142.678402 -108.333032) (xy 139.917087 -108.333032) (xy 139.913429 -108.345489)
			(xy 139.88195 -108.424119) (xy 139.843139 -108.4994) (xy 139.797349 -108.570652) (xy 139.744993 -108.637228)
			(xy 139.686545 -108.698526) (xy 139.622535 -108.753991) (xy 139.553543 -108.80312) (xy 139.480193 -108.845469)
			(xy 139.40315 -108.880653) (xy 139.323111 -108.908355) (xy 139.240802 -108.928323) (xy 139.156967 -108.940376)
			(xy 139.072366 -108.944407) (xy 138.987765 -108.940376) (xy 138.90393 -108.928323) (xy 138.821621 -108.908355)
			(xy 138.741582 -108.880653) (xy 138.664539 -108.845469) (xy 138.591189 -108.80312) (xy 138.522197 -108.753991)
			(xy 138.458187 -108.698526) (xy 138.399739 -108.637228) (xy 138.347383 -108.570652) (xy 138.301593 -108.4994)
			(xy 138.262782 -108.424119) (xy 138.231303 -108.345489) (xy 138.207442 -108.264222) (xy 138.191413 -108.181056)
			(xy 138.183362 -108.096742) (xy 135.42915 -108.096742) (xy 135.433682 -108.101963) (xy 135.463179 -108.147753)
			(xy 135.485871 -108.19727) (xy 135.501296 -108.249509) (xy 135.505698 -108.27639) (xy 135.507222 -108.287058)
			(xy 135.518398 -108.305346) (xy 135.598916 -108.359448) (xy 135.619998 -108.363258) (xy 135.630412 -108.360718)
			(xy 135.660228 -108.353838) (xy 135.720974 -108.346454) (xy 135.75157 -108.345986) (xy 135.783113 -108.346436)
			(xy 135.845716 -108.354236) (xy 135.906873 -108.369719) (xy 135.965646 -108.392649) (xy 136.02113 -108.422672)
			(xy 136.072475 -108.459327) (xy 136.118892 -108.502053) (xy 136.159667 -108.550191) (xy 136.194174 -108.603004)
			(xy 136.221884 -108.659679) (xy 136.242371 -108.719347) (xy 136.255319 -108.78109) (xy 136.260531 -108.843962)
			(xy 136.257927 -108.906994) (xy 136.247545 -108.969221) (xy 136.229546 -109.029686) (xy 136.204206 -109.08746)
			(xy 136.171914 -109.141655) (xy 136.133167 -109.191441) (xy 136.088559 -109.236051) (xy 136.038775 -109.274801)
			(xy 135.984581 -109.307095) (xy 135.926808 -109.332438) (xy 135.866345 -109.350439) (xy 135.804118 -109.360824)
			(xy 135.741086 -109.363432) (xy 135.678214 -109.358223) (xy 135.61647 -109.345277) (xy 135.556801 -109.324793)
			(xy 135.500125 -109.297086) (xy 135.447311 -109.262581) (xy 135.39917 -109.221808) (xy 135.356443 -109.175394)
			(xy 135.319784 -109.124051) (xy 135.289759 -109.068567) (xy 135.266827 -109.009796) (xy 135.25134 -108.94864)
			(xy 135.243537 -108.886037) (xy 135.243062 -108.854494) (xy 135.244078 -108.820712) (xy 135.244078 -108.820458)
			(xy 135.244193 -108.809818) (xy 135.236842 -108.789875) (xy 135.229854 -108.78185) (xy 135.177784 -108.727748)
			(xy 135.170068 -108.720515) (xy 135.150512 -108.712518) (xy 135.139938 -108.712254) (xy 135.139684 -108.712254)
			(xy 135.128254 -108.712508) (xy 135.127746 -108.712508) (xy 135.100507 -108.712005) (xy 135.046586 -108.704219)
			(xy 134.994322 -108.688842) (xy 134.944777 -108.666186) (xy 134.898958 -108.636713) (xy 134.857798 -108.601022)
			(xy 134.822135 -108.559838) (xy 134.792692 -108.514) (xy 134.770069 -108.46444) (xy 134.754727 -108.412165)
			(xy 134.746977 -108.35824) (xy 134.746492 -108.331) (xy 17.236694 -108.331) (xy 17.236694 -108.413804)
			(xy 17.23627 -108.423874) (xy 17.228554 -108.442477) (xy 17.221708 -108.449872) (xy 17.000728 -108.670852)
			(xy 16.997636 -108.674051) (xy 16.992529 -108.681336) (xy 16.990568 -108.68533) (xy 16.987266 -108.692442)
			(xy 16.98625 -108.701586) (xy 16.982866 -108.729952) (xy 16.968757 -108.785307) (xy 16.946564 -108.837945)
			(xy 16.916781 -108.886691) (xy 16.880072 -108.93046) (xy 16.858996 -108.949744) (xy 16.851376 -108.956602)
			(xy 16.847312 -108.964984) (xy 16.845383 -108.969014) (xy 16.842818 -108.977573) (xy 16.842232 -108.982002)
			(xy 16.841216 -108.997242) (xy 16.839692 -109.019594) (xy 16.839692 -109.020102) (xy 16.837152 -109.055662)
			(xy 16.836919 -109.060689) (xy 16.838201 -109.070668) (xy 16.839692 -109.075474) (xy 16.84274 -109.084618)
			(xy 16.849344 -109.092238) (xy 16.868759 -109.115383) (xy 16.90255 -109.165463) (xy 16.930174 -109.219191)
			(xy 16.945597 -109.26064) (xy 34.761428 -109.26064) (xy 34.765458 -109.176039) (xy 34.777511 -109.092204)
			(xy 34.797479 -109.009895) (xy 34.825181 -108.929856) (xy 34.860365 -108.852813) (xy 34.902714 -108.779463)
			(xy 34.951843 -108.710471) (xy 35.007308 -108.646461) (xy 35.068606 -108.588013) (xy 35.135182 -108.535657)
			(xy 35.206434 -108.489867) (xy 35.281715 -108.451056) (xy 35.360345 -108.419577) (xy 35.441612 -108.395716)
			(xy 35.524778 -108.379687) (xy 35.609092 -108.371636) (xy 35.65144 -108.371132) (xy 35.694663 -108.371665)
			(xy 35.7807 -108.380045) (xy 35.865519 -108.396734) (xy 35.948319 -108.421572) (xy 36.028318 -108.454326)
			(xy 36.104763 -108.494687) (xy 36.176931 -108.542274) (xy 36.244141 -108.596638) (xy 36.305761 -108.657266)
			(xy 36.361208 -108.723586) (xy 36.386008 -108.75899) (xy 36.391922 -108.766819) (xy 36.408246 -108.77767)
			(xy 36.417758 -108.780072) (xy 36.497006 -108.796328) (xy 36.51631 -108.792518) (xy 36.524692 -108.787184)
			(xy 36.547842 -108.772864) (xy 36.597358 -108.750255) (xy 36.649588 -108.734926) (xy 36.703469 -108.727189)
			(xy 36.730686 -108.726732) (xy 36.73094 -108.726732) (xy 36.758192 -108.727141) (xy 36.812141 -108.734903)
			(xy 36.864437 -108.750263) (xy 36.914014 -108.772909) (xy 36.959864 -108.802379) (xy 37.001054 -108.838074)
			(xy 37.036745 -108.879268) (xy 37.066211 -108.925121) (xy 37.088851 -108.974701) (xy 37.104206 -109.026998)
			(xy 37.111962 -109.080948) (xy 37.111962 -109.135452) (xy 37.104206 -109.189402) (xy 37.088851 -109.241699)
			(xy 37.066211 -109.291279) (xy 37.036745 -109.337132) (xy 37.001054 -109.378326) (xy 36.959864 -109.414021)
			(xy 36.914014 -109.443491) (xy 36.864437 -109.466137) (xy 36.812141 -109.481497) (xy 36.758192 -109.489259)
			(xy 36.73094 -109.489748) (xy 36.703234 -109.489239) (xy 36.648408 -109.481203) (xy 36.62172 -109.473746)
			(xy 36.621466 -109.473746) (xy 36.611967 -109.471402) (xy 36.592507 -109.473213) (xy 36.58362 -109.477302)
			(xy 36.511992 -109.514894) (xy 36.499292 -109.52988) (xy 36.496244 -109.539278) (xy 36.482328 -109.579808)
			(xy 36.447772 -109.658231) (xy 36.405836 -109.732968) (xy 36.356907 -109.803325) (xy 36.301439 -109.868652)
			(xy 36.239946 -109.928342) (xy 36.172998 -109.981842) (xy 36.172756 -109.982) (xy 126.998982 -109.982)
			(xy 127.003053 -109.926378) (xy 127.015179 -109.871941) (xy 127.035102 -109.81985) (xy 127.062398 -109.771215)
			(xy 127.096484 -109.727072) (xy 127.136633 -109.688363) (xy 127.181991 -109.655912) (xy 127.231591 -109.630411)
			(xy 127.284375 -109.612404) (xy 127.339218 -109.602274) (xy 127.394952 -109.600237) (xy 127.450389 -109.606337)
			(xy 127.504346 -109.620443) (xy 127.555675 -109.642255) (xy 127.603281 -109.671309) (xy 127.646149 -109.706984)
			(xy 127.683366 -109.748521) (xy 127.714139 -109.795034) (xy 127.737811 -109.845531) (xy 127.753879 -109.898938)
			(xy 127.761999 -109.954114) (xy 127.762508 -109.982) (xy 127.761999 -110.009886) (xy 127.753879 -110.065062)
			(xy 127.737811 -110.118469) (xy 127.714139 -110.168966) (xy 127.683366 -110.215479) (xy 127.646149 -110.257016)
			(xy 127.603281 -110.292691) (xy 127.555675 -110.321745) (xy 127.504346 -110.343557) (xy 127.450389 -110.357663)
			(xy 127.394952 -110.363763) (xy 127.339218 -110.361726) (xy 127.284375 -110.351596) (xy 127.231591 -110.333589)
			(xy 127.181991 -110.308088) (xy 127.136633 -110.275637) (xy 127.096484 -110.236928) (xy 127.062398 -110.192785)
			(xy 127.035102 -110.14415) (xy 127.015179 -110.092059) (xy 127.003053 -110.037622) (xy 126.998982 -109.982)
			(xy 36.172756 -109.982) (xy 36.101216 -110.028657) (xy 36.025265 -110.068351) (xy 35.945849 -110.100559)
			(xy 35.863703 -110.12498) (xy 35.77959 -110.141389) (xy 35.694289 -110.149634) (xy 35.65144 -110.150148)
			(xy 35.609092 -110.149644) (xy 35.524778 -110.141593) (xy 35.441612 -110.125564) (xy 35.360345 -110.101703)
			(xy 35.281715 -110.070224) (xy 35.206434 -110.031413) (xy 35.135182 -109.985623) (xy 35.068606 -109.933267)
			(xy 35.007308 -109.874819) (xy 34.951843 -109.810809) (xy 34.902714 -109.741817) (xy 34.860365 -109.668467)
			(xy 34.825181 -109.591424) (xy 34.797479 -109.511385) (xy 34.777511 -109.429076) (xy 34.765458 -109.345241)
			(xy 34.761428 -109.26064) (xy 16.945597 -109.26064) (xy 16.951242 -109.275812) (xy 16.965457 -109.33453)
			(xy 16.972619 -109.394517) (xy 16.973042 -109.424724) (xy 16.972577 -109.455455) (xy 16.965166 -109.516468)
			(xy 16.950456 -109.576143) (xy 16.92866 -109.633611) (xy 16.900097 -109.688032) (xy 16.865182 -109.738614)
			(xy 16.824426 -109.784619) (xy 16.778422 -109.825376) (xy 16.72784 -109.860291) (xy 16.67342 -109.888856)
			(xy 16.615953 -109.910653) (xy 16.556278 -109.925364) (xy 16.495265 -109.932776) (xy 16.464534 -109.933232)
			(xy 16.42958 -109.932649) (xy 16.360332 -109.923071) (xy 16.293046 -109.904106) (xy 16.228989 -109.87611)
			(xy 16.169367 -109.83961) (xy 16.141954 -109.817916) (xy 16.136764 -109.813846) (xy 16.124794 -109.808317)
			(xy 16.118332 -109.806994) (xy 16.109442 -109.806232) (xy 15.88643 -109.806232) (xy 15.878302 -109.80674)
			(xy 15.870451 -109.80837) (xy 15.856225 -109.815748) (xy 15.850362 -109.821218) (xy 15.188692 -110.482888)
			(xy 15.912082 -110.482888) (xy 15.916153 -110.427266) (xy 15.928279 -110.372829) (xy 15.948202 -110.320738)
			(xy 15.975498 -110.272103) (xy 16.009584 -110.22796) (xy 16.049733 -110.189251) (xy 16.095091 -110.1568)
			(xy 16.144691 -110.131299) (xy 16.197475 -110.113292) (xy 16.252318 -110.103162) (xy 16.308052 -110.101125)
			(xy 16.363489 -110.107225) (xy 16.417446 -110.121331) (xy 16.468775 -110.143143) (xy 16.516381 -110.172197)
			(xy 16.559249 -110.207872) (xy 16.596466 -110.249409) (xy 16.627239 -110.295922) (xy 16.650911 -110.346419)
			(xy 16.666979 -110.399826) (xy 16.672474 -110.437167) (xy 137.075317 -110.437167) (xy 137.077952 -110.35336)
			(xy 137.088462 -110.270173) (xy 137.106754 -110.188344) (xy 137.132666 -110.1086) (xy 137.165967 -110.031648)
			(xy 137.206362 -109.958172) (xy 137.253492 -109.888823) (xy 137.30694 -109.824217) (xy 137.36623 -109.764928)
			(xy 137.430837 -109.711482) (xy 137.500187 -109.664353) (xy 137.573664 -109.623959) (xy 137.650617 -109.590659)
			(xy 137.730361 -109.564749) (xy 137.81219 -109.546459) (xy 137.895378 -109.535951) (xy 137.979185 -109.533317)
			(xy 138.062868 -109.538583) (xy 138.145683 -109.5517) (xy 138.226897 -109.572553) (xy 138.305789 -109.600955)
			(xy 138.381657 -109.636657) (xy 138.434677 -109.668013) (xy 142.851372 -109.668013) (xy 142.851372 -109.604091)
			(xy 142.859383 -109.540673) (xy 142.87528 -109.478759) (xy 142.898812 -109.419326) (xy 142.929606 -109.363311)
			(xy 142.967179 -109.311596) (xy 143.010936 -109.264999) (xy 143.060189 -109.224254) (xy 143.11416 -109.190003)
			(xy 143.171999 -109.162786) (xy 143.232792 -109.143033) (xy 143.295582 -109.131055) (xy 143.359378 -109.127042)
			(xy 143.423174 -109.131055) (xy 143.485964 -109.143033) (xy 143.546757 -109.162786) (xy 143.604596 -109.190003)
			(xy 143.658567 -109.224254) (xy 143.70782 -109.264999) (xy 143.751577 -109.311596) (xy 143.78915 -109.363311)
			(xy 143.819944 -109.419326) (xy 143.843476 -109.478759) (xy 143.859373 -109.540673) (xy 143.867384 -109.604091)
			(xy 143.867886 -109.636052) (xy 143.867384 -109.668013) (xy 143.859373 -109.731431) (xy 143.843476 -109.793345)
			(xy 143.819944 -109.852778) (xy 143.78915 -109.908793) (xy 143.751577 -109.960508) (xy 143.70782 -110.007105)
			(xy 143.658567 -110.04785) (xy 143.604596 -110.082101) (xy 143.546757 -110.109318) (xy 143.485964 -110.129071)
			(xy 143.423174 -110.141049) (xy 143.359378 -110.145063) (xy 143.295582 -110.141049) (xy 143.232792 -110.129071)
			(xy 143.171999 -110.109318) (xy 143.11416 -110.082101) (xy 143.060189 -110.04785) (xy 143.010936 -110.007105)
			(xy 142.967179 -109.960508) (xy 142.929606 -109.908793) (xy 142.898812 -109.852778) (xy 142.87528 -109.793345)
			(xy 142.859383 -109.731431) (xy 142.851372 -109.668013) (xy 138.434677 -109.668013) (xy 138.453828 -109.679339)
			(xy 138.521663 -109.728624) (xy 138.584558 -109.784074) (xy 138.641956 -109.845197) (xy 138.693348 -109.91145)
			(xy 138.738276 -109.982246) (xy 138.776342 -110.056955) (xy 138.807209 -110.134915) (xy 138.830602 -110.215435)
			(xy 138.846313 -110.297798) (xy 138.848943 -110.325619) (xy 143.94408 -110.325619) (xy 143.94408 -110.261697)
			(xy 143.952091 -110.198279) (xy 143.967988 -110.136365) (xy 143.99152 -110.076932) (xy 144.022314 -110.020917)
			(xy 144.059887 -109.969202) (xy 144.103644 -109.922605) (xy 144.152897 -109.88186) (xy 144.206868 -109.847609)
			(xy 144.264707 -109.820392) (xy 144.3255 -109.800639) (xy 144.38829 -109.788661) (xy 144.452086 -109.784648)
			(xy 144.515882 -109.788661) (xy 144.578672 -109.800639) (xy 144.639465 -109.820392) (xy 144.697304 -109.847609)
			(xy 144.751275 -109.88186) (xy 144.800528 -109.922605) (xy 144.844285 -109.969202) (xy 144.881858 -110.020917)
			(xy 144.912652 -110.076932) (xy 144.936184 -110.136365) (xy 144.952081 -110.198279) (xy 144.960092 -110.261697)
			(xy 144.960594 -110.293658) (xy 144.960092 -110.325619) (xy 144.952081 -110.389037) (xy 144.936184 -110.450951)
			(xy 144.912652 -110.510384) (xy 144.881858 -110.566399) (xy 144.844285 -110.618114) (xy 144.800528 -110.664711)
			(xy 144.751275 -110.705456) (xy 144.697304 -110.739707) (xy 144.639465 -110.766924) (xy 144.578672 -110.786677)
			(xy 144.515882 -110.798655) (xy 144.452086 -110.802669) (xy 144.38829 -110.798655) (xy 144.3255 -110.786677)
			(xy 144.264707 -110.766924) (xy 144.206868 -110.739707) (xy 144.152897 -110.705456) (xy 144.103644 -110.664711)
			(xy 144.059887 -110.618114) (xy 144.022314 -110.566399) (xy 143.99152 -110.510384) (xy 143.967988 -110.450951)
			(xy 143.952091 -110.389037) (xy 143.94408 -110.325619) (xy 138.848943 -110.325619) (xy 138.854204 -110.381274)
			(xy 138.854688 -110.423198) (xy 138.854173 -110.465244) (xy 138.846239 -110.54896) (xy 138.830442 -110.631554)
			(xy 138.806922 -110.712289) (xy 138.77589 -110.790445) (xy 138.737622 -110.865325) (xy 138.69246 -110.93626)
			(xy 138.640807 -111.002617) (xy 138.636015 -111.0077) (xy 144.80962 -111.0077) (xy 144.813635 -110.943893)
			(xy 144.825616 -110.881092) (xy 144.845373 -110.820288) (xy 144.872595 -110.76244) (xy 144.906854 -110.70846)
			(xy 144.947608 -110.659199) (xy 144.994215 -110.615435) (xy 145.04594 -110.577858) (xy 145.101967 -110.547061)
			(xy 145.161412 -110.523528) (xy 145.223337 -110.507632) (xy 145.286767 -110.499623) (xy 145.318734 -110.499144)
			(xy 145.351446 -110.499612) (xy 145.416329 -110.508008) (xy 145.4796 -110.524656) (xy 145.540212 -110.549281)
			(xy 145.597166 -110.581477) (xy 145.64952 -110.620712) (xy 145.673318 -110.643162) (xy 145.680176 -110.649766)
			(xy 145.697194 -110.656878) (xy 145.784316 -110.66018) (xy 145.80235 -110.65383) (xy 145.809462 -110.647734)
			(xy 145.832426 -110.62888) (xy 145.88199 -110.596107) (xy 145.935038 -110.569338) (xy 145.990846 -110.548937)
			(xy 146.048651 -110.535183) (xy 146.107666 -110.528263) (xy 146.137376 -110.527846) (xy 146.13763 -110.527846)
			(xy 146.168351 -110.528294) (xy 146.229346 -110.535698) (xy 146.289005 -110.550394) (xy 146.34646 -110.572167)
			(xy 146.400875 -110.600702) (xy 146.426428 -110.617762) (xy 146.435113 -110.623155) (xy 146.45513 -110.627216)
			(xy 146.475147 -110.623155) (xy 146.483832 -110.617762) (xy 146.509377 -110.60069) (xy 146.563794 -110.57216)
			(xy 146.621252 -110.550393) (xy 146.680913 -110.535703) (xy 146.741909 -110.528307) (xy 146.77263 -110.527846)
			(xy 146.807234 -110.528462) (xy 146.875798 -110.537889) (xy 146.909282 -110.546642) (xy 146.917916 -110.548664)
			(xy 146.935586 -110.547377) (xy 146.943826 -110.544102) (xy 146.971004 -110.531656) (xy 146.978912 -110.527734)
			(xy 146.991636 -110.515513) (xy 146.995896 -110.50778) (xy 147.010162 -110.479638) (xy 147.044681 -110.42682)
			(xy 147.085466 -110.378677) (xy 147.131891 -110.335947) (xy 147.183244 -110.299285) (xy 147.238737 -110.269256)
			(xy 147.297517 -110.246319) (xy 147.358682 -110.230826) (xy 147.421294 -110.223017) (xy 147.452842 -110.222538)
			(xy 147.484804 -110.222951) (xy 147.548224 -110.230967) (xy 147.610139 -110.246869) (xy 147.669573 -110.270405)
			(xy 147.725589 -110.301204) (xy 147.777303 -110.33878) (xy 147.8239 -110.382542) (xy 147.864645 -110.431798)
			(xy 147.898896 -110.485772) (xy 147.926112 -110.543613) (xy 147.945865 -110.604409) (xy 147.957843 -110.667202)
			(xy 147.961857 -110.731) (xy 147.957843 -110.794798) (xy 147.945865 -110.857591) (xy 147.926112 -110.918387)
			(xy 147.898896 -110.976228) (xy 147.864645 -111.030202) (xy 147.8239 -111.079458) (xy 147.777303 -111.12322)
			(xy 147.725589 -111.160796) (xy 147.669573 -111.191595) (xy 147.610139 -111.215131) (xy 147.548224 -111.231033)
			(xy 147.484804 -111.239049) (xy 147.452842 -111.239554) (xy 147.418238 -111.238943) (xy 147.349674 -111.229512)
			(xy 147.31619 -111.220758) (xy 147.307558 -111.218722) (xy 147.289886 -111.220018) (xy 147.281646 -111.223298)
			(xy 147.254468 -111.235744) (xy 147.246572 -111.239688) (xy 147.233841 -111.251893) (xy 147.229576 -111.25962)
			(xy 147.215332 -111.287774) (xy 147.18081 -111.340591) (xy 147.140023 -111.388735) (xy 147.093595 -111.431465)
			(xy 147.042239 -111.468125) (xy 146.986743 -111.498154) (xy 146.927961 -111.521089) (xy 146.866793 -111.536578)
			(xy 146.804179 -111.544385) (xy 146.77263 -111.544862) (xy 146.74191 -111.544382) (xy 146.680916 -111.536986)
			(xy 146.621257 -111.522297) (xy 146.563802 -111.50053) (xy 146.509386 -111.472002) (xy 146.483832 -111.454946)
			(xy 146.475147 -111.449553) (xy 146.45513 -111.445492) (xy 146.435113 -111.449553) (xy 146.426428 -111.454946)
			(xy 146.400867 -111.471993) (xy 146.346454 -111.500527) (xy 146.289001 -111.5223) (xy 146.229343 -111.536995)
			(xy 146.16835 -111.544398) (xy 146.13763 -111.544862) (xy 146.104919 -111.544352) (xy 146.040038 -111.535964)
			(xy 145.976768 -111.519325) (xy 145.916155 -111.494707) (xy 145.859201 -111.462518) (xy 145.806845 -111.42329)
			(xy 145.783046 -111.400844) (xy 145.776188 -111.39424) (xy 145.75917 -111.387128) (xy 145.672048 -111.383826)
			(xy 145.654014 -111.390176) (xy 145.646902 -111.396272) (xy 145.623915 -111.415097) (xy 145.574356 -111.447873)
			(xy 145.521313 -111.474647) (xy 145.46551 -111.495053) (xy 145.407708 -111.508813) (xy 145.348696 -111.515739)
			(xy 145.318988 -111.51616) (xy 145.318734 -111.51616) (xy 145.286767 -111.515777) (xy 145.223337 -111.507768)
			(xy 145.161412 -111.491872) (xy 145.101967 -111.468339) (xy 145.04594 -111.437542) (xy 144.994215 -111.399965)
			(xy 144.947608 -111.356201) (xy 144.906854 -111.30694) (xy 144.872595 -111.25296) (xy 144.845373 -111.195112)
			(xy 144.825616 -111.134308) (xy 144.813635 -111.071507) (xy 144.80962 -111.0077) (xy 138.636015 -111.0077)
			(xy 138.583123 -111.063805) (xy 138.519923 -111.119277) (xy 138.486134 -111.144304) (xy 138.475122 -111.152852)
			(xy 138.457766 -111.174648) (xy 138.446955 -111.200328) (xy 138.443495 -111.227975) (xy 138.447645 -111.255527)
			(xy 138.459095 -111.280928) (xy 138.47699 -111.302284) (xy 138.499996 -111.318002) (xy 138.513058 -111.322866)
			(xy 138.537887 -111.331741) (xy 138.585008 -111.355403) (xy 138.62842 -111.385331) (xy 138.667295 -111.420953)
			(xy 138.700892 -111.461591) (xy 138.728571 -111.50647) (xy 138.749804 -111.554735) (xy 138.764186 -111.605463)
			(xy 138.771442 -111.65769) (xy 138.771884 -111.684054) (xy 138.771398 -111.711305) (xy 138.763642 -111.765253)
			(xy 138.748287 -111.817548) (xy 138.725645 -111.867125) (xy 138.720707 -111.874808) (xy 139.027406 -111.874808)
			(xy 139.031477 -111.819186) (xy 139.043603 -111.764749) (xy 139.063526 -111.712658) (xy 139.090822 -111.664023)
			(xy 139.124908 -111.61988) (xy 139.165057 -111.581171) (xy 139.210415 -111.54872) (xy 139.260015 -111.523219)
			(xy 139.312799 -111.505212) (xy 139.367642 -111.495082) (xy 139.423376 -111.493045) (xy 139.478813 -111.499145)
			(xy 139.53277 -111.513251) (xy 139.584099 -111.535063) (xy 139.631705 -111.564117) (xy 139.674573 -111.599792)
			(xy 139.71179 -111.641329) (xy 139.742563 -111.687842) (xy 139.766235 -111.738339) (xy 139.782303 -111.791746)
			(xy 139.790423 -111.846922) (xy 139.790932 -111.874808) (xy 139.790423 -111.902694) (xy 139.782303 -111.95787)
			(xy 139.766235 -112.011277) (xy 139.742563 -112.061774) (xy 139.71179 -112.108287) (xy 139.674573 -112.149824)
			(xy 139.631705 -112.185499) (xy 139.584099 -112.214553) (xy 139.53277 -112.236365) (xy 139.478813 -112.250471)
			(xy 139.423376 -112.256571) (xy 139.367642 -112.254534) (xy 139.312799 -112.244404) (xy 139.260015 -112.226397)
			(xy 139.210415 -112.200896) (xy 139.165057 -112.168445) (xy 139.124908 -112.129736) (xy 139.090822 -112.085593)
			(xy 139.063526 -112.036958) (xy 139.043603 -111.984867) (xy 139.031477 -111.93043) (xy 139.027406 -111.874808)
			(xy 138.720707 -111.874808) (xy 138.696179 -111.912975) (xy 138.660488 -111.954166) (xy 138.619297 -111.989857)
			(xy 138.573447 -112.019323) (xy 138.52387 -112.041965) (xy 138.471575 -112.05732) (xy 138.417627 -112.065076)
			(xy 138.363125 -112.065076) (xy 138.309177 -112.05732) (xy 138.256882 -112.041965) (xy 138.207305 -112.019323)
			(xy 138.161455 -111.989857) (xy 138.120264 -111.954166) (xy 138.084573 -111.912975) (xy 138.055107 -111.867125)
			(xy 138.032465 -111.817548) (xy 138.01711 -111.765253) (xy 138.009354 -111.711305) (xy 138.008868 -111.684054)
			(xy 138.009379 -111.655735) (xy 138.017753 -111.599721) (xy 138.034323 -111.545562) (xy 138.058726 -111.494452)
			(xy 138.074146 -111.470694) (xy 138.08151 -111.458877) (xy 138.090222 -111.432445) (xy 138.091472 -111.404643)
			(xy 138.085168 -111.377536) (xy 138.071779 -111.353138) (xy 138.052299 -111.333261) (xy 138.028175 -111.319384)
			(xy 138.0012 -111.312537) (xy 137.987278 -111.312452) (xy 137.96518 -111.312706) (xy 137.923256 -111.312204)
			(xy 137.83978 -111.304311) (xy 137.757417 -111.288598) (xy 137.676898 -111.265203) (xy 137.598939 -111.234335)
			(xy 137.52423 -111.196267) (xy 137.453436 -111.151337) (xy 137.387183 -111.099945) (xy 137.326062 -111.042545)
			(xy 137.270613 -110.979649) (xy 137.221329 -110.911813) (xy 137.178648 -110.839641) (xy 137.142949 -110.763772)
			(xy 137.114547 -110.68488) (xy 137.093696 -110.603666) (xy 137.080581 -110.52085) (xy 137.075317 -110.437167)
			(xy 16.672474 -110.437167) (xy 16.675099 -110.455002) (xy 16.675608 -110.482888) (xy 16.675099 -110.510774)
			(xy 16.666979 -110.56595) (xy 16.650911 -110.619357) (xy 16.627239 -110.669854) (xy 16.596466 -110.716367)
			(xy 16.559249 -110.757904) (xy 16.516381 -110.793579) (xy 16.468775 -110.822633) (xy 16.417446 -110.844445)
			(xy 16.363489 -110.858551) (xy 16.308052 -110.864651) (xy 16.252318 -110.862614) (xy 16.197475 -110.852484)
			(xy 16.144691 -110.834477) (xy 16.095091 -110.808976) (xy 16.049733 -110.776525) (xy 16.009584 -110.737816)
			(xy 15.975498 -110.693673) (xy 15.948202 -110.645038) (xy 15.928279 -110.592947) (xy 15.916153 -110.53851)
			(xy 15.912082 -110.482888) (xy 15.188692 -110.482888) (xy 13.42898 -112.2426) (xy 34.693352 -112.2426)
			(xy 34.693879 -112.215225) (xy 34.701706 -112.161038) (xy 34.717198 -112.108527) (xy 34.740038 -112.058769)
			(xy 34.769757 -112.012788) (xy 34.805743 -111.971527) (xy 34.847258 -111.935834) (xy 34.893449 -111.906443)
			(xy 34.943367 -111.883956) (xy 34.995988 -111.868837) (xy 35.023044 -111.864648) (xy 35.031411 -111.863206)
			(xy 35.046526 -111.855482) (xy 35.058301 -111.843257) (xy 35.06216 -111.835692) (xy 35.103816 -111.746538)
			(xy 35.102038 -111.72063) (xy 35.09518 -111.709708) (xy 35.081212 -111.686745) (xy 35.059184 -111.63772)
			(xy 35.044251 -111.586089) (xy 35.036711 -111.532874) (xy 35.036252 -111.506) (xy 35.036778 -111.478751)
			(xy 35.044533 -111.424806) (xy 35.059886 -111.372515) (xy 35.082524 -111.32294) (xy 35.111987 -111.277092)
			(xy 35.147674 -111.235903) (xy 35.18886 -111.200211) (xy 35.234705 -111.170744) (xy 35.284277 -111.1481)
			(xy 35.336567 -111.132742) (xy 35.390511 -111.124981) (xy 35.41776 -111.124492) (xy 35.444691 -111.124981)
			(xy 35.498019 -111.132539) (xy 35.549753 -111.147526) (xy 35.598864 -111.169642) (xy 35.644374 -111.198448)
			(xy 35.685379 -111.233371) (xy 35.721063 -111.273715) (xy 35.736276 -111.295942) (xy 35.741302 -111.302935)
			(xy 35.754984 -111.313373) (xy 35.771354 -111.318678) (xy 35.779964 -111.318802) (xy 35.879024 -111.316516)
			(xy 35.901376 -111.303562) (xy 35.908234 -111.29264) (xy 35.908234 -111.292386) (xy 35.923081 -111.268488)
			(xy 35.95874 -111.22497) (xy 36.000404 -111.187161) (xy 36.047169 -111.155882) (xy 36.098021 -111.13181)
			(xy 36.151857 -111.115469) (xy 36.207509 -111.107211) (xy 36.23564 -111.106712) (xy 36.263244 -111.107164)
			(xy 36.317879 -111.115103) (xy 36.370798 -111.130837) (xy 36.420894 -111.15404) (xy 36.467121 -111.184224)
			(xy 36.508511 -111.220759) (xy 36.5442 -111.262881) (xy 36.559236 -111.286036) (xy 36.566348 -111.297466)
			(xy 36.590478 -111.31042) (xy 36.692332 -111.306356) (xy 36.70125 -111.305679) (xy 36.717801 -111.29893)
			(xy 36.731043 -111.286925) (xy 36.735512 -111.279178) (xy 36.747856 -111.256264) (xy 36.777918 -111.213774)
			(xy 36.813481 -111.175769) (xy 36.853883 -111.142954) (xy 36.898373 -111.115941) (xy 36.946125 -111.09523)
			(xy 36.996249 -111.081206) (xy 37.047815 -111.074132) (xy 37.07384 -111.073692) (xy 37.100481 -111.074126)
			(xy 37.153242 -111.081557) (xy 37.204457 -111.096255) (xy 37.253129 -111.117934) (xy 37.298313 -111.146172)
			(xy 37.339129 -111.180421) (xy 37.374785 -111.220015) (xy 37.39007 -111.24184) (xy 37.397436 -111.252762)
			(xy 37.421312 -111.2647) (xy 37.53485 -111.259112) (xy 37.557202 -111.244888) (xy 37.563552 -111.233204)
			(xy 37.577947 -111.207642) (xy 37.613421 -111.160919) (xy 37.655625 -111.120174) (xy 37.703566 -111.086364)
			(xy 37.756114 -111.060286) (xy 37.812034 -111.042554) (xy 37.870008 -111.033586) (xy 37.89934 -111.033052)
			(xy 37.92659 -111.03354) (xy 37.980536 -111.041301) (xy 38.032828 -111.05666) (xy 38.082403 -111.079302)
			(xy 38.128251 -111.108769) (xy 38.16944 -111.14446) (xy 38.205131 -111.185649) (xy 38.234598 -111.231497)
			(xy 38.25724 -111.281072) (xy 38.272599 -111.333364) (xy 38.28036 -111.38731) (xy 38.280848 -111.41456)
			(xy 38.280352 -111.442663) (xy 38.272111 -111.49826) (xy 38.2558 -111.552046) (xy 38.231773 -111.602857)
			(xy 38.20055 -111.649591) (xy 38.162807 -111.691238) (xy 38.141402 -111.709454) (xy 38.141148 -111.709708)
			(xy 38.134383 -111.71573) (xy 38.125338 -111.731412) (xy 38.122303 -111.749259) (xy 38.123622 -111.758222)
			(xy 38.142672 -111.859568) (xy 38.161214 -111.880396) (xy 38.174422 -111.884714) (xy 38.199659 -111.893334)
			(xy 38.247604 -111.91669) (xy 38.291831 -111.946493) (xy 38.331477 -111.982163) (xy 38.365771 -112.023006)
			(xy 38.394044 -112.068225) (xy 38.415746 -112.116941) (xy 38.430455 -112.168203) (xy 38.437883 -112.221015)
			(xy 38.438328 -112.24768) (xy 38.438153 -112.256781) (xy 38.803574 -112.256781) (xy 38.803574 -112.192859)
			(xy 38.811585 -112.129441) (xy 38.827482 -112.067527) (xy 38.851014 -112.008094) (xy 38.881808 -111.952079)
			(xy 38.919381 -111.900364) (xy 38.963138 -111.853767) (xy 39.012391 -111.813022) (xy 39.066362 -111.778771)
			(xy 39.124201 -111.751554) (xy 39.184994 -111.731801) (xy 39.247784 -111.719823) (xy 39.31158 -111.71581)
			(xy 39.375376 -111.719823) (xy 39.438166 -111.731801) (xy 39.498959 -111.751554) (xy 39.556798 -111.778771)
			(xy 39.610769 -111.813022) (xy 39.660022 -111.853767) (xy 39.703779 -111.900364) (xy 39.741352 -111.952079)
			(xy 39.772146 -112.008094) (xy 39.795678 -112.067527) (xy 39.805413 -112.10544) (xy 41.495472 -112.10544)
			(xy 41.495926 -112.078063) (xy 41.503762 -112.023872) (xy 41.519263 -111.971358) (xy 41.542112 -111.921599)
			(xy 41.571838 -111.875617) (xy 41.607833 -111.834356) (xy 41.649355 -111.798665) (xy 41.695554 -111.769275)
			(xy 41.745479 -111.746791) (xy 41.798105 -111.731675) (xy 41.825164 -111.727488) (xy 41.833515 -111.725977)
			(xy 41.84863 -111.718284) (xy 41.860414 -111.706086) (xy 41.86428 -111.698532) (xy 41.905936 -111.609378)
			(xy 41.904158 -111.58347) (xy 41.8973 -111.572548) (xy 41.883351 -111.549575) (xy 41.861317 -111.500553)
			(xy 41.84638 -111.448926) (xy 41.838833 -111.395713) (xy 41.838372 -111.36884) (xy 41.838892 -111.341589)
			(xy 41.846643 -111.287641) (xy 41.861993 -111.235346) (xy 41.88463 -111.185767) (xy 41.914092 -111.139915)
			(xy 41.94978 -111.098722) (xy 41.990967 -111.063028) (xy 42.036814 -111.033559) (xy 42.086389 -111.010914)
			(xy 42.138682 -110.995556) (xy 42.192629 -110.987797) (xy 42.21988 -110.987332) (xy 42.246812 -110.987787)
			(xy 42.300142 -110.99535) (xy 42.351878 -111.010341) (xy 42.400989 -111.032462) (xy 42.4465 -111.061273)
			(xy 42.487503 -111.096202) (xy 42.523184 -111.136553) (xy 42.538396 -111.158782) (xy 42.5434 -111.165793)
			(xy 42.557093 -111.176224) (xy 42.573471 -111.181522) (xy 42.582084 -111.181642) (xy 42.681144 -111.179356)
			(xy 42.703496 -111.166402) (xy 42.710354 -111.15548) (xy 42.710354 -111.155226) (xy 42.72527 -111.131373)
			(xy 42.760916 -111.087853) (xy 42.802568 -111.05004) (xy 42.849321 -111.018755) (xy 42.900162 -110.994676)
			(xy 42.953988 -110.978325) (xy 43.009633 -110.970057) (xy 43.03776 -110.969552) (xy 43.065364 -110.970016)
			(xy 43.119997 -110.977956) (xy 43.172914 -110.993691) (xy 43.223009 -111.016892) (xy 43.269236 -111.047073)
			(xy 43.310627 -111.083605) (xy 43.346319 -111.125723) (xy 43.361356 -111.148876) (xy 43.368468 -111.160306)
			(xy 43.392598 -111.17326) (xy 43.494452 -111.169196) (xy 43.503376 -111.168563) (xy 43.519932 -111.161799)
			(xy 43.53317 -111.149774) (xy 43.537632 -111.142018) (xy 43.550052 -111.119147) (xy 43.580103 -111.076657)
			(xy 43.615654 -111.038649) (xy 43.656044 -111.005831) (xy 43.700524 -110.978811) (xy 43.748265 -110.958093)
			(xy 43.79838 -110.944062) (xy 43.849939 -110.936977) (xy 43.87596 -110.936532) (xy 43.9026 -110.937009)
			(xy 43.95536 -110.94443) (xy 44.006574 -110.959119) (xy 44.055247 -110.98079) (xy 44.100432 -111.009023)
			(xy 44.141249 -111.043267) (xy 44.176905 -111.082857) (xy 44.19219 -111.10468) (xy 44.199556 -111.115602)
			(xy 44.223432 -111.12754) (xy 44.33697 -111.121952) (xy 44.359322 -111.107728) (xy 44.365672 -111.096044)
			(xy 44.380068 -111.070483) (xy 44.41554 -111.023758) (xy 44.457743 -110.98301) (xy 44.505684 -110.9492)
			(xy 44.558233 -110.923122) (xy 44.614153 -110.905391) (xy 44.672128 -110.896424) (xy 44.70146 -110.895892)
			(xy 44.728712 -110.896393) (xy 44.782661 -110.904144) (xy 44.834959 -110.919495) (xy 44.884539 -110.942133)
			(xy 44.930392 -110.971597) (xy 44.971585 -111.007287) (xy 45.007279 -111.048476) (xy 45.036748 -111.094326)
			(xy 45.059391 -111.143904) (xy 45.074747 -111.196199) (xy 45.082505 -111.250148) (xy 45.082968 -111.2774)
			(xy 45.082493 -111.305503) (xy 45.074246 -111.361101) (xy 45.057931 -111.414887) (xy 45.0339 -111.465698)
			(xy 45.002674 -111.512432) (xy 44.964928 -111.554079) (xy 44.943522 -111.572294) (xy 44.943268 -111.572548)
			(xy 44.936542 -111.578609) (xy 44.927486 -111.594271) (xy 44.924434 -111.612104) (xy 44.925742 -111.621062)
			(xy 44.944792 -111.722408) (xy 44.963334 -111.743236) (xy 44.976542 -111.747554) (xy 45.001796 -111.756128)
			(xy 45.049743 -111.779489) (xy 45.093969 -111.809298) (xy 45.133615 -111.844974) (xy 45.167908 -111.885823)
			(xy 45.196179 -111.931048) (xy 45.217878 -111.979769) (xy 45.232582 -112.031037) (xy 45.240005 -112.083853)
			(xy 45.240448 -112.11052) (xy 45.240279 -112.119621) (xy 45.605694 -112.119621) (xy 45.605694 -112.055699)
			(xy 45.613705 -111.992281) (xy 45.629602 -111.930367) (xy 45.653134 -111.870934) (xy 45.683928 -111.814919)
			(xy 45.721501 -111.763204) (xy 45.765258 -111.716607) (xy 45.814511 -111.675862) (xy 45.868482 -111.641611)
			(xy 45.926321 -111.614394) (xy 45.987114 -111.594641) (xy 46.049904 -111.582663) (xy 46.1137 -111.57865)
			(xy 46.177496 -111.582663) (xy 46.240286 -111.594641) (xy 46.301079 -111.614394) (xy 46.358918 -111.641611)
			(xy 46.412889 -111.675862) (xy 46.462142 -111.716607) (xy 46.505899 -111.763204) (xy 46.543472 -111.814919)
			(xy 46.574266 -111.870934) (xy 46.597798 -111.930367) (xy 46.613695 -111.992281) (xy 46.617941 -112.025895)
			(xy 78.67624 -112.025895) (xy 78.67624 -111.961973) (xy 78.684251 -111.898555) (xy 78.700148 -111.836641)
			(xy 78.72368 -111.777208) (xy 78.754474 -111.721193) (xy 78.792047 -111.669478) (xy 78.835804 -111.622881)
			(xy 78.885057 -111.582136) (xy 78.939028 -111.547885) (xy 78.996867 -111.520668) (xy 79.05766 -111.500915)
			(xy 79.12045 -111.488937) (xy 79.184246 -111.484924) (xy 79.248042 -111.488937) (xy 79.310832 -111.500915)
			(xy 79.371625 -111.520668) (xy 79.429464 -111.547885) (xy 79.483435 -111.582136) (xy 79.532688 -111.622881)
			(xy 79.576445 -111.669478) (xy 79.614018 -111.721193) (xy 79.644812 -111.777208) (xy 79.668344 -111.836641)
			(xy 79.684241 -111.898555) (xy 79.692252 -111.961973) (xy 79.692754 -111.993934) (xy 79.692252 -112.025895)
			(xy 79.684241 -112.089313) (xy 79.668344 -112.151227) (xy 79.644812 -112.21066) (xy 79.614018 -112.266675)
			(xy 79.576445 -112.31839) (xy 79.532688 -112.364987) (xy 79.483435 -112.405732) (xy 79.429464 -112.439983)
			(xy 79.371625 -112.4672) (xy 79.310832 -112.486953) (xy 79.248042 -112.498931) (xy 79.184246 -112.502945)
			(xy 79.12045 -112.498931) (xy 79.05766 -112.486953) (xy 78.996867 -112.4672) (xy 78.939028 -112.439983)
			(xy 78.885057 -112.405732) (xy 78.835804 -112.364987) (xy 78.792047 -112.31839) (xy 78.754474 -112.266675)
			(xy 78.72368 -112.21066) (xy 78.700148 -112.151227) (xy 78.684251 -112.089313) (xy 78.67624 -112.025895)
			(xy 46.617941 -112.025895) (xy 46.621706 -112.055699) (xy 46.622208 -112.08766) (xy 46.621706 -112.119621)
			(xy 46.613695 -112.183039) (xy 46.597798 -112.244953) (xy 46.574266 -112.304386) (xy 46.543472 -112.360401)
			(xy 46.505899 -112.412116) (xy 46.462142 -112.458713) (xy 46.412889 -112.499458) (xy 46.358918 -112.533709)
			(xy 46.301079 -112.560926) (xy 46.240286 -112.580679) (xy 46.177496 -112.592657) (xy 46.1137 -112.596671)
			(xy 46.049904 -112.592657) (xy 45.987114 -112.580679) (xy 45.926321 -112.560926) (xy 45.868482 -112.533709)
			(xy 45.814511 -112.499458) (xy 45.765258 -112.458713) (xy 45.721501 -112.412116) (xy 45.683928 -112.360401)
			(xy 45.653134 -112.304386) (xy 45.629602 -112.244953) (xy 45.613705 -112.183039) (xy 45.605694 -112.119621)
			(xy 45.240279 -112.119621) (xy 45.239941 -112.13777) (xy 45.232183 -112.191715) (xy 45.216827 -112.244007)
			(xy 45.194187 -112.293581) (xy 45.164722 -112.33943) (xy 45.129033 -112.380619) (xy 45.087846 -112.41631)
			(xy 45.041999 -112.445777) (xy 44.992425 -112.46842) (xy 44.940134 -112.483778) (xy 44.88619 -112.49154)
			(xy 44.85894 -112.492028) (xy 44.830806 -112.491539) (xy 44.775145 -112.48329) (xy 44.7213 -112.466952)
			(xy 44.670442 -112.442879) (xy 44.623672 -112.411593) (xy 44.582008 -112.373774) (xy 44.563792 -112.352328)
			(xy 44.556352 -112.344014) (xy 44.536317 -112.334263) (xy 44.525184 -112.333532) (xy 44.436538 -112.332262)
			(xy 44.416218 -112.341152) (xy 44.408852 -112.349534) (xy 44.390648 -112.369517) (xy 44.3496 -112.404687)
			(xy 44.304001 -112.433715) (xy 44.254765 -112.456023) (xy 44.202874 -112.471164) (xy 44.149367 -112.478835)
			(xy 44.12234 -112.479328) (xy 44.095702 -112.478825) (xy 44.042944 -112.471405) (xy 43.991731 -112.456719)
			(xy 43.943059 -112.435051) (xy 43.897874 -112.406823) (xy 43.857056 -112.372584) (xy 43.821397 -112.333)
			(xy 43.80611 -112.31118) (xy 43.798744 -112.300258) (xy 43.775884 -112.288574) (xy 43.663616 -112.291622)
			(xy 43.641264 -112.30483) (xy 43.63466 -112.316006) (xy 43.619762 -112.339917) (xy 43.584131 -112.383553)
			(xy 43.542468 -112.421471) (xy 43.49568 -112.452846) (xy 43.444784 -112.476996) (xy 43.390889 -112.493393)
			(xy 43.335167 -112.501682) (xy 43.307 -112.502188) (xy 43.278731 -112.50168) (xy 43.222812 -112.493348)
			(xy 43.168735 -112.476852) (xy 43.117686 -112.452554) (xy 43.070783 -112.420986) (xy 43.029054 -112.382839)
			(xy 43.010836 -112.361218) (xy 43.003327 -112.352885) (xy 42.983168 -112.34312) (xy 42.971974 -112.342422)
			(xy 42.88282 -112.341152) (xy 42.862246 -112.350296) (xy 42.85488 -112.358932) (xy 42.836662 -112.379416)
			(xy 42.795381 -112.415485) (xy 42.749363 -112.445275) (xy 42.699555 -112.468172) (xy 42.646983 -112.483704)
			(xy 42.592729 -112.491553) (xy 42.56532 -112.492028) (xy 42.53986 -112.491633) (xy 42.489393 -112.484861)
			(xy 42.440275 -112.471435) (xy 42.39338 -112.451594) (xy 42.349541 -112.42569) (xy 42.309539 -112.394184)
			(xy 42.291508 -112.376204) (xy 42.284396 -112.368838) (xy 42.265854 -112.360964) (xy 42.172636 -112.360202)
			(xy 42.154094 -112.367822) (xy 42.146728 -112.375188) (xy 42.125135 -112.395994) (xy 42.076632 -112.431249)
			(xy 42.02321 -112.458478) (xy 41.966184 -112.477011) (xy 41.906961 -112.486392) (xy 41.87698 -112.486948)
			(xy 41.84973 -112.486441) (xy 41.795785 -112.478683) (xy 41.743493 -112.463327) (xy 41.693919 -112.440687)
			(xy 41.64807 -112.411222) (xy 41.606881 -112.375533) (xy 41.57119 -112.334346) (xy 41.541723 -112.288499)
			(xy 41.51908 -112.238925) (xy 41.503722 -112.186634) (xy 41.49596 -112.13269) (xy 41.495472 -112.10544)
			(xy 39.805413 -112.10544) (xy 39.811575 -112.129441) (xy 39.819586 -112.192859) (xy 39.820088 -112.22482)
			(xy 39.819586 -112.256781) (xy 39.811575 -112.320199) (xy 39.795678 -112.382113) (xy 39.772146 -112.441546)
			(xy 39.741352 -112.497561) (xy 39.703779 -112.549276) (xy 39.660022 -112.595873) (xy 39.630857 -112.62)
			(xy 94.978533 -112.62) (xy 94.982547 -112.55621) (xy 94.994523 -112.493427) (xy 95.014274 -112.432639)
			(xy 95.041488 -112.374806) (xy 95.075735 -112.32084) (xy 95.116476 -112.271592) (xy 95.163068 -112.227838)
			(xy 95.214777 -112.190269) (xy 95.270786 -112.159476) (xy 95.330213 -112.135947) (xy 95.392121 -112.12005)
			(xy 95.455532 -112.112038) (xy 95.48749 -112.111536) (xy 95.518211 -112.112006) (xy 95.579204 -112.119405)
			(xy 95.638863 -112.134096) (xy 95.696319 -112.155865) (xy 95.750734 -112.184395) (xy 95.776288 -112.201452)
			(xy 95.784973 -112.206845) (xy 95.80499 -112.210906) (xy 95.825007 -112.206845) (xy 95.833692 -112.201452)
			(xy 95.859246 -112.184394) (xy 95.913661 -112.155863) (xy 95.971116 -112.134092) (xy 96.030775 -112.1194)
			(xy 96.091769 -112.112) (xy 96.153211 -112.112) (xy 96.214205 -112.1194) (xy 96.273864 -112.134092)
			(xy 96.331319 -112.155863) (xy 96.385734 -112.184394) (xy 96.411288 -112.201452) (xy 96.419973 -112.206845)
			(xy 96.43999 -112.210906) (xy 96.460007 -112.206845) (xy 96.468692 -112.201452) (xy 96.494247 -112.184396)
			(xy 96.548662 -112.155864) (xy 96.606117 -112.134093) (xy 96.665775 -112.1194) (xy 96.726769 -112.111999)
			(xy 96.75749 -112.111536) (xy 96.789461 -112.112083) (xy 96.852897 -112.12012) (xy 96.914825 -112.136043)
			(xy 96.97427 -112.159601) (xy 97.030293 -112.190424) (xy 97.056448 -112.208818) (xy 97.06541 -112.214757)
			(xy 97.08642 -112.219231) (xy 97.10743 -112.214757) (xy 97.116392 -112.208818) (xy 97.142538 -112.190409)
			(xy 97.198564 -112.159585) (xy 97.25801 -112.136024) (xy 97.31994 -112.120096) (xy 97.383378 -112.112053)
			(xy 97.41535 -112.111536) (xy 97.447317 -112.111926) (xy 97.510748 -112.119933) (xy 97.572675 -112.135828)
			(xy 97.632121 -112.159359) (xy 97.688149 -112.190156) (xy 97.739875 -112.227733) (xy 97.786484 -112.271496)
			(xy 97.827239 -112.320757) (xy 97.861499 -112.374737) (xy 97.888722 -112.432586) (xy 97.90848 -112.49339)
			(xy 97.920461 -112.556192) (xy 97.924476 -112.62) (xy 97.920461 -112.683808) (xy 97.916829 -112.702848)
			(xy 132.417056 -112.702848) (xy 132.421127 -112.647226) (xy 132.433253 -112.592789) (xy 132.453176 -112.540698)
			(xy 132.480472 -112.492063) (xy 132.514558 -112.44792) (xy 132.554707 -112.409211) (xy 132.600065 -112.37676)
			(xy 132.649665 -112.351259) (xy 132.702449 -112.333252) (xy 132.757292 -112.323122) (xy 132.813026 -112.321085)
			(xy 132.868463 -112.327185) (xy 132.92242 -112.341291) (xy 132.973749 -112.363103) (xy 133.021355 -112.392157)
			(xy 133.064223 -112.427832) (xy 133.10144 -112.469369) (xy 133.132213 -112.515882) (xy 133.155885 -112.566379)
			(xy 133.171953 -112.619786) (xy 133.180073 -112.674962) (xy 133.180582 -112.702848) (xy 133.180217 -112.722871)
			(xy 139.596108 -112.722871) (xy 139.596108 -112.658949) (xy 139.604119 -112.595531) (xy 139.620016 -112.533617)
			(xy 139.643548 -112.474184) (xy 139.674342 -112.418169) (xy 139.711915 -112.366454) (xy 139.755672 -112.319857)
			(xy 139.804925 -112.279112) (xy 139.858896 -112.244861) (xy 139.916735 -112.217644) (xy 139.977528 -112.197891)
			(xy 140.040318 -112.185913) (xy 140.104114 -112.1819) (xy 140.16791 -112.185913) (xy 140.2307 -112.197891)
			(xy 140.291493 -112.217644) (xy 140.349332 -112.244861) (xy 140.403303 -112.279112) (xy 140.452556 -112.319857)
			(xy 140.496313 -112.366454) (xy 140.533886 -112.418169) (xy 140.551705 -112.450583) (xy 153.35732 -112.450583)
			(xy 153.35732 -112.386661) (xy 153.365331 -112.323243) (xy 153.381228 -112.261329) (xy 153.40476 -112.201896)
			(xy 153.435554 -112.145881) (xy 153.473127 -112.094166) (xy 153.516884 -112.047569) (xy 153.566137 -112.006824)
			(xy 153.620108 -111.972573) (xy 153.677947 -111.945356) (xy 153.73874 -111.925603) (xy 153.80153 -111.913625)
			(xy 153.865326 -111.909612) (xy 153.929122 -111.913625) (xy 153.991912 -111.925603) (xy 154.052705 -111.945356)
			(xy 154.110544 -111.972573) (xy 154.164515 -112.006824) (xy 154.213768 -112.047569) (xy 154.257525 -112.094166)
			(xy 154.295098 -112.145881) (xy 154.325892 -112.201896) (xy 154.349424 -112.261329) (xy 154.365321 -112.323243)
			(xy 154.373332 -112.386661) (xy 154.373834 -112.418622) (xy 154.373332 -112.450583) (xy 154.365321 -112.514001)
			(xy 154.363267 -112.522) (xy 155.847032 -112.522) (xy 155.851103 -112.466378) (xy 155.863229 -112.411941)
			(xy 155.883152 -112.35985) (xy 155.910448 -112.311215) (xy 155.944534 -112.267072) (xy 155.984683 -112.228363)
			(xy 156.030041 -112.195912) (xy 156.079641 -112.170411) (xy 156.132425 -112.152404) (xy 156.187268 -112.142274)
			(xy 156.243002 -112.140237) (xy 156.298439 -112.146337) (xy 156.352396 -112.160443) (xy 156.403725 -112.182255)
			(xy 156.451331 -112.211309) (xy 156.494199 -112.246984) (xy 156.519818 -112.275577) (xy 160.091368 -112.275577)
			(xy 160.091368 -112.211655) (xy 160.099379 -112.148237) (xy 160.115276 -112.086323) (xy 160.138808 -112.02689)
			(xy 160.169602 -111.970875) (xy 160.207175 -111.91916) (xy 160.250932 -111.872563) (xy 160.300185 -111.831818)
			(xy 160.354156 -111.797567) (xy 160.411995 -111.77035) (xy 160.472788 -111.750597) (xy 160.535578 -111.738619)
			(xy 160.599374 -111.734606) (xy 160.66317 -111.738619) (xy 160.72596 -111.750597) (xy 160.786753 -111.77035)
			(xy 160.844592 -111.797567) (xy 160.898563 -111.831818) (xy 160.947816 -111.872563) (xy 160.991573 -111.91916)
			(xy 161.029146 -111.970875) (xy 161.05994 -112.02689) (xy 161.083472 -112.086323) (xy 161.099369 -112.148237)
			(xy 161.10738 -112.211655) (xy 161.107882 -112.243616) (xy 161.10738 -112.275577) (xy 161.099369 -112.338995)
			(xy 161.083472 -112.400909) (xy 161.05994 -112.460342) (xy 161.029146 -112.516357) (xy 160.991573 -112.568072)
			(xy 160.947816 -112.614669) (xy 160.898563 -112.655414) (xy 160.844592 -112.689665) (xy 160.786753 -112.716882)
			(xy 160.72596 -112.736635) (xy 160.66317 -112.748613) (xy 160.599374 -112.752627) (xy 160.535578 -112.748613)
			(xy 160.472788 -112.736635) (xy 160.411995 -112.716882) (xy 160.354156 -112.689665) (xy 160.300185 -112.655414)
			(xy 160.250932 -112.614669) (xy 160.207175 -112.568072) (xy 160.169602 -112.516357) (xy 160.138808 -112.460342)
			(xy 160.115276 -112.400909) (xy 160.099379 -112.338995) (xy 160.091368 -112.275577) (xy 156.519818 -112.275577)
			(xy 156.531416 -112.288521) (xy 156.562189 -112.335034) (xy 156.585861 -112.385531) (xy 156.601929 -112.438938)
			(xy 156.610049 -112.494114) (xy 156.610558 -112.522) (xy 156.610049 -112.549886) (xy 156.601929 -112.605062)
			(xy 156.585861 -112.658469) (xy 156.562189 -112.708966) (xy 156.531416 -112.755479) (xy 156.494199 -112.797016)
			(xy 156.451331 -112.832691) (xy 156.403725 -112.861745) (xy 156.352396 -112.883557) (xy 156.298439 -112.897663)
			(xy 156.243002 -112.903763) (xy 156.187268 -112.901726) (xy 156.132425 -112.891596) (xy 156.079641 -112.873589)
			(xy 156.030041 -112.848088) (xy 155.984683 -112.815637) (xy 155.944534 -112.776928) (xy 155.910448 -112.732785)
			(xy 155.883152 -112.68415) (xy 155.863229 -112.632059) (xy 155.851103 -112.577622) (xy 155.847032 -112.522)
			(xy 154.363267 -112.522) (xy 154.349424 -112.575915) (xy 154.325892 -112.635348) (xy 154.295098 -112.691363)
			(xy 154.257525 -112.743078) (xy 154.213768 -112.789675) (xy 154.164515 -112.83042) (xy 154.110544 -112.864671)
			(xy 154.052705 -112.891888) (xy 153.991912 -112.911641) (xy 153.929122 -112.923619) (xy 153.865326 -112.927633)
			(xy 153.80153 -112.923619) (xy 153.73874 -112.911641) (xy 153.677947 -112.891888) (xy 153.620108 -112.864671)
			(xy 153.566137 -112.83042) (xy 153.516884 -112.789675) (xy 153.473127 -112.743078) (xy 153.435554 -112.691363)
			(xy 153.40476 -112.635348) (xy 153.381228 -112.575915) (xy 153.365331 -112.514001) (xy 153.35732 -112.450583)
			(xy 140.551705 -112.450583) (xy 140.56468 -112.474184) (xy 140.588212 -112.533617) (xy 140.604109 -112.595531)
			(xy 140.61212 -112.658949) (xy 140.612622 -112.69091) (xy 140.61212 -112.722871) (xy 140.604109 -112.786289)
			(xy 140.588212 -112.848203) (xy 140.56468 -112.907636) (xy 140.533886 -112.963651) (xy 140.496313 -113.015366)
			(xy 140.452556 -113.061963) (xy 140.448764 -113.0651) (xy 148.799541 -113.0651) (xy 148.803555 -113.001301)
			(xy 148.815533 -112.938507) (xy 148.835286 -112.87771) (xy 148.862503 -112.819868) (xy 148.896755 -112.765894)
			(xy 148.937501 -112.716637) (xy 148.984099 -112.672875) (xy 149.035814 -112.635299) (xy 149.091831 -112.6045)
			(xy 149.151266 -112.580965) (xy 149.213182 -112.565063) (xy 149.276603 -112.557048) (xy 149.308566 -112.556544)
			(xy 149.343823 -112.55717) (xy 149.41366 -112.566917) (xy 149.481482 -112.586216) (xy 149.545988 -112.614697)
			(xy 149.576282 -112.632744) (xy 149.585282 -112.637706) (xy 149.605575 -112.640816) (xy 149.625478 -112.635779)
			(xy 149.63394 -112.62995) (xy 149.660638 -112.610189) (xy 149.718187 -112.577023) (xy 149.779569 -112.551643)
			(xy 149.843736 -112.534483) (xy 149.909593 -112.525836) (xy 149.942804 -112.525302) (xy 149.974765 -112.525784)
			(xy 150.038184 -112.533796) (xy 150.100099 -112.549694) (xy 150.159533 -112.573226) (xy 150.215549 -112.604021)
			(xy 150.267264 -112.641594) (xy 150.313861 -112.685353) (xy 150.354607 -112.734607) (xy 150.388859 -112.788579)
			(xy 150.416076 -112.846418) (xy 150.435829 -112.907212) (xy 150.447807 -112.970003) (xy 150.451821 -113.0338)
			(xy 150.448033 -113.094008) (xy 164.943028 -113.094008) (xy 164.943538 -113.06209) (xy 164.951515 -112.998754)
			(xy 164.967358 -112.936915) (xy 164.990817 -112.877546) (xy 165.021524 -112.82158) (xy 165.058994 -112.769898)
			(xy 165.10264 -112.723314) (xy 165.151773 -112.682559) (xy 165.205622 -112.648275) (xy 165.263339 -112.621001)
			(xy 165.324015 -112.601167) (xy 165.386698 -112.589085) (xy 165.418516 -112.586516) (xy 165.42726 -112.58558)
			(xy 165.443372 -112.578565) (xy 165.450012 -112.5728) (xy 165.471856 -112.552226) (xy 165.477919 -112.546006)
			(xy 165.485829 -112.530552) (xy 165.48735 -112.522) (xy 165.491739 -112.493093) (xy 165.508214 -112.436994)
			(xy 165.533061 -112.384069) (xy 165.565699 -112.335559) (xy 165.58514 -112.31372) (xy 165.59126 -112.306529)
			(xy 165.598236 -112.288999) (xy 165.598447 -112.270132) (xy 165.595554 -112.261142) (xy 165.563296 -112.176052)
			(xy 165.559606 -112.167335) (xy 165.546915 -112.153303) (xy 165.530005 -112.144815) (xy 165.520624 -112.14354)
			(xy 165.489625 -112.139961) (xy 165.42874 -112.126283) (xy 165.369987 -112.105255) (xy 165.31425 -112.077194)
			(xy 165.262368 -112.042521) (xy 165.215119 -112.001759) (xy 165.173216 -111.955519) (xy 165.137288 -111.904497)
			(xy 165.107875 -111.849461) (xy 165.085421 -111.791239) (xy 165.070262 -111.730706) (xy 165.062627 -111.668773)
			(xy 165.062154 -111.637572) (xy 165.062656 -111.605611) (xy 165.070667 -111.542193) (xy 165.086564 -111.480279)
			(xy 165.110096 -111.420846) (xy 165.14089 -111.364831) (xy 165.178463 -111.313116) (xy 165.22222 -111.266519)
			(xy 165.271473 -111.225774) (xy 165.325444 -111.191523) (xy 165.383283 -111.164306) (xy 165.444076 -111.144553)
			(xy 165.506866 -111.132575) (xy 165.570662 -111.128562) (xy 165.634458 -111.132575) (xy 165.697248 -111.144553)
			(xy 165.758041 -111.164306) (xy 165.81588 -111.191523) (xy 165.869851 -111.225774) (xy 165.919104 -111.266519)
			(xy 165.962861 -111.313116) (xy 166.000434 -111.364831) (xy 166.031228 -111.420846) (xy 166.05476 -111.480279)
			(xy 166.070657 -111.542193) (xy 166.078668 -111.605611) (xy 166.07917 -111.637572) (xy 166.078695 -111.668896)
			(xy 166.071001 -111.731071) (xy 166.055727 -111.79183) (xy 166.033104 -111.850251) (xy 166.003475 -111.905451)
			(xy 165.967289 -111.956592) (xy 165.925093 -112.0029) (xy 165.901624 -112.023652) (xy 165.890702 -112.03305)
			(xy 165.881812 -112.060482) (xy 165.91153 -112.176814) (xy 165.932358 -112.19688) (xy 165.946328 -112.199928)
			(xy 165.974312 -112.206636) (xy 166.028065 -112.227169) (xy 166.078126 -112.255539) (xy 166.123359 -112.291104)
			(xy 166.162741 -112.333058) (xy 166.195377 -112.380448) (xy 166.220529 -112.432201) (xy 166.237626 -112.487143)
			(xy 166.246279 -112.54403) (xy 166.24681 -112.5728) (xy 166.246324 -112.601631) (xy 166.237641 -112.658636)
			(xy 166.220472 -112.713683) (xy 166.195209 -112.765517) (xy 166.162429 -112.812955) (xy 166.122879 -112.854916)
			(xy 166.077461 -112.890443) (xy 166.027211 -112.918725) (xy 166.00043 -112.929416) (xy 165.992432 -112.932865)
			(xy 165.979187 -112.944159) (xy 165.974522 -112.951514) (xy 165.959536 -112.977422) (xy 165.955463 -112.985207)
			(xy 165.952349 -113.002486) (xy 165.95344 -113.011204) (xy 165.956539 -113.031573) (xy 165.959847 -113.072644)
			(xy 165.960044 -113.093246) (xy 165.960044 -113.094008) (xy 165.959542 -113.125969) (xy 165.951531 -113.189387)
			(xy 165.935634 -113.251301) (xy 165.912102 -113.310734) (xy 165.881308 -113.366749) (xy 165.843735 -113.418464)
			(xy 165.799978 -113.465061) (xy 165.750725 -113.505806) (xy 165.696754 -113.540057) (xy 165.638915 -113.567274)
			(xy 165.578122 -113.587027) (xy 165.515332 -113.599005) (xy 165.451536 -113.603019) (xy 165.38774 -113.599005)
			(xy 165.32495 -113.587027) (xy 165.264157 -113.567274) (xy 165.206318 -113.540057) (xy 165.152347 -113.505806)
			(xy 165.103094 -113.465061) (xy 165.059337 -113.418464) (xy 165.021764 -113.366749) (xy 164.99097 -113.310734)
			(xy 164.967438 -113.251301) (xy 164.951541 -113.189387) (xy 164.94353 -113.125969) (xy 164.943028 -113.094008)
			(xy 150.448033 -113.094008) (xy 150.447807 -113.097597) (xy 150.435829 -113.160388) (xy 150.416076 -113.221182)
			(xy 150.388859 -113.279021) (xy 150.354607 -113.332993) (xy 150.313861 -113.382247) (xy 150.267264 -113.426006)
			(xy 150.215549 -113.463579) (xy 150.159533 -113.494374) (xy 150.100099 -113.517906) (xy 150.038184 -113.533804)
			(xy 149.974765 -113.541816) (xy 149.942804 -113.542318) (xy 149.907546 -113.541712) (xy 149.837708 -113.531959)
			(xy 149.769886 -113.512655) (xy 149.705381 -113.484168) (xy 149.675088 -113.466118) (xy 149.666099 -113.461135)
			(xy 149.645799 -113.458036) (xy 149.625893 -113.463081) (xy 149.61743 -113.468912) (xy 149.590738 -113.488681)
			(xy 149.533188 -113.521847) (xy 149.471804 -113.547225) (xy 149.407636 -113.564383) (xy 149.341778 -113.573027)
			(xy 149.308566 -113.57356) (xy 149.276603 -113.573152) (xy 149.213182 -113.565137) (xy 149.151266 -113.549235)
			(xy 149.091831 -113.5257) (xy 149.035814 -113.494901) (xy 148.984099 -113.457325) (xy 148.937501 -113.413563)
			(xy 148.896755 -113.364306) (xy 148.862503 -113.310331) (xy 148.835286 -113.25249) (xy 148.815533 -113.191693)
			(xy 148.803555 -113.128899) (xy 148.799541 -113.0651) (xy 140.448764 -113.0651) (xy 140.403303 -113.102708)
			(xy 140.349332 -113.136959) (xy 140.291493 -113.164176) (xy 140.2307 -113.183929) (xy 140.16791 -113.195907)
			(xy 140.104114 -113.199921) (xy 140.040318 -113.195907) (xy 139.977528 -113.183929) (xy 139.916735 -113.164176)
			(xy 139.858896 -113.136959) (xy 139.804925 -113.102708) (xy 139.755672 -113.061963) (xy 139.711915 -113.015366)
			(xy 139.674342 -112.963651) (xy 139.643548 -112.907636) (xy 139.620016 -112.848203) (xy 139.604119 -112.786289)
			(xy 139.596108 -112.722871) (xy 133.180217 -112.722871) (xy 133.180073 -112.730734) (xy 133.171953 -112.78591)
			(xy 133.155885 -112.839317) (xy 133.132213 -112.889814) (xy 133.10144 -112.936327) (xy 133.064223 -112.977864)
			(xy 133.021355 -113.013539) (xy 132.973749 -113.042593) (xy 132.92242 -113.064405) (xy 132.868463 -113.078511)
			(xy 132.813026 -113.084611) (xy 132.757292 -113.082574) (xy 132.702449 -113.072444) (xy 132.649665 -113.054437)
			(xy 132.600065 -113.028936) (xy 132.554707 -112.996485) (xy 132.514558 -112.957776) (xy 132.480472 -112.913633)
			(xy 132.453176 -112.864998) (xy 132.433253 -112.812907) (xy 132.421127 -112.75847) (xy 132.417056 -112.702848)
			(xy 97.916829 -112.702848) (xy 97.90848 -112.74661) (xy 97.888722 -112.807414) (xy 97.861499 -112.865263)
			(xy 97.827239 -112.919243) (xy 97.786484 -112.968504) (xy 97.739875 -113.012267) (xy 97.688149 -113.049844)
			(xy 97.632121 -113.080641) (xy 97.572675 -113.104172) (xy 97.510748 -113.120067) (xy 97.447317 -113.128074)
			(xy 97.41535 -113.128552) (xy 97.383378 -113.128039) (xy 97.319941 -113.119994) (xy 97.258012 -113.104063)
			(xy 97.198568 -113.080497) (xy 97.142546 -113.049668) (xy 97.116392 -113.03127) (xy 97.10743 -113.025331)
			(xy 97.08642 -113.020857) (xy 97.06541 -113.025331) (xy 97.056448 -113.03127) (xy 97.030289 -113.049659)
			(xy 96.974267 -113.080487) (xy 96.914824 -113.104052) (xy 96.852897 -113.119985) (xy 96.789462 -113.128032)
			(xy 96.75749 -113.128552) (xy 96.726769 -113.128094) (xy 96.665775 -113.120693) (xy 96.606116 -113.105999)
			(xy 96.54866 -113.084228) (xy 96.494246 -113.055695) (xy 96.468692 -113.038636) (xy 96.460007 -113.033243)
			(xy 96.43999 -113.029182) (xy 96.419973 -113.033243) (xy 96.411288 -113.038636) (xy 96.385734 -113.055694)
			(xy 96.331319 -113.084225) (xy 96.273864 -113.105996) (xy 96.214205 -113.120688) (xy 96.153211 -113.128088)
			(xy 96.091769 -113.128088) (xy 96.030775 -113.120688) (xy 95.971116 -113.105996) (xy 95.913661 -113.084225)
			(xy 95.859246 -113.055694) (xy 95.833692 -113.038636) (xy 95.825007 -113.033243) (xy 95.80499 -113.029182)
			(xy 95.784973 -113.033243) (xy 95.776288 -113.038636) (xy 95.750737 -113.055699) (xy 95.696322 -113.08423)
			(xy 95.638866 -113.106) (xy 95.579206 -113.120691) (xy 95.518211 -113.12809) (xy 95.48749 -113.128552)
			(xy 95.455532 -113.127962) (xy 95.392121 -113.11995) (xy 95.330213 -113.104053) (xy 95.270786 -113.080524)
			(xy 95.214777 -113.049731) (xy 95.163068 -113.012162) (xy 95.116476 -112.968408) (xy 95.075735 -112.91916)
			(xy 95.041488 -112.865194) (xy 95.014274 -112.807361) (xy 94.994523 -112.746573) (xy 94.982547 -112.68379)
			(xy 94.978533 -112.62) (xy 39.630857 -112.62) (xy 39.610769 -112.636618) (xy 39.556798 -112.670869)
			(xy 39.498959 -112.698086) (xy 39.438166 -112.717839) (xy 39.375376 -112.729817) (xy 39.31158 -112.733831)
			(xy 39.247784 -112.729817) (xy 39.184994 -112.717839) (xy 39.124201 -112.698086) (xy 39.066362 -112.670869)
			(xy 39.012391 -112.636618) (xy 38.963138 -112.595873) (xy 38.919381 -112.549276) (xy 38.881808 -112.497561)
			(xy 38.851014 -112.441546) (xy 38.827482 -112.382113) (xy 38.811585 -112.320199) (xy 38.803574 -112.256781)
			(xy 38.438153 -112.256781) (xy 38.437803 -112.27493) (xy 38.43005 -112.328875) (xy 38.414698 -112.381168)
			(xy 38.392061 -112.430744) (xy 38.362599 -112.476593) (xy 38.326911 -112.517783) (xy 38.285725 -112.553475)
			(xy 38.239879 -112.582942) (xy 38.190305 -112.605584) (xy 38.138014 -112.620941) (xy 38.08407 -112.6287)
			(xy 38.05682 -112.629188) (xy 38.028684 -112.628727) (xy 37.973022 -112.620475) (xy 37.919176 -112.604132)
			(xy 37.868317 -112.580054) (xy 37.821549 -112.548762) (xy 37.779887 -112.510937) (xy 37.761672 -112.489488)
			(xy 37.754231 -112.481176) (xy 37.734197 -112.471421) (xy 37.723064 -112.470692) (xy 37.634418 -112.469422)
			(xy 37.614098 -112.478312) (xy 37.606732 -112.486694) (xy 37.588551 -112.506699) (xy 37.547496 -112.541864)
			(xy 37.501893 -112.570888) (xy 37.452652 -112.593192) (xy 37.400758 -112.608329) (xy 37.347248 -112.615996)
			(xy 37.32022 -112.616488) (xy 37.29358 -112.616018) (xy 37.24082 -112.608594) (xy 37.189606 -112.593904)
			(xy 37.140933 -112.572231) (xy 37.095749 -112.543998) (xy 37.054932 -112.509753) (xy 37.019276 -112.470163)
			(xy 37.00399 -112.44834) (xy 36.996624 -112.437418) (xy 36.973764 -112.425734) (xy 36.861496 -112.428782)
			(xy 36.839144 -112.44199) (xy 36.83254 -112.453166) (xy 36.817677 -112.4771) (xy 36.782039 -112.520733)
			(xy 36.740369 -112.558647) (xy 36.693574 -112.590019) (xy 36.642673 -112.614164) (xy 36.588774 -112.630558)
			(xy 36.533049 -112.638844) (xy 36.50488 -112.639348) (xy 36.47661 -112.638868) (xy 36.420689 -112.630533)
			(xy 36.36661 -112.614032) (xy 36.315561 -112.589729) (xy 36.268659 -112.558155) (xy 36.226933 -112.520002)
			(xy 36.208716 -112.498378) (xy 36.201206 -112.490045) (xy 36.181048 -112.480278) (xy 36.169854 -112.479582)
			(xy 36.0807 -112.478312) (xy 36.060126 -112.487456) (xy 36.05276 -112.496092) (xy 36.034566 -112.516598)
			(xy 35.993278 -112.552663) (xy 35.947255 -112.582448) (xy 35.897442 -112.60534) (xy 35.844867 -112.620869)
			(xy 35.79061 -112.628714) (xy 35.7632 -112.629188) (xy 35.737741 -112.628753) (xy 35.687275 -112.621991)
			(xy 35.638157 -112.608574) (xy 35.591262 -112.58874) (xy 35.547423 -112.562842) (xy 35.507419 -112.531341)
			(xy 35.489388 -112.513364) (xy 35.482276 -112.505998) (xy 35.463734 -112.498124) (xy 35.370516 -112.497362)
			(xy 35.351974 -112.504982) (xy 35.344608 -112.512348) (xy 35.323017 -112.533157) (xy 35.274514 -112.568412)
			(xy 35.221091 -112.595641) (xy 35.164065 -112.614174) (xy 35.104841 -112.623553) (xy 35.07486 -112.624108)
			(xy 35.047608 -112.623659) (xy 34.993659 -112.615897) (xy 34.941363 -112.600537) (xy 34.891786 -112.577891)
			(xy 34.845936 -112.548421) (xy 34.804746 -112.512726) (xy 34.769055 -112.471532) (xy 34.739589 -112.425679)
			(xy 34.716949 -112.376099) (xy 34.701594 -112.323802) (xy 34.693838 -112.269852) (xy 34.693352 -112.2426)
			(xy 13.42898 -112.2426) (xy 12.643358 -113.028222) (xy 13.52753 -113.028222) (xy 13.531601 -112.9726)
			(xy 13.543727 -112.918163) (xy 13.56365 -112.866072) (xy 13.590946 -112.817437) (xy 13.625032 -112.773294)
			(xy 13.665181 -112.734585) (xy 13.710539 -112.702134) (xy 13.760139 -112.676633) (xy 13.812923 -112.658626)
			(xy 13.867766 -112.648496) (xy 13.9235 -112.646459) (xy 13.978937 -112.652559) (xy 14.032894 -112.666665)
			(xy 14.084223 -112.688477) (xy 14.093204 -112.693958) (xy 16.982692 -112.693958) (xy 16.986763 -112.638336)
			(xy 16.998889 -112.583899) (xy 17.018812 -112.531808) (xy 17.046108 -112.483173) (xy 17.080194 -112.43903)
			(xy 17.120343 -112.400321) (xy 17.165701 -112.36787) (xy 17.215301 -112.342369) (xy 17.268085 -112.324362)
			(xy 17.322928 -112.314232) (xy 17.378662 -112.312195) (xy 17.434099 -112.318295) (xy 17.488056 -112.332401)
			(xy 17.539385 -112.354213) (xy 17.586991 -112.383267) (xy 17.629859 -112.418942) (xy 17.667076 -112.460479)
			(xy 17.697849 -112.506992) (xy 17.721521 -112.557489) (xy 17.737589 -112.610896) (xy 17.745709 -112.666072)
			(xy 17.746218 -112.693958) (xy 17.745709 -112.721844) (xy 17.737589 -112.77702) (xy 17.721521 -112.830427)
			(xy 17.697849 -112.880924) (xy 17.667076 -112.927437) (xy 17.629859 -112.968974) (xy 17.586991 -113.004649)
			(xy 17.539385 -113.033703) (xy 17.488056 -113.055515) (xy 17.434099 -113.069621) (xy 17.378662 -113.075721)
			(xy 17.322928 -113.073684) (xy 17.268085 -113.063554) (xy 17.215301 -113.045547) (xy 17.165701 -113.020046)
			(xy 17.120343 -112.987595) (xy 17.080194 -112.948886) (xy 17.046108 -112.904743) (xy 17.018812 -112.856108)
			(xy 16.998889 -112.804017) (xy 16.986763 -112.74958) (xy 16.982692 -112.693958) (xy 14.093204 -112.693958)
			(xy 14.131829 -112.717531) (xy 14.174697 -112.753206) (xy 14.211914 -112.794743) (xy 14.242687 -112.841256)
			(xy 14.266359 -112.891753) (xy 14.282427 -112.94516) (xy 14.290547 -113.000336) (xy 14.291056 -113.028222)
			(xy 14.290547 -113.056108) (xy 14.282427 -113.111284) (xy 14.266359 -113.164691) (xy 14.242687 -113.215188)
			(xy 14.211914 -113.261701) (xy 14.174697 -113.303238) (xy 14.131829 -113.338913) (xy 14.084223 -113.367967)
			(xy 14.032894 -113.389779) (xy 13.978937 -113.403885) (xy 13.9235 -113.409985) (xy 13.867766 -113.407948)
			(xy 13.812923 -113.397818) (xy 13.760139 -113.379811) (xy 13.710539 -113.35431) (xy 13.665181 -113.321859)
			(xy 13.625032 -113.28315) (xy 13.590946 -113.239007) (xy 13.56365 -113.190372) (xy 13.543727 -113.138281)
			(xy 13.531601 -113.083844) (xy 13.52753 -113.028222) (xy 12.643358 -113.028222) (xy 11.799062 -113.872518)
			(xy 11.794026 -113.877937) (xy 11.787048 -113.890973) (xy 11.785346 -113.898172) (xy 11.783822 -113.905538)
			(xy 11.785346 -113.92027) (xy 11.788394 -113.927636) (xy 11.797448 -113.950645) (xy 11.810206 -113.998417)
			(xy 11.816667 -114.047439) (xy 11.817096 -114.072162) (xy 11.817096 -114.07902) (xy 11.816473 -114.099472)
			(xy 11.811378 -114.140073) (xy 11.806936 -114.160046) (xy 11.805666 -114.169698) (xy 11.805666 -114.17046)
			(xy 11.805713 -114.176442) (xy 11.808288 -114.18812) (xy 11.810746 -114.193574) (xy 11.8237 -114.220498)
			(xy 11.824716 -114.22253) (xy 11.826378 -114.225633) (xy 11.83046 -114.23137) (xy 11.832844 -114.23396)
			(xy 11.835469 -114.236548) (xy 11.841334 -114.241011) (xy 11.844528 -114.24285) (xy 11.84529 -114.243358)
			(xy 11.848084 -114.244628) (xy 11.864215 -114.252167) (xy 11.895485 -114.269203) (xy 11.910568 -114.278664)
			(xy 11.923011 -114.286738) (xy 11.94703 -114.304148) (xy 11.958574 -114.313462) (xy 11.959082 -114.313716)
			(xy 11.966702 -114.31905) (xy 11.971045 -114.321353) (xy 11.980382 -114.324424) (xy 11.985244 -114.325146)
			(xy 11.986768 -114.325146) (xy 11.991086 -114.3254) (xy 12.14501 -114.3254) (xy 12.149328 -114.325146)
			(xy 12.150852 -114.325146) (xy 12.155714 -114.324422) (xy 12.165053 -114.321357) (xy 12.169394 -114.31905)
			(xy 12.177014 -114.313716) (xy 12.177522 -114.313462) (xy 12.189075 -114.304159) (xy 12.213091 -114.286747)
			(xy 12.225528 -114.278664) (xy 12.240615 -114.269209) (xy 12.271885 -114.252174) (xy 12.288012 -114.244628)
			(xy 12.290806 -114.243358) (xy 12.291568 -114.24285) (xy 12.294757 -114.241004) (xy 12.300619 -114.236538)
			(xy 12.303252 -114.23396) (xy 12.31138 -114.22253) (xy 12.312396 -114.220498) (xy 12.32535 -114.193574)
			(xy 12.327533 -114.188833) (xy 12.330103 -114.178717) (xy 12.33043 -114.173508) (xy 12.32916 -114.159792)
			(xy 12.324441 -114.138385) (xy 12.319351 -114.094843) (xy 12.319 -114.072924) (xy 12.319486 -114.045673)
			(xy 12.327242 -113.991725) (xy 12.342597 -113.93943) (xy 12.365239 -113.889853) (xy 12.394705 -113.844003)
			(xy 12.430396 -113.802812) (xy 12.471587 -113.767121) (xy 12.517437 -113.737655) (xy 12.567014 -113.715013)
			(xy 12.619309 -113.699658) (xy 12.673257 -113.691902) (xy 12.727759 -113.691902) (xy 12.781707 -113.699658)
			(xy 12.834002 -113.715013) (xy 12.883579 -113.737655) (xy 12.929429 -113.767121) (xy 12.97062 -113.802812)
			(xy 13.006311 -113.844003) (xy 13.035777 -113.889853) (xy 13.040388 -113.89995) (xy 142.766032 -113.89995)
			(xy 142.770103 -113.844328) (xy 142.782229 -113.789891) (xy 142.802152 -113.7378) (xy 142.829448 -113.689165)
			(xy 142.863534 -113.645022) (xy 142.903683 -113.606313) (xy 142.949041 -113.573862) (xy 142.998641 -113.548361)
			(xy 143.051425 -113.530354) (xy 143.106268 -113.520224) (xy 143.162002 -113.518187) (xy 143.217439 -113.524287)
			(xy 143.271396 -113.538393) (xy 143.322725 -113.560205) (xy 143.370331 -113.589259) (xy 143.388092 -113.60404)
			(xy 155.312108 -113.60404) (xy 155.316179 -113.548418) (xy 155.328305 -113.493981) (xy 155.348228 -113.44189)
			(xy 155.375524 -113.393255) (xy 155.40961 -113.349112) (xy 155.449759 -113.310403) (xy 155.495117 -113.277952)
			(xy 155.544717 -113.252451) (xy 155.597501 -113.234444) (xy 155.652344 -113.224314) (xy 155.708078 -113.222277)
			(xy 155.763515 -113.228377) (xy 155.817472 -113.242483) (xy 155.868801 -113.264295) (xy 155.916407 -113.293349)
			(xy 155.959275 -113.329024) (xy 155.996492 -113.370561) (xy 156.027265 -113.417074) (xy 156.050937 -113.467571)
			(xy 156.067005 -113.520978) (xy 156.075125 -113.576154) (xy 156.075634 -113.60404) (xy 156.075125 -113.631926)
			(xy 156.067005 -113.687102) (xy 156.050937 -113.740509) (xy 156.027265 -113.791006) (xy 155.996492 -113.837519)
			(xy 155.959275 -113.879056) (xy 155.916407 -113.914731) (xy 155.868801 -113.943785) (xy 155.817472 -113.965597)
			(xy 155.763515 -113.979703) (xy 155.708078 -113.985803) (xy 155.652344 -113.983766) (xy 155.597501 -113.973636)
			(xy 155.544717 -113.955629) (xy 155.495117 -113.930128) (xy 155.449759 -113.897677) (xy 155.40961 -113.858968)
			(xy 155.375524 -113.814825) (xy 155.348228 -113.76619) (xy 155.328305 -113.714099) (xy 155.316179 -113.659662)
			(xy 155.312108 -113.60404) (xy 143.388092 -113.60404) (xy 143.413199 -113.624934) (xy 143.450416 -113.666471)
			(xy 143.481189 -113.712984) (xy 143.504861 -113.763481) (xy 143.520929 -113.816888) (xy 143.529049 -113.872064)
			(xy 143.529558 -113.89995) (xy 143.529049 -113.927836) (xy 143.520929 -113.983012) (xy 143.504861 -114.036419)
			(xy 143.481189 -114.086916) (xy 143.450416 -114.133429) (xy 143.413199 -114.174966) (xy 143.370331 -114.210641)
			(xy 143.322725 -114.239695) (xy 143.271396 -114.261507) (xy 143.217439 -114.275613) (xy 143.162002 -114.281713)
			(xy 143.106268 -114.279676) (xy 143.051425 -114.269546) (xy 142.998641 -114.251539) (xy 142.949041 -114.226038)
			(xy 142.903683 -114.193587) (xy 142.863534 -114.154878) (xy 142.829448 -114.110735) (xy 142.802152 -114.0621)
			(xy 142.782229 -114.010009) (xy 142.770103 -113.955572) (xy 142.766032 -113.89995) (xy 13.040388 -113.89995)
			(xy 13.058419 -113.93943) (xy 13.073774 -113.991725) (xy 13.08153 -114.045673) (xy 13.082016 -114.072924)
			(xy 13.08227 -114.072924) (xy 13.081834 -114.099149) (xy 13.07465 -114.151104) (xy 13.060422 -114.201586)
			(xy 13.039418 -114.249646) (xy 13.012032 -114.294378) (xy 12.97878 -114.334939) (xy 12.959842 -114.353086)
			(xy 12.954 -114.35842) (xy 12.952222 -114.361722) (xy 12.940538 -114.382804) (xy 12.937236 -114.39144)
			(xy 12.932918 -114.41684) (xy 12.932267 -114.421727) (xy 12.93265 -114.431577) (xy 12.93368 -114.436398)
			(xy 12.934599 -114.440184) (xy 12.937408 -114.447452) (xy 12.939268 -114.450876) (xy 12.955659 -114.480047)
			(xy 12.981478 -114.541778) (xy 12.998964 -114.606365) (xy 13.007813 -114.67269) (xy 13.008356 -114.706146)
			(xy 13.008356 -114.711988) (xy 13.007494 -114.745063) (xy 12.998256 -114.81058) (xy 12.980598 -114.874345)
			(xy 12.954818 -114.935281) (xy 12.921353 -114.992358) (xy 12.880766 -115.044612) (xy 12.833745 -115.09116)
			(xy 12.781083 -115.131217) (xy 12.768967 -115.138157) (xy 107.226348 -115.138157) (xy 107.226348 -115.074235)
			(xy 107.234359 -115.010817) (xy 107.250256 -114.948903) (xy 107.273788 -114.88947) (xy 107.304582 -114.833455)
			(xy 107.342155 -114.78174) (xy 107.385912 -114.735143) (xy 107.435165 -114.694398) (xy 107.489136 -114.660147)
			(xy 107.546975 -114.63293) (xy 107.607768 -114.613177) (xy 107.670558 -114.601199) (xy 107.734354 -114.597186)
			(xy 107.79815 -114.601199) (xy 107.86094 -114.613177) (xy 107.921733 -114.63293) (xy 107.979572 -114.660147)
			(xy 108.033543 -114.694398) (xy 108.082796 -114.735143) (xy 108.126553 -114.78174) (xy 108.154641 -114.8204)
			(xy 133.881114 -114.8204) (xy 133.885128 -114.756605) (xy 133.897106 -114.693816) (xy 133.91686 -114.633023)
			(xy 133.944077 -114.575186) (xy 133.978329 -114.521216) (xy 134.019075 -114.471965) (xy 134.065673 -114.428209)
			(xy 134.117388 -114.390639) (xy 134.173404 -114.359847) (xy 134.232838 -114.336319) (xy 134.294752 -114.320425)
			(xy 134.358169 -114.312417) (xy 134.39013 -114.311938) (xy 134.421369 -114.312459) (xy 134.483374 -114.320128)
			(xy 134.543973 -114.335334) (xy 134.602253 -114.357848) (xy 134.657337 -114.387331) (xy 134.708394 -114.423339)
			(xy 134.754657 -114.46533) (xy 134.795427 -114.512672) (xy 134.830092 -114.564651) (xy 134.844536 -114.592354)
			(xy 134.848752 -114.600005) (xy 134.861353 -114.612085) (xy 134.869174 -114.615976) (xy 134.896606 -114.627914)
			(xy 134.904731 -114.631115) (xy 134.922133 -114.632419) (xy 134.930642 -114.630454) (xy 134.963588 -114.622003)
			(xy 135.030999 -114.612948) (xy 135.065008 -114.61242) (xy 135.065262 -114.61242) (xy 135.097228 -114.612843)
			(xy 135.160655 -114.620851) (xy 135.222579 -114.636746) (xy 135.282022 -114.660278) (xy 135.287247 -114.66315)
			(xy 145.180046 -114.66315) (xy 145.180046 -114.578454) (xy 145.188097 -114.49414) (xy 145.204126 -114.410974)
			(xy 145.227987 -114.329707) (xy 145.259466 -114.251077) (xy 145.298277 -114.175796) (xy 145.344067 -114.104544)
			(xy 145.396423 -114.037968) (xy 145.454871 -113.97667) (xy 145.518881 -113.921205) (xy 145.587873 -113.872076)
			(xy 145.661223 -113.829727) (xy 145.738266 -113.794543) (xy 145.818305 -113.766841) (xy 145.900614 -113.746873)
			(xy 145.984449 -113.73482) (xy 146.06905 -113.73079) (xy 146.153651 -113.73482) (xy 146.237486 -113.746873)
			(xy 146.319795 -113.766841) (xy 146.399834 -113.794543) (xy 146.476877 -113.829727) (xy 146.550227 -113.872076)
			(xy 146.619219 -113.921205) (xy 146.683229 -113.97667) (xy 146.741677 -114.037968) (xy 146.794033 -114.104544)
			(xy 146.839823 -114.175796) (xy 146.877254 -114.2484) (xy 160.895006 -114.2484) (xy 160.899021 -114.184603)
			(xy 160.910999 -114.121811) (xy 160.930754 -114.061017) (xy 160.957973 -114.003178) (xy 160.992226 -113.949206)
			(xy 161.032975 -113.899954) (xy 161.079575 -113.856197) (xy 161.131293 -113.818627) (xy 161.187311 -113.787835)
			(xy 161.246747 -113.764307) (xy 161.308664 -113.748415) (xy 161.372084 -113.740408) (xy 161.404046 -113.73993)
			(xy 161.434957 -113.740377) (xy 161.496322 -113.747887) (xy 161.556325 -113.762779) (xy 161.61408 -113.784833)
			(xy 161.668737 -113.813725) (xy 161.71949 -113.849027) (xy 161.76559 -113.89022) (xy 161.786316 -113.913158)
			(xy 161.78657 -113.913412) (xy 161.793952 -113.920959) (xy 161.813118 -113.929753) (xy 161.823654 -113.93043)
			(xy 161.898838 -113.931954) (xy 161.909374 -113.931615) (xy 161.928795 -113.923475) (xy 161.93643 -113.916206)
			(xy 161.936684 -113.915952) (xy 161.960795 -113.891237) (xy 162.01454 -113.847892) (xy 162.073657 -113.812219)
			(xy 162.137057 -113.784874) (xy 162.203574 -113.76636) (xy 162.271985 -113.757017) (xy 162.306508 -113.75644)
			(xy 162.337242 -113.75683) (xy 162.398262 -113.764241) (xy 162.457944 -113.778953) (xy 162.515417 -113.800752)
			(xy 162.569843 -113.829319) (xy 162.620429 -113.86424) (xy 162.666436 -113.905003) (xy 162.707195 -113.951015)
			(xy 162.742109 -114.001605) (xy 162.770671 -114.056034) (xy 162.792464 -114.11351) (xy 162.807169 -114.173193)
			(xy 162.814573 -114.234214) (xy 162.815016 -114.264948) (xy 162.81456 -114.295777) (xy 162.807093 -114.356981)
			(xy 162.792275 -114.416832) (xy 162.770323 -114.47445) (xy 162.756342 -114.50193) (xy 162.751924 -114.511309)
			(xy 162.750241 -114.531952) (xy 162.756883 -114.551569) (xy 162.763454 -114.559588) (xy 162.783908 -114.582967)
			(xy 162.819541 -114.633852) (xy 162.848705 -114.688702) (xy 162.870965 -114.746697) (xy 162.885987 -114.806975)
			(xy 162.893549 -114.868633) (xy 162.89401 -114.899694) (xy 162.893557 -114.930426) (xy 162.886149 -114.991442)
			(xy 162.87144 -115.05112) (xy 162.849645 -115.108589) (xy 162.821082 -115.163013) (xy 162.786167 -115.213597)
			(xy 162.74541 -115.259604) (xy 162.699404 -115.300362) (xy 162.681227 -115.312909) (xy 164.210994 -115.312909)
			(xy 164.210994 -115.248987) (xy 164.219005 -115.185569) (xy 164.234902 -115.123655) (xy 164.258434 -115.064222)
			(xy 164.289228 -115.008207) (xy 164.326801 -114.956492) (xy 164.370558 -114.909895) (xy 164.419811 -114.86915)
			(xy 164.473782 -114.834899) (xy 164.531621 -114.807682) (xy 164.592414 -114.787929) (xy 164.655204 -114.775951)
			(xy 164.719 -114.771938) (xy 164.782796 -114.775951) (xy 164.845586 -114.787929) (xy 164.906379 -114.807682)
			(xy 164.964218 -114.834899) (xy 165.018189 -114.86915) (xy 165.067442 -114.909895) (xy 165.111199 -114.956492)
			(xy 165.148772 -115.008207) (xy 165.179566 -115.064222) (xy 165.203098 -115.123655) (xy 165.218995 -115.185569)
			(xy 165.227006 -115.248987) (xy 165.227508 -115.280948) (xy 165.227006 -115.312909) (xy 165.218995 -115.376327)
			(xy 165.203098 -115.438241) (xy 165.179566 -115.497674) (xy 165.148772 -115.553689) (xy 165.111199 -115.605404)
			(xy 165.067442 -115.652001) (xy 165.018189 -115.692746) (xy 164.964218 -115.726997) (xy 164.906379 -115.754214)
			(xy 164.845586 -115.773967) (xy 164.782796 -115.785945) (xy 164.719 -115.789959) (xy 164.655204 -115.785945)
			(xy 164.592414 -115.773967) (xy 164.531621 -115.754214) (xy 164.473782 -115.726997) (xy 164.419811 -115.692746)
			(xy 164.370558 -115.652001) (xy 164.326801 -115.605404) (xy 164.289228 -115.553689) (xy 164.258434 -115.497674)
			(xy 164.234902 -115.438241) (xy 164.219005 -115.376327) (xy 164.210994 -115.312909) (xy 162.681227 -115.312909)
			(xy 162.64882 -115.335278) (xy 162.594397 -115.363842) (xy 162.536927 -115.385638) (xy 162.47725 -115.400347)
			(xy 162.416234 -115.407756) (xy 162.385502 -115.408202) (xy 162.376358 -115.408202) (xy 162.367252 -115.408373)
			(xy 162.350065 -115.414355) (xy 162.34283 -115.419886) (xy 162.319462 -115.439444) (xy 162.312912 -115.445569)
			(xy 162.304074 -115.461157) (xy 162.30219 -115.469924) (xy 162.297232 -115.496206) (xy 162.280904 -115.547135)
			(xy 162.257624 -115.595286) (xy 162.22785 -115.639715) (xy 162.192163 -115.679551) (xy 162.151264 -115.714014)
			(xy 162.105954 -115.742429) (xy 162.057119 -115.764239) (xy 162.005718 -115.779016) (xy 161.952758 -115.786472)
			(xy 161.926016 -115.786916) (xy 161.898764 -115.78643) (xy 161.844814 -115.778675) (xy 161.792517 -115.763322)
			(xy 161.742938 -115.740682) (xy 161.697085 -115.711216) (xy 161.655892 -115.675525) (xy 161.620198 -115.634334)
			(xy 161.59073 -115.588483) (xy 161.568087 -115.538905) (xy 161.55273 -115.486609) (xy 161.544972 -115.43266)
			(xy 161.544508 -115.405408) (xy 161.544981 -115.377728) (xy 161.552961 -115.322947) (xy 161.568783 -115.269897)
			(xy 161.592114 -115.219694) (xy 161.622463 -115.173395) (xy 161.659191 -115.131975) (xy 161.701527 -115.096304)
			(xy 161.748577 -115.067134) (xy 161.799353 -115.045079) (xy 161.82594 -115.037362) (xy 161.834457 -115.034604)
			(xy 161.849009 -115.024199) (xy 161.854388 -115.017042) (xy 161.871914 -114.991642) (xy 161.876718 -114.983892)
			(xy 161.881016 -114.966187) (xy 161.880296 -114.957098) (xy 161.878765 -114.942796) (xy 161.877111 -114.914077)
			(xy 161.876994 -114.899694) (xy 161.877436 -114.868865) (xy 161.884909 -114.80766) (xy 161.899731 -114.74781)
			(xy 161.921686 -114.690192) (xy 161.935668 -114.662712) (xy 161.940136 -114.653353) (xy 161.9418 -114.632696)
			(xy 161.935138 -114.613072) (xy 161.928556 -114.605054) (xy 161.924238 -114.600228) (xy 161.923984 -114.599974)
			(xy 161.916583 -114.592448) (xy 161.897431 -114.583643) (xy 161.8869 -114.582956) (xy 161.811716 -114.581432)
			(xy 161.80118 -114.581776) (xy 161.781758 -114.58991) (xy 161.774124 -114.59718) (xy 161.77387 -114.597434)
			(xy 161.749778 -114.622169) (xy 161.696029 -114.665512) (xy 161.636909 -114.701183) (xy 161.573505 -114.728525)
			(xy 161.506984 -114.747034) (xy 161.43857 -114.756372) (xy 161.404046 -114.756946) (xy 161.372084 -114.756392)
			(xy 161.308664 -114.748385) (xy 161.246747 -114.732493) (xy 161.187311 -114.708965) (xy 161.131293 -114.678173)
			(xy 161.079575 -114.640603) (xy 161.032975 -114.596846) (xy 160.992226 -114.547594) (xy 160.957973 -114.493622)
			(xy 160.930754 -114.435783) (xy 160.910999 -114.374989) (xy 160.899021 -114.312197) (xy 160.895006 -114.2484)
			(xy 146.877254 -114.2484) (xy 146.878634 -114.251077) (xy 146.910113 -114.329707) (xy 146.933974 -114.410974)
			(xy 146.950003 -114.49414) (xy 146.958054 -114.578454) (xy 146.958558 -114.620802) (xy 146.958054 -114.66315)
			(xy 146.950003 -114.747464) (xy 146.933974 -114.83063) (xy 146.910113 -114.911897) (xy 146.878634 -114.990527)
			(xy 146.839823 -115.065808) (xy 146.794033 -115.13706) (xy 146.741677 -115.203636) (xy 146.683229 -115.264934)
			(xy 146.619219 -115.320399) (xy 146.550227 -115.369528) (xy 146.476877 -115.411877) (xy 146.399834 -115.447061)
			(xy 146.319795 -115.474763) (xy 146.237486 -115.494731) (xy 146.153651 -115.506784) (xy 146.06905 -115.510815)
			(xy 145.984449 -115.506784) (xy 145.900614 -115.494731) (xy 145.818305 -115.474763) (xy 145.738266 -115.447061)
			(xy 145.661223 -115.411877) (xy 145.587873 -115.369528) (xy 145.518881 -115.320399) (xy 145.454871 -115.264934)
			(xy 145.396423 -115.203636) (xy 145.344067 -115.13706) (xy 145.298277 -115.065808) (xy 145.259466 -114.990527)
			(xy 145.227987 -114.911897) (xy 145.204126 -114.83063) (xy 145.188097 -114.747464) (xy 145.180046 -114.66315)
			(xy 135.287247 -114.66315) (xy 135.338047 -114.691074) (xy 135.38977 -114.728649) (xy 135.436376 -114.772411)
			(xy 135.477129 -114.82167) (xy 135.511386 -114.875648) (xy 135.538608 -114.933494) (xy 135.558365 -114.994296)
			(xy 135.570345 -115.057095) (xy 135.57436 -115.1209) (xy 135.570345 -115.184705) (xy 135.558365 -115.247504)
			(xy 135.538608 -115.308306) (xy 135.511386 -115.366152) (xy 135.477129 -115.42013) (xy 135.436376 -115.469389)
			(xy 135.38977 -115.513151) (xy 135.338047 -115.550726) (xy 135.282022 -115.581522) (xy 135.222579 -115.605054)
			(xy 135.160655 -115.620949) (xy 135.097228 -115.628957) (xy 135.065262 -115.629436) (xy 135.034023 -115.628936)
			(xy 134.972016 -115.621266) (xy 134.911416 -115.606058) (xy 134.853135 -115.583542) (xy 134.798051 -115.554056)
			(xy 134.746993 -115.518045) (xy 134.700731 -115.476051) (xy 134.659962 -115.428707) (xy 134.625299 -115.376725)
			(xy 134.610856 -115.34902) (xy 134.60665 -115.341363) (xy 134.594042 -115.329287) (xy 134.586218 -115.325398)
			(xy 134.558786 -115.31346) (xy 134.550662 -115.310255) (xy 134.533259 -115.308954) (xy 134.52475 -115.31092)
			(xy 134.491805 -115.319375) (xy 134.424393 -115.328427) (xy 134.390384 -115.328954) (xy 134.39013 -115.328954)
			(xy 134.358169 -115.328383) (xy 134.294752 -115.320375) (xy 134.232838 -115.304481) (xy 134.173404 -115.280953)
			(xy 134.117388 -115.250161) (xy 134.065673 -115.212591) (xy 134.019075 -115.168835) (xy 133.978329 -115.119584)
			(xy 133.944077 -115.065614) (xy 133.91686 -115.007777) (xy 133.897106 -114.946984) (xy 133.885128 -114.884195)
			(xy 133.881114 -114.8204) (xy 108.154641 -114.8204) (xy 108.164126 -114.833455) (xy 108.19492 -114.88947)
			(xy 108.218452 -114.948903) (xy 108.234349 -115.010817) (xy 108.24236 -115.074235) (xy 108.242862 -115.106196)
			(xy 108.24236 -115.138157) (xy 108.234349 -115.201575) (xy 108.218452 -115.263489) (xy 108.19492 -115.322922)
			(xy 108.164126 -115.378937) (xy 108.126553 -115.430652) (xy 108.082796 -115.477249) (xy 108.033543 -115.517994)
			(xy 107.979572 -115.552245) (xy 107.921733 -115.579462) (xy 107.86094 -115.599215) (xy 107.79815 -115.611193)
			(xy 107.734354 -115.615207) (xy 107.670558 -115.611193) (xy 107.607768 -115.599215) (xy 107.546975 -115.579462)
			(xy 107.489136 -115.552245) (xy 107.435165 -115.517994) (xy 107.385912 -115.477249) (xy 107.342155 -115.430652)
			(xy 107.304582 -115.378937) (xy 107.273788 -115.322922) (xy 107.250256 -115.263489) (xy 107.234359 -115.201575)
			(xy 107.226348 -115.138157) (xy 12.768967 -115.138157) (xy 12.72367 -115.164104) (xy 12.662477 -115.189266)
			(xy 12.598537 -115.206279) (xy 12.53293 -115.214854) (xy 12.499848 -115.215416) (xy 12.464894 -115.214834)
			(xy 12.395645 -115.205258) (xy 12.328359 -115.186294) (xy 12.264301 -115.158298) (xy 12.204678 -115.121798)
			(xy 12.177268 -115.1001) (xy 12.172078 -115.09603) (xy 12.160108 -115.0905) (xy 12.153646 -115.089178)
			(xy 12.144756 -115.088416) (xy 11.99134 -115.088416) (xy 11.98245 -115.089178) (xy 11.975999 -115.090534)
			(xy 11.964037 -115.096061) (xy 11.958828 -115.1001) (xy 11.931431 -115.121817) (xy 11.871809 -115.158327)
			(xy 11.807749 -115.186327) (xy 11.740458 -115.20529) (xy 11.671204 -115.214858) (xy 11.636248 -115.215416)
			(xy 11.602898 -115.214895) (xy 11.536768 -115.206182) (xy 11.472345 -115.188901) (xy 11.410734 -115.163346)
			(xy 11.352992 -115.129958) (xy 11.300109 -115.089308) (xy 11.252994 -115.042094) (xy 11.212454 -114.989127)
			(xy 11.179186 -114.931315) (xy 11.153759 -114.869651) (xy 11.136612 -114.805192) (xy 11.131804 -114.772186)
			(xy 11.131804 -114.771424) (xy 11.130689 -114.764285) (xy 11.125013 -114.751005) (xy 11.120628 -114.745262)
			(xy 11.11631 -114.739928) (xy 11.110722 -114.736118) (xy 11.098276 -114.729768) (xy 11.00836 -114.699288)
			(xy 10.9997 -114.697363) (xy 10.982038 -114.698882) (xy 10.965945 -114.706318) (xy 10.959338 -114.712242)
			(xy 9.990879 -115.680701) (xy 158.973514 -115.680701) (xy 158.973514 -115.616779) (xy 158.981525 -115.553361)
			(xy 158.997422 -115.491447) (xy 159.020954 -115.432014) (xy 159.051748 -115.375999) (xy 159.089321 -115.324284)
			(xy 159.133078 -115.277687) (xy 159.182331 -115.236942) (xy 159.236302 -115.202691) (xy 159.294141 -115.175474)
			(xy 159.354934 -115.155721) (xy 159.417724 -115.143743) (xy 159.48152 -115.13973) (xy 159.545316 -115.143743)
			(xy 159.608106 -115.155721) (xy 159.668899 -115.175474) (xy 159.726738 -115.202691) (xy 159.780709 -115.236942)
			(xy 159.829962 -115.277687) (xy 159.873719 -115.324284) (xy 159.911292 -115.375999) (xy 159.942086 -115.432014)
			(xy 159.965618 -115.491447) (xy 159.981515 -115.553361) (xy 159.989526 -115.616779) (xy 159.990028 -115.64874)
			(xy 159.989526 -115.680701) (xy 159.981515 -115.744119) (xy 159.965618 -115.806033) (xy 159.942086 -115.865466)
			(xy 159.911292 -115.921481) (xy 159.873719 -115.973196) (xy 159.829962 -116.019793) (xy 159.780709 -116.060538)
			(xy 159.726738 -116.094789) (xy 159.668899 -116.122006) (xy 159.608106 -116.141759) (xy 159.545316 -116.153737)
			(xy 159.48152 -116.157751) (xy 159.417724 -116.153737) (xy 159.354934 -116.141759) (xy 159.294141 -116.122006)
			(xy 159.236302 -116.094789) (xy 159.182331 -116.060538) (xy 159.133078 -116.019793) (xy 159.089321 -115.973196)
			(xy 159.051748 -115.921481) (xy 159.020954 -115.865466) (xy 158.997422 -115.806033) (xy 158.981525 -115.744119)
			(xy 158.973514 -115.680701) (xy 9.990879 -115.680701) (xy 9.35863 -116.31295) (xy 147.828252 -116.31295)
			(xy 147.832323 -116.257328) (xy 147.844449 -116.202891) (xy 147.864372 -116.1508) (xy 147.891668 -116.102165)
			(xy 147.925754 -116.058022) (xy 147.965903 -116.019313) (xy 148.011261 -115.986862) (xy 148.060861 -115.961361)
			(xy 148.113645 -115.943354) (xy 148.168488 -115.933224) (xy 148.224222 -115.931187) (xy 148.279659 -115.937287)
			(xy 148.333616 -115.951393) (xy 148.384945 -115.973205) (xy 148.432551 -116.002259) (xy 148.475419 -116.037934)
			(xy 148.512636 -116.079471) (xy 148.543409 -116.125984) (xy 148.567081 -116.176481) (xy 148.583149 -116.229888)
			(xy 148.591269 -116.285064) (xy 148.591778 -116.31295) (xy 148.591269 -116.340836) (xy 148.583149 -116.396012)
			(xy 148.567081 -116.449419) (xy 148.543409 -116.499916) (xy 148.512636 -116.546429) (xy 148.475419 -116.587966)
			(xy 148.432551 -116.623641) (xy 148.384945 -116.652695) (xy 148.333616 -116.674507) (xy 148.279659 -116.688613)
			(xy 148.224222 -116.694713) (xy 148.168488 -116.692676) (xy 148.113645 -116.682546) (xy 148.060861 -116.664539)
			(xy 148.011261 -116.639038) (xy 147.965903 -116.606587) (xy 147.925754 -116.567878) (xy 147.891668 -116.523735)
			(xy 147.864372 -116.4751) (xy 147.844449 -116.423009) (xy 147.832323 -116.368572) (xy 147.828252 -116.31295)
			(xy 9.35863 -116.31295) (xy 7.94618 -117.7254) (xy 136.807533 -117.7254) (xy 136.811546 -117.661612)
			(xy 136.823522 -117.598831) (xy 136.843272 -117.538045) (xy 136.870484 -117.480214) (xy 136.904729 -117.426249)
			(xy 136.945468 -117.377001) (xy 136.992057 -117.333247) (xy 137.043763 -117.295678) (xy 137.099769 -117.264884)
			(xy 137.159193 -117.241353) (xy 137.221098 -117.225455) (xy 137.284507 -117.21744) (xy 137.316464 -117.216936)
			(xy 137.347762 -117.217405) (xy 137.409883 -117.225096) (xy 137.470591 -117.240352) (xy 137.528968 -117.262944)
			(xy 137.584131 -117.292529) (xy 137.635246 -117.328661) (xy 137.681539 -117.370793) (xy 137.70229 -117.394228)
			(xy 137.70229 -117.394482) (xy 137.708671 -117.401166) (xy 137.724941 -117.409894) (xy 137.73404 -117.4115)
			(xy 137.81024 -117.421914) (xy 137.828274 -117.417596) (xy 137.836148 -117.412516) (xy 137.859864 -117.397169)
			(xy 137.910868 -117.37289) (xy 137.964891 -117.356388) (xy 138.020756 -117.348023) (xy 138.049 -117.347492)
			(xy 138.076251 -117.347978) (xy 138.130199 -117.355734) (xy 138.182494 -117.371089) (xy 138.209801 -117.38356)
			(xy 144.261838 -117.38356) (xy 144.265909 -117.327938) (xy 144.278035 -117.273501) (xy 144.297958 -117.22141)
			(xy 144.325254 -117.172775) (xy 144.35934 -117.128632) (xy 144.399489 -117.089923) (xy 144.444847 -117.057472)
			(xy 144.494447 -117.031971) (xy 144.547231 -117.013964) (xy 144.602074 -117.003834) (xy 144.657808 -117.001797)
			(xy 144.713245 -117.007897) (xy 144.767202 -117.022003) (xy 144.818531 -117.043815) (xy 144.866137 -117.072869)
			(xy 144.909005 -117.108544) (xy 144.946222 -117.150081) (xy 144.976995 -117.196594) (xy 145.000667 -117.247091)
			(xy 145.016735 -117.300498) (xy 145.024855 -117.355674) (xy 145.025364 -117.38356) (xy 145.024855 -117.411446)
			(xy 145.016735 -117.466622) (xy 145.000667 -117.520029) (xy 144.999768 -117.521947) (xy 149.226772 -117.521947)
			(xy 149.226772 -117.458025) (xy 149.234783 -117.394607) (xy 149.25068 -117.332693) (xy 149.274212 -117.27326)
			(xy 149.305006 -117.217245) (xy 149.342579 -117.16553) (xy 149.386336 -117.118933) (xy 149.435589 -117.078188)
			(xy 149.48956 -117.043937) (xy 149.547399 -117.01672) (xy 149.608192 -116.996967) (xy 149.670982 -116.984989)
			(xy 149.734778 -116.980976) (xy 149.798574 -116.984989) (xy 149.861364 -116.996967) (xy 149.922157 -117.01672)
			(xy 149.979996 -117.043937) (xy 150.033967 -117.078188) (xy 150.08322 -117.118933) (xy 150.126977 -117.16553)
			(xy 150.16455 -117.217245) (xy 150.195344 -117.27326) (xy 150.218876 -117.332693) (xy 150.234773 -117.394607)
			(xy 150.242784 -117.458025) (xy 150.243286 -117.489986) (xy 150.242784 -117.521947) (xy 150.234773 -117.585365)
			(xy 150.218876 -117.647279) (xy 150.195344 -117.706712) (xy 150.169128 -117.7544) (xy 150.603202 -117.7544)
			(xy 150.607273 -117.698778) (xy 150.619399 -117.644341) (xy 150.639322 -117.59225) (xy 150.666618 -117.543615)
			(xy 150.700704 -117.499472) (xy 150.740853 -117.460763) (xy 150.786211 -117.428312) (xy 150.835811 -117.402811)
			(xy 150.888595 -117.384804) (xy 150.943438 -117.374674) (xy 150.999172 -117.372637) (xy 151.054609 -117.378737)
			(xy 151.108566 -117.392843) (xy 151.159895 -117.414655) (xy 151.207501 -117.443709) (xy 151.250369 -117.479384)
			(xy 151.287586 -117.520921) (xy 151.318359 -117.567434) (xy 151.342031 -117.617931) (xy 151.358099 -117.671338)
			(xy 151.366219 -117.726514) (xy 151.366728 -117.7544) (xy 151.366219 -117.782286) (xy 151.358099 -117.837462)
			(xy 151.342031 -117.890869) (xy 151.318359 -117.941366) (xy 151.287586 -117.987879) (xy 151.250369 -118.029416)
			(xy 151.207501 -118.065091) (xy 151.159895 -118.094145) (xy 151.108566 -118.115957) (xy 151.054609 -118.130063)
			(xy 151.033806 -118.132352) (xy 157.585156 -118.132352) (xy 157.585633 -118.105351) (xy 157.593254 -118.051888)
			(xy 157.608338 -118.000035) (xy 157.630583 -117.950826) (xy 157.659544 -117.905246) (xy 157.694643 -117.864205)
			(xy 157.735178 -117.828523) (xy 157.780339 -117.798913) (xy 157.829225 -117.775967) (xy 157.854904 -117.767608)
			(xy 157.868147 -117.763052) (xy 157.891695 -117.747918) (xy 157.910241 -117.726952) (xy 157.922389 -117.701734)
			(xy 157.927223 -117.674163) (xy 157.92438 -117.646316) (xy 157.914074 -117.620291) (xy 157.89708 -117.598048)
			(xy 157.886146 -117.5893) (xy 157.859536 -117.56861) (xy 157.81142 -117.521408) (xy 157.769961 -117.468263)
			(xy 157.735888 -117.410106) (xy 157.709796 -117.347957) (xy 157.692143 -117.282907) (xy 157.683239 -117.216094)
			(xy 157.682692 -117.182392) (xy 157.683194 -117.150431) (xy 157.691205 -117.087013) (xy 157.707102 -117.025099)
			(xy 157.730634 -116.965666) (xy 157.761428 -116.909651) (xy 157.799001 -116.857936) (xy 157.842758 -116.811339)
			(xy 157.892011 -116.770594) (xy 157.945982 -116.736343) (xy 158.003821 -116.709126) (xy 158.064614 -116.689373)
			(xy 158.127404 -116.677395) (xy 158.1912 -116.673382) (xy 158.254996 -116.677395) (xy 158.317786 -116.689373)
			(xy 158.378579 -116.709126) (xy 158.436418 -116.736343) (xy 158.490389 -116.770594) (xy 158.539642 -116.811339)
			(xy 158.583399 -116.857936) (xy 158.620972 -116.909651) (xy 158.651766 -116.965666) (xy 158.675298 -117.025099)
			(xy 158.691195 -117.087013) (xy 158.699206 -117.150431) (xy 158.699708 -117.182392) (xy 158.699228 -117.214569)
			(xy 158.69111 -117.278407) (xy 158.675002 -117.340712) (xy 158.651163 -117.400486) (xy 158.619972 -117.456775)
			(xy 158.581929 -117.508679) (xy 158.537641 -117.555369) (xy 158.487817 -117.596098) (xy 158.433252 -117.630215)
			(xy 158.374819 -117.657175) (xy 158.313451 -117.676548) (xy 158.281878 -117.682772) (xy 158.26819 -117.685719)
			(xy 158.243048 -117.698017) (xy 158.222186 -117.716676) (xy 158.207169 -117.740294) (xy 158.199122 -117.767101)
			(xy 158.19865 -117.795086) (xy 158.205789 -117.822149) (xy 158.220002 -117.84626) (xy 158.229808 -117.856254)
			(xy 158.248181 -117.87429) (xy 158.280352 -117.914486) (xy 158.303577 -117.953239) (xy 160.944554 -117.953239)
			(xy 160.944554 -117.889317) (xy 160.952565 -117.825899) (xy 160.968462 -117.763985) (xy 160.991994 -117.704552)
			(xy 161.022788 -117.648537) (xy 161.060361 -117.596822) (xy 161.104118 -117.550225) (xy 161.153371 -117.50948)
			(xy 161.207342 -117.475229) (xy 161.265181 -117.448012) (xy 161.325974 -117.428259) (xy 161.388764 -117.416281)
			(xy 161.45256 -117.412268) (xy 161.516356 -117.416281) (xy 161.579146 -117.428259) (xy 161.639939 -117.448012)
			(xy 161.697778 -117.475229) (xy 161.751749 -117.50948) (xy 161.801002 -117.550225) (xy 161.844759 -117.596822)
			(xy 161.882332 -117.648537) (xy 161.913126 -117.704552) (xy 161.936658 -117.763985) (xy 161.952555 -117.825899)
			(xy 161.960566 -117.889317) (xy 161.961068 -117.921278) (xy 161.960566 -117.953239) (xy 161.952555 -118.016657)
			(xy 161.936658 -118.078571) (xy 161.913126 -118.138004) (xy 161.882332 -118.194019) (xy 161.844759 -118.245734)
			(xy 161.801002 -118.292331) (xy 161.751749 -118.333076) (xy 161.697778 -118.367327) (xy 161.669854 -118.380467)
			(xy 164.864282 -118.380467) (xy 164.864282 -118.316545) (xy 164.872293 -118.253127) (xy 164.88819 -118.191213)
			(xy 164.911722 -118.13178) (xy 164.942516 -118.075765) (xy 164.980089 -118.02405) (xy 165.023846 -117.977453)
			(xy 165.073099 -117.936708) (xy 165.12707 -117.902457) (xy 165.184909 -117.87524) (xy 165.245702 -117.855487)
			(xy 165.308492 -117.843509) (xy 165.372288 -117.839496) (xy 165.436084 -117.843509) (xy 165.498874 -117.855487)
			(xy 165.559667 -117.87524) (xy 165.617506 -117.902457) (xy 165.671477 -117.936708) (xy 165.72073 -117.977453)
			(xy 165.764487 -118.02405) (xy 165.80206 -118.075765) (xy 165.832854 -118.13178) (xy 165.856386 -118.191213)
			(xy 165.872283 -118.253127) (xy 165.880294 -118.316545) (xy 165.880796 -118.348506) (xy 165.880294 -118.380467)
			(xy 165.872283 -118.443885) (xy 165.856386 -118.505799) (xy 165.832854 -118.565232) (xy 165.80206 -118.621247)
			(xy 165.764487 -118.672962) (xy 165.72073 -118.719559) (xy 165.671477 -118.760304) (xy 165.617506 -118.794555)
			(xy 165.559667 -118.821772) (xy 165.498874 -118.841525) (xy 165.436084 -118.853503) (xy 165.372288 -118.857517)
			(xy 165.308492 -118.853503) (xy 165.245702 -118.841525) (xy 165.184909 -118.821772) (xy 165.12707 -118.794555)
			(xy 165.073099 -118.760304) (xy 165.023846 -118.719559) (xy 164.980089 -118.672962) (xy 164.942516 -118.621247)
			(xy 164.911722 -118.565232) (xy 164.88819 -118.505799) (xy 164.872293 -118.443885) (xy 164.864282 -118.380467)
			(xy 161.669854 -118.380467) (xy 161.639939 -118.394544) (xy 161.579146 -118.414297) (xy 161.516356 -118.426275)
			(xy 161.45256 -118.430289) (xy 161.388764 -118.426275) (xy 161.325974 -118.414297) (xy 161.265181 -118.394544)
			(xy 161.207342 -118.367327) (xy 161.153371 -118.333076) (xy 161.104118 -118.292331) (xy 161.060361 -118.245734)
			(xy 161.022788 -118.194019) (xy 160.991994 -118.138004) (xy 160.968462 -118.078571) (xy 160.952565 -118.016657)
			(xy 160.944554 -117.953239) (xy 158.303577 -117.953239) (xy 158.306819 -117.958648) (xy 158.327101 -118.00597)
			(xy 158.340828 -118.055591) (xy 158.347752 -118.106609) (xy 158.348172 -118.132352) (xy 158.347686 -118.159603)
			(xy 158.33993 -118.213551) (xy 158.324575 -118.265846) (xy 158.301933 -118.315423) (xy 158.272467 -118.361273)
			(xy 158.236776 -118.402464) (xy 158.195585 -118.438155) (xy 158.149735 -118.467621) (xy 158.100158 -118.490263)
			(xy 158.047863 -118.505618) (xy 157.993915 -118.513374) (xy 157.939413 -118.513374) (xy 157.885465 -118.505618)
			(xy 157.83317 -118.490263) (xy 157.783593 -118.467621) (xy 157.737743 -118.438155) (xy 157.696552 -118.402464)
			(xy 157.660861 -118.361273) (xy 157.631395 -118.315423) (xy 157.608753 -118.265846) (xy 157.593398 -118.213551)
			(xy 157.585642 -118.159603) (xy 157.585156 -118.132352) (xy 151.033806 -118.132352) (xy 150.999172 -118.136163)
			(xy 150.943438 -118.134126) (xy 150.888595 -118.123996) (xy 150.835811 -118.105989) (xy 150.786211 -118.080488)
			(xy 150.740853 -118.048037) (xy 150.700704 -118.009328) (xy 150.666618 -117.965185) (xy 150.639322 -117.91655)
			(xy 150.619399 -117.864459) (xy 150.607273 -117.810022) (xy 150.603202 -117.7544) (xy 150.169128 -117.7544)
			(xy 150.16455 -117.762727) (xy 150.126977 -117.814442) (xy 150.08322 -117.861039) (xy 150.033967 -117.901784)
			(xy 149.979996 -117.936035) (xy 149.922157 -117.963252) (xy 149.861364 -117.983005) (xy 149.798574 -117.994983)
			(xy 149.734778 -117.998997) (xy 149.670982 -117.994983) (xy 149.608192 -117.983005) (xy 149.547399 -117.963252)
			(xy 149.48956 -117.936035) (xy 149.435589 -117.901784) (xy 149.386336 -117.861039) (xy 149.342579 -117.814442)
			(xy 149.305006 -117.762727) (xy 149.274212 -117.706712) (xy 149.25068 -117.647279) (xy 149.234783 -117.585365)
			(xy 149.226772 -117.521947) (xy 144.999768 -117.521947) (xy 144.976995 -117.570526) (xy 144.946222 -117.617039)
			(xy 144.909005 -117.658576) (xy 144.866137 -117.694251) (xy 144.818531 -117.723305) (xy 144.767202 -117.745117)
			(xy 144.713245 -117.759223) (xy 144.657808 -117.765323) (xy 144.602074 -117.763286) (xy 144.547231 -117.753156)
			(xy 144.494447 -117.735149) (xy 144.444847 -117.709648) (xy 144.399489 -117.677197) (xy 144.35934 -117.638488)
			(xy 144.325254 -117.594345) (xy 144.297958 -117.54571) (xy 144.278035 -117.493619) (xy 144.265909 -117.439182)
			(xy 144.261838 -117.38356) (xy 138.209801 -117.38356) (xy 138.232071 -117.393731) (xy 138.277921 -117.423197)
			(xy 138.319112 -117.458888) (xy 138.354803 -117.500079) (xy 138.384269 -117.545929) (xy 138.406911 -117.595506)
			(xy 138.422266 -117.647801) (xy 138.430022 -117.701749) (xy 138.430022 -117.756251) (xy 138.422266 -117.810199)
			(xy 138.406911 -117.862494) (xy 138.384269 -117.912071) (xy 138.354803 -117.957921) (xy 138.319112 -117.999112)
			(xy 138.277921 -118.034803) (xy 138.232071 -118.064269) (xy 138.182494 -118.086911) (xy 138.130199 -118.102266)
			(xy 138.076251 -118.110022) (xy 138.049 -118.110508) (xy 138.020296 -118.109993) (xy 137.963541 -118.101348)
			(xy 137.908718 -118.084313) (xy 137.857058 -118.05927) (xy 137.8331 -118.043452) (xy 137.825245 -118.038547)
			(xy 137.807281 -118.034112) (xy 137.798048 -118.034816) (xy 137.730992 -118.043452) (xy 137.721908 -118.044995)
			(xy 137.705623 -118.053572) (xy 137.699242 -118.060216) (xy 137.698988 -118.06047) (xy 137.678276 -118.083457)
			(xy 137.632161 -118.124716) (xy 137.58138 -118.160073) (xy 137.526683 -118.189006) (xy 137.46888 -118.211088)
			(xy 137.408824 -118.225991) (xy 137.347403 -118.233496) (xy 137.316464 -118.233952) (xy 137.284507 -118.23336)
			(xy 137.221098 -118.225345) (xy 137.159193 -118.209447) (xy 137.099769 -118.185916) (xy 137.043763 -118.155122)
			(xy 136.992057 -118.117553) (xy 136.945468 -118.073799) (xy 136.904729 -118.024551) (xy 136.870484 -117.970586)
			(xy 136.843272 -117.912755) (xy 136.823522 -117.851969) (xy 136.811546 -117.789188) (xy 136.807533 -117.7254)
			(xy 7.94618 -117.7254) (xy 7.186465 -118.485115) (xy 96.56673 -118.485115) (xy 96.56673 -118.421193)
			(xy 96.574741 -118.357775) (xy 96.590638 -118.295861) (xy 96.61417 -118.236428) (xy 96.644964 -118.180413)
			(xy 96.682537 -118.128698) (xy 96.726294 -118.082101) (xy 96.775547 -118.041356) (xy 96.829518 -118.007105)
			(xy 96.887357 -117.979888) (xy 96.94815 -117.960135) (xy 97.01094 -117.948157) (xy 97.074736 -117.944144)
			(xy 97.138532 -117.948157) (xy 97.201322 -117.960135) (xy 97.262115 -117.979888) (xy 97.319954 -118.007105)
			(xy 97.373925 -118.041356) (xy 97.423178 -118.082101) (xy 97.466935 -118.128698) (xy 97.504508 -118.180413)
			(xy 97.535302 -118.236428) (xy 97.558834 -118.295861) (xy 97.574731 -118.357775) (xy 97.575517 -118.364)
			(xy 146.379436 -118.364) (xy 146.383507 -118.308378) (xy 146.395633 -118.253941) (xy 146.415556 -118.20185)
			(xy 146.442852 -118.153215) (xy 146.476938 -118.109072) (xy 146.517087 -118.070363) (xy 146.562445 -118.037912)
			(xy 146.612045 -118.012411) (xy 146.664829 -117.994404) (xy 146.719672 -117.984274) (xy 146.775406 -117.982237)
			(xy 146.830843 -117.988337) (xy 146.8848 -118.002443) (xy 146.936129 -118.024255) (xy 146.983735 -118.053309)
			(xy 146.999003 -118.066015) (xy 147.419054 -118.066015) (xy 147.419054 -118.002093) (xy 147.427065 -117.938675)
			(xy 147.442962 -117.876761) (xy 147.466494 -117.817328) (xy 147.497288 -117.761313) (xy 147.534861 -117.709598)
			(xy 147.578618 -117.663001) (xy 147.627871 -117.622256) (xy 147.681842 -117.588005) (xy 147.739681 -117.560788)
			(xy 147.800474 -117.541035) (xy 147.863264 -117.529057) (xy 147.92706 -117.525044) (xy 147.990856 -117.529057)
			(xy 148.053646 -117.541035) (xy 148.114439 -117.560788) (xy 148.172278 -117.588005) (xy 148.226249 -117.622256)
			(xy 148.275502 -117.663001) (xy 148.319259 -117.709598) (xy 148.356832 -117.761313) (xy 148.387626 -117.817328)
			(xy 148.411158 -117.876761) (xy 148.427055 -117.938675) (xy 148.435066 -118.002093) (xy 148.435568 -118.034054)
			(xy 148.435066 -118.066015) (xy 148.427055 -118.129433) (xy 148.411158 -118.191347) (xy 148.387626 -118.25078)
			(xy 148.356832 -118.306795) (xy 148.319259 -118.35851) (xy 148.275502 -118.405107) (xy 148.226249 -118.445852)
			(xy 148.172278 -118.480103) (xy 148.114439 -118.50732) (xy 148.053646 -118.527073) (xy 147.990856 -118.539051)
			(xy 147.92706 -118.543065) (xy 147.863264 -118.539051) (xy 147.800474 -118.527073) (xy 147.739681 -118.50732)
			(xy 147.681842 -118.480103) (xy 147.627871 -118.445852) (xy 147.578618 -118.405107) (xy 147.534861 -118.35851)
			(xy 147.497288 -118.306795) (xy 147.466494 -118.25078) (xy 147.442962 -118.191347) (xy 147.427065 -118.129433)
			(xy 147.419054 -118.066015) (xy 146.999003 -118.066015) (xy 147.026603 -118.088984) (xy 147.06382 -118.130521)
			(xy 147.094593 -118.177034) (xy 147.118265 -118.227531) (xy 147.134333 -118.280938) (xy 147.142453 -118.336114)
			(xy 147.142962 -118.364) (xy 147.142453 -118.391886) (xy 147.134333 -118.447062) (xy 147.118265 -118.500469)
			(xy 147.094593 -118.550966) (xy 147.06382 -118.597479) (xy 147.026603 -118.639016) (xy 146.983735 -118.674691)
			(xy 146.936129 -118.703745) (xy 146.8848 -118.725557) (xy 146.830843 -118.739663) (xy 146.775406 -118.745763)
			(xy 146.719672 -118.743726) (xy 146.664829 -118.733596) (xy 146.612045 -118.715589) (xy 146.562445 -118.690088)
			(xy 146.517087 -118.657637) (xy 146.476938 -118.618928) (xy 146.442852 -118.574785) (xy 146.415556 -118.52615)
			(xy 146.395633 -118.474059) (xy 146.383507 -118.419622) (xy 146.379436 -118.364) (xy 97.575517 -118.364)
			(xy 97.582742 -118.421193) (xy 97.583244 -118.453154) (xy 97.582742 -118.485115) (xy 97.574731 -118.548533)
			(xy 97.558834 -118.610447) (xy 97.535302 -118.66988) (xy 97.504508 -118.725895) (xy 97.466935 -118.77761)
			(xy 97.423178 -118.824207) (xy 97.373925 -118.864952) (xy 97.319954 -118.899203) (xy 97.262115 -118.92642)
			(xy 97.201322 -118.946173) (xy 97.138532 -118.958151) (xy 97.074736 -118.962165) (xy 97.01094 -118.958151)
			(xy 96.94815 -118.946173) (xy 96.887357 -118.92642) (xy 96.829518 -118.899203) (xy 96.775547 -118.864952)
			(xy 96.726294 -118.824207) (xy 96.682537 -118.77761) (xy 96.644964 -118.725895) (xy 96.61417 -118.66988)
			(xy 96.590638 -118.610447) (xy 96.574741 -118.548533) (xy 96.56673 -118.485115) (xy 7.186465 -118.485115)
			(xy 6.128512 -119.543068) (xy 6.125806 -119.545919) (xy 6.121211 -119.552296) (xy 6.119368 -119.555768)
			(xy 6.116789 -119.561196) (xy 6.113973 -119.572875) (xy 6.11378 -119.578882) (xy 6.11378 -119.89645)
			(xy 97.324682 -119.89645) (xy 97.324682 -119.84195) (xy 97.332437 -119.788006) (xy 97.347791 -119.735714)
			(xy 97.37043 -119.686139) (xy 97.399893 -119.64029) (xy 97.435581 -119.599101) (xy 97.476768 -119.56341)
			(xy 97.522614 -119.533943) (xy 97.572187 -119.511301) (xy 97.624478 -119.495943) (xy 97.678422 -119.488184)
			(xy 97.705672 -119.487696) (xy 97.738872 -119.488407) (xy 97.804267 -119.499905) (xy 97.83572 -119.510556)
			(xy 97.846134 -119.514366) (xy 97.868232 -119.512334) (xy 97.945194 -119.468646) (xy 97.954501 -119.462788)
			(xy 97.967414 -119.445022) (xy 97.970086 -119.434356) (xy 97.970086 -119.433848) (xy 97.975453 -119.408037)
			(xy 97.992419 -119.358122) (xy 98.016096 -119.311019) (xy 98.046034 -119.267625) (xy 98.081662 -119.228766)
			(xy 98.122301 -119.195184) (xy 98.167178 -119.167518) (xy 98.215437 -119.146295) (xy 98.266158 -119.131919)
			(xy 98.318376 -119.124664) (xy 98.344736 -119.124222) (xy 98.371988 -119.12465) (xy 98.425936 -119.132412)
			(xy 98.47823 -119.147771) (xy 98.487749 -119.152119) (xy 107.748826 -119.152119) (xy 107.748826 -119.088197)
			(xy 107.756837 -119.024779) (xy 107.772734 -118.962865) (xy 107.796266 -118.903432) (xy 107.82706 -118.847417)
			(xy 107.864633 -118.795702) (xy 107.90839 -118.749105) (xy 107.957643 -118.70836) (xy 108.011614 -118.674109)
			(xy 108.069453 -118.646892) (xy 108.130246 -118.627139) (xy 108.193036 -118.615161) (xy 108.256832 -118.611148)
			(xy 108.320628 -118.615161) (xy 108.383418 -118.627139) (xy 108.444211 -118.646892) (xy 108.50205 -118.674109)
			(xy 108.556021 -118.70836) (xy 108.605274 -118.749105) (xy 108.649031 -118.795702) (xy 108.686604 -118.847417)
			(xy 108.717398 -118.903432) (xy 108.74093 -118.962865) (xy 108.756827 -119.024779) (xy 108.764838 -119.088197)
			(xy 108.76534 -119.120158) (xy 108.764838 -119.152119) (xy 108.756827 -119.215537) (xy 108.74093 -119.277451)
			(xy 108.717398 -119.336884) (xy 108.686604 -119.392899) (xy 108.649031 -119.444614) (xy 108.605274 -119.491211)
			(xy 108.556021 -119.531956) (xy 108.50205 -119.566207) (xy 108.444211 -119.593424) (xy 108.383418 -119.613177)
			(xy 108.320628 -119.625155) (xy 108.256832 -119.629169) (xy 108.193036 -119.625155) (xy 108.130246 -119.613177)
			(xy 108.069453 -119.593424) (xy 108.011614 -119.566207) (xy 107.957643 -119.531956) (xy 107.90839 -119.491211)
			(xy 107.864633 -119.444614) (xy 107.82706 -119.392899) (xy 107.796266 -119.336884) (xy 107.772734 -119.277451)
			(xy 107.756837 -119.215537) (xy 107.748826 -119.152119) (xy 98.487749 -119.152119) (xy 98.527807 -119.170416)
			(xy 98.573656 -119.199886) (xy 98.614846 -119.23558) (xy 98.650536 -119.276772) (xy 98.680001 -119.322625)
			(xy 98.702642 -119.372203) (xy 98.717996 -119.424499) (xy 98.725752 -119.478448) (xy 98.725752 -119.532952)
			(xy 98.717996 -119.586901) (xy 98.702642 -119.639197) (xy 98.680001 -119.688775) (xy 98.650536 -119.734628)
			(xy 98.614846 -119.77582) (xy 98.573656 -119.811514) (xy 98.527807 -119.840984) (xy 98.47823 -119.863629)
			(xy 98.425936 -119.878988) (xy 98.371988 -119.88675) (xy 98.344736 -119.887238) (xy 98.311536 -119.886529)
			(xy 98.24614 -119.87503) (xy 98.214688 -119.864378) (xy 98.204274 -119.860568) (xy 98.182176 -119.8626)
			(xy 98.105214 -119.906288) (xy 98.095897 -119.912133) (xy 98.095746 -119.912341) (xy 109.544352 -119.912341)
			(xy 109.544352 -119.848419) (xy 109.552363 -119.785001) (xy 109.56826 -119.723087) (xy 109.591792 -119.663654)
			(xy 109.622586 -119.607639) (xy 109.660159 -119.555924) (xy 109.703916 -119.509327) (xy 109.753169 -119.468582)
			(xy 109.80714 -119.434331) (xy 109.864979 -119.407114) (xy 109.925772 -119.387361) (xy 109.988562 -119.375383)
			(xy 110.052358 -119.37137) (xy 110.116154 -119.375383) (xy 110.178944 -119.387361) (xy 110.239737 -119.407114)
			(xy 110.297576 -119.434331) (xy 110.351547 -119.468582) (xy 110.4008 -119.509327) (xy 110.444557 -119.555924)
			(xy 110.48213 -119.607639) (xy 110.512924 -119.663654) (xy 110.536456 -119.723087) (xy 110.552353 -119.785001)
			(xy 110.560364 -119.848419) (xy 110.560866 -119.88038) (xy 110.560364 -119.912341) (xy 110.552353 -119.975759)
			(xy 110.536456 -120.037673) (xy 110.512924 -120.097106) (xy 110.48213 -120.153121) (xy 110.444557 -120.204836)
			(xy 110.4008 -120.251433) (xy 110.351547 -120.292178) (xy 110.297576 -120.326429) (xy 110.239737 -120.353646)
			(xy 110.178944 -120.373399) (xy 110.116154 -120.385377) (xy 110.052358 -120.389391) (xy 109.988562 -120.385377)
			(xy 109.925772 -120.373399) (xy 109.864979 -120.353646) (xy 109.80714 -120.326429) (xy 109.753169 -120.292178)
			(xy 109.703916 -120.251433) (xy 109.660159 -120.204836) (xy 109.622586 -120.153121) (xy 109.591792 -120.097106)
			(xy 109.56826 -120.037673) (xy 109.552363 -119.975759) (xy 109.544352 -119.912341) (xy 98.095746 -119.912341)
			(xy 98.082989 -119.929909) (xy 98.080322 -119.940578) (xy 98.080322 -119.941086) (xy 98.074899 -119.966884)
			(xy 98.057942 -120.016799) (xy 98.034273 -120.063903) (xy 98.004343 -120.107298) (xy 97.968721 -120.146158)
			(xy 97.928088 -120.179742) (xy 97.883216 -120.20741) (xy 97.834962 -120.228635) (xy 97.784244 -120.243013)
			(xy 97.73203 -120.250269) (xy 97.705672 -120.250712) (xy 97.678422 -120.250216) (xy 97.624478 -120.242457)
			(xy 97.572187 -120.227099) (xy 97.522614 -120.204457) (xy 97.476768 -120.17499) (xy 97.435581 -120.139299)
			(xy 97.399893 -120.09811) (xy 97.37043 -120.052261) (xy 97.347791 -120.002686) (xy 97.332437 -119.950394)
			(xy 97.324682 -119.89645) (xy 6.11378 -119.89645) (xy 6.11378 -120.862301) (xy 37.035734 -120.862301)
			(xy 37.035734 -120.798379) (xy 37.043745 -120.734961) (xy 37.059642 -120.673047) (xy 37.083174 -120.613614)
			(xy 37.113968 -120.557599) (xy 37.151541 -120.505884) (xy 37.195298 -120.459287) (xy 37.244551 -120.418542)
			(xy 37.298522 -120.384291) (xy 37.356361 -120.357074) (xy 37.417154 -120.337321) (xy 37.479944 -120.325343)
			(xy 37.54374 -120.32133) (xy 37.607536 -120.325343) (xy 37.670326 -120.337321) (xy 37.731119 -120.357074)
			(xy 37.788958 -120.384291) (xy 37.842929 -120.418542) (xy 37.892182 -120.459287) (xy 37.935939 -120.505884)
			(xy 37.973512 -120.557599) (xy 38.004306 -120.613614) (xy 38.021311 -120.656561) (xy 43.182534 -120.656561)
			(xy 43.182534 -120.592639) (xy 43.190545 -120.529221) (xy 43.206442 -120.467307) (xy 43.229974 -120.407874)
			(xy 43.260768 -120.351859) (xy 43.298341 -120.300144) (xy 43.342098 -120.253547) (xy 43.391351 -120.212802)
			(xy 43.445322 -120.178551) (xy 43.503161 -120.151334) (xy 43.563954 -120.131581) (xy 43.626744 -120.119603)
			(xy 43.69054 -120.11559) (xy 43.754336 -120.119603) (xy 43.817126 -120.131581) (xy 43.877919 -120.151334)
			(xy 43.935758 -120.178551) (xy 43.989729 -120.212802) (xy 44.038982 -120.253547) (xy 44.082739 -120.300144)
			(xy 44.120312 -120.351859) (xy 44.151106 -120.407874) (xy 44.174638 -120.467307) (xy 44.190535 -120.529221)
			(xy 44.198546 -120.592639) (xy 44.199048 -120.6246) (xy 44.198546 -120.656561) (xy 44.190535 -120.719979)
			(xy 44.174638 -120.781893) (xy 44.151106 -120.841326) (xy 44.120312 -120.897341) (xy 44.082739 -120.949056)
			(xy 44.07834 -120.953741) (xy 98.49713 -120.953741) (xy 98.49713 -120.889819) (xy 98.505141 -120.826401)
			(xy 98.521038 -120.764487) (xy 98.54457 -120.705054) (xy 98.575364 -120.649039) (xy 98.612937 -120.597324)
			(xy 98.656694 -120.550727) (xy 98.705947 -120.509982) (xy 98.759918 -120.475731) (xy 98.817757 -120.448514)
			(xy 98.87855 -120.428761) (xy 98.94134 -120.416783) (xy 99.005136 -120.41277) (xy 99.068932 -120.416783)
			(xy 99.131722 -120.428761) (xy 99.192515 -120.448514) (xy 99.250354 -120.475731) (xy 99.304325 -120.509982)
			(xy 99.353578 -120.550727) (xy 99.397335 -120.597324) (xy 99.434908 -120.649039) (xy 99.465702 -120.705054)
			(xy 99.489234 -120.764487) (xy 99.502349 -120.815565) (xy 110.293398 -120.815565) (xy 110.293398 -120.751643)
			(xy 110.301409 -120.688225) (xy 110.317306 -120.626311) (xy 110.340838 -120.566878) (xy 110.371632 -120.510863)
			(xy 110.409205 -120.459148) (xy 110.452962 -120.412551) (xy 110.502215 -120.371806) (xy 110.556186 -120.337555)
			(xy 110.614025 -120.310338) (xy 110.674818 -120.290585) (xy 110.737608 -120.278607) (xy 110.801404 -120.274594)
			(xy 110.8652 -120.278607) (xy 110.92799 -120.290585) (xy 110.988783 -120.310338) (xy 111.046622 -120.337555)
			(xy 111.100593 -120.371806) (xy 111.149846 -120.412551) (xy 111.193603 -120.459148) (xy 111.231176 -120.510863)
			(xy 111.24732 -120.540229) (xy 111.835432 -120.540229) (xy 111.835432 -120.476307) (xy 111.843443 -120.412889)
			(xy 111.85934 -120.350975) (xy 111.882872 -120.291542) (xy 111.913666 -120.235527) (xy 111.951239 -120.183812)
			(xy 111.994996 -120.137215) (xy 112.044249 -120.09647) (xy 112.09822 -120.062219) (xy 112.156059 -120.035002)
			(xy 112.216852 -120.015249) (xy 112.279642 -120.003271) (xy 112.343438 -119.999258) (xy 112.407234 -120.003271)
			(xy 112.470024 -120.015249) (xy 112.530817 -120.035002) (xy 112.588656 -120.062219) (xy 112.642627 -120.09647)
			(xy 112.69188 -120.137215) (xy 112.735637 -120.183812) (xy 112.77321 -120.235527) (xy 112.804004 -120.291542)
			(xy 112.827536 -120.350975) (xy 112.843433 -120.412889) (xy 112.845626 -120.430247) (xy 113.663978 -120.430247)
			(xy 113.663978 -120.366325) (xy 113.671989 -120.302907) (xy 113.687886 -120.240993) (xy 113.711418 -120.18156)
			(xy 113.742212 -120.125545) (xy 113.779785 -120.07383) (xy 113.823542 -120.027233) (xy 113.872795 -119.986488)
			(xy 113.926766 -119.952237) (xy 113.984605 -119.92502) (xy 114.045398 -119.905267) (xy 114.108188 -119.893289)
			(xy 114.171984 -119.889276) (xy 114.23578 -119.893289) (xy 114.29857 -119.905267) (xy 114.359363 -119.92502)
			(xy 114.417202 -119.952237) (xy 114.471173 -119.986488) (xy 114.520426 -120.027233) (xy 114.561229 -120.070684)
			(xy 138.619943 -120.070684) (xy 138.622554 -120.007662) (xy 138.63294 -119.945448) (xy 138.650942 -119.884996)
			(xy 138.676283 -119.827235) (xy 138.708573 -119.773051) (xy 138.747318 -119.723278) (xy 138.791922 -119.67868)
			(xy 138.841699 -119.639941) (xy 138.895886 -119.607656) (xy 138.95365 -119.582322) (xy 139.014104 -119.564327)
			(xy 139.07632 -119.553948) (xy 139.139342 -119.551345) (xy 139.202202 -119.556556) (xy 139.263934 -119.569503)
			(xy 139.323591 -119.589986) (xy 139.380257 -119.617691) (xy 139.43306 -119.652192) (xy 139.48119 -119.692959)
			(xy 139.523909 -119.739367) (xy 139.560559 -119.790702) (xy 139.590578 -119.846176) (xy 139.613504 -119.904937)
			(xy 139.62374 -119.945361) (xy 147.151084 -119.945361) (xy 147.151084 -119.881439) (xy 147.159095 -119.818021)
			(xy 147.174992 -119.756107) (xy 147.198524 -119.696674) (xy 147.229318 -119.640659) (xy 147.266891 -119.588944)
			(xy 147.310648 -119.542347) (xy 147.359901 -119.501602) (xy 147.413872 -119.467351) (xy 147.471711 -119.440134)
			(xy 147.532504 -119.420381) (xy 147.595294 -119.408403) (xy 147.65909 -119.40439) (xy 147.722886 -119.408403)
			(xy 147.785676 -119.420381) (xy 147.846469 -119.440134) (xy 147.884929 -119.458232) (xy 148.335492 -119.458232)
			(xy 148.335996 -119.415884) (xy 148.344047 -119.33157) (xy 148.360076 -119.248404) (xy 148.383937 -119.167137)
			(xy 148.415416 -119.088507) (xy 148.454227 -119.013226) (xy 148.500017 -118.941974) (xy 148.552373 -118.875398)
			(xy 148.610821 -118.8141) (xy 148.674831 -118.758635) (xy 148.743823 -118.709506) (xy 148.817173 -118.667157)
			(xy 148.894216 -118.631973) (xy 148.974255 -118.604271) (xy 149.056564 -118.584303) (xy 149.140399 -118.57225)
			(xy 149.225 -118.56822) (xy 149.309601 -118.57225) (xy 149.393436 -118.584303) (xy 149.475745 -118.604271)
			(xy 149.555784 -118.631973) (xy 149.632827 -118.667157) (xy 149.706177 -118.709506) (xy 149.775169 -118.758635)
			(xy 149.839179 -118.8141) (xy 149.897627 -118.875398) (xy 149.949983 -118.941974) (xy 149.995773 -119.013226)
			(xy 150.034584 -119.088507) (xy 150.066063 -119.167137) (xy 150.089924 -119.248404) (xy 150.105953 -119.33157)
			(xy 150.114004 -119.415884) (xy 150.114508 -119.458232) (xy 150.114006 -119.500235) (xy 150.106077 -119.583866)
			(xy 150.090301 -119.666378) (xy 150.06682 -119.747035) (xy 150.048309 -119.793696) (xy 159.888932 -119.793696)
			(xy 159.888932 -119.709) (xy 159.896983 -119.624686) (xy 159.913012 -119.54152) (xy 159.936873 -119.460253)
			(xy 159.968352 -119.381623) (xy 160.007163 -119.306342) (xy 160.052953 -119.23509) (xy 160.105309 -119.168514)
			(xy 160.163757 -119.107216) (xy 160.227767 -119.051751) (xy 160.296759 -119.002622) (xy 160.370109 -118.960273)
			(xy 160.447152 -118.925089) (xy 160.527191 -118.897387) (xy 160.6095 -118.877419) (xy 160.693335 -118.865366)
			(xy 160.777936 -118.861336) (xy 160.862537 -118.865366) (xy 160.946372 -118.877419) (xy 161.028681 -118.897387)
			(xy 161.10872 -118.925089) (xy 161.185763 -118.960273) (xy 161.259113 -119.002622) (xy 161.328105 -119.051751)
			(xy 161.392115 -119.107216) (xy 161.450563 -119.168514) (xy 161.502919 -119.23509) (xy 161.548709 -119.306342)
			(xy 161.58752 -119.381623) (xy 161.618999 -119.460253) (xy 161.64286 -119.54152) (xy 161.658889 -119.624686)
			(xy 161.66694 -119.709) (xy 161.667444 -119.751348) (xy 161.66694 -119.793696) (xy 161.658889 -119.87801)
			(xy 161.64286 -119.961176) (xy 161.618999 -120.042443) (xy 161.58752 -120.121073) (xy 161.548709 -120.196354)
			(xy 161.502919 -120.267606) (xy 161.450563 -120.334182) (xy 161.392115 -120.39548) (xy 161.388633 -120.398497)
			(xy 164.87495 -120.398497) (xy 164.87495 -120.334575) (xy 164.882961 -120.271157) (xy 164.898858 -120.209243)
			(xy 164.92239 -120.14981) (xy 164.953184 -120.093795) (xy 164.990757 -120.04208) (xy 165.034514 -119.995483)
			(xy 165.083767 -119.954738) (xy 165.137738 -119.920487) (xy 165.195577 -119.89327) (xy 165.25637 -119.873517)
			(xy 165.31916 -119.861539) (xy 165.382956 -119.857526) (xy 165.446752 -119.861539) (xy 165.509542 -119.873517)
			(xy 165.570335 -119.89327) (xy 165.628174 -119.920487) (xy 165.682145 -119.954738) (xy 165.731398 -119.995483)
			(xy 165.775155 -120.04208) (xy 165.812728 -120.093795) (xy 165.843522 -120.14981) (xy 165.867054 -120.209243)
			(xy 165.882951 -120.271157) (xy 165.890962 -120.334575) (xy 165.891464 -120.366536) (xy 165.890962 -120.398497)
			(xy 165.882951 -120.461915) (xy 165.867054 -120.523829) (xy 165.843522 -120.583262) (xy 165.812728 -120.639277)
			(xy 165.775155 -120.690992) (xy 165.731398 -120.737589) (xy 165.682145 -120.778334) (xy 165.628174 -120.812585)
			(xy 165.570335 -120.839802) (xy 165.509542 -120.859555) (xy 165.446752 -120.871533) (xy 165.382956 -120.875547)
			(xy 165.31916 -120.871533) (xy 165.25637 -120.859555) (xy 165.195577 -120.839802) (xy 165.137738 -120.812585)
			(xy 165.083767 -120.778334) (xy 165.034514 -120.737589) (xy 164.990757 -120.690992) (xy 164.953184 -120.639277)
			(xy 164.92239 -120.583262) (xy 164.898858 -120.523829) (xy 164.882961 -120.461915) (xy 164.87495 -120.398497)
			(xy 161.388633 -120.398497) (xy 161.328105 -120.450945) (xy 161.259113 -120.500074) (xy 161.185763 -120.542423)
			(xy 161.10872 -120.577607) (xy 161.028681 -120.605309) (xy 160.946372 -120.625277) (xy 160.862537 -120.63733)
			(xy 160.777936 -120.641361) (xy 160.693335 -120.63733) (xy 160.6095 -120.625277) (xy 160.527191 -120.605309)
			(xy 160.447152 -120.577607) (xy 160.370109 -120.542423) (xy 160.296759 -120.500074) (xy 160.227767 -120.450945)
			(xy 160.163757 -120.39548) (xy 160.105309 -120.334182) (xy 160.052953 -120.267606) (xy 160.007163 -120.196354)
			(xy 159.968352 -120.121073) (xy 159.936873 -120.042443) (xy 159.913012 -119.961176) (xy 159.896983 -119.87801)
			(xy 159.888932 -119.793696) (xy 150.048309 -119.793696) (xy 150.035842 -119.825121) (xy 149.997643 -119.89994)
			(xy 149.952563 -119.970826) (xy 149.901004 -120.037148) (xy 149.843423 -120.098316) (xy 149.780335 -120.153785)
			(xy 149.712299 -120.203062) (xy 149.676358 -120.224804) (xy 149.668299 -120.230099) (xy 149.656554 -120.245376)
			(xy 149.653498 -120.254522) (xy 149.644862 -120.283986) (xy 149.642697 -120.293022) (xy 149.644245 -120.311518)
			(xy 149.64791 -120.320054) (xy 149.659868 -120.346004) (xy 149.676729 -120.400596) (xy 149.68525 -120.457094)
			(xy 149.685756 -120.485662) (xy 149.68527 -120.512913) (xy 149.677514 -120.566861) (xy 149.666092 -120.605761)
			(xy 157.175194 -120.605761) (xy 157.175194 -120.541839) (xy 157.183205 -120.478421) (xy 157.199102 -120.416507)
			(xy 157.222634 -120.357074) (xy 157.253428 -120.301059) (xy 157.291001 -120.249344) (xy 157.334758 -120.202747)
			(xy 157.384011 -120.162002) (xy 157.437982 -120.127751) (xy 157.495821 -120.100534) (xy 157.556614 -120.080781)
			(xy 157.619404 -120.068803) (xy 157.6832 -120.06479) (xy 157.746996 -120.068803) (xy 157.809786 -120.080781)
			(xy 157.870579 -120.100534) (xy 157.928418 -120.127751) (xy 157.982389 -120.162002) (xy 158.031642 -120.202747)
			(xy 158.075399 -120.249344) (xy 158.112972 -120.301059) (xy 158.143766 -120.357074) (xy 158.167298 -120.416507)
			(xy 158.183195 -120.478421) (xy 158.191206 -120.541839) (xy 158.191708 -120.5738) (xy 158.191206 -120.605761)
			(xy 158.183195 -120.669179) (xy 158.167298 -120.731093) (xy 158.143766 -120.790526) (xy 158.112972 -120.846541)
			(xy 158.075399 -120.898256) (xy 158.031642 -120.944853) (xy 157.982389 -120.985598) (xy 157.928418 -121.019849)
			(xy 157.870579 -121.047066) (xy 157.809786 -121.066819) (xy 157.746996 -121.078797) (xy 157.6832 -121.082811)
			(xy 157.619404 -121.078797) (xy 157.556614 -121.066819) (xy 157.495821 -121.047066) (xy 157.437982 -121.019849)
			(xy 157.384011 -120.985598) (xy 157.334758 -120.944853) (xy 157.291001 -120.898256) (xy 157.253428 -120.846541)
			(xy 157.222634 -120.790526) (xy 157.199102 -120.731093) (xy 157.183205 -120.669179) (xy 157.175194 -120.605761)
			(xy 149.666092 -120.605761) (xy 149.662159 -120.619156) (xy 149.639517 -120.668733) (xy 149.610051 -120.714583)
			(xy 149.57436 -120.755774) (xy 149.533169 -120.791465) (xy 149.487319 -120.820931) (xy 149.437742 -120.843573)
			(xy 149.385447 -120.858928) (xy 149.331499 -120.866684) (xy 149.276997 -120.866684) (xy 149.223049 -120.858928)
			(xy 149.170754 -120.843573) (xy 149.121177 -120.820931) (xy 149.075327 -120.791465) (xy 149.034136 -120.755774)
			(xy 148.998445 -120.714583) (xy 148.968979 -120.668733) (xy 148.946337 -120.619156) (xy 148.930982 -120.566861)
			(xy 148.923226 -120.512913) (xy 148.92274 -120.485662) (xy 148.92274 -120.485408) (xy 148.923267 -120.457301)
			(xy 148.931553 -120.401701) (xy 148.93925 -120.374664) (xy 148.94153 -120.365672) (xy 148.940226 -120.347181)
			(xy 148.93671 -120.338596) (xy 148.923756 -120.31091) (xy 148.919286 -120.302287) (xy 148.905195 -120.288952)
			(xy 148.896324 -120.285002) (xy 148.858572 -120.269508) (xy 148.785829 -120.232512) (xy 148.716778 -120.189012)
			(xy 148.652 -120.139372) (xy 148.592039 -120.084009) (xy 148.5374 -120.023389) (xy 148.48854 -119.95802)
			(xy 148.445871 -119.888453) (xy 148.409751 -119.815271) (xy 148.380483 -119.739089) (xy 148.358314 -119.660547)
			(xy 148.343429 -119.580305) (xy 148.335953 -119.499037) (xy 148.335492 -119.458232) (xy 147.884929 -119.458232)
			(xy 147.904308 -119.467351) (xy 147.958279 -119.501602) (xy 148.007532 -119.542347) (xy 148.051289 -119.588944)
			(xy 148.088862 -119.640659) (xy 148.119656 -119.696674) (xy 148.143188 -119.756107) (xy 148.159085 -119.818021)
			(xy 148.167096 -119.881439) (xy 148.167598 -119.9134) (xy 148.167096 -119.945361) (xy 148.159085 -120.008779)
			(xy 148.143188 -120.070693) (xy 148.119656 -120.130126) (xy 148.088862 -120.186141) (xy 148.051289 -120.237856)
			(xy 148.007532 -120.284453) (xy 147.958279 -120.325198) (xy 147.904308 -120.359449) (xy 147.846469 -120.386666)
			(xy 147.785676 -120.406419) (xy 147.722886 -120.418397) (xy 147.65909 -120.422411) (xy 147.595294 -120.418397)
			(xy 147.532504 -120.406419) (xy 147.471711 -120.386666) (xy 147.413872 -120.359449) (xy 147.359901 -120.325198)
			(xy 147.310648 -120.284453) (xy 147.266891 -120.237856) (xy 147.229318 -120.186141) (xy 147.198524 -120.130126)
			(xy 147.174992 -120.070693) (xy 147.159095 -120.008779) (xy 147.151084 -119.945361) (xy 139.62374 -119.945361)
			(xy 139.628987 -119.966083) (xy 139.636787 -120.028674) (xy 139.637262 -120.060212) (xy 139.637262 -120.060974)
			(xy 139.637183 -120.072931) (xy 139.636042 -120.096817) (xy 139.634976 -120.108726) (xy 139.633706 -120.12168)
			(xy 139.643866 -120.145556) (xy 139.731242 -120.21439) (xy 139.756896 -120.218708) (xy 139.769088 -120.21439)
			(xy 139.795725 -120.205638) (xy 139.85043 -120.193341) (xy 139.906153 -120.187121) (xy 139.934188 -120.186704)
			(xy 139.93495 -120.186704) (xy 139.965683 -120.187109) (xy 140.026699 -120.194523) (xy 140.086377 -120.209238)
			(xy 140.143846 -120.231038) (xy 140.198268 -120.259607) (xy 140.248851 -120.294526) (xy 140.294856 -120.335288)
			(xy 140.335612 -120.381298) (xy 140.370525 -120.431885) (xy 140.399087 -120.486311) (xy 140.420881 -120.543783)
			(xy 140.435588 -120.603462) (xy 140.442995 -120.664479) (xy 140.443458 -120.695212) (xy 140.443394 -120.708061)
			(xy 140.442122 -120.733727) (xy 140.440918 -120.74652) (xy 140.440918 -120.746774) (xy 140.440342 -120.757526)
			(xy 140.447174 -120.777923) (xy 140.454126 -120.786144) (xy 140.5128 -120.849898) (xy 140.532866 -120.858534)
			(xy 140.543788 -120.85828) (xy 140.55344 -120.85828) (xy 140.584479 -120.858723) (xy 140.646097 -120.866262)
			(xy 140.706339 -120.881247) (xy 140.764308 -120.903455) (xy 140.819142 -120.932556) (xy 140.870025 -120.968116)
			(xy 140.9162 -121.009607) (xy 140.956979 -121.056412) (xy 140.991757 -121.107833) (xy 141.000631 -121.125191)
			(xy 147.603458 -121.125191) (xy 147.603458 -121.061269) (xy 147.611469 -120.997851) (xy 147.627366 -120.935937)
			(xy 147.650898 -120.876504) (xy 147.681692 -120.820489) (xy 147.719265 -120.768774) (xy 147.763022 -120.722177)
			(xy 147.812275 -120.681432) (xy 147.866246 -120.647181) (xy 147.924085 -120.619964) (xy 147.984878 -120.600211)
			(xy 148.047668 -120.588233) (xy 148.111464 -120.58422) (xy 148.17526 -120.588233) (xy 148.23805 -120.600211)
			(xy 148.298843 -120.619964) (xy 148.356682 -120.647181) (xy 148.410653 -120.681432) (xy 148.459906 -120.722177)
			(xy 148.503663 -120.768774) (xy 148.541236 -120.820489) (xy 148.57203 -120.876504) (xy 148.595562 -120.935937)
			(xy 148.611459 -120.997851) (xy 148.61947 -121.061269) (xy 148.619972 -121.09323) (xy 148.61947 -121.125191)
			(xy 148.611459 -121.188609) (xy 148.595562 -121.250523) (xy 148.57203 -121.309956) (xy 148.541236 -121.365971)
			(xy 148.503663 -121.417686) (xy 148.459906 -121.464283) (xy 148.410653 -121.505028) (xy 148.356682 -121.539279)
			(xy 148.298843 -121.566496) (xy 148.23805 -121.586249) (xy 148.17526 -121.598227) (xy 148.111464 -121.602241)
			(xy 148.047668 -121.598227) (xy 147.984878 -121.586249) (xy 147.924085 -121.566496) (xy 147.866246 -121.539279)
			(xy 147.812275 -121.505028) (xy 147.763022 -121.464283) (xy 147.719265 -121.417686) (xy 147.681692 -121.365971)
			(xy 147.650898 -121.309956) (xy 147.627366 -121.250523) (xy 147.611469 -121.188609) (xy 147.603458 -121.125191)
			(xy 141.000631 -121.125191) (xy 141.020015 -121.163106) (xy 141.041334 -121.221408) (xy 141.055395 -121.281872)
			(xy 141.059154 -121.312686) (xy 141.06017 -121.32183) (xy 141.068552 -121.33834) (xy 141.13256 -121.396506)
			(xy 141.149832 -121.403364) (xy 141.15923 -121.403364) (xy 141.192327 -121.404188) (xy 141.257894 -121.413377)
			(xy 141.321713 -121.430997) (xy 141.382707 -121.45675) (xy 141.439843 -121.4902) (xy 141.492154 -121.530781)
			(xy 141.538758 -121.577808) (xy 141.578864 -121.630485) (xy 141.591775 -121.653003) (xy 158.84245 -121.653003)
			(xy 158.84245 -121.589081) (xy 158.850461 -121.525663) (xy 158.866358 -121.463749) (xy 158.88989 -121.404316)
			(xy 158.920684 -121.348301) (xy 158.958257 -121.296586) (xy 159.002014 -121.249989) (xy 159.051267 -121.209244)
			(xy 159.105238 -121.174993) (xy 159.163077 -121.147776) (xy 159.22387 -121.128023) (xy 159.28666 -121.116045)
			(xy 159.350456 -121.112032) (xy 159.414252 -121.116045) (xy 159.477042 -121.128023) (xy 159.537835 -121.147776)
			(xy 159.595674 -121.174993) (xy 159.649645 -121.209244) (xy 159.698898 -121.249989) (xy 159.742655 -121.296586)
			(xy 159.780228 -121.348301) (xy 159.811022 -121.404316) (xy 159.834554 -121.463749) (xy 159.841419 -121.490486)
			(xy 160.398966 -121.490486) (xy 160.403037 -121.434864) (xy 160.415163 -121.380427) (xy 160.435086 -121.328336)
			(xy 160.462382 -121.279701) (xy 160.496468 -121.235558) (xy 160.536617 -121.196849) (xy 160.581975 -121.164398)
			(xy 160.631575 -121.138897) (xy 160.684359 -121.12089) (xy 160.739202 -121.11076) (xy 160.794936 -121.108723)
			(xy 160.850373 -121.114823) (xy 160.90433 -121.128929) (xy 160.955659 -121.150741) (xy 161.003265 -121.179795)
			(xy 161.046133 -121.21547) (xy 161.08335 -121.257007) (xy 161.114123 -121.30352) (xy 161.137795 -121.354017)
			(xy 161.153863 -121.407424) (xy 161.161983 -121.4626) (xy 161.162492 -121.490486) (xy 161.161983 -121.518372)
			(xy 161.153863 -121.573548) (xy 161.137795 -121.626955) (xy 161.114123 -121.677452) (xy 161.08335 -121.723965)
			(xy 161.078795 -121.729049) (xy 164.787092 -121.729049) (xy 164.787092 -121.674551) (xy 164.794848 -121.620608)
			(xy 164.810201 -121.568317) (xy 164.832839 -121.518744) (xy 164.862302 -121.472896) (xy 164.897989 -121.431709)
			(xy 164.939174 -121.396018) (xy 164.985019 -121.366552) (xy 165.034591 -121.343911) (xy 165.08688 -121.328554)
			(xy 165.140823 -121.320794) (xy 165.168072 -121.320306) (xy 165.198174 -121.320878) (xy 165.257631 -121.330336)
			(xy 165.314868 -121.349005) (xy 165.368467 -121.376424) (xy 165.393116 -121.393712) (xy 165.401244 -121.399808)
			(xy 165.42004 -121.404634) (xy 165.509448 -121.392442) (xy 165.526212 -121.383044) (xy 165.532562 -121.37517)
			(xy 165.55333 -121.350103) (xy 165.600158 -121.304884) (xy 165.652373 -121.266011) (xy 165.709123 -121.234121)
			(xy 165.769478 -121.209734) (xy 165.832453 -121.193249) (xy 165.897016 -121.184937) (xy 165.929564 -121.184416)
			(xy 165.960296 -121.184872) (xy 166.021313 -121.192276) (xy 166.080992 -121.206983) (xy 166.138464 -121.228776)
			(xy 166.192889 -121.257338) (xy 166.243474 -121.292252) (xy 166.289481 -121.33301) (xy 166.33024 -121.379017)
			(xy 166.365156 -121.429601) (xy 166.393719 -121.484026) (xy 166.415514 -121.541496) (xy 166.430221 -121.601175)
			(xy 166.437628 -121.662192) (xy 166.438072 -121.692924) (xy 166.437538 -121.726314) (xy 166.428787 -121.792517)
			(xy 166.411451 -121.857007) (xy 166.385829 -121.918676) (xy 166.352361 -121.976463) (xy 166.311622 -122.029376)
			(xy 166.264312 -122.076506) (xy 166.211244 -122.117042) (xy 166.182548 -122.134122) (xy 166.173658 -122.139202)
			(xy 166.161466 -122.155204) (xy 166.137336 -122.244358) (xy 166.139876 -122.263916) (xy 166.144956 -122.27306)
			(xy 166.161105 -122.30214) (xy 166.186543 -122.363603) (xy 166.203761 -122.427855) (xy 166.212466 -122.493801)
			(xy 166.213028 -122.52706) (xy 166.212526 -122.559021) (xy 166.204515 -122.622439) (xy 166.188618 -122.684353)
			(xy 166.165086 -122.743786) (xy 166.134292 -122.799801) (xy 166.096719 -122.851516) (xy 166.052962 -122.898113)
			(xy 166.003709 -122.938858) (xy 165.949738 -122.973109) (xy 165.891899 -123.000326) (xy 165.831106 -123.020079)
			(xy 165.768316 -123.032057) (xy 165.70452 -123.036071) (xy 165.640724 -123.032057) (xy 165.577934 -123.020079)
			(xy 165.517141 -123.000326) (xy 165.459302 -122.973109) (xy 165.405331 -122.938858) (xy 165.356078 -122.898113)
			(xy 165.312321 -122.851516) (xy 165.274748 -122.799801) (xy 165.243954 -122.743786) (xy 165.220422 -122.684353)
			(xy 165.204525 -122.622439) (xy 165.196514 -122.559021) (xy 165.196012 -122.52706) (xy 165.196487 -122.496675)
			(xy 165.20376 -122.436341) (xy 165.21816 -122.377302) (xy 165.239485 -122.320395) (xy 165.26743 -122.266431)
			(xy 165.28415 -122.241056) (xy 165.284404 -122.240802) (xy 165.289371 -122.232744) (xy 165.293481 -122.214279)
			(xy 165.290593 -122.195584) (xy 165.286182 -122.187208) (xy 165.233604 -122.09526) (xy 165.207696 -122.081544)
			(xy 165.193472 -122.08256) (xy 165.168072 -122.083322) (xy 165.140823 -122.082806) (xy 165.08688 -122.075046)
			(xy 165.034591 -122.059689) (xy 164.985019 -122.037048) (xy 164.939174 -122.007582) (xy 164.897989 -121.971891)
			(xy 164.862302 -121.930704) (xy 164.832839 -121.884856) (xy 164.810201 -121.835283) (xy 164.794848 -121.782992)
			(xy 164.787092 -121.729049) (xy 161.078795 -121.729049) (xy 161.046133 -121.765502) (xy 161.003265 -121.801177)
			(xy 160.955659 -121.830231) (xy 160.90433 -121.852043) (xy 160.850373 -121.866149) (xy 160.794936 -121.872249)
			(xy 160.739202 -121.870212) (xy 160.684359 -121.860082) (xy 160.631575 -121.842075) (xy 160.581975 -121.816574)
			(xy 160.536617 -121.784123) (xy 160.496468 -121.745414) (xy 160.462382 -121.701271) (xy 160.435086 -121.652636)
			(xy 160.415163 -121.600545) (xy 160.403037 -121.546108) (xy 160.398966 -121.490486) (xy 159.841419 -121.490486)
			(xy 159.850451 -121.525663) (xy 159.858462 -121.589081) (xy 159.858964 -121.621042) (xy 159.858462 -121.653003)
			(xy 159.850451 -121.716421) (xy 159.834554 -121.778335) (xy 159.811022 -121.837768) (xy 159.780228 -121.893783)
			(xy 159.742655 -121.945498) (xy 159.698898 -121.992095) (xy 159.649645 -122.03284) (xy 159.595674 -122.067091)
			(xy 159.537835 -122.094308) (xy 159.477042 -122.114061) (xy 159.414252 -122.126039) (xy 159.350456 -122.130053)
			(xy 159.28666 -122.126039) (xy 159.22387 -122.114061) (xy 159.163077 -122.094308) (xy 159.105238 -122.067091)
			(xy 159.051267 -122.03284) (xy 159.002014 -121.992095) (xy 158.958257 -121.945498) (xy 158.920684 -121.893783)
			(xy 158.88989 -121.837768) (xy 158.866358 -121.778335) (xy 158.850461 -121.716421) (xy 158.84245 -121.653003)
			(xy 141.591775 -121.653003) (xy 141.611796 -121.687921) (xy 141.636995 -121.749145) (xy 141.654037 -121.813122)
			(xy 141.662632 -121.878768) (xy 141.663166 -121.911872) (xy 141.662736 -121.942605) (xy 141.65533 -122.003624)
			(xy 141.640622 -122.063304) (xy 141.618827 -122.120777) (xy 141.590263 -122.175203) (xy 141.555346 -122.225788)
			(xy 141.514586 -122.271796) (xy 141.468577 -122.312555) (xy 141.417991 -122.34747) (xy 141.363564 -122.376033)
			(xy 141.306091 -122.397826) (xy 141.24641 -122.412532) (xy 141.185391 -122.419937) (xy 141.154658 -122.42038)
			(xy 141.123618 -122.419974) (xy 141.061997 -122.412434) (xy 141.001752 -122.397448) (xy 140.943781 -122.375237)
			(xy 140.888945 -122.346134) (xy 140.838061 -122.31057) (xy 140.791886 -122.269075) (xy 140.751107 -122.222266)
			(xy 140.71633 -122.170841) (xy 140.688074 -122.115564) (xy 140.666759 -122.057257) (xy 140.652701 -121.99679)
			(xy 140.648944 -121.965974) (xy 140.647928 -121.95683) (xy 140.639546 -121.94032) (xy 140.575538 -121.882154)
			(xy 140.558266 -121.875296) (xy 140.548868 -121.875296) (xy 140.515768 -121.874513) (xy 140.450199 -121.865323)
			(xy 140.386376 -121.847701) (xy 140.32538 -121.821946) (xy 140.268243 -121.788493) (xy 140.21593 -121.747907)
			(xy 140.169326 -121.700876) (xy 140.12922 -121.648194) (xy 140.09629 -121.590754) (xy 140.071092 -121.529525)
			(xy 140.054054 -121.465544) (xy 140.045463 -121.399893) (xy 140.044932 -121.366788) (xy 140.044996 -121.353939)
			(xy 140.046268 -121.328273) (xy 140.047472 -121.31548) (xy 140.047472 -121.315226) (xy 140.048051 -121.304474)
			(xy 140.041217 -121.284077) (xy 140.034264 -121.275856) (xy 139.97559 -121.212102) (xy 139.955524 -121.203466)
			(xy 139.944602 -121.20372) (xy 139.93495 -121.20372) (xy 139.904218 -121.203291) (xy 139.843204 -121.195877)
			(xy 139.783528 -121.181164) (xy 139.72606 -121.159364) (xy 139.671639 -121.130798) (xy 139.621057 -121.09588)
			(xy 139.575053 -121.05512) (xy 139.534297 -121.009113) (xy 139.499383 -120.958529) (xy 139.47082 -120.904105)
			(xy 139.449025 -120.846636) (xy 139.434316 -120.786959) (xy 139.426906 -120.725944) (xy 139.426442 -120.695212)
			(xy 139.426442 -120.69445) (xy 139.426515 -120.682493) (xy 139.42766 -120.658607) (xy 139.428728 -120.646698)
			(xy 139.429998 -120.633744) (xy 139.419838 -120.609868) (xy 139.332462 -120.541034) (xy 139.306808 -120.536716)
			(xy 139.294616 -120.541034) (xy 139.267978 -120.549782) (xy 139.213274 -120.562082) (xy 139.15755 -120.568303)
			(xy 139.129516 -120.56872) (xy 139.128754 -120.56872) (xy 139.097216 -120.568184) (xy 139.034626 -120.560376)
			(xy 138.973482 -120.544887) (xy 138.914723 -120.521953) (xy 138.859253 -120.491928) (xy 138.807922 -120.455272)
			(xy 138.761519 -120.412549) (xy 138.720757 -120.364413) (xy 138.686262 -120.311606) (xy 138.658564 -120.254938)
			(xy 138.638088 -120.195278) (xy 138.625148 -120.133544) (xy 138.619943 -120.070684) (xy 114.561229 -120.070684)
			(xy 114.564183 -120.07383) (xy 114.601756 -120.125545) (xy 114.63255 -120.18156) (xy 114.656082 -120.240993)
			(xy 114.671979 -120.302907) (xy 114.67999 -120.366325) (xy 114.680492 -120.398286) (xy 114.67999 -120.430247)
			(xy 114.671979 -120.493665) (xy 114.656082 -120.555579) (xy 114.63255 -120.615012) (xy 114.601756 -120.671027)
			(xy 114.564183 -120.722742) (xy 114.520426 -120.769339) (xy 114.471173 -120.810084) (xy 114.417202 -120.844335)
			(xy 114.359363 -120.871552) (xy 114.29857 -120.891305) (xy 114.23578 -120.903283) (xy 114.171984 -120.907297)
			(xy 114.108188 -120.903283) (xy 114.045398 -120.891305) (xy 113.984605 -120.871552) (xy 113.926766 -120.844335)
			(xy 113.872795 -120.810084) (xy 113.823542 -120.769339) (xy 113.779785 -120.722742) (xy 113.742212 -120.671027)
			(xy 113.711418 -120.615012) (xy 113.687886 -120.555579) (xy 113.671989 -120.493665) (xy 113.663978 -120.430247)
			(xy 112.845626 -120.430247) (xy 112.851444 -120.476307) (xy 112.851946 -120.508268) (xy 112.851444 -120.540229)
			(xy 112.843433 -120.603647) (xy 112.827536 -120.665561) (xy 112.804004 -120.724994) (xy 112.77321 -120.781009)
			(xy 112.735637 -120.832724) (xy 112.69188 -120.879321) (xy 112.642627 -120.920066) (xy 112.588656 -120.954317)
			(xy 112.530817 -120.981534) (xy 112.470024 -121.001287) (xy 112.407234 -121.013265) (xy 112.343438 -121.017279)
			(xy 112.279642 -121.013265) (xy 112.216852 -121.001287) (xy 112.156059 -120.981534) (xy 112.09822 -120.954317)
			(xy 112.044249 -120.920066) (xy 111.994996 -120.879321) (xy 111.951239 -120.832724) (xy 111.913666 -120.781009)
			(xy 111.882872 -120.724994) (xy 111.85934 -120.665561) (xy 111.843443 -120.603647) (xy 111.835432 -120.540229)
			(xy 111.24732 -120.540229) (xy 111.26197 -120.566878) (xy 111.285502 -120.626311) (xy 111.301399 -120.688225)
			(xy 111.30941 -120.751643) (xy 111.309912 -120.783604) (xy 111.30941 -120.815565) (xy 111.301399 -120.878983)
			(xy 111.285502 -120.940897) (xy 111.26197 -121.00033) (xy 111.231176 -121.056345) (xy 111.193603 -121.10806)
			(xy 111.149846 -121.154657) (xy 111.100593 -121.195402) (xy 111.046622 -121.229653) (xy 110.988783 -121.25687)
			(xy 110.92799 -121.276623) (xy 110.8652 -121.288601) (xy 110.801404 -121.292615) (xy 110.737608 -121.288601)
			(xy 110.674818 -121.276623) (xy 110.614025 -121.25687) (xy 110.556186 -121.229653) (xy 110.502215 -121.195402)
			(xy 110.452962 -121.154657) (xy 110.409205 -121.10806) (xy 110.371632 -121.056345) (xy 110.340838 -121.00033)
			(xy 110.317306 -120.940897) (xy 110.301409 -120.878983) (xy 110.293398 -120.815565) (xy 99.502349 -120.815565)
			(xy 99.505131 -120.826401) (xy 99.513142 -120.889819) (xy 99.513644 -120.92178) (xy 99.513142 -120.953741)
			(xy 99.505131 -121.017159) (xy 99.489234 -121.079073) (xy 99.465702 -121.138506) (xy 99.434908 -121.194521)
			(xy 99.397335 -121.246236) (xy 99.353578 -121.292833) (xy 99.304325 -121.333578) (xy 99.250354 -121.367829)
			(xy 99.192515 -121.395046) (xy 99.131722 -121.414799) (xy 99.068932 -121.426777) (xy 99.005136 -121.430791)
			(xy 98.94134 -121.426777) (xy 98.87855 -121.414799) (xy 98.817757 -121.395046) (xy 98.759918 -121.367829)
			(xy 98.705947 -121.333578) (xy 98.656694 -121.292833) (xy 98.612937 -121.246236) (xy 98.575364 -121.194521)
			(xy 98.54457 -121.138506) (xy 98.521038 -121.079073) (xy 98.505141 -121.017159) (xy 98.49713 -120.953741)
			(xy 44.07834 -120.953741) (xy 44.038982 -120.995653) (xy 43.989729 -121.036398) (xy 43.935758 -121.070649)
			(xy 43.877919 -121.097866) (xy 43.817126 -121.117619) (xy 43.754336 -121.129597) (xy 43.69054 -121.133611)
			(xy 43.626744 -121.129597) (xy 43.563954 -121.117619) (xy 43.503161 -121.097866) (xy 43.445322 -121.070649)
			(xy 43.391351 -121.036398) (xy 43.342098 -120.995653) (xy 43.298341 -120.949056) (xy 43.260768 -120.897341)
			(xy 43.229974 -120.841326) (xy 43.206442 -120.781893) (xy 43.190545 -120.719979) (xy 43.182534 -120.656561)
			(xy 38.021311 -120.656561) (xy 38.027838 -120.673047) (xy 38.043735 -120.734961) (xy 38.051746 -120.798379)
			(xy 38.052248 -120.83034) (xy 38.051746 -120.862301) (xy 38.043735 -120.925719) (xy 38.027838 -120.987633)
			(xy 38.004306 -121.047066) (xy 37.973512 -121.103081) (xy 37.935939 -121.154796) (xy 37.892182 -121.201393)
			(xy 37.842929 -121.242138) (xy 37.788958 -121.276389) (xy 37.731119 -121.303606) (xy 37.670326 -121.323359)
			(xy 37.607536 -121.335337) (xy 37.54374 -121.339351) (xy 37.479944 -121.335337) (xy 37.417154 -121.323359)
			(xy 37.356361 -121.303606) (xy 37.298522 -121.276389) (xy 37.244551 -121.242138) (xy 37.195298 -121.201393)
			(xy 37.151541 -121.154796) (xy 37.113968 -121.103081) (xy 37.083174 -121.047066) (xy 37.059642 -120.987633)
			(xy 37.043745 -120.925719) (xy 37.035734 -120.862301) (xy 6.11378 -120.862301) (xy 6.11378 -121.755365)
			(xy 95.751898 -121.755365) (xy 95.751898 -121.691443) (xy 95.759909 -121.628025) (xy 95.775806 -121.566111)
			(xy 95.799338 -121.506678) (xy 95.830132 -121.450663) (xy 95.867705 -121.398948) (xy 95.911462 -121.352351)
			(xy 95.960715 -121.311606) (xy 96.014686 -121.277355) (xy 96.072525 -121.250138) (xy 96.133318 -121.230385)
			(xy 96.196108 -121.218407) (xy 96.259904 -121.214394) (xy 96.3237 -121.218407) (xy 96.38649 -121.230385)
			(xy 96.447283 -121.250138) (xy 96.505122 -121.277355) (xy 96.559093 -121.311606) (xy 96.608346 -121.352351)
			(xy 96.652103 -121.398948) (xy 96.689676 -121.450663) (xy 96.72047 -121.506678) (xy 96.744002 -121.566111)
			(xy 96.759899 -121.628025) (xy 96.76791 -121.691443) (xy 96.767985 -121.696226) (xy 101.122732 -121.696226)
			(xy 101.126803 -121.640604) (xy 101.138929 -121.586167) (xy 101.158852 -121.534076) (xy 101.186148 -121.485441)
			(xy 101.220234 -121.441298) (xy 101.260383 -121.402589) (xy 101.305741 -121.370138) (xy 101.355341 -121.344637)
			(xy 101.408125 -121.32663) (xy 101.462968 -121.3165) (xy 101.518702 -121.314463) (xy 101.574139 -121.320563)
			(xy 101.628096 -121.334669) (xy 101.679425 -121.356481) (xy 101.727031 -121.385535) (xy 101.769899 -121.42121)
			(xy 101.807116 -121.462747) (xy 101.837889 -121.50926) (xy 101.861561 -121.559757) (xy 101.877629 -121.613164)
			(xy 101.885749 -121.66834) (xy 101.885901 -121.676668) (xy 104.627932 -121.676668) (xy 104.632003 -121.621046)
			(xy 104.644129 -121.566609) (xy 104.664052 -121.514518) (xy 104.691348 -121.465883) (xy 104.725434 -121.42174)
			(xy 104.765583 -121.383031) (xy 104.810941 -121.35058) (xy 104.860541 -121.325079) (xy 104.913325 -121.307072)
			(xy 104.968168 -121.296942) (xy 105.023902 -121.294905) (xy 105.079339 -121.301005) (xy 105.133296 -121.315111)
			(xy 105.184625 -121.336923) (xy 105.232231 -121.365977) (xy 105.275099 -121.401652) (xy 105.312316 -121.443189)
			(xy 105.343089 -121.489702) (xy 105.366761 -121.540199) (xy 105.382829 -121.593606) (xy 105.390949 -121.648782)
			(xy 105.391101 -121.65711) (xy 108.133132 -121.65711) (xy 108.137203 -121.601488) (xy 108.149329 -121.547051)
			(xy 108.169252 -121.49496) (xy 108.196548 -121.446325) (xy 108.230634 -121.402182) (xy 108.270783 -121.363473)
			(xy 108.316141 -121.331022) (xy 108.365741 -121.305521) (xy 108.418525 -121.287514) (xy 108.473368 -121.277384)
			(xy 108.529102 -121.275347) (xy 108.584539 -121.281447) (xy 108.638496 -121.295553) (xy 108.689825 -121.317365)
			(xy 108.737431 -121.346419) (xy 108.780299 -121.382094) (xy 108.817516 -121.423631) (xy 108.848289 -121.470144)
			(xy 108.871961 -121.520641) (xy 108.888029 -121.574048) (xy 108.896149 -121.629224) (xy 108.896658 -121.65711)
			(xy 108.896149 -121.684996) (xy 108.888029 -121.740172) (xy 108.871961 -121.793579) (xy 108.848289 -121.844076)
			(xy 108.817516 -121.890589) (xy 108.780299 -121.932126) (xy 108.737431 -121.967801) (xy 108.712194 -121.983203)
			(xy 112.914932 -121.983203) (xy 112.914932 -121.919281) (xy 112.922943 -121.855863) (xy 112.93884 -121.793949)
			(xy 112.962372 -121.734516) (xy 112.993166 -121.678501) (xy 113.030739 -121.626786) (xy 113.074496 -121.580189)
			(xy 113.123749 -121.539444) (xy 113.17772 -121.505193) (xy 113.235559 -121.477976) (xy 113.296352 -121.458223)
			(xy 113.359142 -121.446245) (xy 113.422938 -121.442232) (xy 113.486734 -121.446245) (xy 113.549524 -121.458223)
			(xy 113.610317 -121.477976) (xy 113.668156 -121.505193) (xy 113.722127 -121.539444) (xy 113.725837 -121.542513)
			(xy 114.62232 -121.542513) (xy 114.62232 -121.478591) (xy 114.630331 -121.415173) (xy 114.646228 -121.353259)
			(xy 114.66976 -121.293826) (xy 114.700554 -121.237811) (xy 114.738127 -121.186096) (xy 114.781884 -121.139499)
			(xy 114.831137 -121.098754) (xy 114.885108 -121.064503) (xy 114.942947 -121.037286) (xy 115.00374 -121.017533)
			(xy 115.06653 -121.005555) (xy 115.130326 -121.001542) (xy 115.194122 -121.005555) (xy 115.256912 -121.017533)
			(xy 115.317705 -121.037286) (xy 115.375544 -121.064503) (xy 115.429515 -121.098754) (xy 115.478768 -121.139499)
			(xy 115.522525 -121.186096) (xy 115.560098 -121.237811) (xy 115.590892 -121.293826) (xy 115.614424 -121.353259)
			(xy 115.630321 -121.415173) (xy 115.638332 -121.478591) (xy 115.638834 -121.510552) (xy 115.638332 -121.542513)
			(xy 115.630321 -121.605931) (xy 115.614424 -121.667845) (xy 115.590892 -121.727278) (xy 115.560098 -121.783293)
			(xy 115.522525 -121.835008) (xy 115.478768 -121.881605) (xy 115.429515 -121.92235) (xy 115.375544 -121.956601)
			(xy 115.317705 -121.983818) (xy 115.256912 -122.003571) (xy 115.194122 -122.015549) (xy 115.130326 -122.019563)
			(xy 115.06653 -122.015549) (xy 115.00374 -122.003571) (xy 114.942947 -121.983818) (xy 114.885108 -121.956601)
			(xy 114.831137 -121.92235) (xy 114.781884 -121.881605) (xy 114.738127 -121.835008) (xy 114.700554 -121.783293)
			(xy 114.66976 -121.727278) (xy 114.646228 -121.667845) (xy 114.630331 -121.605931) (xy 114.62232 -121.542513)
			(xy 113.725837 -121.542513) (xy 113.77138 -121.580189) (xy 113.815137 -121.626786) (xy 113.85271 -121.678501)
			(xy 113.883504 -121.734516) (xy 113.907036 -121.793949) (xy 113.922933 -121.855863) (xy 113.930944 -121.919281)
			(xy 113.931446 -121.951242) (xy 113.930944 -121.983203) (xy 113.922933 -122.046621) (xy 113.907036 -122.108535)
			(xy 113.883504 -122.167968) (xy 113.85271 -122.223983) (xy 113.815137 -122.275698) (xy 113.77138 -122.322295)
			(xy 113.722127 -122.36304) (xy 113.668156 -122.397291) (xy 113.610317 -122.424508) (xy 113.549524 -122.444261)
			(xy 113.486734 -122.456239) (xy 113.422938 -122.460253) (xy 113.359142 -122.456239) (xy 113.296352 -122.444261)
			(xy 113.235559 -122.424508) (xy 113.17772 -122.397291) (xy 113.123749 -122.36304) (xy 113.074496 -122.322295)
			(xy 113.030739 -122.275698) (xy 112.993166 -122.223983) (xy 112.962372 -122.167968) (xy 112.93884 -122.108535)
			(xy 112.922943 -122.046621) (xy 112.914932 -121.983203) (xy 108.712194 -121.983203) (xy 108.689825 -121.996855)
			(xy 108.638496 -122.018667) (xy 108.584539 -122.032773) (xy 108.529102 -122.038873) (xy 108.473368 -122.036836)
			(xy 108.418525 -122.026706) (xy 108.365741 -122.008699) (xy 108.316141 -121.983198) (xy 108.270783 -121.950747)
			(xy 108.230634 -121.912038) (xy 108.196548 -121.867895) (xy 108.169252 -121.81926) (xy 108.149329 -121.767169)
			(xy 108.137203 -121.712732) (xy 108.133132 -121.65711) (xy 105.391101 -121.65711) (xy 105.391458 -121.676668)
			(xy 105.390949 -121.704554) (xy 105.382829 -121.75973) (xy 105.366761 -121.813137) (xy 105.343089 -121.863634)
			(xy 105.312316 -121.910147) (xy 105.275099 -121.951684) (xy 105.232231 -121.987359) (xy 105.184625 -122.016413)
			(xy 105.133296 -122.038225) (xy 105.079339 -122.052331) (xy 105.023902 -122.058431) (xy 104.968168 -122.056394)
			(xy 104.913325 -122.046264) (xy 104.860541 -122.028257) (xy 104.810941 -122.002756) (xy 104.765583 -121.970305)
			(xy 104.725434 -121.931596) (xy 104.691348 -121.887453) (xy 104.664052 -121.838818) (xy 104.644129 -121.786727)
			(xy 104.632003 -121.73229) (xy 104.627932 -121.676668) (xy 101.885901 -121.676668) (xy 101.886258 -121.696226)
			(xy 101.885749 -121.724112) (xy 101.877629 -121.779288) (xy 101.861561 -121.832695) (xy 101.837889 -121.883192)
			(xy 101.807116 -121.929705) (xy 101.769899 -121.971242) (xy 101.727031 -122.006917) (xy 101.679425 -122.035971)
			(xy 101.628096 -122.057783) (xy 101.574139 -122.071889) (xy 101.518702 -122.077989) (xy 101.462968 -122.075952)
			(xy 101.408125 -122.065822) (xy 101.355341 -122.047815) (xy 101.305741 -122.022314) (xy 101.260383 -121.989863)
			(xy 101.220234 -121.951154) (xy 101.186148 -121.907011) (xy 101.158852 -121.858376) (xy 101.138929 -121.806285)
			(xy 101.126803 -121.751848) (xy 101.122732 -121.696226) (xy 96.767985 -121.696226) (xy 96.768412 -121.723404)
			(xy 96.76791 -121.755365) (xy 96.759899 -121.818783) (xy 96.744002 -121.880697) (xy 96.72047 -121.94013)
			(xy 96.689676 -121.996145) (xy 96.652103 -122.04786) (xy 96.608346 -122.094457) (xy 96.559093 -122.135202)
			(xy 96.505122 -122.169453) (xy 96.447283 -122.19667) (xy 96.38649 -122.216423) (xy 96.3237 -122.228401)
			(xy 96.259904 -122.232415) (xy 96.196108 -122.228401) (xy 96.133318 -122.216423) (xy 96.072525 -122.19667)
			(xy 96.014686 -122.169453) (xy 95.960715 -122.135202) (xy 95.911462 -122.094457) (xy 95.867705 -122.04786)
			(xy 95.830132 -121.996145) (xy 95.799338 -121.94013) (xy 95.775806 -121.880697) (xy 95.759909 -121.818783)
			(xy 95.751898 -121.755365) (xy 6.11378 -121.755365) (xy 6.11378 -122.936) (xy 111.250982 -122.936)
			(xy 111.255053 -122.880378) (xy 111.267179 -122.825941) (xy 111.287102 -122.77385) (xy 111.314398 -122.725215)
			(xy 111.348484 -122.681072) (xy 111.388633 -122.642363) (xy 111.433991 -122.609912) (xy 111.483591 -122.584411)
			(xy 111.536375 -122.566404) (xy 111.591218 -122.556274) (xy 111.646952 -122.554237) (xy 111.702389 -122.560337)
			(xy 111.756346 -122.574443) (xy 111.807675 -122.596255) (xy 111.855281 -122.625309) (xy 111.898149 -122.660984)
			(xy 111.935366 -122.702521) (xy 111.966139 -122.749034) (xy 111.989811 -122.799531) (xy 112.005879 -122.852938)
			(xy 112.013999 -122.908114) (xy 112.014508 -122.936) (xy 112.013999 -122.963886) (xy 112.005879 -123.019062)
			(xy 111.989811 -123.072469) (xy 111.974702 -123.1047) (xy 141.957045 -123.1047) (xy 141.961059 -123.040902)
			(xy 141.973037 -122.978109) (xy 141.99279 -122.917313) (xy 142.020006 -122.859472) (xy 142.054257 -122.805498)
			(xy 142.095002 -122.756242) (xy 142.141599 -122.712481) (xy 142.193313 -122.674905) (xy 142.249329 -122.644106)
			(xy 142.308763 -122.62057) (xy 142.370678 -122.604669) (xy 142.434098 -122.596652) (xy 142.46606 -122.596148)
			(xy 142.499051 -122.596666) (xy 142.564479 -122.605188) (xy 142.628253 -122.622107) (xy 142.689302 -122.647138)
			(xy 142.746597 -122.679861) (xy 142.799175 -122.719724) (xy 142.846151 -122.766056) (xy 142.886734 -122.81808)
			(xy 142.900224 -122.840961) (xy 151.256994 -122.840961) (xy 151.256994 -122.777039) (xy 151.265005 -122.713621)
			(xy 151.280902 -122.651707) (xy 151.304434 -122.592274) (xy 151.335228 -122.536259) (xy 151.372801 -122.484544)
			(xy 151.416558 -122.437947) (xy 151.465811 -122.397202) (xy 151.519782 -122.362951) (xy 151.577621 -122.335734)
			(xy 151.638414 -122.315981) (xy 151.701204 -122.304003) (xy 151.765 -122.29999) (xy 151.828796 -122.304003)
			(xy 151.891586 -122.315981) (xy 151.952379 -122.335734) (xy 152.010218 -122.362951) (xy 152.064189 -122.397202)
			(xy 152.113442 -122.437947) (xy 152.157199 -122.484544) (xy 152.194772 -122.536259) (xy 152.225566 -122.592274)
			(xy 152.249098 -122.651707) (xy 152.264995 -122.713621) (xy 152.272102 -122.769884) (xy 157.430468 -122.769884)
			(xy 157.434539 -122.714262) (xy 157.446665 -122.659825) (xy 157.466588 -122.607734) (xy 157.493884 -122.559099)
			(xy 157.52797 -122.514956) (xy 157.568119 -122.476247) (xy 157.613477 -122.443796) (xy 157.663077 -122.418295)
			(xy 157.715861 -122.400288) (xy 157.770704 -122.390158) (xy 157.826438 -122.388121) (xy 157.881875 -122.394221)
			(xy 157.935832 -122.408327) (xy 157.987161 -122.430139) (xy 158.034767 -122.459193) (xy 158.077635 -122.494868)
			(xy 158.114852 -122.536405) (xy 158.145625 -122.582918) (xy 158.169297 -122.633415) (xy 158.185365 -122.686822)
			(xy 158.193485 -122.741998) (xy 158.193994 -122.769884) (xy 158.193485 -122.79777) (xy 158.185365 -122.852946)
			(xy 158.169297 -122.906353) (xy 158.145625 -122.95685) (xy 158.114852 -123.003363) (xy 158.077635 -123.0449)
			(xy 158.034767 -123.080575) (xy 157.987161 -123.109629) (xy 157.935832 -123.131441) (xy 157.881875 -123.145547)
			(xy 157.826438 -123.151647) (xy 157.770704 -123.14961) (xy 157.715861 -123.13948) (xy 157.663077 -123.121473)
			(xy 157.613477 -123.095972) (xy 157.568119 -123.063521) (xy 157.52797 -123.024812) (xy 157.493884 -122.980669)
			(xy 157.466588 -122.932034) (xy 157.446665 -122.879943) (xy 157.434539 -122.825506) (xy 157.430468 -122.769884)
			(xy 152.272102 -122.769884) (xy 152.273006 -122.777039) (xy 152.273508 -122.809) (xy 152.273006 -122.840961)
			(xy 152.264995 -122.904379) (xy 152.249098 -122.966293) (xy 152.225566 -123.025726) (xy 152.194772 -123.081741)
			(xy 152.157199 -123.133456) (xy 152.113442 -123.180053) (xy 152.064189 -123.220798) (xy 152.010218 -123.255049)
			(xy 151.952379 -123.282266) (xy 151.891586 -123.302019) (xy 151.828796 -123.313997) (xy 151.765 -123.318011)
			(xy 151.701204 -123.313997) (xy 151.638414 -123.302019) (xy 151.577621 -123.282266) (xy 151.519782 -123.255049)
			(xy 151.465811 -123.220798) (xy 151.416558 -123.180053) (xy 151.372801 -123.133456) (xy 151.335228 -123.081741)
			(xy 151.304434 -123.025726) (xy 151.280902 -122.966293) (xy 151.265005 -122.904379) (xy 151.256994 -122.840961)
			(xy 142.900224 -122.840961) (xy 142.920243 -122.874918) (xy 142.946113 -122.935616) (xy 142.955518 -122.967242)
			(xy 142.958612 -122.976472) (xy 142.970492 -122.991875) (xy 142.978632 -122.997214) (xy 143.039338 -123.032774)
			(xy 143.047982 -123.037362) (xy 143.067324 -123.040233) (xy 143.07693 -123.038362) (xy 143.077184 -123.038362)
			(xy 143.106274 -123.03183) (xy 143.165483 -123.024831) (xy 143.195294 -123.024392) (xy 143.195802 -123.024392)
			(xy 143.227763 -123.024894) (xy 143.291181 -123.032906) (xy 143.353094 -123.048803) (xy 143.412527 -123.072334)
			(xy 143.468543 -123.103129) (xy 143.520256 -123.140701) (xy 143.566853 -123.184459) (xy 143.607599 -123.233712)
			(xy 143.64185 -123.287683) (xy 143.669066 -123.345521) (xy 143.688819 -123.406315) (xy 143.700797 -123.469104)
			(xy 143.704811 -123.5329) (xy 143.700797 -123.596696) (xy 143.688819 -123.659485) (xy 143.669066 -123.720279)
			(xy 143.64185 -123.778117) (xy 143.607599 -123.832088) (xy 143.566853 -123.881341) (xy 143.520256 -123.925099)
			(xy 143.468543 -123.962671) (xy 143.412527 -123.993466) (xy 143.353094 -124.016997) (xy 143.291181 -124.032894)
			(xy 143.227763 -124.040906) (xy 143.195802 -124.041408) (xy 143.162812 -124.040883) (xy 143.097386 -124.032357)
			(xy 143.033613 -124.015436) (xy 142.972567 -123.990404) (xy 142.915273 -123.957682) (xy 142.862697 -123.91782)
			(xy 142.815721 -123.871489) (xy 142.775136 -123.819469) (xy 142.741625 -123.762633) (xy 142.715751 -123.701938)
			(xy 142.706344 -123.670314) (xy 142.703241 -123.661087) (xy 142.691369 -123.645681) (xy 142.68323 -123.640342)
			(xy 142.622524 -123.604782) (xy 142.613887 -123.600176) (xy 142.59454 -123.597315) (xy 142.584932 -123.599194)
			(xy 142.584678 -123.599194) (xy 142.555586 -123.605716) (xy 142.496378 -123.612721) (xy 142.466568 -123.613164)
			(xy 142.46606 -123.613164) (xy 142.434098 -123.612748) (xy 142.370678 -123.604731) (xy 142.308763 -123.58883)
			(xy 142.249329 -123.565294) (xy 142.193313 -123.534495) (xy 142.141599 -123.496919) (xy 142.095002 -123.453158)
			(xy 142.054257 -123.403902) (xy 142.020006 -123.349928) (xy 141.99279 -123.292087) (xy 141.973037 -123.23129)
			(xy 141.961059 -123.168498) (xy 141.957045 -123.1047) (xy 111.974702 -123.1047) (xy 111.966139 -123.122966)
			(xy 111.935366 -123.169479) (xy 111.898149 -123.211016) (xy 111.855281 -123.246691) (xy 111.807675 -123.275745)
			(xy 111.756346 -123.297557) (xy 111.702389 -123.311663) (xy 111.646952 -123.317763) (xy 111.591218 -123.315726)
			(xy 111.536375 -123.305596) (xy 111.483591 -123.287589) (xy 111.433991 -123.262088) (xy 111.388633 -123.229637)
			(xy 111.348484 -123.190928) (xy 111.314398 -123.146785) (xy 111.287102 -123.09815) (xy 111.267179 -123.046059)
			(xy 111.255053 -122.991622) (xy 111.250982 -122.936) (xy 6.11378 -122.936) (xy 6.11378 -125.513338)
			(xy 35.46856 -125.513338) (xy 35.469005 -125.482207) (xy 35.476614 -125.42041) (xy 35.49171 -125.360005)
			(xy 35.514068 -125.301895) (xy 35.543352 -125.246949) (xy 35.579126 -125.195988) (xy 35.620853 -125.149777)
			(xy 35.644074 -125.129036) (xy 35.650723 -125.122704) (xy 35.659458 -125.106574) (xy 35.661092 -125.09754)
			(xy 35.66541 -125.06706) (xy 35.666237 -125.05801) (xy 35.662216 -125.040304) (xy 35.657536 -125.032516)
			(xy 35.642895 -125.009164) (xy 35.619722 -124.959157) (xy 35.603998 -124.906333) (xy 35.59605 -124.851794)
			(xy 35.59556 -124.824236) (xy 35.596084 -124.795919) (xy 35.604473 -124.73991) (xy 35.621043 -124.685754)
			(xy 35.64543 -124.63464) (xy 35.660838 -124.610876) (xy 35.665663 -124.602993) (xy 35.669967 -124.585035)
			(xy 35.66922 -124.575824) (xy 35.664902 -124.54509) (xy 35.663369 -124.535868) (xy 35.654498 -124.519428)
			(xy 35.64763 -124.513086) (xy 35.623941 -124.492368) (xy 35.581398 -124.44599) (xy 35.544904 -124.394716)
			(xy 35.515018 -124.33933) (xy 35.492196 -124.280678) (xy 35.476787 -124.219659) (xy 35.469027 -124.157204)
			(xy 35.46856 -124.125736) (xy 35.469062 -124.093775) (xy 35.477073 -124.030357) (xy 35.49297 -123.968443)
			(xy 35.516502 -123.90901) (xy 35.547296 -123.852995) (xy 35.584869 -123.80128) (xy 35.628626 -123.754683)
			(xy 35.677879 -123.713938) (xy 35.73185 -123.679687) (xy 35.789689 -123.65247) (xy 35.850482 -123.632717)
			(xy 35.913272 -123.620739) (xy 35.977068 -123.616726) (xy 36.040864 -123.620739) (xy 36.103654 -123.632717)
			(xy 36.164447 -123.65247) (xy 36.222286 -123.679687) (xy 36.276257 -123.713938) (xy 36.32551 -123.754683)
			(xy 36.369267 -123.80128) (xy 36.40684 -123.852995) (xy 36.437634 -123.90901) (xy 36.461166 -123.968443)
			(xy 36.477063 -124.030357) (xy 36.485074 -124.093775) (xy 36.485576 -124.125736) (xy 36.485096 -124.157202)
			(xy 36.477327 -124.219652) (xy 36.461912 -124.280666) (xy 36.439087 -124.339312) (xy 36.4092 -124.394693)
			(xy 36.376277 -124.44095) (xy 117.962932 -124.44095) (xy 117.967003 -124.385328) (xy 117.979129 -124.330891)
			(xy 117.999052 -124.2788) (xy 118.026348 -124.230165) (xy 118.060434 -124.186022) (xy 118.100583 -124.147313)
			(xy 118.145941 -124.114862) (xy 118.195541 -124.089361) (xy 118.248325 -124.071354) (xy 118.303168 -124.061224)
			(xy 118.358902 -124.059187) (xy 118.414339 -124.065287) (xy 118.468296 -124.079393) (xy 118.519625 -124.101205)
			(xy 118.567231 -124.130259) (xy 118.610099 -124.165934) (xy 118.647316 -124.207471) (xy 118.678089 -124.253984)
			(xy 118.701761 -124.304481) (xy 118.717829 -124.357888) (xy 118.725949 -124.413064) (xy 118.726458 -124.44095)
			(xy 118.725949 -124.468836) (xy 118.717829 -124.524012) (xy 118.701761 -124.577419) (xy 118.678089 -124.627916)
			(xy 118.647316 -124.674429) (xy 118.645581 -124.676365) (xy 144.252436 -124.676365) (xy 144.252436 -124.612443)
			(xy 144.260447 -124.549025) (xy 144.276344 -124.487111) (xy 144.299876 -124.427678) (xy 144.33067 -124.371663)
			(xy 144.368243 -124.319948) (xy 144.412 -124.273351) (xy 144.461253 -124.232606) (xy 144.515224 -124.198355)
			(xy 144.573063 -124.171138) (xy 144.633856 -124.151385) (xy 144.696646 -124.139407) (xy 144.760442 -124.135394)
			(xy 144.824238 -124.139407) (xy 144.887028 -124.151385) (xy 144.947821 -124.171138) (xy 145.00566 -124.198355)
			(xy 145.059631 -124.232606) (xy 145.108884 -124.273351) (xy 145.152641 -124.319948) (xy 145.190214 -124.371663)
			(xy 145.221008 -124.427678) (xy 145.24454 -124.487111) (xy 145.260437 -124.549025) (xy 145.261571 -124.558001)
			(xy 164.464994 -124.558001) (xy 164.464994 -124.494079) (xy 164.473005 -124.430661) (xy 164.488902 -124.368747)
			(xy 164.512434 -124.309314) (xy 164.543228 -124.253299) (xy 164.580801 -124.201584) (xy 164.624558 -124.154987)
			(xy 164.673811 -124.114242) (xy 164.727782 -124.079991) (xy 164.785621 -124.052774) (xy 164.846414 -124.033021)
			(xy 164.909204 -124.021043) (xy 164.973 -124.01703) (xy 165.036796 -124.021043) (xy 165.099586 -124.033021)
			(xy 165.160379 -124.052774) (xy 165.218218 -124.079991) (xy 165.272189 -124.114242) (xy 165.321442 -124.154987)
			(xy 165.365199 -124.201584) (xy 165.402772 -124.253299) (xy 165.433566 -124.309314) (xy 165.457098 -124.368747)
			(xy 165.472995 -124.430661) (xy 165.481006 -124.494079) (xy 165.481508 -124.52604) (xy 165.481006 -124.558001)
			(xy 165.472995 -124.621419) (xy 165.457098 -124.683333) (xy 165.433566 -124.742766) (xy 165.402772 -124.798781)
			(xy 165.365199 -124.850496) (xy 165.321442 -124.897093) (xy 165.272189 -124.937838) (xy 165.218218 -124.972089)
			(xy 165.160379 -124.999306) (xy 165.099586 -125.019059) (xy 165.036796 -125.031037) (xy 164.973 -125.035051)
			(xy 164.909204 -125.031037) (xy 164.846414 -125.019059) (xy 164.785621 -124.999306) (xy 164.727782 -124.972089)
			(xy 164.673811 -124.937838) (xy 164.624558 -124.897093) (xy 164.580801 -124.850496) (xy 164.543228 -124.798781)
			(xy 164.512434 -124.742766) (xy 164.488902 -124.683333) (xy 164.473005 -124.621419) (xy 164.464994 -124.558001)
			(xy 145.261571 -124.558001) (xy 145.268448 -124.612443) (xy 145.26895 -124.644404) (xy 145.268448 -124.676365)
			(xy 145.260437 -124.739783) (xy 145.24454 -124.801697) (xy 145.221008 -124.86113) (xy 145.190214 -124.917145)
			(xy 145.152641 -124.96886) (xy 145.108884 -125.015457) (xy 145.059631 -125.056202) (xy 145.00566 -125.090453)
			(xy 144.947821 -125.11767) (xy 144.887028 -125.137423) (xy 144.824238 -125.149401) (xy 144.760442 -125.153415)
			(xy 144.696646 -125.149401) (xy 144.633856 -125.137423) (xy 144.573063 -125.11767) (xy 144.515224 -125.090453)
			(xy 144.461253 -125.056202) (xy 144.412 -125.015457) (xy 144.368243 -124.96886) (xy 144.33067 -124.917145)
			(xy 144.299876 -124.86113) (xy 144.276344 -124.801697) (xy 144.260447 -124.739783) (xy 144.252436 -124.676365)
			(xy 118.645581 -124.676365) (xy 118.610099 -124.715966) (xy 118.567231 -124.751641) (xy 118.519625 -124.780695)
			(xy 118.468296 -124.802507) (xy 118.414339 -124.816613) (xy 118.358902 -124.822713) (xy 118.303168 -124.820676)
			(xy 118.248325 -124.810546) (xy 118.195541 -124.792539) (xy 118.145941 -124.767038) (xy 118.100583 -124.734587)
			(xy 118.060434 -124.695878) (xy 118.026348 -124.651735) (xy 117.999052 -124.6031) (xy 117.979129 -124.551009)
			(xy 117.967003 -124.496572) (xy 117.962932 -124.44095) (xy 36.376277 -124.44095) (xy 36.372708 -124.445964)
			(xy 36.330169 -124.492341) (xy 36.306506 -124.513086) (xy 36.299729 -124.5195) (xy 36.290869 -124.535904)
			(xy 36.289234 -124.54509) (xy 36.284916 -124.575824) (xy 36.284103 -124.585042) (xy 36.288401 -124.603024)
			(xy 36.293298 -124.610876) (xy 36.308713 -124.634636) (xy 36.333115 -124.685746) (xy 36.349686 -124.739904)
			(xy 36.358061 -124.795918) (xy 36.358576 -124.824236) (xy 36.358088 -124.851794) (xy 36.350143 -124.906335)
			(xy 36.334423 -124.959162) (xy 36.311257 -125.009174) (xy 36.2966 -125.032516) (xy 36.291957 -125.040321)
			(xy 36.28792 -125.058015) (xy 36.288726 -125.06706) (xy 36.293044 -125.09754) (xy 36.294665 -125.106581)
			(xy 36.303386 -125.122729) (xy 36.310062 -125.129036) (xy 36.333298 -125.149759) (xy 36.375024 -125.195973)
			(xy 36.410793 -125.246937) (xy 36.440073 -125.301886) (xy 36.462423 -125.36) (xy 36.47751 -125.420408)
			(xy 36.485108 -125.482206) (xy 36.485274 -125.493229) (xy 95.918776 -125.493229) (xy 95.918776 -125.429307)
			(xy 95.926787 -125.365889) (xy 95.942684 -125.303975) (xy 95.966216 -125.244542) (xy 95.99701 -125.188527)
			(xy 96.034583 -125.136812) (xy 96.07834 -125.090215) (xy 96.127593 -125.04947) (xy 96.181564 -125.015219)
			(xy 96.239403 -124.988002) (xy 96.300196 -124.968249) (xy 96.362986 -124.956271) (xy 96.426782 -124.952258)
			(xy 96.490578 -124.956271) (xy 96.553368 -124.968249) (xy 96.614161 -124.988002) (xy 96.672 -125.015219)
			(xy 96.725971 -125.04947) (xy 96.775224 -125.090215) (xy 96.818981 -125.136812) (xy 96.856554 -125.188527)
			(xy 96.887348 -125.244542) (xy 96.91088 -125.303975) (xy 96.926777 -125.365889) (xy 96.934788 -125.429307)
			(xy 96.93529 -125.461268) (xy 96.934788 -125.493229) (xy 96.926777 -125.556647) (xy 96.922571 -125.573028)
			(xy 97.962718 -125.573028) (xy 97.966789 -125.517406) (xy 97.978915 -125.462969) (xy 97.998838 -125.410878)
			(xy 98.026134 -125.362243) (xy 98.06022 -125.3181) (xy 98.100369 -125.279391) (xy 98.145727 -125.24694)
			(xy 98.195327 -125.221439) (xy 98.248111 -125.203432) (xy 98.302954 -125.193302) (xy 98.358688 -125.191265)
			(xy 98.414125 -125.197365) (xy 98.468082 -125.211471) (xy 98.519411 -125.233283) (xy 98.567017 -125.262337)
			(xy 98.609885 -125.298012) (xy 98.647102 -125.339549) (xy 98.677875 -125.386062) (xy 98.701547 -125.436559)
			(xy 98.717615 -125.489966) (xy 98.725735 -125.545142) (xy 98.726244 -125.573028) (xy 98.725924 -125.590554)
			(xy 102.422704 -125.590554) (xy 102.426775 -125.534932) (xy 102.438901 -125.480495) (xy 102.458824 -125.428404)
			(xy 102.48612 -125.379769) (xy 102.520206 -125.335626) (xy 102.560355 -125.296917) (xy 102.605713 -125.264466)
			(xy 102.655313 -125.238965) (xy 102.708097 -125.220958) (xy 102.76294 -125.210828) (xy 102.818674 -125.208791)
			(xy 102.874111 -125.214891) (xy 102.928068 -125.228997) (xy 102.979397 -125.250809) (xy 103.027003 -125.279863)
			(xy 103.069871 -125.315538) (xy 103.107088 -125.357075) (xy 103.137861 -125.403588) (xy 103.161533 -125.454085)
			(xy 103.177601 -125.507492) (xy 103.185721 -125.562668) (xy 103.185873 -125.570996) (xy 105.927904 -125.570996)
			(xy 105.931975 -125.515374) (xy 105.944101 -125.460937) (xy 105.964024 -125.408846) (xy 105.99132 -125.360211)
			(xy 106.025406 -125.316068) (xy 106.065555 -125.277359) (xy 106.110913 -125.244908) (xy 106.160513 -125.219407)
			(xy 106.213297 -125.2014) (xy 106.26814 -125.19127) (xy 106.323874 -125.189233) (xy 106.379311 -125.195333)
			(xy 106.433268 -125.209439) (xy 106.484597 -125.231251) (xy 106.532203 -125.260305) (xy 106.575071 -125.29598)
			(xy 106.612288 -125.337517) (xy 106.643061 -125.38403) (xy 106.666733 -125.434527) (xy 106.682801 -125.487934)
			(xy 106.690921 -125.54311) (xy 106.691073 -125.551438) (xy 109.433104 -125.551438) (xy 109.437175 -125.495816)
			(xy 109.449301 -125.441379) (xy 109.469224 -125.389288) (xy 109.49652 -125.340653) (xy 109.530606 -125.29651)
			(xy 109.570755 -125.257801) (xy 109.616113 -125.22535) (xy 109.665713 -125.199849) (xy 109.718497 -125.181842)
			(xy 109.77334 -125.171712) (xy 109.829074 -125.169675) (xy 109.884511 -125.175775) (xy 109.938468 -125.189881)
			(xy 109.989797 -125.211693) (xy 110.037403 -125.240747) (xy 110.080271 -125.276422) (xy 110.117488 -125.317959)
			(xy 110.148261 -125.364472) (xy 110.171933 -125.414969) (xy 110.188001 -125.468376) (xy 110.196121 -125.523552)
			(xy 110.19663 -125.551438) (xy 110.196121 -125.579324) (xy 110.190143 -125.619948) (xy 153.76804 -125.619948)
			(xy 153.76804 -125.535252) (xy 153.776091 -125.450938) (xy 153.79212 -125.367772) (xy 153.815981 -125.286505)
			(xy 153.84746 -125.207875) (xy 153.886271 -125.132594) (xy 153.932061 -125.061342) (xy 153.984417 -124.994766)
			(xy 154.042865 -124.933468) (xy 154.106875 -124.878003) (xy 154.175867 -124.828874) (xy 154.249217 -124.786525)
			(xy 154.32626 -124.751341) (xy 154.406299 -124.723639) (xy 154.488608 -124.703671) (xy 154.572443 -124.691618)
			(xy 154.657044 -124.687588) (xy 154.741645 -124.691618) (xy 154.82548 -124.703671) (xy 154.907789 -124.723639)
			(xy 154.987828 -124.751341) (xy 155.064871 -124.786525) (xy 155.138221 -124.828874) (xy 155.207213 -124.878003)
			(xy 155.271223 -124.933468) (xy 155.329671 -124.994766) (xy 155.382027 -125.061342) (xy 155.427817 -125.132594)
			(xy 155.466628 -125.207875) (xy 155.498107 -125.286505) (xy 155.521968 -125.367772) (xy 155.523237 -125.374357)
			(xy 155.931356 -125.374357) (xy 155.931356 -125.310435) (xy 155.939367 -125.247017) (xy 155.955264 -125.185103)
			(xy 155.978796 -125.12567) (xy 156.00959 -125.069655) (xy 156.047163 -125.01794) (xy 156.09092 -124.971343)
			(xy 156.140173 -124.930598) (xy 156.194144 -124.896347) (xy 156.251983 -124.86913) (xy 156.312776 -124.849377)
			(xy 156.375566 -124.837399) (xy 156.439362 -124.833386) (xy 156.503158 -124.837399) (xy 156.565948 -124.849377)
			(xy 156.626741 -124.86913) (xy 156.68458 -124.896347) (xy 156.738551 -124.930598) (xy 156.787804 -124.971343)
			(xy 156.831561 -125.01794) (xy 156.869134 -125.069655) (xy 156.899928 -125.12567) (xy 156.92346 -125.185103)
			(xy 156.939357 -125.247017) (xy 156.947368 -125.310435) (xy 156.94787 -125.342396) (xy 156.947368 -125.374357)
			(xy 156.939357 -125.437775) (xy 156.92346 -125.499689) (xy 156.899928 -125.559122) (xy 156.869134 -125.615137)
			(xy 156.831561 -125.666852) (xy 156.787804 -125.713449) (xy 156.738551 -125.754194) (xy 156.68458 -125.788445)
			(xy 156.626741 -125.815662) (xy 156.565948 -125.835415) (xy 156.503158 -125.847393) (xy 156.439362 -125.851407)
			(xy 156.375566 -125.847393) (xy 156.312776 -125.835415) (xy 156.251983 -125.815662) (xy 156.194144 -125.788445)
			(xy 156.140173 -125.754194) (xy 156.09092 -125.713449) (xy 156.047163 -125.666852) (xy 156.00959 -125.615137)
			(xy 155.978796 -125.559122) (xy 155.955264 -125.499689) (xy 155.939367 -125.437775) (xy 155.931356 -125.374357)
			(xy 155.523237 -125.374357) (xy 155.537997 -125.450938) (xy 155.546048 -125.535252) (xy 155.546552 -125.5776)
			(xy 155.546048 -125.619948) (xy 155.537997 -125.704262) (xy 155.521968 -125.787428) (xy 155.498107 -125.868695)
			(xy 155.466628 -125.947325) (xy 155.427817 -126.022606) (xy 155.382027 -126.093858) (xy 155.329671 -126.160434)
			(xy 155.271223 -126.221732) (xy 155.207213 -126.277197) (xy 155.138221 -126.326326) (xy 155.064871 -126.368675)
			(xy 154.987828 -126.403859) (xy 154.907789 -126.431561) (xy 154.82548 -126.451529) (xy 154.741645 -126.463582)
			(xy 154.657044 -126.467613) (xy 154.572443 -126.463582) (xy 154.488608 -126.451529) (xy 154.406299 -126.431561)
			(xy 154.32626 -126.403859) (xy 154.249217 -126.368675) (xy 154.175867 -126.326326) (xy 154.106875 -126.277197)
			(xy 154.042865 -126.221732) (xy 153.984417 -126.160434) (xy 153.932061 -126.093858) (xy 153.886271 -126.022606)
			(xy 153.84746 -125.947325) (xy 153.815981 -125.868695) (xy 153.79212 -125.787428) (xy 153.776091 -125.704262)
			(xy 153.76804 -125.619948) (xy 110.190143 -125.619948) (xy 110.188001 -125.6345) (xy 110.171933 -125.687907)
			(xy 110.148261 -125.738404) (xy 110.117488 -125.784917) (xy 110.080271 -125.826454) (xy 110.037403 -125.862129)
			(xy 109.989797 -125.891183) (xy 109.938468 -125.912995) (xy 109.884511 -125.927101) (xy 109.829074 -125.933201)
			(xy 109.77334 -125.931164) (xy 109.718497 -125.921034) (xy 109.665713 -125.903027) (xy 109.616113 -125.877526)
			(xy 109.570755 -125.845075) (xy 109.530606 -125.806366) (xy 109.49652 -125.762223) (xy 109.469224 -125.713588)
			(xy 109.449301 -125.661497) (xy 109.437175 -125.60706) (xy 109.433104 -125.551438) (xy 106.691073 -125.551438)
			(xy 106.69143 -125.570996) (xy 106.690921 -125.598882) (xy 106.682801 -125.654058) (xy 106.666733 -125.707465)
			(xy 106.643061 -125.757962) (xy 106.612288 -125.804475) (xy 106.575071 -125.846012) (xy 106.532203 -125.881687)
			(xy 106.484597 -125.910741) (xy 106.433268 -125.932553) (xy 106.379311 -125.946659) (xy 106.323874 -125.952759)
			(xy 106.26814 -125.950722) (xy 106.213297 -125.940592) (xy 106.160513 -125.922585) (xy 106.110913 -125.897084)
			(xy 106.065555 -125.864633) (xy 106.025406 -125.825924) (xy 105.99132 -125.781781) (xy 105.964024 -125.733146)
			(xy 105.944101 -125.681055) (xy 105.931975 -125.626618) (xy 105.927904 -125.570996) (xy 103.185873 -125.570996)
			(xy 103.18623 -125.590554) (xy 103.185721 -125.61844) (xy 103.177601 -125.673616) (xy 103.161533 -125.727023)
			(xy 103.137861 -125.77752) (xy 103.107088 -125.824033) (xy 103.069871 -125.86557) (xy 103.027003 -125.901245)
			(xy 102.979397 -125.930299) (xy 102.928068 -125.952111) (xy 102.874111 -125.966217) (xy 102.818674 -125.972317)
			(xy 102.76294 -125.97028) (xy 102.708097 -125.96015) (xy 102.655313 -125.942143) (xy 102.605713 -125.916642)
			(xy 102.560355 -125.884191) (xy 102.520206 -125.845482) (xy 102.48612 -125.801339) (xy 102.458824 -125.752704)
			(xy 102.438901 -125.700613) (xy 102.426775 -125.646176) (xy 102.422704 -125.590554) (xy 98.725924 -125.590554)
			(xy 98.725735 -125.600914) (xy 98.717615 -125.65609) (xy 98.701547 -125.709497) (xy 98.677875 -125.759994)
			(xy 98.647102 -125.806507) (xy 98.609885 -125.848044) (xy 98.567017 -125.883719) (xy 98.519411 -125.912773)
			(xy 98.468082 -125.934585) (xy 98.414125 -125.948691) (xy 98.358688 -125.954791) (xy 98.302954 -125.952754)
			(xy 98.248111 -125.942624) (xy 98.195327 -125.924617) (xy 98.145727 -125.899116) (xy 98.100369 -125.866665)
			(xy 98.06022 -125.827956) (xy 98.026134 -125.783813) (xy 97.998838 -125.735178) (xy 97.978915 -125.683087)
			(xy 97.966789 -125.62865) (xy 97.962718 -125.573028) (xy 96.922571 -125.573028) (xy 96.91088 -125.618561)
			(xy 96.887348 -125.677994) (xy 96.856554 -125.734009) (xy 96.818981 -125.785724) (xy 96.775224 -125.832321)
			(xy 96.725971 -125.873066) (xy 96.672 -125.907317) (xy 96.614161 -125.934534) (xy 96.553368 -125.954287)
			(xy 96.490578 -125.966265) (xy 96.426782 -125.970279) (xy 96.362986 -125.966265) (xy 96.300196 -125.954287)
			(xy 96.239403 -125.934534) (xy 96.181564 -125.907317) (xy 96.127593 -125.873066) (xy 96.07834 -125.832321)
			(xy 96.034583 -125.785724) (xy 95.99701 -125.734009) (xy 95.966216 -125.677994) (xy 95.942684 -125.618561)
			(xy 95.926787 -125.556647) (xy 95.918776 -125.493229) (xy 36.485274 -125.493229) (xy 36.485576 -125.513338)
			(xy 36.485074 -125.545299) (xy 36.477063 -125.608717) (xy 36.461166 -125.670631) (xy 36.437634 -125.730064)
			(xy 36.40684 -125.786079) (xy 36.369267 -125.837794) (xy 36.32551 -125.884391) (xy 36.276257 -125.925136)
			(xy 36.222286 -125.959387) (xy 36.164447 -125.986604) (xy 36.103654 -126.006357) (xy 36.040864 -126.018335)
			(xy 35.977068 -126.022349) (xy 35.913272 -126.018335) (xy 35.850482 -126.006357) (xy 35.789689 -125.986604)
			(xy 35.73185 -125.959387) (xy 35.677879 -125.925136) (xy 35.628626 -125.884391) (xy 35.584869 -125.837794)
			(xy 35.547296 -125.786079) (xy 35.516502 -125.730064) (xy 35.49297 -125.670631) (xy 35.477073 -125.608717)
			(xy 35.469062 -125.545299) (xy 35.46856 -125.513338) (xy 6.11378 -125.513338) (xy 6.11378 -126.133309)
			(xy 85.937592 -126.133309) (xy 85.937592 -126.069387) (xy 85.945603 -126.005969) (xy 85.9615 -125.944055)
			(xy 85.985032 -125.884622) (xy 86.015826 -125.828607) (xy 86.053399 -125.776892) (xy 86.097156 -125.730295)
			(xy 86.146409 -125.68955) (xy 86.20038 -125.655299) (xy 86.258219 -125.628082) (xy 86.319012 -125.608329)
			(xy 86.381802 -125.596351) (xy 86.445598 -125.592338) (xy 86.509394 -125.596351) (xy 86.572184 -125.608329)
			(xy 86.632977 -125.628082) (xy 86.690816 -125.655299) (xy 86.744787 -125.68955) (xy 86.79404 -125.730295)
			(xy 86.837797 -125.776892) (xy 86.87537 -125.828607) (xy 86.906164 -125.884622) (xy 86.929696 -125.944055)
			(xy 86.945593 -126.005969) (xy 86.953604 -126.069387) (xy 86.954106 -126.101348) (xy 86.953604 -126.133309)
			(xy 86.947604 -126.180807) (xy 103.88193 -126.180807) (xy 103.88193 -126.116885) (xy 103.889941 -126.053467)
			(xy 103.905838 -125.991553) (xy 103.92937 -125.93212) (xy 103.960164 -125.876105) (xy 103.997737 -125.82439)
			(xy 104.041494 -125.777793) (xy 104.090747 -125.737048) (xy 104.144718 -125.702797) (xy 104.202557 -125.67558)
			(xy 104.26335 -125.655827) (xy 104.32614 -125.643849) (xy 104.389936 -125.639836) (xy 104.453732 -125.643849)
			(xy 104.516522 -125.655827) (xy 104.577315 -125.67558) (xy 104.635154 -125.702797) (xy 104.689125 -125.737048)
			(xy 104.738378 -125.777793) (xy 104.782135 -125.82439) (xy 104.819708 -125.876105) (xy 104.850502 -125.93212)
			(xy 104.874034 -125.991553) (xy 104.889931 -126.053467) (xy 104.897942 -126.116885) (xy 104.898444 -126.148846)
			(xy 104.898249 -126.161249) (xy 107.38713 -126.161249) (xy 107.38713 -126.097327) (xy 107.395141 -126.033909)
			(xy 107.411038 -125.971995) (xy 107.43457 -125.912562) (xy 107.465364 -125.856547) (xy 107.502937 -125.804832)
			(xy 107.546694 -125.758235) (xy 107.595947 -125.71749) (xy 107.649918 -125.683239) (xy 107.707757 -125.656022)
			(xy 107.76855 -125.636269) (xy 107.83134 -125.624291) (xy 107.895136 -125.620278) (xy 107.958932 -125.624291)
			(xy 108.021722 -125.636269) (xy 108.082515 -125.656022) (xy 108.140354 -125.683239) (xy 108.194325 -125.71749)
			(xy 108.243578 -125.758235) (xy 108.287335 -125.804832) (xy 108.324908 -125.856547) (xy 108.355702 -125.912562)
			(xy 108.379234 -125.971995) (xy 108.395131 -126.033909) (xy 108.403142 -126.097327) (xy 108.403644 -126.129288)
			(xy 108.403142 -126.161249) (xy 108.395131 -126.224667) (xy 108.379234 -126.286581) (xy 108.374333 -126.29896)
			(xy 113.857022 -126.29896) (xy 113.861093 -126.243338) (xy 113.873219 -126.188901) (xy 113.893142 -126.13681)
			(xy 113.920438 -126.088175) (xy 113.954524 -126.044032) (xy 113.994673 -126.005323) (xy 114.040031 -125.972872)
			(xy 114.089631 -125.947371) (xy 114.142415 -125.929364) (xy 114.197258 -125.919234) (xy 114.252992 -125.917197)
			(xy 114.308429 -125.923297) (xy 114.362386 -125.937403) (xy 114.413715 -125.959215) (xy 114.461321 -125.988269)
			(xy 114.504189 -126.023944) (xy 114.541406 -126.065481) (xy 114.572179 -126.111994) (xy 114.595851 -126.162491)
			(xy 114.611919 -126.215898) (xy 114.620039 -126.271074) (xy 114.620548 -126.29896) (xy 114.620039 -126.326846)
			(xy 114.611919 -126.382022) (xy 114.595851 -126.435429) (xy 114.572179 -126.485926) (xy 114.571865 -126.4864)
			(xy 115.676701 -126.4864) (xy 115.680715 -126.422606) (xy 115.692692 -126.359818) (xy 115.712445 -126.299026)
			(xy 115.739661 -126.241189) (xy 115.773911 -126.187219) (xy 115.814655 -126.137968) (xy 115.86125 -126.094211)
			(xy 115.912963 -126.05664) (xy 115.968976 -126.025846) (xy 116.028408 -126.002315) (xy 116.09032 -125.986418)
			(xy 116.153736 -125.978406) (xy 116.185696 -125.977904) (xy 116.217695 -125.978323) (xy 116.281187 -125.986364)
			(xy 116.343169 -126.002308) (xy 116.40266 -126.025903) (xy 116.45872 -126.056775) (xy 116.510465 -126.094437)
			(xy 116.557075 -126.138293) (xy 116.597815 -126.18765) (xy 116.63204 -126.241729) (xy 116.65921 -126.299675)
			(xy 116.678895 -126.360571) (xy 116.685314 -126.391924) (xy 116.685314 -126.392178) (xy 116.687857 -126.402442)
			(xy 116.699932 -126.419769) (xy 116.708682 -126.425706) (xy 116.772436 -126.465076) (xy 116.781699 -126.470099)
			(xy 116.802547 -126.472993) (xy 116.812822 -126.470664) (xy 116.813076 -126.470664) (xy 116.847036 -126.461645)
			(xy 116.916628 -126.451954) (xy 116.95176 -126.45136) (xy 116.952014 -126.45136) (xy 116.983972 -126.451927)
			(xy 117.047385 -126.459939) (xy 117.109294 -126.475836) (xy 117.127134 -126.4829) (xy 160.376024 -126.4829)
			(xy 160.380039 -126.419094) (xy 160.392019 -126.356294) (xy 160.411776 -126.295491) (xy 160.438997 -126.237644)
			(xy 160.473255 -126.183665) (xy 160.514008 -126.134405) (xy 160.560613 -126.090642) (xy 160.612337 -126.053065)
			(xy 160.668362 -126.022267) (xy 160.727805 -125.998734) (xy 160.78973 -125.982838) (xy 160.853158 -125.974828)
			(xy 160.885124 -125.974348) (xy 160.915845 -125.974799) (xy 160.97684 -125.982202) (xy 161.036499 -125.996897)
			(xy 161.093954 -126.01867) (xy 161.148369 -126.047205) (xy 161.173922 -126.064264) (xy 161.182607 -126.069657)
			(xy 161.202624 -126.073718) (xy 161.222641 -126.069657) (xy 161.231326 -126.064264) (xy 161.256873 -126.047195)
			(xy 161.31129 -126.018665) (xy 161.368747 -125.996896) (xy 161.428407 -125.982206) (xy 161.489403 -125.974809)
			(xy 161.520124 -125.974348) (xy 161.553553 -125.974818) (xy 161.619836 -125.983571) (xy 161.684399 -126.000937)
			(xy 161.746129 -126.026616) (xy 161.803961 -126.060164) (xy 161.856896 -126.101003) (xy 161.904022 -126.148428)
			(xy 161.944525 -126.201621) (xy 161.961576 -126.23038) (xy 161.966323 -126.237978) (xy 161.980005 -126.24953)
			(xy 161.996819 -126.255684) (xy 162.005772 -126.256034) (xy 162.093656 -126.256034) (xy 162.102616 -126.255714)
			(xy 162.119449 -126.249574) (xy 162.133126 -126.237999) (xy 162.137852 -126.23038) (xy 162.154885 -126.201614)
			(xy 162.195405 -126.14844) (xy 162.242541 -126.101032) (xy 162.295482 -126.060208) (xy 162.353314 -126.026671)
			(xy 162.415042 -126.000999) (xy 162.4796 -125.983634) (xy 162.545877 -125.974877) (xy 162.579304 -125.974348)
			(xy 162.611262 -125.974938) (xy 162.674674 -125.982949) (xy 162.736582 -125.998845) (xy 162.79601 -126.022375)
			(xy 162.85202 -126.053167) (xy 162.903729 -126.090736) (xy 162.950322 -126.13449) (xy 162.991063 -126.183738)
			(xy 163.025311 -126.237705) (xy 163.052525 -126.295538) (xy 163.072277 -126.356326) (xy 163.084253 -126.41911)
			(xy 163.088267 -126.4829) (xy 163.084253 -126.54669) (xy 163.072277 -126.609474) (xy 163.052525 -126.670262)
			(xy 163.025311 -126.728095) (xy 162.991063 -126.782062) (xy 162.950322 -126.83131) (xy 162.903729 -126.875064)
			(xy 162.85202 -126.912633) (xy 162.79601 -126.943425) (xy 162.736582 -126.966955) (xy 162.674674 -126.982851)
			(xy 162.611262 -126.990862) (xy 162.579304 -126.991364) (xy 162.545876 -126.990866) (xy 162.479595 -126.982116)
			(xy 162.415032 -126.964754) (xy 162.353303 -126.93908) (xy 162.295471 -126.905535) (xy 162.242535 -126.8647)
			(xy 162.195408 -126.817278) (xy 162.154904 -126.764089) (xy 162.137852 -126.735332) (xy 162.133114 -126.727728)
			(xy 162.119425 -126.716185) (xy 162.102609 -126.710031) (xy 162.093656 -126.709678) (xy 162.005772 -126.709678)
			(xy 161.996813 -126.710012) (xy 161.97998 -126.716144) (xy 161.966303 -126.727715) (xy 161.961576 -126.735332)
			(xy 161.944528 -126.764088) (xy 161.90401 -126.817262) (xy 161.856875 -126.864669) (xy 161.803937 -126.905494)
			(xy 161.746107 -126.939032) (xy 161.684381 -126.964706) (xy 161.619825 -126.982073) (xy 161.55355 -126.990833)
			(xy 161.520124 -126.991364) (xy 161.489404 -126.990886) (xy 161.42841 -126.98349) (xy 161.368751 -126.968801)
			(xy 161.311296 -126.947033) (xy 161.25688 -126.918505) (xy 161.231326 -126.901448) (xy 161.222641 -126.896055)
			(xy 161.202624 -126.891994) (xy 161.182607 -126.896055) (xy 161.173922 -126.901448) (xy 161.148363 -126.918498)
			(xy 161.093949 -126.947031) (xy 161.036495 -126.968803) (xy 160.976838 -126.983498) (xy 160.915844 -126.9909)
			(xy 160.885124 -126.991364) (xy 160.853158 -126.990972) (xy 160.78973 -126.982962) (xy 160.727805 -126.967066)
			(xy 160.668362 -126.943533) (xy 160.612337 -126.912735) (xy 160.560613 -126.875158) (xy 160.514008 -126.831395)
			(xy 160.473255 -126.782135) (xy 160.438997 -126.728156) (xy 160.411776 -126.670309) (xy 160.392019 -126.609506)
			(xy 160.380039 -126.546706) (xy 160.376024 -126.4829) (xy 117.127134 -126.4829) (xy 117.168722 -126.499367)
			(xy 117.224732 -126.53016) (xy 117.276441 -126.56773) (xy 117.323034 -126.611485) (xy 117.363776 -126.660734)
			(xy 117.398023 -126.714702) (xy 117.425237 -126.772536) (xy 117.444989 -126.833324) (xy 117.456965 -126.896109)
			(xy 117.460979 -126.9599) (xy 117.456965 -127.023691) (xy 117.444989 -127.086476) (xy 117.425237 -127.147264)
			(xy 117.398023 -127.205098) (xy 117.363776 -127.259066) (xy 117.323034 -127.308315) (xy 117.276441 -127.35207)
			(xy 117.224732 -127.38964) (xy 117.168722 -127.420433) (xy 117.109294 -127.443964) (xy 117.047385 -127.459861)
			(xy 116.983972 -127.467873) (xy 116.952014 -127.468376) (xy 116.920017 -127.467883) (xy 116.856531 -127.459844)
			(xy 116.794555 -127.443904) (xy 116.735068 -127.420316) (xy 116.67901 -127.38945) (xy 116.627267 -127.351796)
			(xy 116.580656 -127.307949) (xy 116.539915 -127.2586) (xy 116.505687 -127.20453) (xy 116.478512 -127.146593)
			(xy 116.45882 -127.085705) (xy 116.452396 -127.054356) (xy 116.452396 -127.054102) (xy 116.449858 -127.043837)
			(xy 116.437779 -127.02651) (xy 116.429028 -127.020574) (xy 116.365274 -126.981204) (xy 116.356007 -126.976189)
			(xy 116.335162 -126.973287) (xy 116.324888 -126.975616) (xy 116.324634 -126.975616) (xy 116.290673 -126.984632)
			(xy 116.221082 -126.994326) (xy 116.18595 -126.99492) (xy 116.185696 -126.99492) (xy 116.153736 -126.994394)
			(xy 116.09032 -126.986382) (xy 116.028408 -126.970485) (xy 115.968976 -126.946954) (xy 115.912963 -126.91616)
			(xy 115.86125 -126.878589) (xy 115.814655 -126.834832) (xy 115.773911 -126.785581) (xy 115.739661 -126.731611)
			(xy 115.712445 -126.673774) (xy 115.692692 -126.612982) (xy 115.680715 -126.550194) (xy 115.676701 -126.4864)
			(xy 114.571865 -126.4864) (xy 114.541406 -126.532439) (xy 114.504189 -126.573976) (xy 114.461321 -126.609651)
			(xy 114.413715 -126.638705) (xy 114.362386 -126.660517) (xy 114.308429 -126.674623) (xy 114.252992 -126.680723)
			(xy 114.197258 -126.678686) (xy 114.142415 -126.668556) (xy 114.089631 -126.650549) (xy 114.040031 -126.625048)
			(xy 113.994673 -126.592597) (xy 113.954524 -126.553888) (xy 113.920438 -126.509745) (xy 113.893142 -126.46111)
			(xy 113.873219 -126.409019) (xy 113.861093 -126.354582) (xy 113.857022 -126.29896) (xy 108.374333 -126.29896)
			(xy 108.355702 -126.346014) (xy 108.324908 -126.402029) (xy 108.287335 -126.453744) (xy 108.243578 -126.500341)
			(xy 108.194325 -126.541086) (xy 108.140354 -126.575337) (xy 108.082515 -126.602554) (xy 108.021722 -126.622307)
			(xy 107.958932 -126.634285) (xy 107.895136 -126.638299) (xy 107.83134 -126.634285) (xy 107.76855 -126.622307)
			(xy 107.707757 -126.602554) (xy 107.649918 -126.575337) (xy 107.595947 -126.541086) (xy 107.546694 -126.500341)
			(xy 107.502937 -126.453744) (xy 107.465364 -126.402029) (xy 107.43457 -126.346014) (xy 107.411038 -126.286581)
			(xy 107.395141 -126.224667) (xy 107.38713 -126.161249) (xy 104.898249 -126.161249) (xy 104.897942 -126.180807)
			(xy 104.889931 -126.244225) (xy 104.874034 -126.306139) (xy 104.850502 -126.365572) (xy 104.819708 -126.421587)
			(xy 104.782135 -126.473302) (xy 104.738378 -126.519899) (xy 104.689125 -126.560644) (xy 104.635154 -126.594895)
			(xy 104.577315 -126.622112) (xy 104.516522 -126.641865) (xy 104.453732 -126.653843) (xy 104.389936 -126.657857)
			(xy 104.32614 -126.653843) (xy 104.26335 -126.641865) (xy 104.202557 -126.622112) (xy 104.144718 -126.594895)
			(xy 104.090747 -126.560644) (xy 104.041494 -126.519899) (xy 103.997737 -126.473302) (xy 103.960164 -126.421587)
			(xy 103.92937 -126.365572) (xy 103.905838 -126.306139) (xy 103.889941 -126.244225) (xy 103.88193 -126.180807)
			(xy 86.947604 -126.180807) (xy 86.945593 -126.196727) (xy 86.929696 -126.258641) (xy 86.906164 -126.318074)
			(xy 86.87537 -126.374089) (xy 86.837797 -126.425804) (xy 86.79404 -126.472401) (xy 86.744787 -126.513146)
			(xy 86.690816 -126.547397) (xy 86.632977 -126.574614) (xy 86.572184 -126.594367) (xy 86.509394 -126.606345)
			(xy 86.445598 -126.610359) (xy 86.381802 -126.606345) (xy 86.319012 -126.594367) (xy 86.258219 -126.574614)
			(xy 86.20038 -126.547397) (xy 86.146409 -126.513146) (xy 86.097156 -126.472401) (xy 86.053399 -126.425804)
			(xy 86.015826 -126.374089) (xy 85.985032 -126.318074) (xy 85.9615 -126.258641) (xy 85.945603 -126.196727)
			(xy 85.937592 -126.133309) (xy 6.11378 -126.133309) (xy 6.11378 -127.874014) (xy 34.642552 -127.874014)
			(xy 34.642552 -127.87376) (xy 34.643056 -127.831412) (xy 34.651107 -127.747098) (xy 34.667136 -127.663932)
			(xy 34.690997 -127.582665) (xy 34.722476 -127.504035) (xy 34.761287 -127.428754) (xy 34.807077 -127.357502)
			(xy 34.859433 -127.290926) (xy 34.917881 -127.229628) (xy 34.981891 -127.174163) (xy 35.050883 -127.125034)
			(xy 35.124233 -127.082685) (xy 35.201276 -127.047501) (xy 35.281315 -127.019799) (xy 35.363624 -126.999831)
			(xy 35.447459 -126.987778) (xy 35.53206 -126.983748) (xy 35.616661 -126.987778) (xy 35.700496 -126.999831)
			(xy 35.782805 -127.019799) (xy 35.862844 -127.047501) (xy 35.939887 -127.082685) (xy 36.013237 -127.125034)
			(xy 36.082229 -127.174163) (xy 36.146239 -127.229628) (xy 36.204687 -127.290926) (xy 36.257043 -127.357502)
			(xy 36.302833 -127.428754) (xy 36.341644 -127.504035) (xy 36.342299 -127.505671) (xy 110.51133 -127.505671)
			(xy 110.51133 -127.441749) (xy 110.519341 -127.378331) (xy 110.535238 -127.316417) (xy 110.55877 -127.256984)
			(xy 110.589564 -127.200969) (xy 110.627137 -127.149254) (xy 110.670894 -127.102657) (xy 110.720147 -127.061912)
			(xy 110.774118 -127.027661) (xy 110.831957 -127.000444) (xy 110.89275 -126.980691) (xy 110.95554 -126.968713)
			(xy 111.019336 -126.9647) (xy 111.083132 -126.968713) (xy 111.145922 -126.980691) (xy 111.206715 -127.000444)
			(xy 111.264554 -127.027661) (xy 111.318525 -127.061912) (xy 111.367778 -127.102657) (xy 111.411535 -127.149254)
			(xy 111.449108 -127.200969) (xy 111.479902 -127.256984) (xy 111.503434 -127.316417) (xy 111.519331 -127.378331)
			(xy 111.527342 -127.441749) (xy 111.527844 -127.47371) (xy 111.527342 -127.505671) (xy 111.519331 -127.569089)
			(xy 111.510114 -127.604985) (xy 112.187476 -127.604985) (xy 112.187476 -127.541063) (xy 112.195487 -127.477645)
			(xy 112.211384 -127.415731) (xy 112.234916 -127.356298) (xy 112.26571 -127.300283) (xy 112.303283 -127.248568)
			(xy 112.34704 -127.201971) (xy 112.396293 -127.161226) (xy 112.450264 -127.126975) (xy 112.508103 -127.099758)
			(xy 112.568896 -127.080005) (xy 112.631686 -127.068027) (xy 112.695482 -127.064014) (xy 112.759278 -127.068027)
			(xy 112.822068 -127.080005) (xy 112.882861 -127.099758) (xy 112.9407 -127.126975) (xy 112.994671 -127.161226)
			(xy 113.043924 -127.201971) (xy 113.087681 -127.248568) (xy 113.125254 -127.300283) (xy 113.156048 -127.356298)
			(xy 113.17958 -127.415731) (xy 113.195477 -127.477645) (xy 113.203488 -127.541063) (xy 113.20399 -127.573024)
			(xy 113.203791 -127.5857) (xy 156.071113 -127.5857) (xy 156.075127 -127.521909) (xy 156.087103 -127.459124)
			(xy 156.106854 -127.398334) (xy 156.134068 -127.3405) (xy 156.168316 -127.286532) (xy 156.209058 -127.237282)
			(xy 156.25565 -127.193527) (xy 156.307359 -127.155956) (xy 156.36337 -127.125162) (xy 156.422798 -127.101631)
			(xy 156.484706 -127.085733) (xy 156.548119 -127.077719) (xy 156.580078 -127.077216) (xy 156.610798 -127.077696)
			(xy 156.671792 -127.085093) (xy 156.73145 -127.099781) (xy 156.788906 -127.121548) (xy 156.843321 -127.150076)
			(xy 156.868876 -127.167132) (xy 156.877561 -127.172525) (xy 156.897578 -127.176586) (xy 156.917595 -127.172525)
			(xy 156.92628 -127.167132) (xy 156.951845 -127.150091) (xy 157.006256 -127.121554) (xy 157.063708 -127.099779)
			(xy 157.123365 -127.085083) (xy 157.184358 -127.07768) (xy 157.215078 -127.077216) (xy 157.247043 -127.077648)
			(xy 157.310468 -127.085658) (xy 157.37239 -127.101554) (xy 157.431831 -127.125086) (xy 157.487854 -127.155883)
			(xy 157.539575 -127.193458) (xy 157.586178 -127.23722) (xy 157.626929 -127.286478) (xy 157.661185 -127.340454)
			(xy 157.688406 -127.398299) (xy 157.708162 -127.4591) (xy 157.720141 -127.521897) (xy 157.724156 -127.5857)
			(xy 157.720141 -127.649503) (xy 157.708162 -127.7123) (xy 157.688406 -127.773101) (xy 157.661185 -127.830946)
			(xy 157.626929 -127.884922) (xy 157.586178 -127.93418) (xy 157.539575 -127.977942) (xy 157.525357 -127.988271)
			(xy 158.084768 -127.988271) (xy 158.084768 -127.924349) (xy 158.092779 -127.860931) (xy 158.108676 -127.799017)
			(xy 158.132208 -127.739584) (xy 158.163002 -127.683569) (xy 158.200575 -127.631854) (xy 158.244332 -127.585257)
			(xy 158.293585 -127.544512) (xy 158.347556 -127.510261) (xy 158.405395 -127.483044) (xy 158.466188 -127.463291)
			(xy 158.528978 -127.451313) (xy 158.592774 -127.4473) (xy 158.65657 -127.451313) (xy 158.71936 -127.463291)
			(xy 158.780153 -127.483044) (xy 158.837992 -127.510261) (xy 158.891963 -127.544512) (xy 158.941216 -127.585257)
			(xy 158.984973 -127.631854) (xy 159.022546 -127.683569) (xy 159.05334 -127.739584) (xy 159.063908 -127.766275)
			(xy 162.827456 -127.766275) (xy 162.827456 -127.702353) (xy 162.835467 -127.638935) (xy 162.851364 -127.577021)
			(xy 162.874896 -127.517588) (xy 162.90569 -127.461573) (xy 162.943263 -127.409858) (xy 162.98702 -127.363261)
			(xy 163.036273 -127.322516) (xy 163.090244 -127.288265) (xy 163.148083 -127.261048) (xy 163.208876 -127.241295)
			(xy 163.271666 -127.229317) (xy 163.335462 -127.225304) (xy 163.399258 -127.229317) (xy 163.462048 -127.241295)
			(xy 163.522841 -127.261048) (xy 163.58068 -127.288265) (xy 163.634651 -127.322516) (xy 163.683904 -127.363261)
			(xy 163.727661 -127.409858) (xy 163.765234 -127.461573) (xy 163.796028 -127.517588) (xy 163.81956 -127.577021)
			(xy 163.835457 -127.638935) (xy 163.843468 -127.702353) (xy 163.84397 -127.734314) (xy 163.843468 -127.766275)
			(xy 163.835457 -127.829693) (xy 163.81956 -127.891607) (xy 163.796028 -127.95104) (xy 163.765234 -128.007055)
			(xy 163.727661 -128.05877) (xy 163.683904 -128.105367) (xy 163.634651 -128.146112) (xy 163.58068 -128.180363)
			(xy 163.522841 -128.20758) (xy 163.462048 -128.227333) (xy 163.399258 -128.239311) (xy 163.335462 -128.243325)
			(xy 163.271666 -128.239311) (xy 163.208876 -128.227333) (xy 163.148083 -128.20758) (xy 163.090244 -128.180363)
			(xy 163.036273 -128.146112) (xy 162.98702 -128.105367) (xy 162.943263 -128.05877) (xy 162.90569 -128.007055)
			(xy 162.874896 -127.95104) (xy 162.851364 -127.891607) (xy 162.835467 -127.829693) (xy 162.827456 -127.766275)
			(xy 159.063908 -127.766275) (xy 159.076872 -127.799017) (xy 159.092769 -127.860931) (xy 159.10078 -127.924349)
			(xy 159.101282 -127.95631) (xy 159.10078 -127.988271) (xy 159.092769 -128.051689) (xy 159.076872 -128.113603)
			(xy 159.05334 -128.173036) (xy 159.022546 -128.229051) (xy 158.984973 -128.280766) (xy 158.941216 -128.327363)
			(xy 158.891963 -128.368108) (xy 158.837992 -128.402359) (xy 158.780153 -128.429576) (xy 158.71936 -128.449329)
			(xy 158.65657 -128.461307) (xy 158.592774 -128.465321) (xy 158.528978 -128.461307) (xy 158.466188 -128.449329)
			(xy 158.405395 -128.429576) (xy 158.347556 -128.402359) (xy 158.293585 -128.368108) (xy 158.244332 -128.327363)
			(xy 158.200575 -128.280766) (xy 158.163002 -128.229051) (xy 158.132208 -128.173036) (xy 158.108676 -128.113603)
			(xy 158.092779 -128.051689) (xy 158.084768 -127.988271) (xy 157.525357 -127.988271) (xy 157.487854 -128.015517)
			(xy 157.431831 -128.046314) (xy 157.37239 -128.069846) (xy 157.310468 -128.085742) (xy 157.247043 -128.093752)
			(xy 157.215078 -128.094232) (xy 157.184357 -128.093766) (xy 157.123364 -128.086365) (xy 157.063705 -128.071672)
			(xy 157.00625 -128.049903) (xy 156.951834 -128.021373) (xy 156.92628 -128.004316) (xy 156.917595 -127.998923)
			(xy 156.897578 -127.994862) (xy 156.877561 -127.998923) (xy 156.868876 -128.004316) (xy 156.843327 -128.021382)
			(xy 156.788911 -128.049913) (xy 156.731455 -128.071682) (xy 156.671794 -128.086373) (xy 156.610799 -128.093771)
			(xy 156.580078 -128.094232) (xy 156.548119 -128.093681) (xy 156.484706 -128.085667) (xy 156.422798 -128.069769)
			(xy 156.36337 -128.046238) (xy 156.307359 -128.015444) (xy 156.25565 -127.977873) (xy 156.209058 -127.934118)
			(xy 156.168316 -127.884868) (xy 156.134068 -127.8309) (xy 156.106854 -127.773066) (xy 156.087103 -127.712276)
			(xy 156.075127 -127.649491) (xy 156.071113 -127.5857) (xy 113.203791 -127.5857) (xy 113.203488 -127.604985)
			(xy 113.195477 -127.668403) (xy 113.17958 -127.730317) (xy 113.156048 -127.78975) (xy 113.125254 -127.845765)
			(xy 113.087681 -127.89748) (xy 113.043924 -127.944077) (xy 112.994671 -127.984822) (xy 112.9407 -128.019073)
			(xy 112.882861 -128.04629) (xy 112.822068 -128.066043) (xy 112.759278 -128.078021) (xy 112.695482 -128.082035)
			(xy 112.631686 -128.078021) (xy 112.568896 -128.066043) (xy 112.508103 -128.04629) (xy 112.450264 -128.019073)
			(xy 112.396293 -127.984822) (xy 112.34704 -127.944077) (xy 112.303283 -127.89748) (xy 112.26571 -127.845765)
			(xy 112.234916 -127.78975) (xy 112.211384 -127.730317) (xy 112.195487 -127.668403) (xy 112.187476 -127.604985)
			(xy 111.510114 -127.604985) (xy 111.503434 -127.631003) (xy 111.479902 -127.690436) (xy 111.449108 -127.746451)
			(xy 111.411535 -127.798166) (xy 111.367778 -127.844763) (xy 111.318525 -127.885508) (xy 111.264554 -127.919759)
			(xy 111.206715 -127.946976) (xy 111.145922 -127.966729) (xy 111.083132 -127.978707) (xy 111.019336 -127.982721)
			(xy 110.95554 -127.978707) (xy 110.89275 -127.966729) (xy 110.831957 -127.946976) (xy 110.774118 -127.919759)
			(xy 110.720147 -127.885508) (xy 110.670894 -127.844763) (xy 110.627137 -127.798166) (xy 110.589564 -127.746451)
			(xy 110.55877 -127.690436) (xy 110.535238 -127.631003) (xy 110.519341 -127.569089) (xy 110.51133 -127.505671)
			(xy 36.342299 -127.505671) (xy 36.373123 -127.582665) (xy 36.396984 -127.663932) (xy 36.413013 -127.747098)
			(xy 36.421064 -127.831412) (xy 36.421568 -127.87376) (xy 36.421568 -127.874014) (xy 36.421101 -127.914407)
			(xy 36.413782 -127.99486) (xy 36.399196 -128.074318) (xy 36.377464 -128.152126) (xy 36.348765 -128.227641)
			(xy 36.313335 -128.300243) (xy 36.29279 -128.335024) (xy 36.288157 -128.343492) (xy 36.285002 -128.362521)
			(xy 36.289054 -128.38138) (xy 36.29406 -128.389634) (xy 36.31799 -128.426247) (xy 36.359289 -128.503358)
			(xy 36.392816 -128.584152) (xy 36.418246 -128.667848) (xy 36.435333 -128.753637) (xy 36.440267 -128.8037)
			(xy 96.565622 -128.8037) (xy 96.569637 -128.739893) (xy 96.581618 -128.677092) (xy 96.601375 -128.616288)
			(xy 96.628598 -128.55844) (xy 96.662856 -128.50446) (xy 96.70361 -128.4552) (xy 96.750217 -128.411436)
			(xy 96.801942 -128.373859) (xy 96.857969 -128.343062) (xy 96.917414 -128.31953) (xy 96.97934 -128.303634)
			(xy 97.042769 -128.295625) (xy 97.074736 -128.295146) (xy 97.106616 -128.295675) (xy 97.169873 -128.303666)
			(xy 97.231634 -128.319505) (xy 97.290929 -128.342943) (xy 97.346828 -128.373613) (xy 97.372932 -128.39192)
			(xy 97.382086 -128.397976) (xy 97.403586 -128.402292) (xy 97.424924 -128.397236) (xy 97.433892 -128.390904)
			(xy 97.460743 -128.370752) (xy 97.518713 -128.33689) (xy 97.580637 -128.310955) (xy 97.645436 -128.293398)
			(xy 97.711983 -128.284527) (xy 97.74555 -128.28397) (xy 97.746058 -128.28397) (xy 97.778021 -128.284492)
			(xy 97.841443 -128.2925) (xy 97.903361 -128.308393) (xy 97.962798 -128.331922) (xy 98.018818 -128.362715)
			(xy 98.070537 -128.400286) (xy 98.117138 -128.444044) (xy 98.157887 -128.493298) (xy 98.192142 -128.547271)
			(xy 98.219361 -128.605112) (xy 98.239116 -128.665908) (xy 98.251095 -128.728701) (xy 98.25511 -128.7925)
			(xy 98.252397 -128.835615) (xy 100.37673 -128.835615) (xy 100.37673 -128.771693) (xy 100.384741 -128.708275)
			(xy 100.400638 -128.646361) (xy 100.42417 -128.586928) (xy 100.454964 -128.530913) (xy 100.492537 -128.479198)
			(xy 100.536294 -128.432601) (xy 100.585547 -128.391856) (xy 100.639518 -128.357605) (xy 100.697357 -128.330388)
			(xy 100.75815 -128.310635) (xy 100.82094 -128.298657) (xy 100.884736 -128.294644) (xy 100.948532 -128.298657)
			(xy 101.011322 -128.310635) (xy 101.072115 -128.330388) (xy 101.129954 -128.357605) (xy 101.183925 -128.391856)
			(xy 101.233178 -128.432601) (xy 101.276935 -128.479198) (xy 101.314508 -128.530913) (xy 101.345302 -128.586928)
			(xy 101.368834 -128.646361) (xy 101.384731 -128.708275) (xy 101.392742 -128.771693) (xy 101.393244 -128.803654)
			(xy 101.392815 -128.830958) (xy 101.773609 -128.830958) (xy 101.773609 -128.776442) (xy 101.781368 -128.722482)
			(xy 101.796728 -128.670174) (xy 101.819376 -128.620586) (xy 101.84885 -128.574725) (xy 101.884552 -128.533527)
			(xy 101.925754 -128.497829) (xy 101.971618 -128.468358) (xy 102.021208 -128.445715) (xy 102.073517 -128.43036)
			(xy 102.127478 -128.422607) (xy 102.154736 -128.422146) (xy 102.182439 -128.422621) (xy 102.237263 -128.430635)
			(xy 102.290353 -128.446491) (xy 102.340593 -128.469854) (xy 102.364032 -128.48463) (xy 102.372108 -128.489467)
			(xy 102.390483 -128.493493) (xy 102.399846 -128.492504) (xy 102.430072 -128.487678) (xy 102.439655 -128.485756)
			(xy 102.456383 -128.475677) (xy 102.462584 -128.46812) (xy 102.487767 -128.435818) (xy 102.543148 -128.375465)
			(xy 102.603842 -128.320457) (xy 102.669333 -128.27126) (xy 102.739069 -128.228289) (xy 102.812458 -128.191909)
			(xy 102.88888 -128.162427) (xy 102.967688 -128.140093) (xy 103.048216 -128.125095) (xy 103.12978 -128.117562)
			(xy 103.170736 -128.117092) (xy 103.213083 -128.117597) (xy 103.297394 -128.125651) (xy 103.380558 -128.141683)
			(xy 103.461821 -128.165547) (xy 103.540448 -128.197027) (xy 103.615727 -128.235839) (xy 103.686976 -128.28163)
			(xy 103.753549 -128.333986) (xy 103.814844 -128.392434) (xy 103.870307 -128.456443) (xy 103.919433 -128.525434)
			(xy 103.96178 -128.598782) (xy 103.996962 -128.675824) (xy 104.024663 -128.755861) (xy 104.038125 -128.811355)
			(xy 105.278851 -128.811355) (xy 105.278851 -128.756845) (xy 105.286609 -128.702891) (xy 105.301967 -128.650589)
			(xy 105.324613 -128.601006) (xy 105.354084 -128.555151) (xy 105.389782 -128.513957) (xy 105.43098 -128.478263)
			(xy 105.476838 -128.448796) (xy 105.526423 -128.426155) (xy 105.578726 -128.410802) (xy 105.632681 -128.403049)
			(xy 105.659936 -128.402588) (xy 105.687982 -128.4031) (xy 105.74347 -128.41131) (xy 105.79716 -128.427549)
			(xy 105.847898 -128.451466) (xy 105.871518 -128.466596) (xy 105.879138 -128.471676) (xy 105.897172 -128.475994)
			(xy 105.982008 -128.46431) (xy 105.998264 -128.45542) (xy 106.00436 -128.448562) (xy 106.032492 -128.416988)
			(xy 106.093781 -128.358712) (xy 106.160323 -128.306513) (xy 106.231516 -128.260864) (xy 106.306719 -128.222174)
			(xy 106.385254 -128.190794) (xy 106.466412 -128.167006) (xy 106.54946 -128.151025) (xy 106.63365 -128.142995)
			(xy 106.675936 -128.142492) (xy 106.718283 -128.142997) (xy 106.802594 -128.151051) (xy 106.885758 -128.167083)
			(xy 106.967021 -128.190947) (xy 107.045648 -128.222427) (xy 107.120927 -128.261239) (xy 107.192176 -128.30703)
			(xy 107.258749 -128.359386) (xy 107.320044 -128.417834) (xy 107.375507 -128.481843) (xy 107.424633 -128.550834)
			(xy 107.46698 -128.624182) (xy 107.502162 -128.701224) (xy 107.529863 -128.781261) (xy 107.54983 -128.863568)
			(xy 107.561883 -128.947401) (xy 107.565913 -129.032) (xy 107.561883 -129.116599) (xy 107.54983 -129.200432)
			(xy 107.529863 -129.282739) (xy 107.502162 -129.362776) (xy 107.46698 -129.439818) (xy 107.424633 -129.513166)
			(xy 107.375507 -129.582157) (xy 107.320044 -129.646166) (xy 107.295057 -129.669992) (xy 108.07606 -129.669992)
			(xy 108.081268 -129.60712) (xy 108.094213 -129.545374) (xy 108.114697 -129.485704) (xy 108.142404 -129.429026)
			(xy 108.176909 -129.376211) (xy 108.217682 -129.328069) (xy 108.264096 -129.28534) (xy 108.31544 -129.248681)
			(xy 108.370924 -129.218654) (xy 108.429696 -129.195721) (xy 108.490853 -129.180233) (xy 108.553456 -129.17243)
			(xy 108.585 -129.171954) (xy 108.629704 -129.173986) (xy 108.643607 -129.174638) (xy 108.670935 -129.169452)
			(xy 108.695851 -129.157088) (xy 108.71651 -129.138462) (xy 108.731379 -129.114954) (xy 108.739356 -129.088307)
			(xy 108.739851 -129.060496) (xy 108.732827 -129.033582) (xy 108.726224 -129.021332) (xy 108.70971 -128.991995)
			(xy 108.683677 -128.929909) (xy 108.666063 -128.864932) (xy 108.657175 -128.798199) (xy 108.656628 -128.764538)
			(xy 108.657027 -128.732995) (xy 108.664826 -128.670392) (xy 108.680308 -128.609234) (xy 108.703237 -128.550461)
			(xy 108.733259 -128.494976) (xy 108.769913 -128.44363) (xy 108.812637 -128.397212) (xy 108.860775 -128.356436)
			(xy 108.913586 -128.321927) (xy 108.970261 -128.294215) (xy 109.029928 -128.273726) (xy 109.091671 -128.260775)
			(xy 109.154542 -128.255561) (xy 109.217575 -128.258163) (xy 109.279802 -128.268543) (xy 109.340268 -128.286539)
			(xy 109.398043 -128.311877) (xy 109.45224 -128.344166) (xy 109.502028 -128.382911) (xy 109.508709 -128.389591)
			(xy 113.29009 -128.389591) (xy 113.29009 -128.325669) (xy 113.298101 -128.262251) (xy 113.313998 -128.200337)
			(xy 113.33753 -128.140904) (xy 113.368324 -128.084889) (xy 113.405897 -128.033174) (xy 113.449654 -127.986577)
			(xy 113.498907 -127.945832) (xy 113.552878 -127.911581) (xy 113.610717 -127.884364) (xy 113.67151 -127.864611)
			(xy 113.7343 -127.852633) (xy 113.798096 -127.84862) (xy 113.861892 -127.852633) (xy 113.924682 -127.864611)
			(xy 113.985475 -127.884364) (xy 114.043314 -127.911581) (xy 114.097285 -127.945832) (xy 114.146538 -127.986577)
			(xy 114.190295 -128.033174) (xy 114.227868 -128.084889) (xy 114.258662 -128.140904) (xy 114.282194 -128.200337)
			(xy 114.298091 -128.262251) (xy 114.306102 -128.325669) (xy 114.306604 -128.35763) (xy 114.306102 -128.389591)
			(xy 114.298091 -128.453009) (xy 114.282194 -128.514923) (xy 114.278617 -128.523957) (xy 159.704526 -128.523957)
			(xy 159.704526 -128.460035) (xy 159.712537 -128.396617) (xy 159.728434 -128.334703) (xy 159.751966 -128.27527)
			(xy 159.78276 -128.219255) (xy 159.820333 -128.16754) (xy 159.86409 -128.120943) (xy 159.913343 -128.080198)
			(xy 159.967314 -128.045947) (xy 160.025153 -128.01873) (xy 160.085946 -127.998977) (xy 160.148736 -127.986999)
			(xy 160.212532 -127.982986) (xy 160.276328 -127.986999) (xy 160.339118 -127.998977) (xy 160.399911 -128.01873)
			(xy 160.45775 -128.045947) (xy 160.511721 -128.080198) (xy 160.560974 -128.120943) (xy 160.604731 -128.16754)
			(xy 160.642304 -128.219255) (xy 160.673098 -128.27527) (xy 160.69663 -128.334703) (xy 160.712527 -128.396617)
			(xy 160.720148 -128.456944) (xy 164.659816 -128.456944) (xy 164.663887 -128.401322) (xy 164.676013 -128.346885)
			(xy 164.695936 -128.294794) (xy 164.723232 -128.246159) (xy 164.757318 -128.202016) (xy 164.797467 -128.163307)
			(xy 164.842825 -128.130856) (xy 164.892425 -128.105355) (xy 164.945209 -128.087348) (xy 165.000052 -128.077218)
			(xy 165.055786 -128.075181) (xy 165.111223 -128.081281) (xy 165.16518 -128.095387) (xy 165.216509 -128.117199)
			(xy 165.264115 -128.146253) (xy 165.306983 -128.181928) (xy 165.3442 -128.223465) (xy 165.374973 -128.269978)
			(xy 165.398645 -128.320475) (xy 165.414713 -128.373882) (xy 165.422833 -128.429058) (xy 165.423342 -128.456944)
			(xy 165.422833 -128.48483) (xy 165.414713 -128.540006) (xy 165.398645 -128.593413) (xy 165.374973 -128.64391)
			(xy 165.3442 -128.690423) (xy 165.306983 -128.73196) (xy 165.264115 -128.767635) (xy 165.216509 -128.796689)
			(xy 165.16518 -128.818501) (xy 165.111223 -128.832607) (xy 165.055786 -128.838707) (xy 165.000052 -128.83667)
			(xy 164.945209 -128.82654) (xy 164.892425 -128.808533) (xy 164.842825 -128.783032) (xy 164.797467 -128.750581)
			(xy 164.757318 -128.711872) (xy 164.723232 -128.667729) (xy 164.695936 -128.619094) (xy 164.676013 -128.567003)
			(xy 164.663887 -128.512566) (xy 164.659816 -128.456944) (xy 160.720148 -128.456944) (xy 160.720538 -128.460035)
			(xy 160.72104 -128.491996) (xy 160.720538 -128.523957) (xy 160.712527 -128.587375) (xy 160.69663 -128.649289)
			(xy 160.673098 -128.708722) (xy 160.642304 -128.764737) (xy 160.604731 -128.816452) (xy 160.560974 -128.863049)
			(xy 160.511721 -128.903794) (xy 160.45775 -128.938045) (xy 160.399911 -128.965262) (xy 160.339118 -128.985015)
			(xy 160.276328 -128.996993) (xy 160.212532 -129.001007) (xy 160.148736 -128.996993) (xy 160.085946 -128.985015)
			(xy 160.025153 -128.965262) (xy 159.967314 -128.938045) (xy 159.913343 -128.903794) (xy 159.86409 -128.863049)
			(xy 159.820333 -128.816452) (xy 159.78276 -128.764737) (xy 159.751966 -128.708722) (xy 159.728434 -128.649289)
			(xy 159.712537 -128.587375) (xy 159.704526 -128.523957) (xy 114.278617 -128.523957) (xy 114.258662 -128.574356)
			(xy 114.227868 -128.630371) (xy 114.190295 -128.682086) (xy 114.146538 -128.728683) (xy 114.097285 -128.769428)
			(xy 114.043314 -128.803679) (xy 113.985475 -128.830896) (xy 113.924682 -128.850649) (xy 113.861892 -128.862627)
			(xy 113.798096 -128.866641) (xy 113.7343 -128.862627) (xy 113.67151 -128.850649) (xy 113.610717 -128.830896)
			(xy 113.552878 -128.803679) (xy 113.498907 -128.769428) (xy 113.449654 -128.728683) (xy 113.405897 -128.682086)
			(xy 113.368324 -128.630371) (xy 113.33753 -128.574356) (xy 113.313998 -128.514923) (xy 113.298101 -128.453009)
			(xy 113.29009 -128.389591) (xy 109.508709 -128.389591) (xy 109.54664 -128.427517) (xy 109.585392 -128.477298)
			(xy 109.617689 -128.531491) (xy 109.643035 -128.589262) (xy 109.661041 -128.649725) (xy 109.671429 -128.711951)
			(xy 109.674041 -128.774984) (xy 109.668835 -128.837856) (xy 109.655893 -128.899601) (xy 109.635413 -128.959271)
			(xy 109.60771 -129.015949) (xy 109.573209 -129.068766) (xy 109.532439 -129.116909) (xy 109.486028 -129.15964)
			(xy 109.434687 -129.196302) (xy 109.379206 -129.226332) (xy 109.320436 -129.249269) (xy 109.259281 -129.26476)
			(xy 109.196679 -129.272568) (xy 109.165136 -129.273046) (xy 109.120432 -129.271014) (xy 109.106527 -129.270391)
			(xy 109.0792 -129.275569) (xy 109.054282 -129.287927) (xy 109.033622 -129.306549) (xy 109.018752 -129.330054)
			(xy 109.010774 -129.356699) (xy 109.01028 -129.384509) (xy 109.017307 -129.41142) (xy 109.023912 -129.423668)
			(xy 109.040429 -129.453004) (xy 109.066461 -129.51509) (xy 109.084074 -129.580067) (xy 109.092961 -129.646801)
			(xy 109.093508 -129.680462) (xy 109.093073 -129.712006) (xy 109.085274 -129.77461) (xy 109.069791 -129.835768)
			(xy 109.046862 -129.894542) (xy 109.016839 -129.950028) (xy 108.980184 -130.001374) (xy 108.938241 -130.046941)
			(xy 111.78133 -130.046941) (xy 111.78133 -129.983019) (xy 111.789341 -129.919601) (xy 111.805238 -129.857687)
			(xy 111.82877 -129.798254) (xy 111.859564 -129.742239) (xy 111.897137 -129.690524) (xy 111.940894 -129.643927)
			(xy 111.990147 -129.603182) (xy 112.044118 -129.568931) (xy 112.101957 -129.541714) (xy 112.16275 -129.521961)
			(xy 112.22554 -129.509983) (xy 112.289336 -129.50597) (xy 112.353132 -129.509983) (xy 112.415922 -129.521961)
			(xy 112.476715 -129.541714) (xy 112.534554 -129.568931) (xy 112.588525 -129.603182) (xy 112.637778 -129.643927)
			(xy 112.681535 -129.690524) (xy 112.719108 -129.742239) (xy 112.749902 -129.798254) (xy 112.773434 -129.857687)
			(xy 112.789331 -129.919601) (xy 112.797342 -129.983019) (xy 112.797844 -130.01498) (xy 112.797342 -130.046941)
			(xy 113.05133 -130.046941) (xy 113.05133 -129.983019) (xy 113.059341 -129.919601) (xy 113.075238 -129.857687)
			(xy 113.09877 -129.798254) (xy 113.129564 -129.742239) (xy 113.167137 -129.690524) (xy 113.210894 -129.643927)
			(xy 113.260147 -129.603182) (xy 113.314118 -129.568931) (xy 113.371957 -129.541714) (xy 113.43275 -129.521961)
			(xy 113.49554 -129.509983) (xy 113.559336 -129.50597) (xy 113.623132 -129.509983) (xy 113.685922 -129.521961)
			(xy 113.746715 -129.541714) (xy 113.804554 -129.568931) (xy 113.858525 -129.603182) (xy 113.907778 -129.643927)
			(xy 113.951535 -129.690524) (xy 113.989108 -129.742239) (xy 114.019902 -129.798254) (xy 114.043434 -129.857687)
			(xy 114.059331 -129.919601) (xy 114.067342 -129.983019) (xy 114.067844 -130.01498) (xy 114.067342 -130.046941)
			(xy 114.32133 -130.046941) (xy 114.32133 -129.983019) (xy 114.329341 -129.919601) (xy 114.345238 -129.857687)
			(xy 114.36877 -129.798254) (xy 114.399564 -129.742239) (xy 114.437137 -129.690524) (xy 114.480894 -129.643927)
			(xy 114.530147 -129.603182) (xy 114.584118 -129.568931) (xy 114.641957 -129.541714) (xy 114.70275 -129.521961)
			(xy 114.76554 -129.509983) (xy 114.829336 -129.50597) (xy 114.893132 -129.509983) (xy 114.955922 -129.521961)
			(xy 115.016715 -129.541714) (xy 115.074554 -129.568931) (xy 115.128525 -129.603182) (xy 115.177778 -129.643927)
			(xy 115.221535 -129.690524) (xy 115.259108 -129.742239) (xy 115.289902 -129.798254) (xy 115.313434 -129.857687)
			(xy 115.329331 -129.919601) (xy 115.337342 -129.983019) (xy 115.337844 -130.01498) (xy 115.337342 -130.046941)
			(xy 115.59133 -130.046941) (xy 115.59133 -129.983019) (xy 115.599341 -129.919601) (xy 115.615238 -129.857687)
			(xy 115.63877 -129.798254) (xy 115.669564 -129.742239) (xy 115.707137 -129.690524) (xy 115.750894 -129.643927)
			(xy 115.800147 -129.603182) (xy 115.854118 -129.568931) (xy 115.911957 -129.541714) (xy 115.97275 -129.521961)
			(xy 116.03554 -129.509983) (xy 116.099336 -129.50597) (xy 116.163132 -129.509983) (xy 116.225922 -129.521961)
			(xy 116.286715 -129.541714) (xy 116.344554 -129.568931) (xy 116.398525 -129.603182) (xy 116.447778 -129.643927)
			(xy 116.491535 -129.690524) (xy 116.529108 -129.742239) (xy 116.559902 -129.798254) (xy 116.583434 -129.857687)
			(xy 116.594984 -129.902669) (xy 156.636714 -129.902669) (xy 156.636714 -129.838747) (xy 156.644725 -129.775329)
			(xy 156.660622 -129.713415) (xy 156.684154 -129.653982) (xy 156.714948 -129.597967) (xy 156.752521 -129.546252)
			(xy 156.796278 -129.499655) (xy 156.845531 -129.45891) (xy 156.899502 -129.424659) (xy 156.957341 -129.397442)
			(xy 157.018134 -129.377689) (xy 157.080924 -129.365711) (xy 157.14472 -129.361698) (xy 157.208516 -129.365711)
			(xy 157.271306 -129.377689) (xy 157.332099 -129.397442) (xy 157.389938 -129.424659) (xy 157.443909 -129.45891)
			(xy 157.493162 -129.499655) (xy 157.536919 -129.546252) (xy 157.574492 -129.597967) (xy 157.605286 -129.653982)
			(xy 157.628818 -129.713415) (xy 157.644715 -129.775329) (xy 157.652726 -129.838747) (xy 157.653228 -129.870708)
			(xy 157.652726 -129.902669) (xy 157.644715 -129.966087) (xy 157.628818 -130.028001) (xy 157.605286 -130.087434)
			(xy 157.574492 -130.143449) (xy 157.536919 -130.195164) (xy 157.532718 -130.199638) (xy 161.317938 -130.199638)
			(xy 161.322009 -130.144016) (xy 161.334135 -130.089579) (xy 161.354058 -130.037488) (xy 161.381354 -129.988853)
			(xy 161.41544 -129.94471) (xy 161.455589 -129.906001) (xy 161.500947 -129.87355) (xy 161.550547 -129.848049)
			(xy 161.603331 -129.830042) (xy 161.658174 -129.819912) (xy 161.713908 -129.817875) (xy 161.769345 -129.823975)
			(xy 161.823302 -129.838081) (xy 161.874631 -129.859893) (xy 161.922237 -129.888947) (xy 161.965105 -129.924622)
			(xy 162.002322 -129.966159) (xy 162.033095 -130.012672) (xy 162.056767 -130.063169) (xy 162.072835 -130.116576)
			(xy 162.080955 -130.171752) (xy 162.081464 -130.199638) (xy 162.080955 -130.227524) (xy 162.072835 -130.2827)
			(xy 162.056767 -130.336107) (xy 162.033095 -130.386604) (xy 162.002322 -130.433117) (xy 161.965105 -130.474654)
			(xy 161.922237 -130.510329) (xy 161.874631 -130.539383) (xy 161.823302 -130.561195) (xy 161.769345 -130.575301)
			(xy 161.713908 -130.581401) (xy 161.658174 -130.579364) (xy 161.603331 -130.569234) (xy 161.550547 -130.551227)
			(xy 161.500947 -130.525726) (xy 161.455589 -130.493275) (xy 161.41544 -130.454566) (xy 161.381354 -130.410423)
			(xy 161.354058 -130.361788) (xy 161.334135 -130.309697) (xy 161.322009 -130.25526) (xy 161.317938 -130.199638)
			(xy 157.532718 -130.199638) (xy 157.493162 -130.241761) (xy 157.443909 -130.282506) (xy 157.389938 -130.316757)
			(xy 157.332099 -130.343974) (xy 157.271306 -130.363727) (xy 157.208516 -130.375705) (xy 157.14472 -130.379719)
			(xy 157.080924 -130.375705) (xy 157.018134 -130.363727) (xy 156.957341 -130.343974) (xy 156.899502 -130.316757)
			(xy 156.845531 -130.282506) (xy 156.796278 -130.241761) (xy 156.752521 -130.195164) (xy 156.714948 -130.143449)
			(xy 156.684154 -130.087434) (xy 156.660622 -130.028001) (xy 156.644725 -129.966087) (xy 156.636714 -129.902669)
			(xy 116.594984 -129.902669) (xy 116.599331 -129.919601) (xy 116.607342 -129.983019) (xy 116.607844 -130.01498)
			(xy 116.607342 -130.046941) (xy 116.599331 -130.110359) (xy 116.583434 -130.172273) (xy 116.559902 -130.231706)
			(xy 116.529108 -130.287721) (xy 116.491535 -130.339436) (xy 116.447778 -130.386033) (xy 116.398525 -130.426778)
			(xy 116.344554 -130.461029) (xy 116.286715 -130.488246) (xy 116.225922 -130.507999) (xy 116.163132 -130.519977)
			(xy 116.099336 -130.523991) (xy 116.03554 -130.519977) (xy 115.97275 -130.507999) (xy 115.911957 -130.488246)
			(xy 115.854118 -130.461029) (xy 115.800147 -130.426778) (xy 115.750894 -130.386033) (xy 115.707137 -130.339436)
			(xy 115.669564 -130.287721) (xy 115.63877 -130.231706) (xy 115.615238 -130.172273) (xy 115.599341 -130.110359)
			(xy 115.59133 -130.046941) (xy 115.337342 -130.046941) (xy 115.329331 -130.110359) (xy 115.313434 -130.172273)
			(xy 115.289902 -130.231706) (xy 115.259108 -130.287721) (xy 115.221535 -130.339436) (xy 115.177778 -130.386033)
			(xy 115.128525 -130.426778) (xy 115.074554 -130.461029) (xy 115.016715 -130.488246) (xy 114.955922 -130.507999)
			(xy 114.893132 -130.519977) (xy 114.829336 -130.523991) (xy 114.76554 -130.519977) (xy 114.70275 -130.507999)
			(xy 114.641957 -130.488246) (xy 114.584118 -130.461029) (xy 114.530147 -130.426778) (xy 114.480894 -130.386033)
			(xy 114.437137 -130.339436) (xy 114.399564 -130.287721) (xy 114.36877 -130.231706) (xy 114.345238 -130.172273)
			(xy 114.329341 -130.110359) (xy 114.32133 -130.046941) (xy 114.067342 -130.046941) (xy 114.059331 -130.110359)
			(xy 114.043434 -130.172273) (xy 114.019902 -130.231706) (xy 113.989108 -130.287721) (xy 113.951535 -130.339436)
			(xy 113.907778 -130.386033) (xy 113.858525 -130.426778) (xy 113.804554 -130.461029) (xy 113.746715 -130.488246)
			(xy 113.685922 -130.507999) (xy 113.623132 -130.519977) (xy 113.559336 -130.523991) (xy 113.49554 -130.519977)
			(xy 113.43275 -130.507999) (xy 113.371957 -130.488246) (xy 113.314118 -130.461029) (xy 113.260147 -130.426778)
			(xy 113.210894 -130.386033) (xy 113.167137 -130.339436) (xy 113.129564 -130.287721) (xy 113.09877 -130.231706)
			(xy 113.075238 -130.172273) (xy 113.059341 -130.110359) (xy 113.05133 -130.046941) (xy 112.797342 -130.046941)
			(xy 112.789331 -130.110359) (xy 112.773434 -130.172273) (xy 112.749902 -130.231706) (xy 112.719108 -130.287721)
			(xy 112.681535 -130.339436) (xy 112.637778 -130.386033) (xy 112.588525 -130.426778) (xy 112.534554 -130.461029)
			(xy 112.476715 -130.488246) (xy 112.415922 -130.507999) (xy 112.353132 -130.519977) (xy 112.289336 -130.523991)
			(xy 112.22554 -130.519977) (xy 112.16275 -130.507999) (xy 112.101957 -130.488246) (xy 112.044118 -130.461029)
			(xy 111.990147 -130.426778) (xy 111.940894 -130.386033) (xy 111.897137 -130.339436) (xy 111.859564 -130.287721)
			(xy 111.82877 -130.231706) (xy 111.805238 -130.172273) (xy 111.789341 -130.110359) (xy 111.78133 -130.046941)
			(xy 108.938241 -130.046941) (xy 108.937458 -130.047792) (xy 108.88932 -130.088569) (xy 108.836507 -130.123077)
			(xy 108.779831 -130.150789) (xy 108.720162 -130.171276) (xy 108.658418 -130.184226) (xy 108.595546 -130.189439)
			(xy 108.532512 -130.186835) (xy 108.470284 -130.176454) (xy 108.409818 -130.158456) (xy 108.352043 -130.133116)
			(xy 108.297846 -130.100825) (xy 108.248059 -130.062077) (xy 108.203448 -130.017469) (xy 108.164697 -129.967686)
			(xy 108.132401 -129.913491) (xy 108.107057 -129.855717) (xy 108.089054 -129.795253) (xy 108.078669 -129.733026)
			(xy 108.07606 -129.669992) (xy 107.295057 -129.669992) (xy 107.258749 -129.704614) (xy 107.192176 -129.75697)
			(xy 107.120927 -129.802761) (xy 107.045648 -129.841573) (xy 106.967021 -129.873053) (xy 106.885758 -129.896917)
			(xy 106.802594 -129.912949) (xy 106.718283 -129.921003) (xy 106.675936 -129.921508) (xy 106.633544 -129.921005)
			(xy 106.549144 -129.912957) (xy 106.465893 -129.89691) (xy 106.384547 -129.873011) (xy 106.305846 -129.841477)
			(xy 106.230505 -129.802593) (xy 106.159207 -129.756715) (xy 106.092601 -129.704257) (xy 106.031291 -129.645697)
			(xy 105.975834 -129.581566) (xy 105.926733 -129.512447) (xy 105.884436 -129.438968) (xy 105.849326 -129.361797)
			(xy 105.821721 -129.281633) (xy 105.81132 -129.240534) (xy 105.808771 -129.231754) (xy 105.798494 -129.216652)
			(xy 105.791254 -129.21107) (xy 105.728262 -129.166874) (xy 105.710736 -129.162302) (xy 105.701338 -129.163318)
			(xy 105.69102 -129.164383) (xy 105.670308 -129.165527) (xy 105.659936 -129.165604) (xy 105.632681 -129.165151)
			(xy 105.578726 -129.157398) (xy 105.526423 -129.142045) (xy 105.476838 -129.119404) (xy 105.43098 -129.089937)
			(xy 105.389782 -129.054243) (xy 105.354084 -129.013049) (xy 105.324613 -128.967194) (xy 105.301967 -128.917611)
			(xy 105.286609 -128.865309) (xy 105.278851 -128.811355) (xy 104.038125 -128.811355) (xy 104.04463 -128.838168)
			(xy 104.056683 -128.922001) (xy 104.060713 -129.0066) (xy 104.056683 -129.091199) (xy 104.04463 -129.175032)
			(xy 104.024663 -129.257339) (xy 103.996962 -129.337376) (xy 103.96178 -129.414418) (xy 103.919433 -129.487766)
			(xy 103.870307 -129.556757) (xy 103.814844 -129.620766) (xy 103.753549 -129.679214) (xy 103.686976 -129.73157)
			(xy 103.61915 -129.775161) (xy 104.012994 -129.775161) (xy 104.012994 -129.711239) (xy 104.021005 -129.647821)
			(xy 104.036902 -129.585907) (xy 104.060434 -129.526474) (xy 104.091228 -129.470459) (xy 104.128801 -129.418744)
			(xy 104.172558 -129.372147) (xy 104.221811 -129.331402) (xy 104.275782 -129.297151) (xy 104.333621 -129.269934)
			(xy 104.394414 -129.250181) (xy 104.457204 -129.238203) (xy 104.521 -129.23419) (xy 104.584796 -129.238203)
			(xy 104.647586 -129.250181) (xy 104.708379 -129.269934) (xy 104.766218 -129.297151) (xy 104.820189 -129.331402)
			(xy 104.869442 -129.372147) (xy 104.913199 -129.418744) (xy 104.950772 -129.470459) (xy 104.981566 -129.526474)
			(xy 105.005098 -129.585907) (xy 105.020995 -129.647821) (xy 105.029006 -129.711239) (xy 105.029508 -129.7432)
			(xy 105.029006 -129.775161) (xy 105.020995 -129.838579) (xy 105.005098 -129.900493) (xy 104.981566 -129.959926)
			(xy 104.950772 -130.015941) (xy 104.913199 -130.067656) (xy 104.869442 -130.114253) (xy 104.820189 -130.154998)
			(xy 104.766218 -130.189249) (xy 104.708379 -130.216466) (xy 104.647586 -130.236219) (xy 104.584796 -130.248197)
			(xy 104.521 -130.252211) (xy 104.457204 -130.248197) (xy 104.394414 -130.236219) (xy 104.333621 -130.216466)
			(xy 104.275782 -130.189249) (xy 104.221811 -130.154998) (xy 104.172558 -130.114253) (xy 104.128801 -130.067656)
			(xy 104.091228 -130.015941) (xy 104.060434 -129.959926) (xy 104.036902 -129.900493) (xy 104.021005 -129.838579)
			(xy 104.012994 -129.775161) (xy 103.61915 -129.775161) (xy 103.615727 -129.777361) (xy 103.540448 -129.816173)
			(xy 103.461821 -129.847653) (xy 103.380558 -129.871517) (xy 103.297394 -129.887549) (xy 103.213083 -129.895603)
			(xy 103.170736 -129.896108) (xy 103.128959 -129.895628) (xy 103.045772 -129.887805) (xy 102.963685 -129.872214)
			(xy 102.883423 -129.848993) (xy 102.805692 -129.818346) (xy 102.731178 -129.780545) (xy 102.660538 -129.735922)
			(xy 102.594394 -129.68487) (xy 102.53333 -129.62784) (xy 102.477884 -129.565334) (xy 102.428544 -129.497903)
			(xy 102.385746 -129.426142) (xy 102.349867 -129.350684) (xy 102.321223 -129.272193) (xy 102.310184 -129.231898)
			(xy 102.307342 -129.222596) (xy 102.29585 -129.206924) (xy 102.287832 -129.201418) (xy 102.261162 -129.185162)
			(xy 102.252913 -129.18063) (xy 102.234414 -129.177244) (xy 102.225094 -129.178558) (xy 102.207669 -129.18165)
			(xy 102.172432 -129.184953) (xy 102.154736 -129.185162) (xy 102.127478 -129.184793) (xy 102.073517 -129.17704)
			(xy 102.021208 -129.161685) (xy 101.971618 -129.139042) (xy 101.925754 -129.109571) (xy 101.884552 -129.073873)
			(xy 101.84885 -129.032675) (xy 101.819376 -128.986814) (xy 101.796728 -128.937226) (xy 101.781368 -128.884918)
			(xy 101.773609 -128.830958) (xy 101.392815 -128.830958) (xy 101.392742 -128.835615) (xy 101.384731 -128.899033)
			(xy 101.368834 -128.960947) (xy 101.345302 -129.02038) (xy 101.314508 -129.076395) (xy 101.276935 -129.12811)
			(xy 101.233178 -129.174707) (xy 101.183925 -129.215452) (xy 101.129954 -129.249703) (xy 101.072115 -129.27692)
			(xy 101.011322 -129.296673) (xy 100.948532 -129.308651) (xy 100.884736 -129.312665) (xy 100.82094 -129.308651)
			(xy 100.75815 -129.296673) (xy 100.697357 -129.27692) (xy 100.639518 -129.249703) (xy 100.585547 -129.215452)
			(xy 100.536294 -129.174707) (xy 100.492537 -129.12811) (xy 100.454964 -129.076395) (xy 100.42417 -129.02038)
			(xy 100.400638 -128.960947) (xy 100.384741 -128.899033) (xy 100.37673 -128.835615) (xy 98.252397 -128.835615)
			(xy 98.251095 -128.856299) (xy 98.239116 -128.919092) (xy 98.219361 -128.979888) (xy 98.192142 -129.037729)
			(xy 98.157887 -129.091702) (xy 98.117138 -129.140956) (xy 98.070537 -129.184714) (xy 98.018818 -129.222285)
			(xy 97.962798 -129.253078) (xy 97.903361 -129.276607) (xy 97.841443 -129.2925) (xy 97.778021 -129.300508)
			(xy 97.746058 -129.300986) (xy 97.714178 -129.300454) (xy 97.650922 -129.292463) (xy 97.589161 -129.276625)
			(xy 97.529865 -129.253187) (xy 97.473966 -129.222519) (xy 97.447862 -129.204212) (xy 97.438713 -129.198147)
			(xy 97.417209 -129.19383) (xy 97.395869 -129.198892) (xy 97.386902 -129.205228) (xy 97.360056 -129.225388)
			(xy 97.302084 -129.259248) (xy 97.240159 -129.285181) (xy 97.175359 -129.302736) (xy 97.108812 -129.311606)
			(xy 97.075244 -129.312162) (xy 97.074736 -129.312162) (xy 97.042769 -129.311775) (xy 96.97934 -129.303766)
			(xy 96.917414 -129.28787) (xy 96.857969 -129.264338) (xy 96.801942 -129.233541) (xy 96.750217 -129.195964)
			(xy 96.70361 -129.1522) (xy 96.662856 -129.10294) (xy 96.628598 -129.04896) (xy 96.601375 -128.991112)
			(xy 96.581618 -128.930308) (xy 96.569637 -128.867507) (xy 96.565622 -128.8037) (xy 36.440267 -128.8037)
			(xy 36.443912 -128.840689) (xy 36.444428 -128.884426) (xy 36.444428 -128.88468) (xy 36.443924 -128.927028)
			(xy 36.435873 -129.011342) (xy 36.419844 -129.094508) (xy 36.395983 -129.175775) (xy 36.364504 -129.254405)
			(xy 36.325693 -129.329686) (xy 36.279903 -129.400938) (xy 36.227547 -129.467514) (xy 36.169099 -129.528812)
			(xy 36.105089 -129.584277) (xy 36.036097 -129.633406) (xy 35.962747 -129.675755) (xy 35.885704 -129.710939)
			(xy 35.805665 -129.738641) (xy 35.723356 -129.758609) (xy 35.639521 -129.770662) (xy 35.55492 -129.774693)
			(xy 35.470319 -129.770662) (xy 35.386484 -129.758609) (xy 35.304175 -129.738641) (xy 35.224136 -129.710939)
			(xy 35.147093 -129.675755) (xy 35.073743 -129.633406) (xy 35.004751 -129.584277) (xy 34.940741 -129.528812)
			(xy 34.882293 -129.467514) (xy 34.829937 -129.400938) (xy 34.784147 -129.329686) (xy 34.745336 -129.254405)
			(xy 34.713857 -129.175775) (xy 34.689996 -129.094508) (xy 34.673967 -129.011342) (xy 34.665916 -128.927028)
			(xy 34.665412 -128.88468) (xy 34.665412 -128.884426) (xy 34.665854 -128.844033) (xy 34.673178 -128.763579)
			(xy 34.687769 -128.68412) (xy 34.709506 -128.606313) (xy 34.738209 -128.530797) (xy 34.773644 -128.458196)
			(xy 34.79419 -128.423416) (xy 34.798793 -128.414934) (xy 34.80196 -128.395913) (xy 34.797921 -128.377059)
			(xy 34.79292 -128.368806) (xy 34.769005 -128.332183) (xy 34.727704 -128.255075) (xy 34.694175 -128.174283)
			(xy 34.668742 -128.090589) (xy 34.651652 -128.004801) (xy 34.64307 -127.917751) (xy 34.642552 -127.874014)
			(xy 6.11378 -127.874014) (xy 6.11378 -130.937465) (xy 87.566748 -130.937465) (xy 87.566748 -130.873543)
			(xy 87.574759 -130.810125) (xy 87.590656 -130.748211) (xy 87.614188 -130.688778) (xy 87.644982 -130.632763)
			(xy 87.682555 -130.581048) (xy 87.726312 -130.534451) (xy 87.775565 -130.493706) (xy 87.829536 -130.459455)
			(xy 87.887375 -130.432238) (xy 87.948168 -130.412485) (xy 88.010958 -130.400507) (xy 88.074754 -130.396494)
			(xy 88.13855 -130.400507) (xy 88.20134 -130.412485) (xy 88.262133 -130.432238) (xy 88.319972 -130.459455)
			(xy 88.373943 -130.493706) (xy 88.423196 -130.534451) (xy 88.466953 -130.581048) (xy 88.489692 -130.612345)
			(xy 118.526046 -130.612345) (xy 118.526046 -130.548423) (xy 118.534057 -130.485005) (xy 118.549954 -130.423091)
			(xy 118.573486 -130.363658) (xy 118.60428 -130.307643) (xy 118.641853 -130.255928) (xy 118.68561 -130.209331)
			(xy 118.734863 -130.168586) (xy 118.788834 -130.134335) (xy 118.846673 -130.107118) (xy 118.907466 -130.087365)
			(xy 118.970256 -130.075387) (xy 119.034052 -130.071374) (xy 119.097848 -130.075387) (xy 119.160638 -130.087365)
			(xy 119.221431 -130.107118) (xy 119.27927 -130.134335) (xy 119.333241 -130.168586) (xy 119.382494 -130.209331)
			(xy 119.426251 -130.255928) (xy 119.463824 -130.307643) (xy 119.494618 -130.363658) (xy 119.51815 -130.423091)
			(xy 119.534047 -130.485005) (xy 119.542058 -130.548423) (xy 119.54256 -130.580384) (xy 119.542058 -130.612345)
			(xy 119.534047 -130.675763) (xy 119.51815 -130.737677) (xy 119.494618 -130.79711) (xy 119.463824 -130.853125)
			(xy 119.426251 -130.90484) (xy 119.382494 -130.951437) (xy 119.333241 -130.992182) (xy 119.27927 -131.026433)
			(xy 119.221431 -131.05365) (xy 119.160638 -131.073403) (xy 119.097848 -131.085381) (xy 119.034052 -131.089395)
			(xy 118.970256 -131.085381) (xy 118.907466 -131.073403) (xy 118.846673 -131.05365) (xy 118.788834 -131.026433)
			(xy 118.734863 -130.992182) (xy 118.68561 -130.951437) (xy 118.641853 -130.90484) (xy 118.60428 -130.853125)
			(xy 118.573486 -130.79711) (xy 118.549954 -130.737677) (xy 118.534057 -130.675763) (xy 118.526046 -130.612345)
			(xy 88.489692 -130.612345) (xy 88.504526 -130.632763) (xy 88.53532 -130.688778) (xy 88.558852 -130.748211)
			(xy 88.574749 -130.810125) (xy 88.58276 -130.873543) (xy 88.583262 -130.905504) (xy 88.58276 -130.937465)
			(xy 88.574749 -131.000883) (xy 88.558852 -131.062797) (xy 88.53532 -131.12223) (xy 88.504526 -131.178245)
			(xy 88.478312 -131.214325) (xy 92.418402 -131.214325) (xy 92.418402 -131.150403) (xy 92.426413 -131.086985)
			(xy 92.44231 -131.025071) (xy 92.465842 -130.965638) (xy 92.496636 -130.909623) (xy 92.534209 -130.857908)
			(xy 92.577966 -130.811311) (xy 92.627219 -130.770566) (xy 92.68119 -130.736315) (xy 92.739029 -130.709098)
			(xy 92.799822 -130.689345) (xy 92.862612 -130.677367) (xy 92.926408 -130.673354) (xy 92.990204 -130.677367)
			(xy 93.052994 -130.689345) (xy 93.113787 -130.709098) (xy 93.171626 -130.736315) (xy 93.225597 -130.770566)
			(xy 93.27485 -130.811311) (xy 93.318607 -130.857908) (xy 93.35618 -130.909623) (xy 93.386974 -130.965638)
			(xy 93.410506 -131.025071) (xy 93.426403 -131.086985) (xy 93.431842 -131.13004) (xy 167.105074 -131.13004)
			(xy 167.109145 -131.074418) (xy 167.121271 -131.019981) (xy 167.141194 -130.96789) (xy 167.16849 -130.919255)
			(xy 167.202576 -130.875112) (xy 167.242725 -130.836403) (xy 167.288083 -130.803952) (xy 167.337683 -130.778451)
			(xy 167.390467 -130.760444) (xy 167.44531 -130.750314) (xy 167.501044 -130.748277) (xy 167.556481 -130.754377)
			(xy 167.610438 -130.768483) (xy 167.661767 -130.790295) (xy 167.709373 -130.819349) (xy 167.752241 -130.855024)
			(xy 167.789458 -130.896561) (xy 167.820231 -130.943074) (xy 167.843903 -130.993571) (xy 167.859971 -131.046978)
			(xy 167.868091 -131.102154) (xy 167.8686 -131.13004) (xy 167.868091 -131.157926) (xy 167.859971 -131.213102)
			(xy 167.843903 -131.266509) (xy 167.820231 -131.317006) (xy 167.789458 -131.363519) (xy 167.752241 -131.405056)
			(xy 167.709373 -131.440731) (xy 167.661767 -131.469785) (xy 167.610438 -131.491597) (xy 167.556481 -131.505703)
			(xy 167.501044 -131.511803) (xy 167.44531 -131.509766) (xy 167.390467 -131.499636) (xy 167.337683 -131.481629)
			(xy 167.288083 -131.456128) (xy 167.242725 -131.423677) (xy 167.202576 -131.384968) (xy 167.16849 -131.340825)
			(xy 167.141194 -131.29219) (xy 167.121271 -131.240099) (xy 167.109145 -131.185662) (xy 167.105074 -131.13004)
			(xy 93.431842 -131.13004) (xy 93.434414 -131.150403) (xy 93.434916 -131.182364) (xy 93.434414 -131.214325)
			(xy 93.426403 -131.277743) (xy 93.410506 -131.339657) (xy 93.386974 -131.39909) (xy 93.35618 -131.455105)
			(xy 93.318607 -131.50682) (xy 93.27485 -131.553417) (xy 93.225597 -131.594162) (xy 93.171626 -131.628413)
			(xy 93.113787 -131.65563) (xy 93.052994 -131.675383) (xy 92.990204 -131.687361) (xy 92.926408 -131.691375)
			(xy 92.862612 -131.687361) (xy 92.799822 -131.675383) (xy 92.739029 -131.65563) (xy 92.68119 -131.628413)
			(xy 92.627219 -131.594162) (xy 92.577966 -131.553417) (xy 92.534209 -131.50682) (xy 92.496636 -131.455105)
			(xy 92.465842 -131.39909) (xy 92.44231 -131.339657) (xy 92.426413 -131.277743) (xy 92.418402 -131.214325)
			(xy 88.478312 -131.214325) (xy 88.466953 -131.22996) (xy 88.423196 -131.276557) (xy 88.373943 -131.317302)
			(xy 88.319972 -131.351553) (xy 88.262133 -131.37877) (xy 88.20134 -131.398523) (xy 88.13855 -131.410501)
			(xy 88.074754 -131.414515) (xy 88.010958 -131.410501) (xy 87.948168 -131.398523) (xy 87.887375 -131.37877)
			(xy 87.829536 -131.351553) (xy 87.775565 -131.317302) (xy 87.726312 -131.276557) (xy 87.682555 -131.22996)
			(xy 87.644982 -131.178245) (xy 87.614188 -131.12223) (xy 87.590656 -131.062797) (xy 87.574759 -131.000883)
			(xy 87.566748 -130.937465) (xy 6.11378 -130.937465) (xy 6.11378 -131.385818) (xy 6.114796 -131.395216)
			(xy 6.114796 -131.395724) (xy 6.11599 -131.400953) (xy 6.120221 -131.410807) (xy 6.123178 -131.415282)
			(xy 6.128512 -131.421632) (xy 6.218131 -131.511251) (xy 11.636242 -131.511251) (xy 11.636242 -131.447329)
			(xy 11.644253 -131.383911) (xy 11.66015 -131.321997) (xy 11.683682 -131.262564) (xy 11.714476 -131.206549)
			(xy 11.752049 -131.154834) (xy 11.795806 -131.108237) (xy 11.845059 -131.067492) (xy 11.89903 -131.033241)
			(xy 11.956869 -131.006024) (xy 12.017662 -130.986271) (xy 12.080452 -130.974293) (xy 12.144248 -130.97028)
			(xy 12.208044 -130.974293) (xy 12.270834 -130.986271) (xy 12.331627 -131.006024) (xy 12.389466 -131.033241)
			(xy 12.443437 -131.067492) (xy 12.49269 -131.108237) (xy 12.536447 -131.154834) (xy 12.57402 -131.206549)
			(xy 12.604814 -131.262564) (xy 12.628346 -131.321997) (xy 12.644243 -131.383911) (xy 12.652254 -131.447329)
			(xy 12.652756 -131.47929) (xy 12.652414 -131.501091) (xy 13.635222 -131.501091) (xy 13.635222 -131.437169)
			(xy 13.643233 -131.373751) (xy 13.65913 -131.311837) (xy 13.682662 -131.252404) (xy 13.713456 -131.196389)
			(xy 13.751029 -131.144674) (xy 13.794786 -131.098077) (xy 13.844039 -131.057332) (xy 13.89801 -131.023081)
			(xy 13.955849 -130.995864) (xy 14.016642 -130.976111) (xy 14.079432 -130.964133) (xy 14.143228 -130.96012)
			(xy 14.207024 -130.964133) (xy 14.269814 -130.976111) (xy 14.330607 -130.995864) (xy 14.388446 -131.023081)
			(xy 14.442417 -131.057332) (xy 14.49167 -131.098077) (xy 14.535427 -131.144674) (xy 14.573 -131.196389)
			(xy 14.603794 -131.252404) (xy 14.627326 -131.311837) (xy 14.643223 -131.373751) (xy 14.651234 -131.437169)
			(xy 14.651736 -131.46913) (xy 14.651234 -131.501091) (xy 14.643223 -131.564509) (xy 14.627326 -131.626423)
			(xy 14.603794 -131.685856) (xy 14.573 -131.741871) (xy 14.535427 -131.793586) (xy 14.49167 -131.840183)
			(xy 14.442417 -131.880928) (xy 14.388446 -131.915179) (xy 14.330607 -131.942396) (xy 14.269814 -131.962149)
			(xy 14.207024 -131.974127) (xy 14.143228 -131.978141) (xy 14.079432 -131.974127) (xy 14.016642 -131.962149)
			(xy 13.955849 -131.942396) (xy 13.89801 -131.915179) (xy 13.844039 -131.880928) (xy 13.794786 -131.840183)
			(xy 13.751029 -131.793586) (xy 13.713456 -131.741871) (xy 13.682662 -131.685856) (xy 13.65913 -131.626423)
			(xy 13.643233 -131.564509) (xy 13.635222 -131.501091) (xy 12.652414 -131.501091) (xy 12.652254 -131.511251)
			(xy 12.644243 -131.574669) (xy 12.628346 -131.636583) (xy 12.604814 -131.696016) (xy 12.57402 -131.752031)
			(xy 12.536447 -131.803746) (xy 12.49269 -131.850343) (xy 12.443437 -131.891088) (xy 12.389466 -131.925339)
			(xy 12.331627 -131.952556) (xy 12.270834 -131.972309) (xy 12.208044 -131.984287) (xy 12.144248 -131.988301)
			(xy 12.080452 -131.984287) (xy 12.017662 -131.972309) (xy 11.956869 -131.952556) (xy 11.89903 -131.925339)
			(xy 11.845059 -131.891088) (xy 11.795806 -131.850343) (xy 11.752049 -131.803746) (xy 11.714476 -131.752031)
			(xy 11.683682 -131.696016) (xy 11.66015 -131.636583) (xy 11.644253 -131.574669) (xy 11.636242 -131.511251)
			(xy 6.218131 -131.511251) (xy 7.253732 -132.546852) (xy 7.261146 -132.553526) (xy 7.279581 -132.561088)
			(xy 7.289546 -132.561584) (xy 7.654036 -132.561584) (xy 7.664104 -132.562013) (xy 7.6827 -132.569735)
			(xy 7.690104 -132.57657) (xy 7.934198 -132.820918) (xy 7.934452 -132.821172) (xy 7.941135 -132.828583)
			(xy 7.948719 -132.847018) (xy 7.949184 -132.856986) (xy 7.949184 -132.858256) (xy 7.949596 -132.868284)
			(xy 7.957257 -132.886819) (xy 7.971431 -132.901009) (xy 7.989956 -132.908692) (xy 7.999984 -132.909056)
			(xy 8.009382 -132.909056) (xy 8.026654 -132.902452) (xy 8.033766 -132.896102) (xy 8.04418 -132.87629)
			(xy 8.047482 -132.868924) (xy 8.050276 -132.86105) (xy 8.052054 -132.852922) (xy 8.057334 -132.824199)
			(xy 8.07546 -132.768685) (xy 8.10182 -132.716575) (xy 8.1358 -132.669081) (xy 8.176609 -132.627309)
			(xy 8.199628 -132.609336) (xy 8.224576 -132.591375) (xy 8.279014 -132.562824) (xy 8.337325 -132.543371)
			(xy 8.398001 -132.53352) (xy 8.428736 -132.532882) (xy 8.429498 -132.532882) (xy 8.449138 -132.533135)
			(xy 8.488207 -132.537202) (xy 8.507476 -132.54101) (xy 8.51789 -132.542026) (xy 8.547354 -132.527802)
			(xy 8.549386 -132.526786) (xy 8.553805 -132.524261) (xy 8.561612 -132.517733) (xy 8.56488 -132.513832)
			(xy 8.605928 -132.463397) (xy 8.69354 -132.367285) (xy 8.787116 -132.27697) (xy 8.886274 -132.192821)
			(xy 8.990608 -132.115183) (xy 9.099691 -132.044373) (xy 9.213078 -131.98068) (xy 9.330304 -131.924365)
			(xy 9.450891 -131.87566) (xy 9.574344 -131.834762) (xy 9.700159 -131.801839) (xy 9.827821 -131.777025)
			(xy 9.956808 -131.760423) (xy 10.086592 -131.7521) (xy 10.151618 -131.751578) (xy 10.215476 -131.75208)
			(xy 10.342941 -131.760099) (xy 10.469651 -131.776106) (xy 10.595105 -131.800038) (xy 10.71881 -131.8318)
			(xy 10.840275 -131.871266) (xy 10.959023 -131.918282) (xy 11.074585 -131.972661) (xy 11.186504 -132.034189)
			(xy 11.294339 -132.102623) (xy 11.397664 -132.177693) (xy 11.496071 -132.259103) (xy 11.589173 -132.346531)
			(xy 11.676601 -132.439633) (xy 11.758011 -132.53804) (xy 11.833081 -132.641365) (xy 11.901515 -132.7492)
			(xy 11.963043 -132.861119) (xy 12.017422 -132.976681) (xy 12.064438 -133.095429) (xy 12.081955 -133.14934)
			(xy 12.279374 -133.14934) (xy 12.283445 -133.093718) (xy 12.295571 -133.039281) (xy 12.315494 -132.98719)
			(xy 12.34279 -132.938555) (xy 12.376876 -132.894412) (xy 12.417025 -132.855703) (xy 12.462383 -132.823252)
			(xy 12.511983 -132.797751) (xy 12.564767 -132.779744) (xy 12.61961 -132.769614) (xy 12.675344 -132.767577)
			(xy 12.730781 -132.773677) (xy 12.784738 -132.787783) (xy 12.836067 -132.809595) (xy 12.883673 -132.838649)
			(xy 12.926541 -132.874324) (xy 12.963758 -132.915861) (xy 12.994531 -132.962374) (xy 13.018203 -133.012871)
			(xy 13.034271 -133.066278) (xy 13.042391 -133.121454) (xy 13.0429 -133.14934) (xy 13.042854 -133.15188)
			(xy 14.045182 -133.15188) (xy 14.049253 -133.096258) (xy 14.061379 -133.041821) (xy 14.081302 -132.98973)
			(xy 14.108598 -132.941095) (xy 14.142684 -132.896952) (xy 14.182833 -132.858243) (xy 14.228191 -132.825792)
			(xy 14.277791 -132.800291) (xy 14.330575 -132.782284) (xy 14.385418 -132.772154) (xy 14.441152 -132.770117)
			(xy 14.496589 -132.776217) (xy 14.550546 -132.790323) (xy 14.601875 -132.812135) (xy 14.649481 -132.841189)
			(xy 14.692349 -132.876864) (xy 14.729566 -132.918401) (xy 14.760339 -132.964914) (xy 14.784011 -133.015411)
			(xy 14.800079 -133.068818) (xy 14.808199 -133.123994) (xy 14.808708 -133.15188) (xy 14.808199 -133.179766)
			(xy 14.800079 -133.234942) (xy 14.784011 -133.288349) (xy 14.760339 -133.338846) (xy 14.729566 -133.385359)
			(xy 14.692349 -133.426896) (xy 14.649481 -133.462571) (xy 14.601875 -133.491625) (xy 14.550546 -133.513437)
			(xy 14.496589 -133.527543) (xy 14.441152 -133.533643) (xy 14.385418 -133.531606) (xy 14.330575 -133.521476)
			(xy 14.277791 -133.503469) (xy 14.228191 -133.477968) (xy 14.182833 -133.445517) (xy 14.142684 -133.406808)
			(xy 14.108598 -133.362665) (xy 14.081302 -133.31403) (xy 14.061379 -133.261939) (xy 14.049253 -133.207502)
			(xy 14.045182 -133.15188) (xy 13.042854 -133.15188) (xy 13.042391 -133.177226) (xy 13.034271 -133.232402)
			(xy 13.018203 -133.285809) (xy 12.994531 -133.336306) (xy 12.963758 -133.382819) (xy 12.926541 -133.424356)
			(xy 12.883673 -133.460031) (xy 12.836067 -133.489085) (xy 12.784738 -133.510897) (xy 12.730781 -133.525003)
			(xy 12.675344 -133.531103) (xy 12.61961 -133.529066) (xy 12.564767 -133.518936) (xy 12.511983 -133.500929)
			(xy 12.462383 -133.475428) (xy 12.417025 -133.442977) (xy 12.376876 -133.404268) (xy 12.34279 -133.360125)
			(xy 12.315494 -133.31149) (xy 12.295571 -133.259399) (xy 12.283445 -133.204962) (xy 12.279374 -133.14934)
			(xy 12.081955 -133.14934) (xy 12.103904 -133.216894) (xy 12.135666 -133.340599) (xy 12.159598 -133.466053)
			(xy 12.175605 -133.592763) (xy 12.183624 -133.720228) (xy 12.183624 -133.847944) (xy 12.175605 -133.975409)
			(xy 12.159598 -134.102119) (xy 12.14052 -134.202127) (xy 15.654776 -134.202127) (xy 15.654776 -134.138205)
			(xy 15.662787 -134.074787) (xy 15.678684 -134.012873) (xy 15.702216 -133.95344) (xy 15.73301 -133.897425)
			(xy 15.770583 -133.84571) (xy 15.81434 -133.799113) (xy 15.863593 -133.758368) (xy 15.917564 -133.724117)
			(xy 15.975403 -133.6969) (xy 16.036196 -133.677147) (xy 16.098986 -133.665169) (xy 16.162782 -133.661156)
			(xy 16.226578 -133.665169) (xy 16.289368 -133.677147) (xy 16.350161 -133.6969) (xy 16.408 -133.724117)
			(xy 16.461971 -133.758368) (xy 16.511224 -133.799113) (xy 16.535827 -133.825313) (xy 19.363131 -133.825313)
			(xy 19.363131 -133.770807) (xy 19.370888 -133.716855) (xy 19.386245 -133.664557) (xy 19.408888 -133.614976)
			(xy 19.438356 -133.569122) (xy 19.47405 -133.527929) (xy 19.515244 -133.492235) (xy 19.561098 -133.462767)
			(xy 19.610678 -133.440124) (xy 19.662977 -133.424768) (xy 19.716929 -133.417011) (xy 19.744182 -133.416548)
			(xy 19.744436 -133.416548) (xy 19.774045 -133.417108) (xy 19.83255 -133.426269) (xy 19.888931 -133.444379)
			(xy 19.915632 -133.457188) (xy 19.92643 -133.46194) (xy 19.949994 -133.462075) (xy 19.960844 -133.457442)
			(xy 20.04441 -133.416294) (xy 20.059142 -133.397244) (xy 20.061174 -133.38556) (xy 20.067617 -133.354429)
			(xy 20.087189 -133.293944) (xy 20.114143 -133.236367) (xy 20.148058 -133.182597) (xy 20.167854 -133.157722)
			(xy 20.173122 -133.150721) (xy 20.178969 -133.13422) (xy 20.179284 -133.125464) (xy 20.179284 -132.844286)
			(xy 20.178918 -132.835601) (xy 20.173062 -132.819243) (xy 20.167854 -132.812282) (xy 20.149161 -132.788852)
			(xy 20.116833 -132.738377) (xy 20.090667 -132.68445) (xy 20.071029 -132.627818) (xy 20.058189 -132.56927)
			(xy 20.054824 -132.539486) (xy 20.053069 -132.527484) (xy 20.040055 -132.507055) (xy 20.029932 -132.50037)
			(xy 19.958812 -132.458968) (xy 19.948082 -132.453519) (xy 19.924093 -132.452175) (xy 19.912838 -132.456428)
			(xy 19.912584 -132.456428) (xy 19.888227 -132.466671) (xy 19.837407 -132.481139) (xy 19.785079 -132.488468)
			(xy 19.75866 -132.48894) (xy 19.731409 -132.48845) (xy 19.677461 -132.480694) (xy 19.625167 -132.465339)
			(xy 19.57559 -132.442698) (xy 19.52974 -132.413232) (xy 19.48855 -132.37754) (xy 19.452858 -132.33635)
			(xy 19.423392 -132.2905) (xy 19.400751 -132.240923) (xy 19.385396 -132.188629) (xy 19.37764 -132.134681)
			(xy 19.37764 -132.080179) (xy 19.385396 -132.026231) (xy 19.400751 -131.973937) (xy 19.423392 -131.92436)
			(xy 19.452858 -131.87851) (xy 19.48855 -131.83732) (xy 19.52974 -131.801628) (xy 19.57559 -131.772162)
			(xy 19.625167 -131.749521) (xy 19.677461 -131.734166) (xy 19.731409 -131.72641) (xy 19.75866 -131.725924)
			(xy 19.786322 -131.726445) (xy 19.841065 -131.734443) (xy 19.894078 -131.750264) (xy 19.944251 -131.773576)
			(xy 19.990531 -131.803889) (xy 20.031948 -131.840569) (xy 20.067634 -131.882845) (xy 20.096839 -131.929832)
			(xy 20.118952 -131.980544) (xy 20.126706 -132.007102) (xy 20.130564 -132.018595) (xy 20.146858 -132.036498)
			(xy 20.157948 -132.041392) (xy 20.24634 -132.074666) (xy 20.270216 -132.072126) (xy 20.28063 -132.065268)
			(xy 20.305632 -132.049271) (xy 20.358648 -132.022579) (xy 20.41441 -132.002236) (xy 20.47216 -131.988519)
			(xy 20.531114 -131.981612) (xy 20.560792 -131.981194) (xy 20.591524 -131.981645) (xy 20.65254 -131.989053)
			(xy 20.712218 -132.003761) (xy 20.769688 -132.025556) (xy 20.824112 -132.05412) (xy 20.874696 -132.089035)
			(xy 20.920703 -132.129793) (xy 20.961462 -132.175799) (xy 20.996377 -132.226383) (xy 21.024941 -132.280806)
			(xy 21.046737 -132.338276) (xy 21.059206 -132.388864) (xy 30.324296 -132.388864) (xy 30.328367 -132.333242)
			(xy 30.340493 -132.278805) (xy 30.360416 -132.226714) (xy 30.387712 -132.178079) (xy 30.421798 -132.133936)
			(xy 30.461947 -132.095227) (xy 30.507305 -132.062776) (xy 30.556905 -132.037275) (xy 30.609689 -132.019268)
			(xy 30.664532 -132.009138) (xy 30.720266 -132.007101) (xy 30.775703 -132.013201) (xy 30.82966 -132.027307)
			(xy 30.880989 -132.049119) (xy 30.928595 -132.078173) (xy 30.971463 -132.113848) (xy 31.00868 -132.155385)
			(xy 31.039453 -132.201898) (xy 31.063125 -132.252395) (xy 31.079193 -132.305802) (xy 31.087313 -132.360978)
			(xy 31.087822 -132.388864) (xy 31.087313 -132.41675) (xy 31.079193 -132.471926) (xy 31.063125 -132.525333)
			(xy 31.039453 -132.57583) (xy 31.01076 -132.619199) (xy 36.825422 -132.619199) (xy 36.825422 -132.555277)
			(xy 36.833433 -132.491859) (xy 36.84933 -132.429945) (xy 36.872862 -132.370512) (xy 36.903656 -132.314497)
			(xy 36.941229 -132.262782) (xy 36.984986 -132.216185) (xy 37.034239 -132.17544) (xy 37.08821 -132.141189)
			(xy 37.146049 -132.113972) (xy 37.206842 -132.094219) (xy 37.269632 -132.082241) (xy 37.333428 -132.078228)
			(xy 37.397224 -132.082241) (xy 37.460014 -132.094219) (xy 37.520807 -132.113972) (xy 37.578646 -132.141189)
			(xy 37.632617 -132.17544) (xy 37.68187 -132.216185) (xy 37.725627 -132.262782) (xy 37.7632 -132.314497)
			(xy 37.793994 -132.370512) (xy 37.817526 -132.429945) (xy 37.833423 -132.491859) (xy 37.841434 -132.555277)
			(xy 37.841936 -132.587238) (xy 37.841434 -132.619199) (xy 37.833423 -132.682617) (xy 37.828164 -132.7031)
			(xy 54.783451 -132.7031) (xy 54.787465 -132.639299) (xy 54.799444 -132.576505) (xy 54.819198 -132.515707)
			(xy 54.846417 -132.457865) (xy 54.880671 -132.403889) (xy 54.921419 -132.354633) (xy 54.968019 -132.310872)
			(xy 55.019737 -132.273297) (xy 55.075756 -132.2425) (xy 55.135194 -132.218967) (xy 55.197112 -132.203068)
			(xy 55.260535 -132.195056) (xy 55.292498 -132.194554) (xy 55.32465 -132.195001) (xy 55.388441 -132.203101)
			(xy 55.4507 -132.219186) (xy 55.510432 -132.242999) (xy 55.566682 -132.274157) (xy 55.618551 -132.312164)
			(xy 55.66521 -132.356412) (xy 55.685944 -132.38099) (xy 55.692394 -132.388257) (xy 55.709384 -132.397653)
			(xy 55.718964 -132.399278) (xy 55.788814 -132.40766) (xy 55.79854 -132.408373) (xy 55.817348 -132.403272)
			(xy 55.82539 -132.397754) (xy 55.825644 -132.397754) (xy 55.847758 -132.381771) (xy 55.895641 -132.355614)
			(xy 55.946761 -132.33654) (xy 56.000075 -132.324937) (xy 56.054498 -132.321043) (xy 56.108921 -132.324937)
			(xy 56.162235 -132.33654) (xy 56.213355 -132.355614) (xy 56.261238 -132.381771) (xy 56.283352 -132.397754)
			(xy 56.283606 -132.397754) (xy 56.291646 -132.403281) (xy 56.310454 -132.40839) (xy 56.320182 -132.40766)
			(xy 56.390032 -132.399278) (xy 56.399598 -132.397616) (xy 56.416573 -132.388221) (xy 56.423052 -132.38099)
			(xy 56.443789 -132.356416) (xy 56.490453 -132.312175) (xy 56.542324 -132.274173) (xy 56.598573 -132.243017)
			(xy 56.658303 -132.219203) (xy 56.720559 -132.203113) (xy 56.784347 -132.195003) (xy 56.848649 -132.195003)
			(xy 56.912437 -132.203113) (xy 56.974693 -132.219203) (xy 57.034423 -132.243017) (xy 57.090672 -132.274173)
			(xy 57.142543 -132.312175) (xy 57.189207 -132.356416) (xy 57.209944 -132.38099) (xy 57.216394 -132.388257)
			(xy 57.233384 -132.397653) (xy 57.242964 -132.399278) (xy 57.312814 -132.40766) (xy 57.32254 -132.408373)
			(xy 57.341348 -132.403272) (xy 57.34939 -132.397754) (xy 57.349644 -132.397754) (xy 57.371758 -132.381771)
			(xy 57.419641 -132.355614) (xy 57.470761 -132.33654) (xy 57.524075 -132.324937) (xy 57.578498 -132.321043)
			(xy 57.632921 -132.324937) (xy 57.686235 -132.33654) (xy 57.737355 -132.355614) (xy 57.785238 -132.381771)
			(xy 57.807352 -132.397754) (xy 57.807606 -132.397754) (xy 57.815646 -132.403281) (xy 57.834454 -132.40839)
			(xy 57.844182 -132.40766) (xy 57.914032 -132.399278) (xy 57.923598 -132.397616) (xy 57.940573 -132.388221)
			(xy 57.947052 -132.38099) (xy 57.967831 -132.356455) (xy 58.014494 -132.312225) (xy 58.066361 -132.274231)
			(xy 58.122603 -132.243079) (xy 58.182325 -132.219266) (xy 58.244572 -132.203171) (xy 58.308351 -132.195053)
			(xy 58.340498 -132.194554) (xy 58.372458 -132.195111) (xy 58.435874 -132.203122) (xy 58.497786 -132.219018)
			(xy 58.557218 -132.242548) (xy 58.613231 -132.273342) (xy 58.664944 -132.310913) (xy 58.71154 -132.354669)
			(xy 58.752284 -132.40392) (xy 58.786534 -132.45789) (xy 58.81375 -132.515727) (xy 58.833502 -132.576518)
			(xy 58.84548 -132.639306) (xy 58.849494 -132.7031) (xy 58.84945 -132.7038) (xy 67.138113 -132.7038)
			(xy 67.142127 -132.64001) (xy 67.154103 -132.577227) (xy 67.173853 -132.516439) (xy 67.201065 -132.458606)
			(xy 67.235311 -132.404639) (xy 67.276051 -132.355389) (xy 67.322642 -132.311634) (xy 67.374349 -132.274063)
			(xy 67.430357 -132.243268) (xy 67.489783 -132.219735) (xy 67.551689 -132.203836) (xy 67.6151 -132.19582)
			(xy 67.647058 -132.195316) (xy 67.677295 -132.195727) (xy 67.737343 -132.202896) (xy 67.796117 -132.217138)
			(xy 67.852786 -132.238252) (xy 67.90655 -132.26594) (xy 67.95665 -132.29981) (xy 67.979798 -132.319268)
			(xy 67.98691 -132.325618) (xy 68.00469 -132.331968) (xy 68.092574 -132.329428) (xy 68.1101 -132.322062)
			(xy 68.116704 -132.315458) (xy 68.140497 -132.293181) (xy 68.192755 -132.254227) (xy 68.249562 -132.222268)
			(xy 68.309986 -132.197829) (xy 68.373037 -132.181309) (xy 68.437682 -132.172978) (xy 68.470272 -132.172456)
			(xy 68.502202 -132.17294) (xy 68.56556 -132.180928) (xy 68.627421 -132.196784) (xy 68.68681 -132.220256)
			(xy 68.742795 -132.250976) (xy 68.794496 -132.288462) (xy 68.841098 -132.332123) (xy 68.88187 -132.381273)
			(xy 68.91617 -132.435139) (xy 68.930266 -132.463794) (xy 68.934639 -132.472191) (xy 68.948333 -132.485244)
			(xy 68.956936 -132.489194) (xy 68.985638 -132.500878) (xy 68.994367 -132.503959) (xy 69.012858 -132.504358)
			(xy 69.021706 -132.50164) (xy 69.052587 -132.491423) (xy 69.116693 -132.480434) (xy 69.149214 -132.479796)
			(xy 69.149468 -132.479796) (xy 69.174398 -132.4802) (xy 69.223832 -132.486698) (xy 69.24802 -132.49275)
			(xy 69.257164 -132.49529) (xy 69.27596 -132.493004) (xy 69.354192 -132.452364) (xy 69.366384 -132.437886)
			(xy 69.369686 -132.428996) (xy 69.380709 -132.399841) (xy 69.408839 -132.344219) (xy 69.443555 -132.292451)
			(xy 69.484336 -132.245313) (xy 69.530571 -132.20351) (xy 69.581567 -132.16767) (xy 69.636561 -132.138329)
			(xy 69.694727 -132.115928) (xy 69.755194 -132.100801) (xy 69.817057 -132.093176) (xy 69.848222 -132.0927)
			(xy 69.880641 -132.09319) (xy 69.944954 -132.101434) (xy 70.007696 -132.117787) (xy 70.067851 -132.141983)
			(xy 70.124443 -132.173629) (xy 70.176552 -132.212212) (xy 70.223335 -132.257106) (xy 70.264031 -132.307582)
			(xy 70.297981 -132.362822) (xy 70.311772 -132.392166) (xy 70.316344 -132.402326) (xy 70.333362 -132.417058)
			(xy 70.430644 -132.444236) (xy 70.452742 -132.440426) (xy 70.46214 -132.433822) (xy 70.487687 -132.416754)
			(xy 70.542104 -132.388222) (xy 70.59956 -132.366453) (xy 70.659221 -132.351763) (xy 70.720217 -132.344366)
			(xy 70.750938 -132.343906) (xy 70.785793 -132.344504) (xy 70.854848 -132.354052) (xy 70.921956 -132.372925)
			(xy 70.954138 -132.386324) (xy 70.954392 -132.386324) (xy 70.96291 -132.389629) (xy 70.981145 -132.390535)
			(xy 70.989952 -132.388102) (xy 71.063358 -132.364226) (xy 71.077836 -132.352542) (xy 71.082408 -132.344668)
			(xy 71.097252 -132.320521) (xy 71.132881 -132.276441) (xy 71.174639 -132.238117) (xy 71.221606 -132.206391)
			(xy 71.27275 -132.181963) (xy 71.326945 -132.16537) (xy 71.382999 -132.156976) (xy 71.411338 -132.156454)
			(xy 71.441099 -132.157061) (xy 71.499899 -132.166309) (xy 71.55655 -132.184573) (xy 71.609678 -132.211412)
			(xy 71.657994 -132.246175) (xy 71.679562 -132.26669) (xy 71.68642 -132.273548) (xy 71.703692 -132.281168)
			(xy 71.791068 -132.284724) (xy 71.808594 -132.278882) (xy 71.81596 -132.272786) (xy 71.838824 -132.254382)
			(xy 71.888017 -132.222362) (xy 71.940569 -132.196219) (xy 71.995781 -132.1763) (xy 72.052919 -132.162871)
			(xy 72.111224 -132.156109) (xy 72.140572 -132.155692) (xy 72.172535 -132.156171) (xy 72.235959 -132.16418)
			(xy 72.297878 -132.180075) (xy 72.357317 -132.203606) (xy 72.413338 -132.234401) (xy 72.465057 -132.271974)
			(xy 72.511659 -132.315734) (xy 72.552409 -132.36499) (xy 72.586663 -132.418964) (xy 72.613883 -132.476807)
			(xy 72.633638 -132.537605) (xy 72.645617 -132.600399) (xy 72.649632 -132.6642) (xy 72.645617 -132.728001)
			(xy 72.633638 -132.790795) (xy 72.613883 -132.851593) (xy 72.586663 -132.909436) (xy 72.552409 -132.96341)
			(xy 72.511659 -133.012666) (xy 72.465057 -133.056426) (xy 72.413338 -133.093999) (xy 72.357317 -133.124794)
			(xy 72.297878 -133.148325) (xy 72.235959 -133.16422) (xy 72.172535 -133.172229) (xy 72.140572 -133.172708)
			(xy 72.107658 -133.172177) (xy 72.042381 -133.163683) (xy 71.978745 -133.146842) (xy 71.917811 -133.121935)
			(xy 71.860599 -133.089376) (xy 71.808064 -133.049711) (xy 71.761084 -133.003602) (xy 71.720442 -132.951819)
			(xy 71.703184 -132.923788) (xy 71.698358 -132.91566) (xy 71.68388 -132.903976) (xy 71.600314 -132.878322)
			(xy 71.581518 -132.879592) (xy 71.572882 -132.883656) (xy 71.547513 -132.894963) (xy 71.494315 -132.910919)
			(xy 71.439362 -132.918974) (xy 71.411592 -132.91947) (xy 71.411338 -132.91947) (xy 71.396995 -132.919326)
			(xy 71.36839 -132.917165) (xy 71.354188 -132.915152) (xy 71.35368 -132.915152) (xy 71.344587 -132.914229)
			(xy 71.326748 -132.918122) (xy 71.318882 -132.922772) (xy 71.254366 -132.964428) (xy 71.243444 -132.979414)
			(xy 71.240904 -132.988304) (xy 71.2316 -133.020045) (xy 71.205814 -133.080956) (xy 71.172346 -133.138009)
			(xy 71.131762 -133.19024) (xy 71.084747 -133.236766) (xy 71.032096 -133.276803) (xy 70.974697 -133.309674)
			(xy 70.91352 -133.334823) (xy 70.849598 -133.351826) (xy 70.78401 -133.360396) (xy 70.750938 -133.360922)
			(xy 70.718521 -133.360369) (xy 70.654212 -133.352132) (xy 70.591471 -133.335787) (xy 70.531317 -133.311599)
			(xy 70.474726 -133.279961) (xy 70.422616 -133.241386) (xy 70.375832 -133.1965) (xy 70.335134 -133.14603)
			(xy 70.301181 -133.090797) (xy 70.287388 -133.061456) (xy 70.282816 -133.051296) (xy 70.265798 -133.036564)
			(xy 70.168516 -133.009386) (xy 70.146418 -133.013196) (xy 70.13702 -133.0198) (xy 70.111458 -133.036845)
			(xy 70.057045 -133.06538) (xy 69.999592 -133.087154) (xy 69.939935 -133.101849) (xy 69.878942 -133.109252)
			(xy 69.848222 -133.109716) (xy 69.847968 -133.109716) (xy 69.815405 -133.10918) (xy 69.750816 -133.100846)
			(xy 69.687816 -133.084342) (xy 69.627435 -133.059939) (xy 69.598794 -133.044438) (xy 69.590412 -133.039612)
			(xy 69.571616 -133.036818) (xy 69.485764 -133.057138) (xy 69.470524 -133.067552) (xy 69.464936 -133.07568)
			(xy 69.449607 -133.09736) (xy 69.413982 -133.136728) (xy 69.373241 -133.170773) (xy 69.32817 -133.198836)
			(xy 69.279641 -133.220375) (xy 69.228594 -133.234973) (xy 69.176015 -133.242349) (xy 69.149468 -133.242812)
			(xy 69.122091 -133.242306) (xy 69.067898 -133.234475) (xy 69.015382 -133.218978) (xy 68.96562 -133.196134)
			(xy 68.919634 -133.166412) (xy 68.878368 -133.130422) (xy 68.860162 -133.10997) (xy 68.853789 -133.103277)
			(xy 68.837514 -133.094553) (xy 68.828412 -133.092952) (xy 68.797678 -133.088888) (xy 68.78825 -133.088012)
			(xy 68.769854 -133.092444) (xy 68.761864 -133.097524) (xy 68.736133 -133.114935) (xy 68.681281 -133.14411)
			(xy 68.623282 -133.166383) (xy 68.563001 -133.181421) (xy 68.501336 -133.189002) (xy 68.470272 -133.189472)
			(xy 68.440035 -133.189046) (xy 68.379988 -133.18188) (xy 68.321214 -133.167641) (xy 68.264545 -133.14653)
			(xy 68.210781 -133.118845) (xy 68.160681 -133.084977) (xy 68.137532 -133.06552) (xy 68.13042 -133.05917)
			(xy 68.11264 -133.05282) (xy 68.024756 -133.05536) (xy 68.00723 -133.062726) (xy 68.000626 -133.06933)
			(xy 67.976818 -133.091591) (xy 67.924563 -133.130547) (xy 67.86776 -133.162508) (xy 67.807338 -133.18695)
			(xy 67.74429 -133.203474) (xy 67.679647 -133.211808) (xy 67.647058 -133.212332) (xy 67.6151 -133.21178)
			(xy 67.551689 -133.203764) (xy 67.489783 -133.187865) (xy 67.430357 -133.164332) (xy 67.374349 -133.133537)
			(xy 67.322642 -133.095966) (xy 67.276051 -133.052211) (xy 67.235311 -133.002961) (xy 67.201065 -132.948994)
			(xy 67.173853 -132.891161) (xy 67.154103 -132.830373) (xy 67.142127 -132.76759) (xy 67.138113 -132.7038)
			(xy 58.84945 -132.7038) (xy 58.84548 -132.766894) (xy 58.833502 -132.829682) (xy 58.81375 -132.890473)
			(xy 58.786534 -132.94831) (xy 58.752284 -133.00228) (xy 58.71154 -133.051531) (xy 58.664944 -133.095287)
			(xy 58.613231 -133.132858) (xy 58.557218 -133.163652) (xy 58.497786 -133.187182) (xy 58.435874 -133.203078)
			(xy 58.372458 -133.211089) (xy 58.340498 -133.21157) (xy 58.308346 -133.211117) (xy 58.244556 -133.203017)
			(xy 58.182297 -133.186932) (xy 58.122566 -133.163121) (xy 58.066316 -133.131963) (xy 58.014446 -133.093957)
			(xy 57.967787 -133.049711) (xy 57.947052 -133.025134) (xy 57.940599 -133.01787) (xy 57.923612 -133.008471)
			(xy 57.914032 -133.006846) (xy 57.844182 -132.998464) (xy 57.834456 -132.997762) (xy 57.81565 -133.002858)
			(xy 57.807606 -133.00837) (xy 57.807352 -133.00837) (xy 57.785238 -133.024353) (xy 57.737355 -133.05051)
			(xy 57.686235 -133.069584) (xy 57.632921 -133.081187) (xy 57.578498 -133.085081) (xy 57.524075 -133.081187)
			(xy 57.470761 -133.069584) (xy 57.419641 -133.05051) (xy 57.371758 -133.024353) (xy 57.349644 -133.00837)
			(xy 57.34939 -133.00837) (xy 57.341349 -133.002843) (xy 57.322542 -132.997733) (xy 57.312814 -132.998464)
			(xy 57.242964 -133.006846) (xy 57.233395 -133.008499) (xy 57.216422 -133.0179) (xy 57.209944 -133.025134)
			(xy 57.189207 -133.049708) (xy 57.142543 -133.093949) (xy 57.090672 -133.131951) (xy 57.034423 -133.163107)
			(xy 56.974693 -133.186921) (xy 56.912437 -133.203011) (xy 56.848649 -133.211121) (xy 56.784347 -133.211121)
			(xy 56.720559 -133.203011) (xy 56.658303 -133.186921) (xy 56.598573 -133.163107) (xy 56.542324 -133.131951)
			(xy 56.490453 -133.093949) (xy 56.443789 -133.049708) (xy 56.423052 -133.025134) (xy 56.416599 -133.01787)
			(xy 56.399612 -133.008471) (xy 56.390032 -133.006846) (xy 56.320182 -132.998464) (xy 56.310456 -132.997762)
			(xy 56.29165 -133.002858) (xy 56.283606 -133.00837) (xy 56.283352 -133.00837) (xy 56.261238 -133.024353)
			(xy 56.213355 -133.05051) (xy 56.162235 -133.069584) (xy 56.108921 -133.081187) (xy 56.054498 -133.085081)
			(xy 56.000075 -133.081187) (xy 55.946761 -133.069584) (xy 55.895641 -133.05051) (xy 55.847758 -133.024353)
			(xy 55.825644 -133.00837) (xy 55.82539 -133.00837) (xy 55.817349 -133.002843) (xy 55.798542 -132.997733)
			(xy 55.788814 -132.998464) (xy 55.718964 -133.006846) (xy 55.709395 -133.008499) (xy 55.692422 -133.0179)
			(xy 55.685944 -133.025134) (xy 55.665173 -133.049676) (xy 55.618508 -133.093904) (xy 55.56664 -133.131897)
			(xy 55.510396 -133.163048) (xy 55.450673 -133.18686) (xy 55.388425 -133.202954) (xy 55.324645 -133.211071)
			(xy 55.292498 -133.21157) (xy 55.260535 -133.211144) (xy 55.197112 -133.203132) (xy 55.135194 -133.187233)
			(xy 55.075756 -133.1637) (xy 55.019737 -133.132903) (xy 54.968019 -133.095328) (xy 54.921419 -133.051567)
			(xy 54.880671 -133.002311) (xy 54.846417 -132.948335) (xy 54.819198 -132.890493) (xy 54.799444 -132.829695)
			(xy 54.787465 -132.766901) (xy 54.783451 -132.7031) (xy 37.828164 -132.7031) (xy 37.817526 -132.744531)
			(xy 37.793994 -132.803964) (xy 37.7632 -132.859979) (xy 37.725627 -132.911694) (xy 37.68187 -132.958291)
			(xy 37.632617 -132.999036) (xy 37.578646 -133.033287) (xy 37.520807 -133.060504) (xy 37.460014 -133.080257)
			(xy 37.397224 -133.092235) (xy 37.333428 -133.096249) (xy 37.269632 -133.092235) (xy 37.206842 -133.080257)
			(xy 37.146049 -133.060504) (xy 37.08821 -133.033287) (xy 37.034239 -132.999036) (xy 36.984986 -132.958291)
			(xy 36.941229 -132.911694) (xy 36.903656 -132.859979) (xy 36.872862 -132.803964) (xy 36.84933 -132.744531)
			(xy 36.833433 -132.682617) (xy 36.825422 -132.619199) (xy 31.01076 -132.619199) (xy 31.00868 -132.622343)
			(xy 30.971463 -132.66388) (xy 30.928595 -132.699555) (xy 30.880989 -132.728609) (xy 30.82966 -132.750421)
			(xy 30.775703 -132.764527) (xy 30.720266 -132.770627) (xy 30.664532 -132.76859) (xy 30.609689 -132.75846)
			(xy 30.556905 -132.740453) (xy 30.507305 -132.714952) (xy 30.461947 -132.682501) (xy 30.421798 -132.643792)
			(xy 30.387712 -132.599649) (xy 30.360416 -132.551014) (xy 30.340493 -132.498923) (xy 30.328367 -132.444486)
			(xy 30.324296 -132.388864) (xy 21.059206 -132.388864) (xy 21.061446 -132.397954) (xy 21.068854 -132.45897)
			(xy 21.0693 -132.489702) (xy 21.068725 -132.524668) (xy 21.059123 -132.593938) (xy 21.040114 -132.661237)
			(xy 21.012056 -132.725294) (xy 20.975481 -132.784899) (xy 20.95373 -132.812282) (xy 20.948459 -132.819281)
			(xy 20.942614 -132.835784) (xy 20.9423 -132.84454) (xy 20.9423 -133.125464) (xy 20.942635 -133.134214)
			(xy 20.948491 -133.150705) (xy 20.95373 -133.157722) (xy 20.975482 -133.185102) (xy 21.012033 -133.244718)
			(xy 21.040076 -133.308778) (xy 21.059085 -133.376073) (xy 21.0687 -133.445338) (xy 21.0693 -133.480302)
			(xy 21.068864 -133.511034) (xy 21.061455 -133.572051) (xy 21.046745 -133.63173) (xy 21.024949 -133.689201)
			(xy 20.996385 -133.743625) (xy 20.961468 -133.794209) (xy 20.920709 -133.840216) (xy 20.901494 -133.857238)
			(xy 36.95141 -133.857238) (xy 36.955481 -133.801616) (xy 36.967607 -133.747179) (xy 36.98753 -133.695088)
			(xy 37.014826 -133.646453) (xy 37.048912 -133.60231) (xy 37.089061 -133.563601) (xy 37.134419 -133.53115)
			(xy 37.184019 -133.505649) (xy 37.236803 -133.487642) (xy 37.291646 -133.477512) (xy 37.34738 -133.475475)
			(xy 37.402817 -133.481575) (xy 37.456774 -133.495681) (xy 37.508103 -133.517493) (xy 37.555709 -133.546547)
			(xy 37.598577 -133.582222) (xy 37.635794 -133.623759) (xy 37.666567 -133.670272) (xy 37.690239 -133.720769)
			(xy 37.706307 -133.774176) (xy 37.714427 -133.829352) (xy 37.714936 -133.857238) (xy 37.714427 -133.885124)
			(xy 37.706307 -133.9403) (xy 37.690239 -133.993707) (xy 37.666567 -134.044204) (xy 37.635794 -134.090717)
			(xy 37.598577 -134.132254) (xy 37.555709 -134.167929) (xy 37.508103 -134.196983) (xy 37.456774 -134.218795)
			(xy 37.402817 -134.232901) (xy 37.34738 -134.239001) (xy 37.291646 -134.236964) (xy 37.236803 -134.226834)
			(xy 37.184019 -134.208827) (xy 37.134419 -134.183326) (xy 37.089061 -134.150875) (xy 37.048912 -134.112166)
			(xy 37.014826 -134.068023) (xy 36.98753 -134.019388) (xy 36.967607 -133.967297) (xy 36.955481 -133.91286)
			(xy 36.95141 -133.857238) (xy 20.901494 -133.857238) (xy 20.874701 -133.880974) (xy 20.824116 -133.91589)
			(xy 20.769691 -133.944453) (xy 20.71222 -133.966248) (xy 20.652541 -133.980957) (xy 20.591524 -133.988365)
			(xy 20.560792 -133.98881) (xy 20.528194 -133.988306) (xy 20.463531 -133.979975) (xy 20.400463 -133.963451)
			(xy 20.340023 -133.939005) (xy 20.283201 -133.907037) (xy 20.256754 -133.887972) (xy 20.246914 -133.881345)
			(xy 20.223597 -133.877115) (xy 20.21205 -133.879844) (xy 20.122642 -133.905752) (xy 20.10537 -133.922008)
			(xy 20.101052 -133.933184) (xy 20.090308 -133.959954) (xy 20.061988 -134.010204) (xy 20.026428 -134.055619)
			(xy 19.984436 -134.095164) (xy 19.936971 -134.127938) (xy 19.885114 -134.153194) (xy 19.830046 -134.170358)
			(xy 19.773022 -134.179037) (xy 19.744182 -134.179564) (xy 19.716929 -134.179109) (xy 19.662977 -134.171352)
			(xy 19.610678 -134.155996) (xy 19.561098 -134.133353) (xy 19.515244 -134.103885) (xy 19.47405 -134.068191)
			(xy 19.438356 -134.026998) (xy 19.408888 -133.981144) (xy 19.386245 -133.931563) (xy 19.370888 -133.879265)
			(xy 19.363131 -133.825313) (xy 16.535827 -133.825313) (xy 16.554981 -133.84571) (xy 16.592554 -133.897425)
			(xy 16.623348 -133.95344) (xy 16.64688 -134.012873) (xy 16.662777 -134.074787) (xy 16.670788 -134.138205)
			(xy 16.67129 -134.170166) (xy 16.670788 -134.202127) (xy 16.662777 -134.265545) (xy 16.64688 -134.327459)
			(xy 16.623348 -134.386892) (xy 16.592554 -134.442907) (xy 16.554981 -134.494622) (xy 16.511224 -134.541219)
			(xy 16.461971 -134.581964) (xy 16.408 -134.616215) (xy 16.350161 -134.643432) (xy 16.289368 -134.663185)
			(xy 16.226578 -134.675163) (xy 16.162782 -134.679177) (xy 16.098986 -134.675163) (xy 16.036196 -134.663185)
			(xy 15.975403 -134.643432) (xy 15.917564 -134.616215) (xy 15.863593 -134.581964) (xy 15.81434 -134.541219)
			(xy 15.770583 -134.494622) (xy 15.73301 -134.442907) (xy 15.702216 -134.386892) (xy 15.678684 -134.327459)
			(xy 15.662787 -134.265545) (xy 15.654776 -134.202127) (xy 12.14052 -134.202127) (xy 12.135666 -134.227573)
			(xy 12.103904 -134.351278) (xy 12.064438 -134.472743) (xy 12.017422 -134.591491) (xy 11.963043 -134.707053)
			(xy 11.901515 -134.818972) (xy 11.842576 -134.911846) (xy 12.289788 -134.911846) (xy 12.293859 -134.856224)
			(xy 12.305985 -134.801787) (xy 12.325908 -134.749696) (xy 12.353204 -134.701061) (xy 12.38729 -134.656918)
			(xy 12.427439 -134.618209) (xy 12.472797 -134.585758) (xy 12.522397 -134.560257) (xy 12.575181 -134.54225)
			(xy 12.630024 -134.53212) (xy 12.685758 -134.530083) (xy 12.741195 -134.536183) (xy 12.795152 -134.550289)
			(xy 12.846481 -134.572101) (xy 12.894087 -134.601155) (xy 12.936955 -134.63683) (xy 12.974172 -134.678367)
			(xy 13.004945 -134.72488) (xy 13.028617 -134.775377) (xy 13.044685 -134.828784) (xy 13.052805 -134.88396)
			(xy 13.05318 -134.90448) (xy 14.024608 -134.90448) (xy 14.028679 -134.848858) (xy 14.040805 -134.794421)
			(xy 14.060728 -134.74233) (xy 14.088024 -134.693695) (xy 14.12211 -134.649552) (xy 14.162259 -134.610843)
			(xy 14.207617 -134.578392) (xy 14.257217 -134.552891) (xy 14.310001 -134.534884) (xy 14.364844 -134.524754)
			(xy 14.420578 -134.522717) (xy 14.476015 -134.528817) (xy 14.529972 -134.542923) (xy 14.581301 -134.564735)
			(xy 14.628907 -134.593789) (xy 14.671775 -134.629464) (xy 14.708992 -134.671001) (xy 14.739765 -134.717514)
			(xy 14.763437 -134.768011) (xy 14.779505 -134.821418) (xy 14.787625 -134.876594) (xy 14.788134 -134.90448)
			(xy 14.787625 -134.932366) (xy 14.779505 -134.987542) (xy 14.763437 -135.040949) (xy 14.739765 -135.091446)
			(xy 14.708992 -135.137959) (xy 14.671775 -135.179496) (xy 14.628907 -135.215171) (xy 14.581301 -135.244225)
			(xy 14.529972 -135.266037) (xy 14.476015 -135.280143) (xy 14.420578 -135.286243) (xy 14.364844 -135.284206)
			(xy 14.310001 -135.274076) (xy 14.257217 -135.256069) (xy 14.207617 -135.230568) (xy 14.162259 -135.198117)
			(xy 14.12211 -135.159408) (xy 14.088024 -135.115265) (xy 14.060728 -135.06663) (xy 14.040805 -135.014539)
			(xy 14.028679 -134.960102) (xy 14.024608 -134.90448) (xy 13.05318 -134.90448) (xy 13.053314 -134.911846)
			(xy 13.052805 -134.939732) (xy 13.044685 -134.994908) (xy 13.028617 -135.048315) (xy 13.004945 -135.098812)
			(xy 12.974172 -135.145325) (xy 12.936955 -135.186862) (xy 12.894087 -135.222537) (xy 12.846481 -135.251591)
			(xy 12.795152 -135.273403) (xy 12.741195 -135.287509) (xy 12.685758 -135.293609) (xy 12.630024 -135.291572)
			(xy 12.575181 -135.281442) (xy 12.522397 -135.263435) (xy 12.472797 -135.237934) (xy 12.427439 -135.205483)
			(xy 12.38729 -135.166774) (xy 12.353204 -135.122631) (xy 12.325908 -135.073996) (xy 12.305985 -135.021905)
			(xy 12.293859 -134.967468) (xy 12.289788 -134.911846) (xy 11.842576 -134.911846) (xy 11.833081 -134.926807)
			(xy 11.758011 -135.030132) (xy 11.676601 -135.128539) (xy 11.589173 -135.221641) (xy 11.496071 -135.309069)
			(xy 11.397664 -135.390479) (xy 11.294339 -135.465549) (xy 11.186504 -135.533983) (xy 11.074585 -135.595511)
			(xy 10.959023 -135.64989) (xy 10.840275 -135.696906) (xy 10.71881 -135.736372) (xy 10.595105 -135.768134)
			(xy 10.469651 -135.792066) (xy 10.342941 -135.808073) (xy 10.215476 -135.816092) (xy 10.151618 -135.816594)
			(xy 10.093973 -135.816168) (xy 9.978871 -135.80959) (xy 9.864327 -135.796506) (xy 9.807448 -135.78713)
			(xy 9.797763 -135.785921) (xy 9.778702 -135.790036) (xy 9.762538 -135.800943) (xy 9.751588 -135.817079)
			(xy 9.749028 -135.8265) (xy 9.735536 -135.886604) (xy 9.702209 -136.005206) (xy 9.66176 -136.121572)
			(xy 9.61434 -136.235275) (xy 9.560121 -136.345898) (xy 9.499303 -136.453035) (xy 9.432109 -136.556292)
			(xy 9.376116 -136.631891) (xy 13.764762 -136.631891) (xy 13.764762 -136.567969) (xy 13.772773 -136.504551)
			(xy 13.78867 -136.442637) (xy 13.812202 -136.383204) (xy 13.842996 -136.327189) (xy 13.880569 -136.275474)
			(xy 13.924326 -136.228877) (xy 13.973579 -136.188132) (xy 14.02755 -136.153881) (xy 14.085389 -136.126664)
			(xy 14.146182 -136.106911) (xy 14.208972 -136.094933) (xy 14.272768 -136.09092) (xy 14.336564 -136.094933)
			(xy 14.399354 -136.106911) (xy 14.460147 -136.126664) (xy 14.517986 -136.153881) (xy 14.571957 -136.188132)
			(xy 14.62121 -136.228877) (xy 14.664967 -136.275474) (xy 14.70254 -136.327189) (xy 14.733334 -136.383204)
			(xy 14.756866 -136.442637) (xy 14.772763 -136.504551) (xy 14.780774 -136.567969) (xy 14.781276 -136.59993)
			(xy 14.780774 -136.631891) (xy 14.772763 -136.695309) (xy 14.756866 -136.757223) (xy 14.733334 -136.816656)
			(xy 14.70254 -136.872671) (xy 14.664967 -136.924386) (xy 14.62121 -136.970983) (xy 14.571957 -137.011728)
			(xy 14.517986 -137.045979) (xy 14.480346 -137.063691) (xy 15.276062 -137.063691) (xy 15.276062 -136.999769)
			(xy 15.284073 -136.936351) (xy 15.29997 -136.874437) (xy 15.323502 -136.815004) (xy 15.354296 -136.758989)
			(xy 15.391869 -136.707274) (xy 15.435626 -136.660677) (xy 15.484879 -136.619932) (xy 15.53885 -136.585681)
			(xy 15.596689 -136.558464) (xy 15.657482 -136.538711) (xy 15.720272 -136.526733) (xy 15.784068 -136.52272)
			(xy 15.847864 -136.526733) (xy 15.910654 -136.538711) (xy 15.971447 -136.558464) (xy 16.029286 -136.585681)
			(xy 16.083257 -136.619932) (xy 16.13251 -136.660677) (xy 16.176267 -136.707274) (xy 16.21384 -136.758989)
			(xy 16.244634 -136.815004) (xy 16.268166 -136.874437) (xy 16.284063 -136.936351) (xy 16.292074 -136.999769)
			(xy 16.292576 -137.03173) (xy 16.292074 -137.063691) (xy 16.284063 -137.127109) (xy 16.268166 -137.189023)
			(xy 16.244634 -137.248456) (xy 16.21384 -137.304471) (xy 16.176267 -137.356186) (xy 16.13251 -137.402783)
			(xy 16.083257 -137.443528) (xy 16.029286 -137.477779) (xy 15.971447 -137.504996) (xy 15.910654 -137.524749)
			(xy 15.847864 -137.536727) (xy 15.784068 -137.540741) (xy 15.720272 -137.536727) (xy 15.657482 -137.524749)
			(xy 15.596689 -137.504996) (xy 15.53885 -137.477779) (xy 15.484879 -137.443528) (xy 15.435626 -137.402783)
			(xy 15.391869 -137.356186) (xy 15.354296 -137.304471) (xy 15.323502 -137.248456) (xy 15.29997 -137.189023)
			(xy 15.284073 -137.127109) (xy 15.276062 -137.063691) (xy 14.480346 -137.063691) (xy 14.460147 -137.073196)
			(xy 14.399354 -137.092949) (xy 14.336564 -137.104927) (xy 14.272768 -137.108941) (xy 14.208972 -137.104927)
			(xy 14.146182 -137.092949) (xy 14.085389 -137.073196) (xy 14.02755 -137.045979) (xy 13.973579 -137.011728)
			(xy 13.924326 -136.970983) (xy 13.880569 -136.924386) (xy 13.842996 -136.872671) (xy 13.812202 -136.816656)
			(xy 13.78867 -136.757223) (xy 13.772773 -136.695309) (xy 13.764762 -136.631891) (xy 9.376116 -136.631891)
			(xy 9.358785 -136.655291) (xy 9.279602 -136.749668) (xy 9.194848 -136.839078) (xy 9.104836 -136.92319)
			(xy 9.009896 -137.001698) (xy 8.910376 -137.074313) (xy 8.858758 -137.10793) (xy 8.849106 -137.115804)
			(xy 8.84047 -137.124948) (xy 8.833104 -137.135108) (xy 8.818626 -137.161016) (xy 8.819896 -137.171938)
			(xy 8.824044 -137.192131) (xy 8.828498 -137.233114) (xy 8.828786 -137.253726) (xy 8.828786 -137.25398)
			(xy 8.828324 -137.281233) (xy 8.820569 -137.335185) (xy 8.805215 -137.387484) (xy 8.782573 -137.437065)
			(xy 8.753105 -137.482919) (xy 8.717411 -137.524113) (xy 8.676218 -137.559806) (xy 8.630364 -137.589274)
			(xy 8.580782 -137.611915) (xy 8.528483 -137.62727) (xy 8.474531 -137.635024) (xy 8.447278 -137.635488)
			(xy 8.424121 -137.635147) (xy 8.378146 -137.62954) (xy 8.355584 -137.624312) (xy 8.35533 -137.624312)
			(xy 8.344018 -137.622131) (xy 8.321531 -137.627025) (xy 8.31215 -137.63371) (xy 8.249158 -137.682986)
			(xy 8.240376 -137.69053) (xy 8.230207 -137.711301) (xy 8.2296 -137.722864) (xy 8.2296 -138.321113)
			(xy 19.363131 -138.321113) (xy 19.363131 -138.266607) (xy 19.370888 -138.212655) (xy 19.386245 -138.160357)
			(xy 19.408888 -138.110776) (xy 19.438356 -138.064922) (xy 19.47405 -138.023729) (xy 19.515244 -137.988035)
			(xy 19.561098 -137.958567) (xy 19.610678 -137.935924) (xy 19.662977 -137.920568) (xy 19.716929 -137.912811)
			(xy 19.744182 -137.912348) (xy 19.759102 -137.912468) (xy 19.788855 -137.914757) (xy 19.803618 -137.91692)
			(xy 19.812762 -137.918444) (xy 19.830288 -137.914888) (xy 19.902424 -137.870438) (xy 19.913346 -137.856214)
			(xy 19.91614 -137.847324) (xy 19.926369 -137.816827) (xy 19.953497 -137.758501) (xy 19.987776 -137.704069)
			(xy 20.007834 -137.678922) (xy 20.013099 -137.671919) (xy 20.018948 -137.655419) (xy 20.019264 -137.646664)
			(xy 20.019264 -137.36574) (xy 20.018934 -137.35699) (xy 20.013075 -137.340498) (xy 20.007834 -137.333482)
			(xy 19.989874 -137.311005) (xy 19.958626 -137.262693) (xy 19.933022 -137.211166) (xy 19.913389 -137.157082)
			(xy 19.899977 -137.101129) (xy 19.896074 -137.072624) (xy 19.896074 -137.07237) (xy 19.894412 -137.062803)
			(xy 19.885017 -137.045829) (xy 19.877786 -137.03935) (xy 19.81581 -136.988804) (xy 19.797268 -136.982962)
			(xy 19.787616 -136.983724) (xy 19.75866 -136.98474) (xy 19.731409 -136.98425) (xy 19.677461 -136.976494)
			(xy 19.625167 -136.961139) (xy 19.57559 -136.938498) (xy 19.52974 -136.909032) (xy 19.48855 -136.87334)
			(xy 19.452858 -136.83215) (xy 19.423392 -136.7863) (xy 19.400751 -136.736723) (xy 19.385396 -136.684429)
			(xy 19.37764 -136.630481) (xy 19.37764 -136.575979) (xy 19.385396 -136.522031) (xy 19.400751 -136.469737)
			(xy 19.423392 -136.42016) (xy 19.452858 -136.37431) (xy 19.48855 -136.33312) (xy 19.52974 -136.297428)
			(xy 19.57559 -136.267962) (xy 19.625167 -136.245321) (xy 19.677461 -136.229966) (xy 19.731409 -136.22221)
			(xy 19.75866 -136.221724) (xy 19.787466 -136.222233) (xy 19.844423 -136.230889) (xy 19.89943 -136.248012)
			(xy 19.951238 -136.273211) (xy 19.998668 -136.305914) (xy 20.040641 -136.345376) (xy 20.076203 -136.390701)
			(xy 20.104545 -136.440859) (xy 20.115276 -136.467596) (xy 20.118578 -136.47674) (xy 20.13204 -136.491218)
			(xy 20.204176 -136.525508) (xy 20.213108 -136.529275) (xy 20.232443 -136.530446) (xy 20.241768 -136.527794)
			(xy 20.26741 -136.51975) (xy 20.319953 -136.508456) (xy 20.373393 -136.502759) (xy 20.400264 -136.502394)
			(xy 20.400772 -136.502394) (xy 20.431504 -136.502864) (xy 20.492519 -136.510269) (xy 20.552197 -136.524976)
			(xy 20.609667 -136.546769) (xy 20.664091 -136.57533) (xy 20.714675 -136.610243) (xy 20.760682 -136.651)
			(xy 20.801441 -136.697004) (xy 20.836357 -136.747587) (xy 20.864921 -136.80201) (xy 20.886716 -136.859478)
			(xy 20.901426 -136.919155) (xy 20.908834 -136.98017) (xy 20.90928 -137.010902) (xy 20.90871 -137.045868)
			(xy 20.899107 -137.115138) (xy 20.880097 -137.182437) (xy 20.852039 -137.246494) (xy 20.815462 -137.306099)
			(xy 20.79371 -137.333482) (xy 20.788448 -137.340487) (xy 20.782596 -137.356985) (xy 20.78228 -137.36574)
			(xy 20.78228 -137.646664) (xy 20.782619 -137.655413) (xy 20.788473 -137.671904) (xy 20.79371 -137.678922)
			(xy 20.815459 -137.706304) (xy 20.852011 -137.76592) (xy 20.880055 -137.829978) (xy 20.899064 -137.897274)
			(xy 20.90868 -137.966538) (xy 20.90928 -138.001502) (xy 20.908864 -138.032235) (xy 20.901455 -138.093253)
			(xy 20.886744 -138.152934) (xy 20.864947 -138.210405) (xy 20.836381 -138.264831) (xy 20.801463 -138.315416)
			(xy 20.760702 -138.361423) (xy 20.714692 -138.402181) (xy 20.664105 -138.437097) (xy 20.609678 -138.465659)
			(xy 20.552205 -138.487453) (xy 20.492524 -138.50216) (xy 20.431505 -138.509566) (xy 20.400772 -138.51001)
			(xy 20.400518 -138.51001) (xy 20.364504 -138.509369) (xy 20.293199 -138.499192) (xy 20.224041 -138.479066)
			(xy 20.190968 -138.464798) (xy 20.182586 -138.460988) (xy 20.164806 -138.459718) (xy 20.083272 -138.48334)
			(xy 20.068794 -138.494262) (xy 20.063968 -138.501882) (xy 20.048801 -138.524345) (xy 20.013114 -138.565141)
			(xy 19.972013 -138.600474) (xy 19.926324 -138.629634) (xy 19.876968 -138.652033) (xy 19.824938 -138.66722)
			(xy 19.771283 -138.67489) (xy 19.744182 -138.675364) (xy 19.716929 -138.674909) (xy 19.662977 -138.667152)
			(xy 19.610678 -138.651796) (xy 19.561098 -138.629153) (xy 19.515244 -138.599685) (xy 19.47405 -138.563991)
			(xy 19.438356 -138.522798) (xy 19.408888 -138.476944) (xy 19.386245 -138.427363) (xy 19.370888 -138.375065)
			(xy 19.363131 -138.321113) (xy 8.2296 -138.321113) (xy 8.2296 -140.30071) (xy 11.968986 -140.30071)
			(xy 11.973057 -140.245088) (xy 11.985183 -140.190651) (xy 12.005106 -140.13856) (xy 12.032402 -140.089925)
			(xy 12.066488 -140.045782) (xy 12.106637 -140.007073) (xy 12.151995 -139.974622) (xy 12.201595 -139.949121)
			(xy 12.254379 -139.931114) (xy 12.309222 -139.920984) (xy 12.364956 -139.918947) (xy 12.420393 -139.925047)
			(xy 12.47435 -139.939153) (xy 12.525679 -139.960965) (xy 12.573285 -139.990019) (xy 12.616153 -140.025694)
			(xy 12.65337 -140.067231) (xy 12.684143 -140.113744) (xy 12.707815 -140.164241) (xy 12.723883 -140.217648)
			(xy 12.732003 -140.272824) (xy 12.732512 -140.30071) (xy 12.732003 -140.328596) (xy 12.723883 -140.383772)
			(xy 12.707815 -140.437179) (xy 12.684143 -140.487676) (xy 12.65337 -140.534189) (xy 12.616153 -140.575726)
			(xy 12.573285 -140.611401) (xy 12.525679 -140.640455) (xy 12.47435 -140.662267) (xy 12.420393 -140.676373)
			(xy 12.364956 -140.682473) (xy 12.309222 -140.680436) (xy 12.254379 -140.670306) (xy 12.201595 -140.652299)
			(xy 12.151995 -140.626798) (xy 12.106637 -140.594347) (xy 12.066488 -140.555638) (xy 12.032402 -140.511495)
			(xy 12.005106 -140.46286) (xy 11.985183 -140.410769) (xy 11.973057 -140.356332) (xy 11.968986 -140.30071)
			(xy 8.2296 -140.30071) (xy 8.2296 -148.619718) (xy 8.229764 -148.625729) (xy 8.232581 -148.637414)
			(xy 8.235188 -148.642832) (xy 8.237028 -148.646306) (xy 8.241622 -148.652684) (xy 8.244332 -148.655532)
			(xy 8.807958 -149.219158) (xy 8.810807 -149.221866) (xy 8.817183 -149.226464) (xy 8.820658 -149.228302)
			(xy 8.826085 -149.230883) (xy 8.837765 -149.233704) (xy 8.843772 -149.23389) (xy 10.516108 -149.23389)
			(xy 10.517378 -149.23516) (xy 10.525506 -149.2377) (xy 10.542778 -149.245066) (xy 10.55116 -149.247606)
			(xy 10.551668 -149.247606) (xy 10.562082 -149.248876) (xy 13.883386 -149.248876) (xy 13.892628 -149.248412)
			(xy 13.909878 -149.241753) (xy 13.923666 -149.229432) (xy 13.928344 -149.221444) (xy 13.97 -149.141688)
			(xy 13.972286 -149.136608) (xy 13.974167 -149.131293) (xy 13.975829 -149.120143) (xy 13.975588 -149.11451)
			(xy 13.974572 -149.100794) (xy 13.966444 -149.08911) (xy 13.949056 -149.063405) (xy 13.919971 -149.00858)
			(xy 13.89777 -148.950626) (xy 13.88278 -148.890402) (xy 13.875224 -148.828803) (xy 13.87475 -148.797772)
			(xy 13.875252 -148.765811) (xy 13.883263 -148.702393) (xy 13.89916 -148.640479) (xy 13.922692 -148.581046)
			(xy 13.953486 -148.525031) (xy 13.991059 -148.473316) (xy 14.034816 -148.426719) (xy 14.084069 -148.385974)
			(xy 14.13804 -148.351723) (xy 14.195879 -148.324506) (xy 14.256672 -148.304753) (xy 14.319462 -148.292775)
			(xy 14.383258 -148.288762) (xy 14.447054 -148.292775) (xy 14.509844 -148.304753) (xy 14.570637 -148.324506)
			(xy 14.628476 -148.351723) (xy 14.682447 -148.385974) (xy 14.7317 -148.426719) (xy 14.775457 -148.473316)
			(xy 14.81303 -148.525031) (xy 14.843824 -148.581046) (xy 14.867356 -148.640479) (xy 14.883253 -148.702393)
			(xy 14.891264 -148.765811) (xy 14.891766 -148.797772) (xy 14.891304 -148.828803) (xy 14.883755 -148.890406)
			(xy 14.868765 -148.950631) (xy 14.846558 -149.008585) (xy 14.817463 -149.063406) (xy 14.800072 -149.08911)
			(xy 14.799818 -149.089364) (xy 14.796119 -149.095098) (xy 14.791614 -149.107974) (xy 14.790928 -149.114764)
			(xy 14.79042 -149.121876) (xy 14.79169 -149.12848) (xy 14.796516 -149.141688) (xy 14.838172 -149.221444)
			(xy 14.842776 -149.229486) (xy 14.856575 -149.241831) (xy 14.873872 -149.248434) (xy 14.88313 -149.248876)
			(xy 15.535148 -149.248876) (xy 15.543506 -149.248494) (xy 15.559316 -149.243054) (xy 15.566136 -149.238208)
			(xy 15.57274 -149.232874) (xy 15.582138 -149.218904) (xy 15.58417 -149.210522) (xy 15.591575 -149.183374)
			(xy 15.614771 -149.132111) (xy 15.646762 -149.085823) (xy 15.666212 -149.065488) (xy 15.91437 -148.81733)
			(xy 15.919196 -148.811742) (xy 15.923863 -148.805001) (xy 15.929038 -148.789455) (xy 15.929356 -148.781262)
			(xy 15.929356 -148.67763) (xy 15.929815 -148.645864) (xy 15.936953 -148.582732) (xy 15.951109 -148.520796)
			(xy 15.972106 -148.460833) (xy 15.999679 -148.403594) (xy 16.033483 -148.349801) (xy 16.073094 -148.300126)
			(xy 16.095218 -148.277326) (xy 28.235148 -136.137396) (xy 28.257941 -136.115202) (xy 28.307675 -136.075527)
			(xy 28.36154 -136.04167) (xy 28.418856 -136.014058) (xy 28.478905 -135.993038) (xy 28.540929 -135.978875)
			(xy 28.60415 -135.971746) (xy 28.63596 -135.97128) (xy 28.739338 -135.97128) (xy 28.747529 -135.970964)
			(xy 28.763067 -135.965771) (xy 28.769818 -135.96112) (xy 28.775406 -135.956294) (xy 29.41447 -135.31723)
			(xy 29.432172 -135.300156) (xy 29.471949 -135.271232) (xy 29.515764 -135.248895) (xy 29.562537 -135.233696)
			(xy 29.611113 -135.226009) (xy 29.635704 -135.225536) (xy 33.836102 -135.225536) (xy 33.843976 -135.225028)
			(xy 33.854161 -135.222877) (xy 33.871718 -135.21173) (xy 33.878012 -135.203438) (xy 33.878012 -135.20293)
			(xy 33.880552 -135.19912) (xy 33.923224 -135.120888) (xy 33.926156 -135.115223) (xy 33.929365 -135.10288)
			(xy 33.929574 -135.096504) (xy 33.924494 -135.079232) (xy 33.922208 -135.072882) (xy 33.91789 -135.063484)
			(xy 33.90435 -135.040748) (xy 33.882986 -134.992337) (xy 33.868513 -134.941438) (xy 33.861208 -134.889028)
			(xy 33.86074 -134.86257) (xy 33.861226 -134.835319) (xy 33.868982 -134.781371) (xy 33.884337 -134.729076)
			(xy 33.906979 -134.679499) (xy 33.936445 -134.633649) (xy 33.972136 -134.592458) (xy 34.013327 -134.556767)
			(xy 34.059177 -134.527301) (xy 34.108754 -134.504659) (xy 34.161049 -134.489304) (xy 34.214997 -134.481548)
			(xy 34.269499 -134.481548) (xy 34.323447 -134.489304) (xy 34.375742 -134.504659) (xy 34.425319 -134.527301)
			(xy 34.471169 -134.556767) (xy 34.51236 -134.592458) (xy 34.548051 -134.633649) (xy 34.577517 -134.679499)
			(xy 34.600159 -134.729076) (xy 34.615514 -134.781371) (xy 34.62327 -134.835319) (xy 34.623756 -134.86257)
			(xy 34.623332 -134.888659) (xy 34.616226 -134.940351) (xy 34.602143 -134.990592) (xy 34.581345 -135.038446)
			(xy 34.56813 -135.060944) (xy 34.565336 -135.066532) (xy 34.561018 -135.07593) (xy 34.554922 -135.096504)
			(xy 34.555154 -135.102876) (xy 34.558372 -135.115209) (xy 34.561272 -135.120888) (xy 34.603944 -135.19912)
			(xy 34.606484 -135.20293) (xy 34.606484 -135.203438) (xy 34.612743 -135.211768) (xy 34.630317 -135.22292)
			(xy 34.64052 -135.225028) (xy 34.648394 -135.225536) (xy 75.430126 -135.225536) (xy 75.440193 -135.225106)
			(xy 75.458784 -135.217378) (xy 75.466194 -135.21055) (xy 77.798422 -132.878576) (xy 77.805818 -132.871725)
			(xy 77.824417 -132.863986) (xy 77.83449 -132.86359) (xy 94.295976 -132.86359) (xy 94.304358 -132.860542)
			(xy 94.332324 -132.850819) (xy 94.389936 -132.837153) (xy 94.448743 -132.830252) (xy 94.478348 -132.829808)
			(xy 94.509077 -132.830275) (xy 94.570086 -132.837688) (xy 94.629756 -132.852401) (xy 94.687218 -132.874199)
			(xy 94.741634 -132.902764) (xy 94.79221 -132.937679) (xy 94.838209 -132.978436) (xy 94.87896 -133.02444)
			(xy 94.913869 -133.075021) (xy 94.942427 -133.12944) (xy 94.964218 -133.186905) (xy 94.978923 -133.246577)
			(xy 94.986329 -133.307587) (xy 94.986634 -133.325362) (xy 95.107504 -133.325362) (xy 95.111575 -133.26974)
			(xy 95.123701 -133.215303) (xy 95.143624 -133.163212) (xy 95.17092 -133.114577) (xy 95.205006 -133.070434)
			(xy 95.245155 -133.031725) (xy 95.290513 -132.999274) (xy 95.340113 -132.973773) (xy 95.392897 -132.955766)
			(xy 95.44774 -132.945636) (xy 95.503474 -132.943599) (xy 95.558911 -132.949699) (xy 95.612868 -132.963805)
			(xy 95.664197 -132.985617) (xy 95.711803 -133.014671) (xy 95.754671 -133.050346) (xy 95.791888 -133.091883)
			(xy 95.822661 -133.138396) (xy 95.846333 -133.188893) (xy 95.862401 -133.2423) (xy 95.870521 -133.297476)
			(xy 95.87103 -133.325362) (xy 96.333816 -133.325362) (xy 96.337887 -133.26974) (xy 96.350013 -133.215303)
			(xy 96.369936 -133.163212) (xy 96.397232 -133.114577) (xy 96.431318 -133.070434) (xy 96.471467 -133.031725)
			(xy 96.516825 -132.999274) (xy 96.566425 -132.973773) (xy 96.619209 -132.955766) (xy 96.674052 -132.945636)
			(xy 96.729786 -132.943599) (xy 96.785223 -132.949699) (xy 96.83918 -132.963805) (xy 96.890509 -132.985617)
			(xy 96.938115 -133.014671) (xy 96.980983 -133.050346) (xy 97.0182 -133.091883) (xy 97.048973 -133.138396)
			(xy 97.072645 -133.188893) (xy 97.088713 -133.2423) (xy 97.096833 -133.297476) (xy 97.097342 -133.325362)
			(xy 97.096833 -133.353248) (xy 97.088713 -133.408424) (xy 97.072645 -133.461831) (xy 97.048973 -133.512328)
			(xy 97.0182 -133.558841) (xy 96.980983 -133.600378) (xy 96.938115 -133.636053) (xy 96.890509 -133.665107)
			(xy 96.83918 -133.686919) (xy 96.785223 -133.701025) (xy 96.729786 -133.707125) (xy 96.674052 -133.705088)
			(xy 96.619209 -133.694958) (xy 96.566425 -133.676951) (xy 96.516825 -133.65145) (xy 96.471467 -133.618999)
			(xy 96.431318 -133.58029) (xy 96.397232 -133.536147) (xy 96.369936 -133.487512) (xy 96.350013 -133.435421)
			(xy 96.337887 -133.380984) (xy 96.333816 -133.325362) (xy 95.87103 -133.325362) (xy 95.870521 -133.353248)
			(xy 95.862401 -133.408424) (xy 95.846333 -133.461831) (xy 95.822661 -133.512328) (xy 95.791888 -133.558841)
			(xy 95.754671 -133.600378) (xy 95.711803 -133.636053) (xy 95.664197 -133.665107) (xy 95.612868 -133.686919)
			(xy 95.558911 -133.701025) (xy 95.503474 -133.707125) (xy 95.44774 -133.705088) (xy 95.392897 -133.694958)
			(xy 95.340113 -133.676951) (xy 95.290513 -133.65145) (xy 95.245155 -133.618999) (xy 95.205006 -133.58029)
			(xy 95.17092 -133.536147) (xy 95.143624 -133.487512) (xy 95.123701 -133.435421) (xy 95.111575 -133.380984)
			(xy 95.107504 -133.325362) (xy 94.986634 -133.325362) (xy 94.986856 -133.338316) (xy 94.9863 -133.37256)
			(xy 94.977105 -133.440428) (xy 94.958871 -133.506444) (xy 94.931928 -133.569409) (xy 94.896766 -133.628182)
			(xy 94.875858 -133.655308) (xy 94.871286 -133.66115) (xy 94.865952 -133.674104) (xy 94.86519 -133.681216)
			(xy 94.864569 -133.687674) (xy 94.866232 -133.700536) (xy 94.868492 -133.706616) (xy 94.90964 -133.791452)
			(xy 94.915556 -133.802164) (xy 94.935056 -133.816886) (xy 94.946978 -133.819646) (xy 94.947486 -133.819646)
			(xy 94.955614 -133.820408) (xy 98.0567 -133.820408) (xy 98.06051 -133.820154) (xy 98.067457 -133.819385)
			(xy 98.080586 -133.81461) (xy 98.086418 -133.810756) (xy 98.095308 -133.802374) (xy 98.098864 -133.797548)
			(xy 98.101658 -133.792722) (xy 98.140266 -133.70433) (xy 98.142823 -133.697922) (xy 98.144764 -133.68427)
			(xy 98.144076 -133.677406) (xy 98.143568 -133.674104) (xy 98.142552 -133.668262) (xy 98.13671 -133.655562)
			(xy 98.130868 -133.649466) (xy 98.11168 -133.628159) (xy 98.079263 -133.580865) (xy 98.054292 -133.52925)
			(xy 98.037329 -133.474479) (xy 98.028758 -133.417785) (xy 98.028252 -133.389116) (xy 98.028738 -133.361865)
			(xy 98.036494 -133.307917) (xy 98.051849 -133.255622) (xy 98.074491 -133.206045) (xy 98.103957 -133.160195)
			(xy 98.139648 -133.119004) (xy 98.180839 -133.083313) (xy 98.226689 -133.053847) (xy 98.276266 -133.031205)
			(xy 98.328561 -133.01585) (xy 98.382509 -133.008094) (xy 98.437011 -133.008094) (xy 98.490959 -133.01585)
			(xy 98.543254 -133.031205) (xy 98.592831 -133.053847) (xy 98.638681 -133.083313) (xy 98.679872 -133.119004)
			(xy 98.715563 -133.160195) (xy 98.745029 -133.206045) (xy 98.767671 -133.255622) (xy 98.783026 -133.307917)
			(xy 98.790782 -133.361865) (xy 98.791268 -133.389116) (xy 98.790756 -133.417369) (xy 98.78242 -133.473255)
			(xy 98.765934 -133.527302) (xy 98.741658 -133.578326) (xy 98.710122 -133.625213) (xy 98.691446 -133.646418)
			(xy 98.68535 -133.655816) (xy 98.675698 -133.675628) (xy 98.675444 -133.67766) (xy 98.674428 -133.68274)
			(xy 98.67519 -133.689852) (xy 98.675739 -133.693525) (xy 98.677783 -133.700666) (xy 98.679254 -133.704076)
			(xy 98.717862 -133.792722) (xy 98.720656 -133.797548) (xy 98.724212 -133.802374) (xy 98.733102 -133.810756)
			(xy 98.738908 -133.814658) (xy 98.752052 -133.819429) (xy 98.75901 -133.820154) (xy 98.76282 -133.820408)
			(xy 114.636042 -133.820408) (xy 114.636804 -133.820408) (xy 114.646395 -133.819854) (xy 114.664147 -133.812544)
			(xy 114.671348 -133.806184) (xy 114.721894 -133.75767) (xy 114.724989 -133.754715) (xy 114.730224 -133.747946)
			(xy 114.732308 -133.744208) (xy 114.737134 -133.733032) (xy 114.737642 -133.723126) (xy 114.739585 -133.69083)
			(xy 114.750638 -133.627079) (xy 114.769688 -133.565246) (xy 114.796427 -133.506329) (xy 114.830425 -133.451279)
			(xy 114.871131 -133.400987) (xy 114.917887 -133.356265) (xy 114.969939 -133.317835) (xy 115.026446 -133.286319)
			(xy 115.086494 -133.262225) (xy 115.149113 -133.245942) (xy 115.213291 -133.237735) (xy 115.277993 -133.237735)
			(xy 115.342171 -133.245942) (xy 115.40479 -133.262225) (xy 115.464838 -133.286319) (xy 115.521345 -133.317835)
			(xy 115.573397 -133.356265) (xy 115.620153 -133.400987) (xy 115.660859 -133.451279) (xy 115.694857 -133.506329)
			(xy 115.721596 -133.565246) (xy 115.740646 -133.627079) (xy 115.751699 -133.69083) (xy 115.753642 -133.723126)
			(xy 115.75415 -133.733032) (xy 115.758976 -133.744208) (xy 115.761068 -133.747941) (xy 115.766299 -133.754711)
			(xy 115.76939 -133.75767) (xy 115.819936 -133.806184) (xy 115.827128 -133.812558) (xy 115.844885 -133.819863)
			(xy 115.85448 -133.820408) (xy 116.26215 -133.820408) (xy 116.270341 -133.820091) (xy 116.285878 -133.814898)
			(xy 116.29263 -133.810248) (xy 116.298218 -133.805422) (xy 117.524784 -132.578856) (xy 117.542475 -132.56186)
			(xy 117.582171 -132.533037) (xy 117.625881 -132.510769) (xy 117.672534 -132.495603) (xy 117.720982 -132.48791)
			(xy 117.74551 -132.487416) (xy 119.260112 -132.487416) (xy 119.284637 -132.487919) (xy 119.33308 -132.495624)
			(xy 119.379727 -132.510797) (xy 119.423432 -132.533065) (xy 119.463127 -132.561883) (xy 119.480838 -132.578856)
			(xy 119.708168 -132.806186) (xy 119.713756 -132.811012) (xy 119.720497 -132.815678) (xy 119.736043 -132.820852)
			(xy 119.744236 -132.821172) (xy 119.996458 -132.821172) (xy 120.028271 -132.8216) (xy 120.091495 -132.828724)
			(xy 120.153524 -132.842887) (xy 120.213575 -132.86391) (xy 120.270893 -132.891528) (xy 120.324756 -132.925395)
			(xy 120.374485 -132.965083) (xy 120.39727 -132.987288) (xy 121.215658 -133.805676) (xy 121.22013 -133.80988)
			(xy 121.230667 -133.816169) (xy 121.236486 -133.818122) (xy 121.236994 -133.818122) (xy 121.242836 -133.819646)
			(xy 121.243344 -133.819646) (xy 121.251472 -133.820408) (xy 151.697436 -133.820408) (xy 151.729203 -133.820865)
			(xy 151.792337 -133.827999) (xy 151.854276 -133.842152) (xy 151.914243 -133.863144) (xy 151.971485 -133.890714)
			(xy 152.025284 -133.924514) (xy 152.074964 -133.96412) (xy 152.09774 -133.98627) (xy 152.298103 -134.186633)
			(xy 153.693108 -134.186633) (xy 153.693108 -134.122711) (xy 153.701119 -134.059293) (xy 153.717016 -133.997379)
			(xy 153.740548 -133.937946) (xy 153.771342 -133.881931) (xy 153.808915 -133.830216) (xy 153.852672 -133.783619)
			(xy 153.901925 -133.742874) (xy 153.955896 -133.708623) (xy 154.013735 -133.681406) (xy 154.074528 -133.661653)
			(xy 154.137318 -133.649675) (xy 154.201114 -133.645662) (xy 154.26491 -133.649675) (xy 154.3277 -133.661653)
			(xy 154.388493 -133.681406) (xy 154.446332 -133.708623) (xy 154.500303 -133.742874) (xy 154.549556 -133.783619)
			(xy 154.593313 -133.830216) (xy 154.630886 -133.881931) (xy 154.66168 -133.937946) (xy 154.685212 -133.997379)
			(xy 154.701109 -134.059293) (xy 154.70912 -134.122711) (xy 154.709622 -134.154672) (xy 154.70912 -134.186633)
			(xy 154.701109 -134.250051) (xy 154.688892 -134.297631) (xy 161.049964 -134.297631) (xy 161.049964 -134.233709)
			(xy 161.057975 -134.170291) (xy 161.073872 -134.108377) (xy 161.097404 -134.048944) (xy 161.128198 -133.992929)
			(xy 161.165771 -133.941214) (xy 161.209528 -133.894617) (xy 161.258781 -133.853872) (xy 161.312752 -133.819621)
			(xy 161.370591 -133.792404) (xy 161.431384 -133.772651) (xy 161.494174 -133.760673) (xy 161.55797 -133.75666)
			(xy 161.621766 -133.760673) (xy 161.684556 -133.772651) (xy 161.745349 -133.792404) (xy 161.803188 -133.819621)
			(xy 161.857159 -133.853872) (xy 161.906412 -133.894617) (xy 161.950169 -133.941214) (xy 161.987742 -133.992929)
			(xy 162.018536 -134.048944) (xy 162.042068 -134.108377) (xy 162.057965 -134.170291) (xy 162.065976 -134.233709)
			(xy 162.066478 -134.26567) (xy 162.065976 -134.297631) (xy 162.057965 -134.361049) (xy 162.042068 -134.422963)
			(xy 162.018536 -134.482396) (xy 161.987742 -134.538411) (xy 161.950169 -134.590126) (xy 161.906412 -134.636723)
			(xy 161.857159 -134.677468) (xy 161.803188 -134.711719) (xy 161.745349 -134.738936) (xy 161.684556 -134.758689)
			(xy 161.621766 -134.770667) (xy 161.55797 -134.774681) (xy 161.494174 -134.770667) (xy 161.431384 -134.758689)
			(xy 161.370591 -134.738936) (xy 161.312752 -134.711719) (xy 161.258781 -134.677468) (xy 161.209528 -134.636723)
			(xy 161.165771 -134.590126) (xy 161.128198 -134.538411) (xy 161.097404 -134.482396) (xy 161.073872 -134.422963)
			(xy 161.057975 -134.361049) (xy 161.049964 -134.297631) (xy 154.688892 -134.297631) (xy 154.685212 -134.311965)
			(xy 154.66168 -134.371398) (xy 154.630886 -134.427413) (xy 154.593313 -134.479128) (xy 154.549556 -134.525725)
			(xy 154.500303 -134.56647) (xy 154.446332 -134.600721) (xy 154.388493 -134.627938) (xy 154.3277 -134.647691)
			(xy 154.26491 -134.659669) (xy 154.201114 -134.663683) (xy 154.137318 -134.659669) (xy 154.074528 -134.647691)
			(xy 154.013735 -134.627938) (xy 153.955896 -134.600721) (xy 153.901925 -134.56647) (xy 153.852672 -134.525725)
			(xy 153.808915 -134.479128) (xy 153.771342 -134.427413) (xy 153.740548 -134.371398) (xy 153.717016 -134.311965)
			(xy 153.701119 -134.250051) (xy 153.693108 -134.186633) (xy 152.298103 -134.186633) (xy 154.75331 -136.64184)
			(xy 154.754326 -136.642602) (xy 154.755342 -136.643618) (xy 154.765255 -136.651541) (xy 154.789912 -136.657402)
			(xy 154.802332 -136.654794) (xy 154.837384 -136.64438) (xy 154.864816 -136.636252) (xy 154.892502 -136.628124)
			(xy 154.89784 -136.62591) (xy 154.907449 -136.619494) (xy 154.911552 -136.615424) (xy 154.912568 -136.614408)
			(xy 154.91714 -136.609582) (xy 154.922474 -136.59866) (xy 154.924252 -136.59104) (xy 154.930007 -136.565604)
			(xy 154.946041 -136.515975) (xy 154.956256 -136.49198) (xy 154.972144 -136.457669) (xy 155.012573 -136.393777)
			(xy 155.036774 -136.364726) (xy 155.039314 -136.361678) (xy 155.043842 -136.355095) (xy 155.048892 -136.339944)
			(xy 155.04922 -136.33196) (xy 155.04922 -136.300464) (xy 155.048822 -136.292494) (xy 155.043768 -136.277368)
			(xy 155.039314 -136.270746) (xy 155.036774 -136.267698) (xy 155.01736 -136.244552) (xy 154.983571 -136.194472)
			(xy 154.955948 -136.140743) (xy 154.93488 -136.084122) (xy 154.920663 -136.025406) (xy 154.913497 -135.965419)
			(xy 154.913076 -135.935212) (xy 154.913578 -135.903251) (xy 154.921589 -135.839833) (xy 154.937486 -135.777919)
			(xy 154.961018 -135.718486) (xy 154.991812 -135.662471) (xy 155.029385 -135.610756) (xy 155.073142 -135.564159)
			(xy 155.122395 -135.523414) (xy 155.176366 -135.489163) (xy 155.234205 -135.461946) (xy 155.294998 -135.442193)
			(xy 155.357788 -135.430215) (xy 155.421584 -135.426202) (xy 155.48538 -135.430215) (xy 155.54817 -135.442193)
			(xy 155.608963 -135.461946) (xy 155.666802 -135.489163) (xy 155.720773 -135.523414) (xy 155.770026 -135.564159)
			(xy 155.813783 -135.610756) (xy 155.851356 -135.662471) (xy 155.88215 -135.718486) (xy 155.905682 -135.777919)
			(xy 155.921579 -135.839833) (xy 155.92959 -135.903251) (xy 155.930092 -135.935212) (xy 155.929659 -135.965418)
			(xy 155.922501 -136.025405) (xy 155.908287 -136.084121) (xy 155.887217 -136.14074) (xy 155.859588 -136.194464)
			(xy 155.825789 -136.244537) (xy 155.806394 -136.267698) (xy 155.803854 -136.270746) (xy 155.799331 -136.277331)
			(xy 155.794293 -136.292482) (xy 155.793948 -136.300464) (xy 155.793948 -136.33196) (xy 155.794335 -136.339934)
			(xy 155.799368 -136.355075) (xy 155.803854 -136.361678) (xy 155.806394 -136.364726) (xy 155.825808 -136.387872)
			(xy 155.859597 -136.437952) (xy 155.887219 -136.491681) (xy 155.908286 -136.548302) (xy 155.922501 -136.607019)
			(xy 155.929664 -136.667006) (xy 155.930092 -136.697212) (xy 155.930092 -136.701276) (xy 155.929347 -136.733286)
			(xy 155.920799 -136.796744) (xy 155.904362 -136.85863) (xy 155.880297 -136.917966) (xy 155.865068 -136.946132)
			(xy 155.861512 -136.952482) (xy 155.85821 -136.96442) (xy 155.85821 -136.968738) (xy 155.858464 -136.974834)
			(xy 155.858949 -136.980001) (xy 155.861769 -136.989986) (xy 155.864052 -136.994646) (xy 155.909772 -137.07237)
			(xy 155.914536 -137.079799) (xy 155.928069 -137.091102) (xy 155.944644 -137.097121) (xy 155.95346 -137.097516)
			(xy 163.658042 -137.097516) (xy 163.66744 -137.0965) (xy 163.667948 -137.0965) (xy 163.67318 -137.095313)
			(xy 163.683042 -137.091093) (xy 163.687506 -137.088118) (xy 163.693856 -137.082784) (xy 163.696904 -137.079736)
			(xy 163.715446 -137.072116) (xy 163.729924 -137.072116) (xy 164.1729 -136.62914) (xy 164.179509 -136.621854)
			(xy 164.1871 -136.603728) (xy 164.187296 -136.584077) (xy 164.184076 -136.574784) (xy 164.181282 -136.567672)
			(xy 164.149786 -136.487662) (xy 164.146796 -136.480948) (xy 164.137632 -136.469465) (xy 164.131752 -136.465056)
			(xy 164.12591 -136.460738) (xy 164.112194 -136.456166) (xy 164.104574 -136.455912) (xy 164.072214 -136.454273)
			(xy 164.008271 -136.4438) (xy 163.946177 -136.425285) (xy 163.88694 -136.399028) (xy 163.831521 -136.365455)
			(xy 163.780819 -136.32511) (xy 163.757864 -136.302242) (xy 163.757356 -136.301734) (xy 163.75322 -136.297848)
			(xy 163.743607 -136.291823) (xy 163.738306 -136.289796) (xy 163.737036 -136.289288) (xy 163.734242 -136.288272)
			(xy 163.732464 -136.287764) (xy 163.721034 -136.286494) (xy 163.691316 -136.290812) (xy 163.674044 -136.293352)
			(xy 163.673536 -136.293352) (xy 163.644326 -136.297416) (xy 163.642548 -136.29767) (xy 163.629848 -136.299448)
			(xy 163.624817 -136.300703) (xy 163.615354 -136.304935) (xy 163.611052 -136.30783) (xy 163.60648 -136.310878)
			(xy 163.598606 -136.319768) (xy 163.595558 -136.325356) (xy 163.580792 -136.352116) (xy 163.545802 -136.40223)
			(xy 163.505057 -136.447789) (xy 163.459146 -136.488136) (xy 163.408729 -136.522689) (xy 163.354534 -136.55095)
			(xy 163.297343 -136.572511) (xy 163.23798 -136.587062) (xy 163.1773 -136.594393) (xy 163.14674 -136.59485)
			(xy 163.114019 -136.594345) (xy 163.049118 -136.585952) (xy 162.985831 -136.5693) (xy 162.925204 -136.544664)
			(xy 162.86824 -136.512451) (xy 162.81588 -136.473195) (xy 162.768992 -136.427544) (xy 162.728349 -136.376253)
			(xy 162.694624 -136.320171) (xy 162.668375 -136.260225) (xy 162.650037 -136.197406) (xy 162.639911 -136.132752)
			(xy 162.638486 -136.100058) (xy 162.638232 -136.094724) (xy 162.638232 -136.089644) (xy 162.632644 -136.077198)
			(xy 162.630523 -136.073598) (xy 162.625295 -136.067082) (xy 162.62223 -136.064244) (xy 162.56762 -136.014206)
			(xy 162.564594 -136.011455) (xy 162.557832 -136.006858) (xy 162.554158 -136.005062) (xy 162.54984 -136.003538)
			(xy 162.54857 -136.003284) (xy 162.541204 -136.000744) (xy 162.530536 -136.001252) (xy 162.497516 -136.002268)
			(xy 162.466817 -136.001758) (xy 162.405875 -135.99427) (xy 162.346279 -135.979498) (xy 162.288895 -135.957656)
			(xy 162.234559 -135.929063) (xy 162.184062 -135.894134) (xy 162.138138 -135.853378) (xy 162.097457 -135.807389)
			(xy 162.062611 -135.756835) (xy 162.034105 -135.702453) (xy 162.012356 -135.645034) (xy 161.997681 -135.585414)
			(xy 161.990291 -135.52446) (xy 161.98977 -135.49376) (xy 161.990236 -135.46303) (xy 161.997649 -135.402019)
			(xy 162.012361 -135.342346) (xy 162.034158 -135.284881) (xy 162.062722 -135.230462) (xy 162.097636 -135.179883)
			(xy 162.138393 -135.13388) (xy 162.184397 -135.093125) (xy 162.234977 -135.058212) (xy 162.289397 -135.02965)
			(xy 162.346863 -135.007855) (xy 162.406537 -134.993146) (xy 162.467548 -134.985735) (xy 162.498278 -134.985252)
			(xy 162.530998 -134.985758) (xy 162.595897 -134.994153) (xy 162.659182 -135.010807) (xy 162.719807 -135.035444)
			(xy 162.776769 -135.067657) (xy 162.829127 -135.106914) (xy 162.876013 -135.152564) (xy 162.916654 -135.203855)
			(xy 162.950377 -135.259936) (xy 162.976625 -135.319881) (xy 162.994962 -135.382699) (xy 163.005088 -135.447351)
			(xy 163.006532 -135.480044) (xy 163.006532 -135.480298) (xy 163.006786 -135.490458) (xy 163.012374 -135.502904)
			(xy 163.014496 -135.506503) (xy 163.019725 -135.513017) (xy 163.022788 -135.515858) (xy 163.077398 -135.565896)
			(xy 163.080424 -135.568646) (xy 163.087188 -135.573241) (xy 163.09086 -135.57504) (xy 163.095178 -135.576564)
			(xy 163.096448 -135.576818) (xy 163.103814 -135.579358) (xy 163.114482 -135.57885) (xy 163.146486 -135.577834)
			(xy 163.14674 -135.577834) (xy 163.180618 -135.578396) (xy 163.247772 -135.587398) (xy 163.313137 -135.605238)
			(xy 163.375554 -135.631599) (xy 163.433918 -135.666014) (xy 163.487196 -135.707875) (xy 163.51123 -135.731758)
			(xy 163.511738 -135.732266) (xy 163.515873 -135.736152) (xy 163.525487 -135.742178) (xy 163.530788 -135.744204)
			(xy 163.532058 -135.744712) (xy 163.534852 -135.745728) (xy 163.53663 -135.746236) (xy 163.54806 -135.747506)
			(xy 163.577778 -135.743188) (xy 163.59505 -135.740648) (xy 163.595558 -135.740648) (xy 163.624768 -135.736584)
			(xy 163.626546 -135.73633) (xy 163.639246 -135.734552) (xy 163.644277 -135.733298) (xy 163.653741 -135.729066)
			(xy 163.658042 -135.72617) (xy 163.662614 -135.723122) (xy 163.670488 -135.714232) (xy 163.673536 -135.708644)
			(xy 163.688302 -135.681883) (xy 163.723292 -135.631769) (xy 163.764036 -135.58621) (xy 163.809948 -135.545862)
			(xy 163.860364 -135.511309) (xy 163.914559 -135.483047) (xy 163.97175 -135.461486) (xy 164.031114 -135.446934)
			(xy 164.091794 -135.439602) (xy 164.122354 -135.43915) (xy 164.135076 -135.43923) (xy 164.160488 -135.440502)
			(xy 164.173154 -135.44169) (xy 164.2061 -135.445539) (xy 164.270676 -135.460693) (xy 164.332734 -135.484113)
			(xy 164.391222 -135.5154) (xy 164.445147 -135.554025) (xy 164.493593 -135.599332) (xy 164.535739 -135.650552)
			(xy 164.57087 -135.706815) (xy 164.598389 -135.767168) (xy 164.61783 -135.830586) (xy 164.628862 -135.895992)
			(xy 164.630608 -135.929116) (xy 164.630862 -135.936482) (xy 164.631116 -135.945118) (xy 164.639498 -135.957056)
			(xy 164.643835 -135.962806) (xy 164.655053 -135.971827) (xy 164.661596 -135.974836) (xy 164.677852 -135.98144)
			(xy 164.67836 -135.98144) (xy 164.693854 -135.987536) (xy 164.694362 -135.987536) (xy 164.74948 -136.00938)
			(xy 164.758781 -136.012531) (xy 164.778401 -136.012301) (xy 164.796508 -136.004745) (xy 164.803836 -135.998204)
			(xy 168.659048 -132.142992) (xy 168.664382 -132.136642) (xy 168.667389 -132.132194) (xy 168.671617 -132.122329)
			(xy 168.672764 -132.117084) (xy 168.672764 -132.116576) (xy 168.67378 -132.107178) (xy 168.67378 -129.257298)
			(xy 168.673524 -129.249887) (xy 168.669258 -129.235691) (xy 168.665398 -129.229358) (xy 168.661334 -129.223262)
			(xy 168.650158 -129.213864) (xy 168.643046 -129.210816) (xy 168.614603 -129.198053) (xy 168.560786 -129.166581)
			(xy 168.51122 -129.128766) (xy 168.466647 -129.085176) (xy 168.427738 -129.036465) (xy 168.395074 -128.983362)
			(xy 168.369147 -128.926665) (xy 168.350344 -128.867224) (xy 168.338948 -128.805931) (xy 168.33513 -128.743704)
			(xy 168.338947 -128.681477) (xy 168.350342 -128.620183) (xy 168.369144 -128.560742) (xy 168.395071 -128.504045)
			(xy 168.427733 -128.450942) (xy 168.466642 -128.40223) (xy 168.511214 -128.358639) (xy 168.560779 -128.320824)
			(xy 168.614596 -128.28935) (xy 168.643046 -128.276604) (xy 168.6433 -128.276604) (xy 168.650025 -128.273447)
			(xy 168.661389 -128.263892) (xy 168.665652 -128.257808) (xy 168.669716 -128.251712) (xy 168.671748 -128.2446)
			(xy 168.672694 -128.24112) (xy 168.673709 -128.233981) (xy 168.67378 -128.230376) (xy 168.67378 -126.86157)
			(xy 168.673571 -126.855339) (xy 168.670492 -126.84326) (xy 168.667684 -126.837694) (xy 168.664267 -126.831777)
			(xy 168.654866 -126.821868) (xy 168.649142 -126.818136) (xy 168.643808 -126.815342) (xy 168.6433 -126.815342)
			(xy 168.638474 -126.81331) (xy 168.576244 -126.793498) (xy 168.546272 -126.783846) (xy 168.53906 -126.781814)
			(xy 168.524086 -126.781557) (xy 168.516808 -126.783338) (xy 168.512744 -126.784608) (xy 168.50741 -126.786386)
			(xy 168.49471 -126.795784) (xy 168.48963 -126.802642) (xy 168.471679 -126.826879) (xy 168.430958 -126.871371)
			(xy 168.385264 -126.910738) (xy 168.335237 -126.944429) (xy 168.281579 -126.97197) (xy 168.225041 -126.992977)
			(xy 168.166417 -127.007154) (xy 168.106529 -127.014303) (xy 168.076372 -127.014732) (xy 168.045888 -127.014305)
			(xy 167.985354 -127.007057) (xy 167.926122 -126.992621) (xy 167.869041 -126.971203) (xy 167.814932 -126.943112)
			(xy 167.764571 -126.908751) (xy 167.741346 -126.889002) (xy 167.737852 -126.886076) (xy 167.730061 -126.881352)
			(xy 167.725852 -126.879604) (xy 167.711628 -126.87427) (xy 167.707701 -126.872873) (xy 167.699533 -126.87121)
			(xy 167.695372 -126.870968) (xy 167.670988 -126.870206) (xy 167.662966 -126.870646) (xy 167.647813 -126.875958)
			(xy 167.64127 -126.88062) (xy 167.640508 -126.881128) (xy 167.613449 -126.901912) (xy 167.55482 -126.936812)
			(xy 167.492049 -126.963553) (xy 167.426263 -126.981653) (xy 167.358647 -126.990788) (xy 167.324532 -126.991364)
			(xy 167.290103 -126.990789) (xy 167.221875 -126.981497) (xy 167.155523 -126.96309) (xy 167.092258 -126.935905)
			(xy 167.033236 -126.900439) (xy 167.006016 -126.87935) (xy 166.999412 -126.874778) (xy 166.988236 -126.868428)
			(xy 166.980108 -126.86538) (xy 166.97212 -126.862902) (xy 166.955407 -126.862652) (xy 166.947342 -126.864872)
			(xy 166.943278 -126.866142) (xy 166.938727 -126.867698) (xy 166.93028 -126.872296) (xy 166.926514 -126.875286)
			(xy 166.89908 -126.89712) (xy 166.83935 -126.933839) (xy 166.775144 -126.962008) (xy 166.707677 -126.981092)
			(xy 166.638229 -126.990731) (xy 166.603172 -126.991364) (xy 166.602918 -126.991364) (xy 166.570329 -126.990838)
			(xy 166.505688 -126.982502) (xy 166.44264 -126.965977) (xy 166.38222 -126.941533) (xy 166.325417 -126.909572)
			(xy 166.273163 -126.870617) (xy 166.24935 -126.848362) (xy 166.249096 -126.848108) (xy 166.24173 -126.840996)
			(xy 166.237412 -126.839218) (xy 166.230046 -126.836424) (xy 166.226342 -126.835262) (xy 166.218686 -126.833983)
			(xy 166.214806 -126.833884) (xy 166.142416 -126.833884) (xy 166.138539 -126.834019) (xy 166.130886 -126.835289)
			(xy 166.127176 -126.836424) (xy 166.11981 -126.839218) (xy 166.115492 -126.840996) (xy 166.108126 -126.848108)
			(xy 166.107872 -126.848362) (xy 166.083993 -126.870695) (xy 166.031506 -126.909682) (xy 166.003224 -126.926086)
			(xy 165.96614 -126.945136) (xy 165.956234 -126.949708) (xy 165.955218 -126.950724) (xy 165.949122 -126.957836)
			(xy 165.94614 -126.961361) (xy 165.941404 -126.969284) (xy 165.939724 -126.973584) (xy 165.914578 -127.042418)
			(xy 165.913094 -127.04684) (xy 165.911564 -127.056041) (xy 165.91153 -127.060706) (xy 165.911784 -127.066294)
			(xy 165.912038 -127.07112) (xy 165.91661 -127.080772) (xy 165.928324 -127.106348) (xy 165.946672 -127.159528)
			(xy 165.959028 -127.21441) (xy 165.965241 -127.270322) (xy 165.965632 -127.29845) (xy 165.965632 -127.299212)
			(xy 165.96513 -127.331173) (xy 165.957119 -127.394591) (xy 165.941222 -127.456505) (xy 165.91769 -127.515938)
			(xy 165.886896 -127.571953) (xy 165.849323 -127.623668) (xy 165.805566 -127.670265) (xy 165.756313 -127.71101)
			(xy 165.702342 -127.745261) (xy 165.644503 -127.772478) (xy 165.58371 -127.792231) (xy 165.52092 -127.804209)
			(xy 165.457124 -127.808223) (xy 165.393328 -127.804209) (xy 165.330538 -127.792231) (xy 165.269745 -127.772478)
			(xy 165.211906 -127.745261) (xy 165.157935 -127.71101) (xy 165.108682 -127.670265) (xy 165.064925 -127.623668)
			(xy 165.027352 -127.571953) (xy 164.996558 -127.515938) (xy 164.973026 -127.456505) (xy 164.957129 -127.394591)
			(xy 164.949118 -127.331173) (xy 164.948616 -127.299212) (xy 164.949114 -127.266963) (xy 164.957269 -127.202984)
			(xy 164.973449 -127.140549) (xy 164.997394 -127.080662) (xy 165.02872 -127.024283) (xy 165.066924 -126.972319)
			(xy 165.111393 -126.925603) (xy 165.161412 -126.884885) (xy 165.216178 -126.850819) (xy 165.245288 -126.836932)
			(xy 165.255194 -126.83236) (xy 165.25621 -126.831344) (xy 165.262306 -126.824232) (xy 165.265284 -126.820705)
			(xy 165.270013 -126.812779) (xy 165.271704 -126.808484) (xy 165.29685 -126.73965) (xy 165.298339 -126.735228)
			(xy 165.299881 -126.726027) (xy 165.299898 -126.721362) (xy 165.299644 -126.715774) (xy 165.29939 -126.710948)
			(xy 165.294818 -126.701296) (xy 165.28288 -126.673864) (xy 165.28288 -126.673356) (xy 165.273886 -126.650309)
			(xy 165.259893 -126.602853) (xy 165.25494 -126.578614) (xy 165.253012 -126.57018) (xy 165.244305 -126.555245)
			(xy 165.237922 -126.549404) (xy 165.220904 -126.534926) (xy 165.217876 -126.53258) (xy 165.211244 -126.528749)
			(xy 165.207696 -126.527306) (xy 165.184328 -126.518162) (xy 165.183058 -126.518162) (xy 165.176454 -126.517908)
			(xy 165.146228 -126.515368) (xy 165.134987 -126.514029) (xy 165.112626 -126.510472) (xy 165.101524 -126.508256)
			(xy 165.09492 -126.506986) (xy 165.091618 -126.506224) (xy 165.077648 -126.509018) (xy 165.067488 -126.513082)
			(xy 165.025324 -126.540768) (xy 165.001956 -126.556262) (xy 164.998444 -126.558957) (xy 164.992313 -126.565342)
			(xy 164.989764 -126.568962) (xy 164.984176 -126.57709) (xy 164.982144 -126.586996) (xy 164.9752 -126.617778)
			(xy 164.954705 -126.677462) (xy 164.926988 -126.734154) (xy 164.892474 -126.786984) (xy 164.851692 -126.835141)
			(xy 164.805269 -126.877886) (xy 164.753917 -126.914563) (xy 164.698425 -126.944609) (xy 164.639643 -126.967563)
			(xy 164.578474 -126.983073) (xy 164.515856 -126.9909) (xy 164.484304 -126.991364) (xy 164.453573 -126.990919)
			(xy 164.392558 -126.98351) (xy 164.332882 -126.968801) (xy 164.275413 -126.947005) (xy 164.220992 -126.918441)
			(xy 164.17041 -126.883525) (xy 164.124406 -126.842766) (xy 164.083651 -126.796759) (xy 164.048739 -126.746174)
			(xy 164.020179 -126.69175) (xy 163.998387 -126.63428) (xy 163.983683 -126.574602) (xy 163.976279 -126.513587)
			(xy 163.975796 -126.482856) (xy 163.975796 -126.471172) (xy 163.97097 -126.460504) (xy 163.968864 -126.456339)
			(xy 163.96337 -126.448796) (xy 163.960048 -126.445518) (xy 163.929568 -126.418848) (xy 163.900612 -126.393702)
			(xy 163.896382 -126.390223) (xy 163.886776 -126.384965) (xy 163.881562 -126.383288) (xy 163.871402 -126.38024)
			(xy 163.86048 -126.381764) (xy 163.843355 -126.383932) (xy 163.808908 -126.386221) (xy 163.791646 -126.386336)
			(xy 163.760102 -126.385863) (xy 163.697499 -126.378065) (xy 163.63634 -126.362583) (xy 163.577567 -126.339655)
			(xy 163.522081 -126.309633) (xy 163.470734 -126.272978) (xy 163.424316 -126.230253) (xy 163.38354 -126.182114)
			(xy 163.349031 -126.129302) (xy 163.32132 -126.072626) (xy 163.300833 -126.012958) (xy 163.287883 -125.951214)
			(xy 163.282671 -125.888342) (xy 163.285275 -125.825308) (xy 163.295657 -125.763081) (xy 163.313656 -125.702615)
			(xy 163.338996 -125.644841) (xy 163.371288 -125.590644) (xy 163.410036 -125.540859) (xy 163.454645 -125.496248)
			(xy 163.50443 -125.457499) (xy 163.558625 -125.425204) (xy 163.616398 -125.399862) (xy 163.676863 -125.381861)
			(xy 163.73909 -125.371477) (xy 163.802124 -125.36887) (xy 163.864996 -125.374081) (xy 163.92674 -125.387028)
			(xy 163.986409 -125.407513) (xy 164.043086 -125.435222) (xy 164.0959 -125.469729) (xy 164.14404 -125.510504)
			(xy 164.186766 -125.55692) (xy 164.223423 -125.608265) (xy 164.253447 -125.66375) (xy 164.276378 -125.722523)
			(xy 164.291862 -125.783681) (xy 164.299662 -125.846284) (xy 164.300154 -125.877828) (xy 164.300154 -125.889512)
			(xy 164.30498 -125.90018) (xy 164.307083 -125.904347) (xy 164.312572 -125.911896) (xy 164.315902 -125.915166)
			(xy 164.346382 -125.941836) (xy 164.375338 -125.966982) (xy 164.37957 -125.970458) (xy 164.389178 -125.975708)
			(xy 164.394388 -125.977396) (xy 164.404548 -125.980444) (xy 164.41547 -125.97892) (xy 164.432595 -125.976754)
			(xy 164.467042 -125.974468) (xy 164.484304 -125.974348) (xy 164.509753 -125.974655) (xy 164.560396 -125.97974)
			(xy 164.585396 -125.984508) (xy 164.592 -125.985778) (xy 164.595302 -125.98654) (xy 164.609272 -125.983746)
			(xy 164.619432 -125.979682) (xy 164.661596 -125.951996) (xy 164.684964 -125.936502) (xy 164.688474 -125.933805)
			(xy 164.694599 -125.927416) (xy 164.697156 -125.923802) (xy 164.702744 -125.915674) (xy 164.704776 -125.905768)
			(xy 164.711722 -125.874988) (xy 164.73222 -125.815308) (xy 164.75994 -125.758621) (xy 164.794456 -125.705797)
			(xy 164.835238 -125.657645) (xy 164.881662 -125.614905) (xy 164.933013 -125.578233) (xy 164.988504 -125.548191)
			(xy 165.047284 -125.525241) (xy 165.108451 -125.509735) (xy 165.171065 -125.50191) (xy 165.202616 -125.5014)
			(xy 165.234556 -125.501896) (xy 165.297934 -125.509888) (xy 165.359811 -125.525757) (xy 165.419213 -125.549253)
			(xy 165.475203 -125.580005) (xy 165.5269 -125.617529) (xy 165.573488 -125.661235) (xy 165.614234 -125.710432)
			(xy 165.648496 -125.764346) (xy 165.675734 -125.822128) (xy 165.695518 -125.882867) (xy 165.70198 -125.91415)
			(xy 165.703904 -125.922586) (xy 165.712606 -125.937527) (xy 165.718998 -125.94336) (xy 165.736016 -125.957838)
			(xy 165.739046 -125.960181) (xy 165.745681 -125.964005) (xy 165.749224 -125.965458) (xy 165.751764 -125.966474)
			(xy 165.760146 -125.969776) (xy 165.764972 -125.971554) (xy 165.776656 -125.974094) (xy 165.784276 -125.97511)
			(xy 165.81281 -125.977203) (xy 165.869183 -125.986993) (xy 165.924103 -126.003038) (xy 165.950646 -126.013718)
			(xy 165.979376 -126.026245) (xy 166.03378 -126.05737) (xy 166.083944 -126.094947) (xy 166.106856 -126.116334)
			(xy 166.107364 -126.116842) (xy 166.107618 -126.117096) (xy 166.114984 -126.124462) (xy 166.127176 -126.129288)
			(xy 166.13088 -126.130448) (xy 166.138536 -126.131723) (xy 166.142416 -126.131828) (xy 166.214806 -126.131828)
			(xy 166.218683 -126.131691) (xy 166.226335 -126.130419) (xy 166.230046 -126.129288) (xy 166.237412 -126.126494)
			(xy 166.24173 -126.124716) (xy 166.249096 -126.117604) (xy 166.24935 -126.11735) (xy 166.273136 -126.095064)
			(xy 166.325391 -126.056104) (xy 166.382198 -126.024143) (xy 166.442625 -125.999705) (xy 166.505679 -125.983193)
			(xy 166.570327 -125.974876) (xy 166.602918 -125.974348) (xy 166.603172 -125.974348) (xy 166.638231 -125.974935)
			(xy 166.707685 -125.98457) (xy 166.775154 -126.003661) (xy 166.839359 -126.031845) (xy 166.89908 -126.068588)
			(xy 166.926514 -126.090426) (xy 166.930302 -126.093386) (xy 166.938738 -126.097991) (xy 166.943278 -126.09957)
			(xy 166.947342 -126.10084) (xy 166.955393 -126.103158) (xy 166.972134 -126.102902) (xy 166.980108 -126.100332)
			(xy 166.988236 -126.097284) (xy 166.999412 -126.090934) (xy 167.006016 -126.086362) (xy 167.033221 -126.065252)
			(xy 167.092243 -126.02978) (xy 167.155511 -126.002596) (xy 167.221868 -125.984199) (xy 167.290102 -125.974925)
			(xy 167.324532 -125.974348) (xy 167.355016 -125.974775) (xy 167.41555 -125.982023) (xy 167.474782 -125.99646)
			(xy 167.531863 -126.017877) (xy 167.585973 -126.045967) (xy 167.636334 -126.080328) (xy 167.659558 -126.100078)
			(xy 167.663051 -126.103005) (xy 167.670842 -126.10773) (xy 167.675052 -126.109476) (xy 167.689276 -126.11481)
			(xy 167.693203 -126.116207) (xy 167.701371 -126.11787) (xy 167.705532 -126.118112) (xy 167.729916 -126.118874)
			(xy 167.737937 -126.118433) (xy 167.753088 -126.113118) (xy 167.759634 -126.10846) (xy 167.760396 -126.107952)
			(xy 167.787455 -126.087169) (xy 167.846084 -126.052271) (xy 167.908856 -126.025532) (xy 167.974642 -126.007432)
			(xy 168.042257 -125.998299) (xy 168.076372 -125.997716) (xy 168.089094 -125.997796) (xy 168.114505 -125.999069)
			(xy 168.127172 -126.000256) (xy 168.127172 -126.000002) (xy 168.157812 -126.003547) (xy 168.217983 -126.017113)
			(xy 168.276072 -126.037854) (xy 168.331228 -126.065466) (xy 168.382641 -126.099543) (xy 168.429557 -126.139587)
			(xy 168.471287 -126.185009) (xy 168.48963 -126.209806) (xy 168.489884 -126.21006) (xy 168.494804 -126.216395)
			(xy 168.507749 -126.225852) (xy 168.515284 -126.228602) (xy 168.51884 -126.229872) (xy 168.52265 -126.231142)
			(xy 168.530524 -126.231142) (xy 168.534468 -126.231055) (xy 168.542253 -126.22978) (xy 168.546018 -126.228602)
			(xy 168.640506 -126.198376) (xy 168.650042 -126.194369) (xy 168.665064 -126.180179) (xy 168.673257 -126.161209)
			(xy 168.67378 -126.150878) (xy 168.67378 -122.851418) (xy 168.673272 -122.840584) (xy 168.664306 -122.82086)
			(xy 168.656508 -122.813318) (xy 168.634292 -122.796308) (xy 168.584178 -122.771444) (xy 168.557194 -122.764042)
			(xy 168.546272 -122.761502) (xy 168.545256 -122.761248) (xy 168.543478 -122.760994) (xy 168.54297 -122.760994)
			(xy 168.535604 -122.759724) (xy 168.535096 -122.759724) (xy 168.522396 -122.757946) (xy 168.521634 -122.757946)
			(xy 168.49725 -122.756676) (xy 168.496742 -122.756676) (xy 168.472845 -122.757277) (xy 168.425919 -122.766351)
			(xy 168.403524 -122.77471) (xy 168.40327 -122.77471) (xy 168.399968 -122.776488) (xy 168.393618 -122.778774)
			(xy 168.392856 -122.779282) (xy 168.388284 -122.780806) (xy 168.387776 -122.78106) (xy 168.329102 -122.804682)
			(xy 168.322158 -122.807219) (xy 168.307448 -122.808636) (xy 168.300146 -122.807476) (xy 168.246806 -122.797062)
			(xy 168.237151 -122.795531) (xy 168.217939 -122.799045) (xy 168.209468 -122.80392) (xy 168.20134 -122.809254)
			(xy 168.18991 -122.825002) (xy 168.187624 -122.8344) (xy 168.17968 -122.863944) (xy 168.157666 -122.921028)
			(xy 168.128961 -122.975056) (xy 168.09398 -123.02525) (xy 168.053229 -123.070884) (xy 168.007296 -123.111298)
			(xy 167.956845 -123.145907) (xy 167.902606 -123.174212) (xy 167.845362 -123.195805) (xy 167.785941 -123.210371)
			(xy 167.725201 -123.217702) (xy 167.69461 -123.218194) (xy 167.670457 -123.21791) (xy 167.62237 -123.213332)
			(xy 167.598598 -123.20905) (xy 167.591994 -123.20778) (xy 167.578786 -123.208796) (xy 167.572436 -123.211082)
			(xy 167.566083 -123.213528) (xy 167.55488 -123.221252) (xy 167.550338 -123.226322) (xy 167.493188 -123.294648)
			(xy 167.488858 -123.300014) (xy 167.483049 -123.312513) (xy 167.481758 -123.319286) (xy 167.480742 -123.325382)
			(xy 167.482266 -123.339098) (xy 167.484806 -123.345194) (xy 167.495498 -123.374309) (xy 167.510527 -123.434486)
			(xy 167.518106 -123.496046) (xy 167.518588 -123.527058) (xy 167.518588 -123.52782) (xy 167.518111 -123.559359)
			(xy 167.510306 -123.621953) (xy 167.494819 -123.683101) (xy 167.471888 -123.741864) (xy 167.441864 -123.797339)
			(xy 167.405209 -123.848674) (xy 167.362486 -123.895081) (xy 167.314351 -123.935848) (xy 167.261543 -123.970347)
			(xy 167.204873 -123.99805) (xy 167.145212 -124.01853) (xy 167.083476 -124.031474) (xy 167.020612 -124.036682)
			(xy 166.957588 -124.034074) (xy 166.89537 -124.023691) (xy 166.834914 -124.005692) (xy 166.777148 -123.980354)
			(xy 166.72296 -123.948064) (xy 166.673183 -123.909321) (xy 166.628579 -123.864717) (xy 166.589836 -123.81494)
			(xy 166.557546 -123.760752) (xy 166.532208 -123.702986) (xy 166.514209 -123.64253) (xy 166.503826 -123.580312)
			(xy 166.501218 -123.517288) (xy 166.506426 -123.454424) (xy 166.51937 -123.392688) (xy 166.53985 -123.333027)
			(xy 166.567553 -123.276357) (xy 166.602052 -123.223549) (xy 166.642819 -123.175414) (xy 166.689226 -123.132691)
			(xy 166.740561 -123.096036) (xy 166.796036 -123.066012) (xy 166.854799 -123.043081) (xy 166.915947 -123.027594)
			(xy 166.978541 -123.019789) (xy 167.01008 -123.019312) (xy 167.034233 -123.019596) (xy 167.08232 -123.024174)
			(xy 167.106092 -123.028456) (xy 167.112696 -123.029726) (xy 167.125904 -123.02871) (xy 167.132254 -123.026424)
			(xy 167.138608 -123.023979) (xy 167.149813 -123.016258) (xy 167.154352 -123.011184) (xy 167.211502 -122.942858)
			(xy 167.215834 -122.937493) (xy 167.221645 -122.924994) (xy 167.222932 -122.91822) (xy 167.223948 -122.912124)
			(xy 167.222424 -122.898408) (xy 167.219884 -122.892312) (xy 167.209192 -122.863197) (xy 167.194163 -122.803021)
			(xy 167.186582 -122.74146) (xy 167.186102 -122.710448) (xy 167.186102 -122.709686) (xy 167.186567 -122.678956)
			(xy 167.193977 -122.617944) (xy 167.208687 -122.558269) (xy 167.230482 -122.500803) (xy 167.259046 -122.446384)
			(xy 167.293961 -122.395804) (xy 167.334718 -122.349801) (xy 167.380722 -122.309046) (xy 167.431304 -122.274134)
			(xy 167.485725 -122.245573) (xy 167.543192 -122.22378) (xy 167.602867 -122.209072) (xy 167.66388 -122.201665)
			(xy 167.69461 -122.201178) (xy 167.714958 -122.201412) (xy 167.755518 -122.204722) (xy 167.775636 -122.207782)
			(xy 167.776144 -122.207782) (xy 167.78732 -122.20956) (xy 167.79748 -122.206766) (xy 167.802703 -122.205108)
			(xy 167.812319 -122.199858) (xy 167.81653 -122.196352) (xy 167.875712 -122.14606) (xy 167.877998 -122.144028)
			(xy 167.883602 -122.13816) (xy 167.891107 -122.123784) (xy 167.89273 -122.115834) (xy 167.893492 -122.107452)
			(xy 167.893492 -120.842278) (xy 167.893428 -120.838672) (xy 167.892407 -120.831534) (xy 167.89146 -120.828054)
			(xy 167.888412 -120.82018) (xy 167.887904 -120.819418) (xy 167.881808 -120.808242) (xy 167.881808 -120.807734)
			(xy 167.870632 -120.787414) (xy 167.867076 -120.784874) (xy 167.860726 -120.780556) (xy 167.834641 -120.762089)
			(xy 167.786842 -120.719661) (xy 167.744733 -120.671581) (xy 167.708976 -120.618605) (xy 167.680136 -120.561569)
			(xy 167.658665 -120.501371) (xy 167.644902 -120.438957) (xy 167.641524 -120.407176) (xy 167.641016 -120.40108)
			(xy 167.639492 -120.360948) (xy 167.639966 -120.329476) (xy 167.647736 -120.267014) (xy 167.663152 -120.205987)
			(xy 167.685978 -120.147328) (xy 167.715865 -120.091932) (xy 167.752356 -120.040646) (xy 167.794896 -119.994253)
			(xy 167.842833 -119.953462) (xy 167.868854 -119.935752) (xy 167.875708 -119.930124) (xy 167.885443 -119.915316)
			(xy 167.887904 -119.906796) (xy 167.889174 -119.895112) (xy 167.889174 -119.810784) (xy 167.88765 -119.798084)
			(xy 167.884951 -119.789073) (xy 167.873988 -119.773806) (xy 167.866314 -119.768366) (xy 167.840534 -119.750646)
			(xy 167.793089 -119.709874) (xy 167.751006 -119.663587) (xy 167.714921 -119.612486) (xy 167.68538 -119.557343)
			(xy 167.662829 -119.498992) (xy 167.647609 -119.438314) (xy 167.639951 -119.376227) (xy 167.639492 -119.344948)
			(xy 167.639966 -119.313476) (xy 167.647736 -119.251014) (xy 167.663152 -119.189987) (xy 167.685978 -119.131328)
			(xy 167.715865 -119.075932) (xy 167.752356 -119.024646) (xy 167.794896 -118.978253) (xy 167.842833 -118.937462)
			(xy 167.868854 -118.919752) (xy 167.875708 -118.914124) (xy 167.885443 -118.899316) (xy 167.887904 -118.890796)
			(xy 167.889174 -118.879112) (xy 167.889174 -118.794784) (xy 167.88765 -118.782084) (xy 167.884951 -118.773073)
			(xy 167.873988 -118.757806) (xy 167.866314 -118.752366) (xy 167.840534 -118.734646) (xy 167.793089 -118.693874)
			(xy 167.751006 -118.647587) (xy 167.714921 -118.596486) (xy 167.68538 -118.541343) (xy 167.662829 -118.482992)
			(xy 167.647609 -118.422314) (xy 167.639951 -118.360227) (xy 167.639492 -118.328948) (xy 167.639971 -118.29771)
			(xy 167.647628 -118.235705) (xy 167.662821 -118.175105) (xy 167.685322 -118.116822) (xy 167.71479 -118.061732)
			(xy 167.750783 -118.010667) (xy 167.79276 -117.964393) (xy 167.840087 -117.923609) (xy 167.892052 -117.888927)
			(xy 167.947874 -117.86087) (xy 168.006711 -117.839861) (xy 168.067678 -117.826216) (xy 168.098724 -117.822726)
			(xy 168.102521 -117.822182) (xy 168.109914 -117.820136) (xy 168.113456 -117.818662) (xy 168.128696 -117.811804)
			(xy 168.132587 -117.809925) (xy 168.139735 -117.805071) (xy 168.14292 -117.802152) (xy 168.14927 -117.796056)
			(xy 168.15054 -117.785896) (xy 168.152572 -117.771926) (xy 168.153588 -117.762782) (xy 168.153836 -117.754862)
			(xy 168.150085 -117.739475) (xy 168.146222 -117.732556) (xy 168.144444 -117.729508) (xy 168.141904 -117.72519)
			(xy 168.128442 -117.714268) (xy 168.12006 -117.71122) (xy 168.090936 -117.7002) (xy 168.035391 -117.672051)
			(xy 167.9837 -117.637329) (xy 167.936635 -117.596554) (xy 167.894903 -117.550337) (xy 167.859127 -117.499369)
			(xy 167.829843 -117.444414) (xy 167.80749 -117.386294) (xy 167.792402 -117.325879) (xy 167.784805 -117.264073)
			(xy 167.784272 -117.232938) (xy 167.784805 -117.199887) (xy 167.793382 -117.134343) (xy 167.810382 -117.070463)
			(xy 167.83552 -117.009327) (xy 167.86837 -116.951965) (xy 167.908378 -116.899344) (xy 167.954871 -116.852354)
			(xy 167.980614 -116.831618) (xy 167.98417 -116.82857) (xy 167.98966 -116.82304) (xy 167.997296 -116.809466)
			(xy 167.999156 -116.8019) (xy 168.000172 -116.791486) (xy 168.000172 -116.711222) (xy 167.999156 -116.700808)
			(xy 167.997286 -116.693245) (xy 167.989651 -116.679675) (xy 167.98417 -116.674138) (xy 167.980614 -116.67109)
			(xy 167.954837 -116.650391) (xy 167.908332 -116.603402) (xy 167.868314 -116.550779) (xy 167.835457 -116.493411)
			(xy 167.810318 -116.432267) (xy 167.79332 -116.368378) (xy 167.784751 -116.302825) (xy 167.784272 -116.26977)
			(xy 167.784738 -116.23904) (xy 167.792149 -116.178028) (xy 167.80686 -116.118354) (xy 167.828657 -116.060888)
			(xy 167.85722 -116.006468) (xy 167.892135 -115.955888) (xy 167.932891 -115.909884) (xy 167.978896 -115.869129)
			(xy 168.029477 -115.834215) (xy 168.083897 -115.805653) (xy 168.141363 -115.783857) (xy 168.201038 -115.769147)
			(xy 168.26205 -115.761737) (xy 168.29278 -115.761262) (xy 168.293034 -115.761262) (xy 168.323253 -115.761693)
			(xy 168.383264 -115.768859) (xy 168.442 -115.783096) (xy 168.498632 -115.804205) (xy 168.525698 -115.81765)
			(xy 168.525952 -115.81765) (xy 168.531597 -115.820406) (xy 168.543802 -115.823366) (xy 168.550082 -115.823492)
			(xy 168.563798 -115.822984) (xy 168.649396 -115.77066) (xy 168.656623 -115.76587) (xy 168.667584 -115.752451)
			(xy 168.673431 -115.736142) (xy 168.67378 -115.72748) (xy 168.67378 -115.418616) (xy 168.672002 -115.405916)
			(xy 168.672002 -115.405408) (xy 168.664242 -115.373718) (xy 168.655964 -115.308999) (xy 168.655492 -115.276376)
			(xy 168.655962 -115.243753) (xy 168.664247 -115.179036) (xy 168.672002 -115.147344) (xy 168.67378 -115.140994)
			(xy 168.67378 -114.812318) (xy 168.67366 -114.806671) (xy 168.671232 -114.795642) (xy 168.668954 -114.790474)
			(xy 168.666414 -114.785902) (xy 168.660572 -114.77752) (xy 168.660318 -114.777012) (xy 168.648126 -114.767614)
			(xy 168.640506 -114.76482) (xy 168.604356 -114.75063) (xy 168.536497 -114.71287) (xy 168.505378 -114.689636)
			(xy 168.498774 -114.684556) (xy 168.479724 -114.677698) (xy 168.473588 -114.67628) (xy 168.460998 -114.676158)
			(xy 168.454832 -114.677444) (xy 168.444418 -114.680492) (xy 168.435274 -114.685064) (xy 168.430194 -114.688112)
			(xy 168.429432 -114.68862) (xy 168.404386 -114.704733) (xy 168.351258 -114.731646) (xy 168.29535 -114.752172)
			(xy 168.237429 -114.76603) (xy 168.178286 -114.773031) (xy 168.148508 -114.773456) (xy 168.14165 -114.773456)
			(xy 168.108628 -114.772516) (xy 168.043235 -114.763144) (xy 167.979606 -114.745382) (xy 167.918814 -114.719529)
			(xy 167.861881 -114.686021) (xy 167.809767 -114.645422) (xy 167.763349 -114.598417) (xy 167.72341 -114.545796)
			(xy 167.690622 -114.488446) (xy 167.665536 -114.427332) (xy 167.648577 -114.363485) (xy 167.640028 -114.297979)
			(xy 167.639492 -114.264948) (xy 167.639935 -114.234214) (xy 167.647339 -114.173194) (xy 167.662044 -114.113511)
			(xy 167.683837 -114.056036) (xy 167.712399 -114.001607) (xy 167.747314 -113.951017) (xy 167.788072 -113.905006)
			(xy 167.83408 -113.864243) (xy 167.884665 -113.829324) (xy 167.939092 -113.800756) (xy 167.996565 -113.778958)
			(xy 168.056246 -113.764247) (xy 168.117266 -113.756838) (xy 168.148 -113.75644) (xy 168.181594 -113.756981)
			(xy 168.248197 -113.76583) (xy 168.313054 -113.783374) (xy 168.375036 -113.809307) (xy 168.433062 -113.843177)
			(xy 168.459912 -113.863374) (xy 168.466262 -113.8682) (xy 168.481756 -113.873534) (xy 168.489088 -113.875912)
			(xy 168.504479 -113.876568) (xy 168.511982 -113.874804) (xy 168.514776 -113.874042) (xy 168.523666 -113.871248)
			(xy 168.52646 -113.870232) (xy 168.532556 -113.866168) (xy 168.558015 -113.849526) (xy 168.612136 -113.821765)
			(xy 168.640506 -113.810796) (xy 168.6433 -113.80978) (xy 168.649701 -113.806715) (xy 168.660643 -113.797687)
			(xy 168.66489 -113.792) (xy 168.667684 -113.787936) (xy 168.668954 -113.786412) (xy 168.669208 -113.785904)
			(xy 168.671494 -113.778538) (xy 168.672548 -113.774881) (xy 168.673696 -113.767357) (xy 168.67378 -113.763552)
			(xy 168.67378 -113.632742) (xy 168.672455 -113.621512) (xy 168.661491 -113.601767) (xy 168.643127 -113.588621)
			(xy 168.632124 -113.586006) (xy 168.63187 -113.586006) (xy 168.60517 -113.580724) (xy 168.553509 -113.563597)
			(xy 168.504804 -113.539307) (xy 168.460043 -113.508344) (xy 168.420134 -113.471337) (xy 168.385886 -113.429037)
			(xy 168.37152 -113.40592) (xy 168.366694 -113.397792) (xy 168.359582 -113.392204) (xy 168.35588 -113.389422)
			(xy 168.347703 -113.38508) (xy 168.343326 -113.383568) (xy 168.27881 -113.363248) (xy 168.274226 -113.361966)
			(xy 168.264765 -113.360938) (xy 168.260014 -113.361216) (xy 168.25087 -113.361724) (xy 168.242488 -113.365534)
			(xy 168.209415 -113.379801) (xy 168.140256 -113.399923) (xy 168.068951 -113.410096) (xy 168.032938 -113.410746)
			(xy 168.032684 -113.410746) (xy 168.000721 -113.410243) (xy 167.9373 -113.402229) (xy 167.875383 -113.38633)
			(xy 167.815947 -113.362796) (xy 167.75993 -113.331998) (xy 167.708213 -113.294423) (xy 167.661614 -113.250662)
			(xy 167.620867 -113.201406) (xy 167.586615 -113.147431) (xy 167.559397 -113.08959) (xy 167.539644 -113.028793)
			(xy 167.527665 -112.965999) (xy 167.523651 -112.9022) (xy 167.527665 -112.838401) (xy 167.539644 -112.775607)
			(xy 167.559397 -112.71481) (xy 167.586615 -112.656969) (xy 167.620867 -112.602994) (xy 167.661614 -112.553738)
			(xy 167.708213 -112.509977) (xy 167.75993 -112.472402) (xy 167.815947 -112.441604) (xy 167.875383 -112.41807)
			(xy 167.9373 -112.402171) (xy 168.000721 -112.394157) (xy 168.032684 -112.39373) (xy 168.063598 -112.394186)
			(xy 168.124971 -112.401679) (xy 168.184983 -112.416559) (xy 168.242749 -112.438603) (xy 168.297415 -112.467489)
			(xy 168.348177 -112.502788) (xy 168.394284 -112.543982) (xy 168.435058 -112.590461) (xy 168.469895 -112.641541)
			(xy 168.498283 -112.696467) (xy 168.519803 -112.75443) (xy 168.527476 -112.784382) (xy 168.52918 -112.79072)
			(xy 168.535356 -112.802294) (xy 168.539668 -112.807242) (xy 168.550336 -112.816132) (xy 168.577006 -112.832388)
			(xy 168.583289 -112.835961) (xy 168.597212 -112.839817) (xy 168.604438 -112.840008) (xy 168.615106 -112.838738)
			(xy 168.63187 -112.835182) (xy 168.632124 -112.835182) (xy 168.643111 -112.832555) (xy 168.661433 -112.819388)
			(xy 168.672382 -112.79966) (xy 168.67378 -112.788446) (xy 168.67378 -112.502188) (xy 168.672002 -112.489488)
			(xy 168.672002 -112.48898) (xy 168.664244 -112.457289) (xy 168.655969 -112.392571) (xy 168.655492 -112.359948)
			(xy 168.655958 -112.327324) (xy 168.664234 -112.262605) (xy 168.672002 -112.230916) (xy 168.67378 -112.224566)
			(xy 168.67378 -111.65078) (xy 168.67378 -111.647986) (xy 168.672964 -111.639144) (xy 168.665996 -111.622823)
			(xy 168.653857 -111.609879) (xy 168.646094 -111.605568) (xy 168.642792 -111.604044) (xy 168.551352 -111.565436)
			(xy 168.549574 -111.564674) (xy 168.543478 -111.563912) (xy 168.529762 -111.563912) (xy 168.524936 -111.564928)
			(xy 168.519856 -111.565944) (xy 168.506902 -111.572802) (xy 168.501568 -111.577882) (xy 168.477782 -111.600167)
			(xy 168.425526 -111.639127) (xy 168.368719 -111.671088) (xy 168.308293 -111.695526) (xy 168.245238 -111.71204)
			(xy 168.180591 -111.720359) (xy 168.148 -111.720884) (xy 168.116007 -111.7204) (xy 168.052526 -111.712369)
			(xy 167.990555 -111.696434) (xy 167.931074 -111.672847) (xy 167.875023 -111.641981) (xy 167.82329 -111.604325)
			(xy 167.776693 -111.560473) (xy 167.735967 -111.511119) (xy 167.701759 -111.457044) (xy 167.687752 -111.428276)
			(xy 167.684196 -111.421926) (xy 167.678862 -111.413798) (xy 167.664892 -111.397288) (xy 167.65862 -111.393449)
			(xy 167.644554 -111.389188) (xy 167.637206 -111.388906) (xy 167.590978 -111.388652) (xy 167.541448 -111.388398)
			(xy 167.535034 -111.389046) (xy 167.522823 -111.393169) (xy 167.517318 -111.396526) (xy 167.51681 -111.396526)
			(xy 167.510925 -111.400634) (xy 167.501508 -111.411458) (xy 167.498268 -111.417862) (xy 167.498268 -111.418116)
			(xy 167.484359 -111.447202) (xy 167.450258 -111.501919) (xy 167.409519 -111.551889) (xy 167.362793 -111.596314)
			(xy 167.31083 -111.634479) (xy 167.254462 -111.665775) (xy 167.194592 -111.689699) (xy 167.13218 -111.705868)
			(xy 167.068224 -111.714024) (xy 167.035988 -111.714534) (xy 167.004026 -111.714031) (xy 166.940606 -111.706018)
			(xy 166.87869 -111.69012) (xy 166.819255 -111.666586) (xy 166.763238 -111.63579) (xy 166.711523 -111.598215)
			(xy 166.664924 -111.554455) (xy 166.624178 -111.5052) (xy 166.589926 -111.451227) (xy 166.562709 -111.393386)
			(xy 166.542955 -111.33259) (xy 166.530977 -111.269798) (xy 166.526963 -111.206) (xy 166.530977 -111.142202)
			(xy 166.542955 -111.07941) (xy 166.562709 -111.018614) (xy 166.589926 -110.960773) (xy 166.624178 -110.9068)
			(xy 166.664924 -110.857545) (xy 166.711523 -110.813785) (xy 166.763238 -110.77621) (xy 166.819255 -110.745414)
			(xy 166.87869 -110.72188) (xy 166.940606 -110.705982) (xy 167.004026 -110.697969) (xy 167.035988 -110.697518)
			(xy 167.067982 -110.698001) (xy 167.131464 -110.706031) (xy 167.193436 -110.721965) (xy 167.252918 -110.745551)
			(xy 167.308969 -110.776416) (xy 167.360703 -110.814073) (xy 167.407302 -110.857924) (xy 167.448028 -110.907278)
			(xy 167.482238 -110.961353) (xy 167.496236 -110.990126) (xy 167.499792 -110.996476) (xy 167.505126 -111.004604)
			(xy 167.519096 -111.021114) (xy 167.525367 -111.024954) (xy 167.539434 -111.029219) (xy 167.546782 -111.029496)
			(xy 167.59301 -111.02975) (xy 167.64254 -111.030004) (xy 167.648955 -111.029358) (xy 167.661167 -111.025237)
			(xy 167.66667 -111.021876) (xy 167.667178 -111.021876) (xy 167.673064 -111.017768) (xy 167.682483 -111.006946)
			(xy 167.68572 -111.00054) (xy 167.68572 -111.000286) (xy 167.700228 -110.96991) (xy 167.736084 -110.912939)
			(xy 167.779147 -110.861199) (xy 167.828662 -110.815596) (xy 167.8559 -110.795816) (xy 167.85919 -110.793508)
			(xy 167.865062 -110.788023) (xy 167.867584 -110.784894) (xy 167.872664 -110.776258) (xy 167.880792 -110.759494)
			(xy 167.883132 -110.754271) (xy 167.885688 -110.743117) (xy 167.885872 -110.737396) (xy 167.885872 -110.675928)
			(xy 167.885723 -110.670203) (xy 167.883157 -110.659045) (xy 167.880792 -110.65383) (xy 167.872664 -110.637066)
			(xy 167.867838 -110.628938) (xy 167.865282 -110.625664) (xy 167.859284 -110.619917) (xy 167.8559 -110.617508)
			(xy 167.831199 -110.599608) (xy 167.78583 -110.558827) (xy 167.745662 -110.512914) (xy 167.711272 -110.462528)
			(xy 167.683152 -110.408392) (xy 167.661706 -110.351282) (xy 167.647242 -110.292018) (xy 167.639967 -110.23145)
			(xy 167.639492 -110.200948) (xy 167.639963 -110.169454) (xy 167.647743 -110.106947) (xy 167.663189 -110.045881)
			(xy 167.686065 -109.987194) (xy 167.71602 -109.931783) (xy 167.752595 -109.880501) (xy 167.795228 -109.834132)
			(xy 167.843265 -109.793389) (xy 167.869362 -109.775752) (xy 167.873426 -109.772704) (xy 167.880184 -109.766811)
			(xy 167.889438 -109.751466) (xy 167.89146 -109.742732) (xy 167.892222 -109.733334) (xy 167.892222 -109.64799)
			(xy 167.89146 -109.638592) (xy 167.889422 -109.629862) (xy 167.880181 -109.614514) (xy 167.873426 -109.60862)
			(xy 167.869362 -109.605572) (xy 167.843273 -109.587925) (xy 167.795243 -109.547177) (xy 167.752616 -109.500806)
			(xy 167.716044 -109.449525) (xy 167.686089 -109.394117) (xy 167.663209 -109.335433) (xy 167.647754 -109.274372)
			(xy 167.639963 -109.211869) (xy 167.639492 -109.180376) (xy 167.639941 -109.149874) (xy 167.647233 -109.089308)
			(xy 167.661708 -109.030046) (xy 167.683161 -108.972939) (xy 167.711282 -108.918804) (xy 167.74567 -108.868416)
			(xy 167.785832 -108.822498) (xy 167.831193 -108.781707) (xy 167.8559 -108.763816) (xy 167.859279 -108.761401)
			(xy 167.865277 -108.755656) (xy 167.867838 -108.752386) (xy 167.872664 -108.744258) (xy 167.880792 -108.727494)
			(xy 167.883132 -108.722271) (xy 167.885688 -108.711117) (xy 167.885872 -108.705396) (xy 167.885872 -108.632498)
			(xy 167.884094 -108.619544) (xy 167.868854 -108.5977) (xy 167.866209 -108.594209) (xy 167.859951 -108.588082)
			(xy 167.856408 -108.585508) (xy 167.856154 -108.585508) (xy 167.83143 -108.567623) (xy 167.786016 -108.526863)
			(xy 167.745804 -108.480962) (xy 167.711372 -108.430581) (xy 167.683215 -108.376442) (xy 167.661737 -108.319323)
			(xy 167.647247 -108.260045) (xy 167.639953 -108.19946) (xy 167.639492 -108.168948) (xy 167.639948 -108.138095)
			(xy 167.64742 -108.076843) (xy 167.662247 -108.016945) (xy 167.684212 -107.959281) (xy 167.712993 -107.904699)
			(xy 167.748165 -107.853998) (xy 167.789214 -107.807926) (xy 167.835534 -107.767159) (xy 167.860726 -107.74934)
			(xy 167.867076 -107.745022) (xy 167.870632 -107.742482) (xy 167.882062 -107.7214) (xy 167.888412 -107.709716)
			(xy 167.89146 -107.701842) (xy 167.892409 -107.698363) (xy 167.893429 -107.691224) (xy 167.893492 -107.687618)
			(xy 167.893492 -106.70286) (xy 167.893721 -106.687445) (xy 167.896898 -106.656779) (xy 167.899842 -106.641646)
			(xy 167.899842 -106.641392) (xy 167.901874 -106.632502) (xy 167.902382 -106.629962) (xy 167.903906 -106.618532)
			(xy 167.880284 -106.57586) (xy 167.877236 -106.573828) (xy 167.850743 -106.556232) (xy 167.801928 -106.515462)
			(xy 167.758576 -106.468924) (xy 167.721364 -106.417346) (xy 167.690873 -106.36153) (xy 167.667577 -106.302349)
			(xy 167.651841 -106.240726) (xy 167.643909 -106.177621) (xy 167.643907 -106.11402) (xy 167.651833 -106.050915)
			(xy 167.667564 -105.98929) (xy 167.690855 -105.930107) (xy 167.721342 -105.874289) (xy 167.75855 -105.822707)
			(xy 167.801898 -105.776167) (xy 167.85071 -105.735393) (xy 167.877236 -105.717848) (xy 167.880284 -105.715816)
			(xy 167.903906 -105.673144) (xy 167.902382 -105.661714) (xy 167.901874 -105.659174) (xy 167.899842 -105.650284)
			(xy 167.899842 -105.65003) (xy 167.8969 -105.634897) (xy 167.893715 -105.604231) (xy 167.893492 -105.588816)
			(xy 167.893492 -105.249218) (xy 167.893031 -105.239583) (xy 167.885858 -105.221692) (xy 167.879522 -105.21442)
			(xy 167.865298 -105.199434) (xy 167.862078 -105.196129) (xy 167.854662 -105.190639) (xy 167.850566 -105.188512)
			(xy 167.843708 -105.18521) (xy 167.833294 -105.18013) (xy 167.822118 -105.176574) (xy 167.794505 -105.172962)
			(xy 167.74066 -105.158762) (xy 167.689452 -105.136882) (xy 167.641971 -105.107787) (xy 167.599227 -105.072095)
			(xy 167.562127 -105.030567) (xy 167.531462 -104.984084) (xy 167.507884 -104.933636) (xy 167.491893 -104.880295)
			(xy 167.48383 -104.825196) (xy 167.483282 -104.797352) (xy 167.483841 -104.768784) (xy 167.492407 -104.712294)
			(xy 167.509295 -104.657711) (xy 167.534128 -104.606253) (xy 167.566352 -104.559071) (xy 167.58539 -104.537764)
			(xy 167.592756 -104.52735) (xy 167.594505 -104.523983) (xy 167.597059 -104.51684) (xy 167.597836 -104.513126)
			(xy 167.597836 -104.512618) (xy 167.598852 -104.503982) (xy 167.599106 -104.484932) (xy 167.59936 -104.471978)
			(xy 167.586914 -104.438958) (xy 167.583358 -104.43464) (xy 167.56414 -104.411547) (xy 167.530685 -104.361642)
			(xy 167.503344 -104.308143) (xy 167.482498 -104.251794) (xy 167.468439 -104.193381) (xy 167.461361 -104.133719)
			(xy 167.46093 -104.103678) (xy 167.461395 -104.072647) (xy 167.46895 -104.011048) (xy 167.483944 -103.950825)
			(xy 167.506156 -103.892875) (xy 167.535254 -103.838058) (xy 167.570807 -103.787189) (xy 167.612286 -103.741025)
			(xy 167.659074 -103.700252) (xy 167.710476 -103.665475) (xy 167.765728 -103.637211) (xy 167.824008 -103.615881)
			(xy 167.854122 -103.608378) (xy 167.854376 -103.608378) (xy 167.862632 -103.606105) (xy 167.877051 -103.59689)
			(xy 167.88257 -103.590344) (xy 167.887904 -103.583486) (xy 167.890444 -103.575866) (xy 167.891814 -103.571808)
			(xy 167.893343 -103.563382) (xy 167.893492 -103.559102) (xy 167.893492 -100.582222) (xy 167.893152 -100.573233)
			(xy 167.886948 -100.556363) (xy 167.875269 -100.542698) (xy 167.867584 -100.538026) (xy 167.790876 -100.494592)
			(xy 167.784823 -100.491396) (xy 167.771558 -100.48804) (xy 167.764714 -100.487988) (xy 167.750998 -100.488242)
			(xy 167.739314 -100.495354) (xy 167.709444 -100.512736) (xy 167.646009 -100.540157) (xy 167.579445 -100.558738)
			(xy 167.510978 -100.568137) (xy 167.476424 -100.56876) (xy 167.475916 -100.56876) (xy 167.445184 -100.568315)
			(xy 167.384169 -100.560908) (xy 167.324491 -100.5462) (xy 167.267022 -100.524405) (xy 167.212599 -100.495841)
			(xy 167.162017 -100.460925) (xy 167.116012 -100.420166) (xy 167.075256 -100.374158) (xy 167.040343 -100.323573)
			(xy 167.011782 -100.269149) (xy 166.989991 -100.211678) (xy 166.975286 -100.152) (xy 166.967883 -100.090984)
			(xy 166.967408 -100.060252) (xy 166.967408 -100.059998) (xy 166.967818 -100.032011) (xy 166.974055 -99.976383)
			(xy 166.979854 -99.949) (xy 166.98066 -99.944859) (xy 166.981049 -99.936432) (xy 166.980616 -99.932236)
			(xy 166.980616 -99.931728) (xy 166.980108 -99.928426) (xy 166.976075 -99.905332) (xy 166.971748 -99.858649)
			(xy 166.971472 -99.835208) (xy 166.971472 -99.8347) (xy 166.971936 -99.803969) (xy 166.979344 -99.742954)
			(xy 166.994053 -99.683277) (xy 167.015848 -99.625808) (xy 167.04441 -99.571385) (xy 167.079324 -99.520801)
			(xy 167.120081 -99.474795) (xy 167.166086 -99.434037) (xy 167.216668 -99.399121) (xy 167.27109 -99.370556)
			(xy 167.328558 -99.348759) (xy 167.388234 -99.334048) (xy 167.449249 -99.326637) (xy 167.47998 -99.326192)
			(xy 167.514083 -99.326746) (xy 167.581677 -99.335868) (xy 167.647447 -99.35394) (xy 167.710212 -99.380635)
			(xy 167.739822 -99.397566) (xy 167.740076 -99.39782) (xy 167.740584 -99.398074) (xy 167.745769 -99.4009)
			(xy 167.757058 -99.404358) (xy 167.762936 -99.404932) (xy 167.766238 -99.404932) (xy 167.772106 -99.404782)
			(xy 167.783529 -99.402088) (xy 167.788844 -99.399598) (xy 167.814752 -99.384866) (xy 167.81526 -99.384866)
			(xy 167.870124 -99.353116) (xy 167.880446 -99.345664) (xy 167.892732 -99.323404) (xy 167.893492 -99.310698)
			(xy 167.893492 -98.183192) (xy 167.892971 -98.173294) (xy 167.885388 -98.155002) (xy 167.87876 -98.147632)
			(xy 167.295576 -97.564702) (xy 167.279436 -97.547894) (xy 167.251925 -97.510287) (xy 167.230441 -97.468939)
			(xy 167.215483 -97.424809) (xy 167.207396 -97.37892) (xy 167.206369 -97.332335) (xy 167.208962 -97.309178)
			(xy 167.209216 -97.3074) (xy 167.209724 -97.299526) (xy 167.209409 -97.292914) (xy 167.2058 -97.280183)
			(xy 167.202612 -97.27438) (xy 167.186864 -97.248218) (xy 167.185086 -97.245424) (xy 167.180196 -97.238972)
			(xy 167.167246 -97.229271) (xy 167.159686 -97.226374) (xy 167.128527 -97.215149) (xy 167.069177 -97.185751)
			(xy 167.014148 -97.148897) (xy 166.964369 -97.105209) (xy 166.920684 -97.055428) (xy 166.883833 -97.000396)
			(xy 166.85444 -96.941045) (xy 166.843202 -96.90989) (xy 166.840345 -96.902309) (xy 166.83063 -96.889356)
			(xy 166.824152 -96.88449) (xy 166.821358 -96.882712) (xy 166.795196 -96.866964) (xy 166.789397 -96.863769)
			(xy 166.776663 -96.860162) (xy 166.77005 -96.859852) (xy 166.762176 -96.86036) (xy 166.760398 -96.860614)
			(xy 166.73724 -96.863224) (xy 166.690649 -96.862221) (xy 166.644752 -96.854146) (xy 166.600617 -96.839185)
			(xy 166.55927 -96.817688) (xy 166.521673 -96.790153) (xy 166.504874 -96.774) (xy 164.99586 -95.264986)
			(xy 164.992492 -95.261787) (xy 164.984824 -95.256546) (xy 164.98062 -95.254572) (xy 164.980112 -95.254572)
			(xy 164.975807 -95.25277) (xy 164.966733 -95.250591) (xy 164.962078 -95.250254) (xy 164.961824 -95.250254)
			(xy 164.933011 -95.24888) (xy 164.876266 -95.238527) (xy 164.821726 -95.219748) (xy 164.770637 -95.19297)
			(xy 164.724161 -95.158805) (xy 164.68336 -95.118032) (xy 164.649164 -95.071579) (xy 164.622353 -95.020507)
			(xy 164.603537 -94.96598) (xy 164.593147 -94.909242) (xy 164.591746 -94.88043) (xy 164.591746 -94.879922)
			(xy 164.591492 -94.87027) (xy 164.587682 -94.861634) (xy 164.585705 -94.857432) (xy 164.58046 -94.849768)
			(xy 164.577268 -94.846394) (xy 163.381436 -93.650562) (xy 162.787076 -93.055948) (xy 162.776662 -93.04782)
			(xy 162.775646 -93.047312) (xy 162.770946 -93.044891) (xy 162.760832 -93.041821) (xy 162.75558 -93.041216)
			(xy 162.754564 -93.041216) (xy 162.752278 -93.040962) (xy 162.688016 -93.039438) (xy 162.68192 -93.039184)
			(xy 162.677931 -93.039141) (xy 162.670021 -93.040168) (xy 162.666172 -93.041216) (xy 162.658298 -93.04401)
			(xy 162.654488 -93.045534) (xy 162.646868 -93.052392) (xy 162.623439 -93.072909) (xy 162.572463 -93.108685)
			(xy 162.5175 -93.13797) (xy 162.459373 -93.160326) (xy 162.398951 -93.175419) (xy 162.337139 -93.183022)
			(xy 162.306 -93.183456) (xy 162.297364 -93.183456) (xy 162.287966 -93.183202) (xy 162.279076 -93.186504)
			(xy 162.275489 -93.187828) (xy 162.268727 -93.191396) (xy 162.265614 -93.193616) (xy 162.214814 -93.237558)
			(xy 162.212274 -93.23959) (xy 162.208876 -93.242677) (xy 162.203124 -93.24983) (xy 162.200844 -93.253814)
			(xy 162.196272 -93.261942) (xy 162.195002 -93.27134) (xy 162.190011 -93.304177) (xy 162.172605 -93.368274)
			(xy 162.147001 -93.429559) (xy 162.113636 -93.486989) (xy 162.073077 -93.539586) (xy 162.026016 -93.586454)
			(xy 161.973253 -93.626797) (xy 161.915687 -93.659926) (xy 161.854297 -93.685278) (xy 161.790129 -93.702422)
			(xy 161.724275 -93.711065) (xy 161.691066 -93.711522) (xy 161.659105 -93.711018) (xy 161.595689 -93.703003)
			(xy 161.533777 -93.687103) (xy 161.474346 -93.663569) (xy 161.418333 -93.632772) (xy 161.366621 -93.595198)
			(xy 161.320026 -93.551439) (xy 161.279283 -93.502186) (xy 161.245033 -93.448215) (xy 161.217818 -93.390377)
			(xy 161.198066 -93.329584) (xy 161.186089 -93.266795) (xy 161.182075 -93.203) (xy 161.186089 -93.139205)
			(xy 161.198066 -93.076416) (xy 161.217818 -93.015623) (xy 161.245033 -92.957785) (xy 161.279283 -92.903814)
			(xy 161.320026 -92.854561) (xy 161.366621 -92.810802) (xy 161.418333 -92.773228) (xy 161.474346 -92.742431)
			(xy 161.533777 -92.718897) (xy 161.595689 -92.702997) (xy 161.659105 -92.694982) (xy 161.691066 -92.694506)
			(xy 161.699702 -92.694506) (xy 161.7091 -92.69476) (xy 161.720276 -92.690696) (xy 161.730944 -92.6846)
			(xy 161.746946 -92.670884) (xy 161.747454 -92.670376) (xy 161.759392 -92.660216) (xy 161.784792 -92.638372)
			(xy 161.78819 -92.635285) (xy 161.793941 -92.628131) (xy 161.796222 -92.624148) (xy 161.800794 -92.61602)
			(xy 161.802064 -92.606622) (xy 161.806614 -92.57645) (xy 161.821995 -92.5174) (xy 161.844325 -92.460613)
			(xy 161.873286 -92.406903) (xy 161.90846 -92.357041) (xy 161.928556 -92.33408) (xy 161.935414 -92.32646)
			(xy 161.936938 -92.32265) (xy 161.939732 -92.314776) (xy 161.94077 -92.310926) (xy 161.941786 -92.303016)
			(xy 161.941764 -92.299028) (xy 161.94151 -92.292932) (xy 161.939986 -92.22867) (xy 161.939672 -92.223397)
			(xy 161.937105 -92.213153) (xy 161.934906 -92.20835) (xy 161.934906 -92.207842) (xy 161.932975 -92.203992)
			(xy 161.927997 -92.196965) (xy 161.925 -92.193872) (xy 161.924492 -92.193364) (xy 161.859976 -92.129102)
			(xy 161.85896 -92.128086) (xy 161.781236 -92.050362) (xy 161.77703 -92.046333) (xy 161.767146 -92.040177)
			(xy 161.761678 -92.03817) (xy 161.750502 -92.03436) (xy 161.738818 -92.035884) (xy 161.721945 -92.038022)
			(xy 161.688007 -92.040307) (xy 161.671 -92.040456) (xy 161.640268 -92.039992) (xy 161.579252 -92.032584)
			(xy 161.519574 -92.017876) (xy 161.462103 -91.996081) (xy 161.407678 -91.967519) (xy 161.357093 -91.932605)
			(xy 161.311085 -91.891849) (xy 161.270324 -91.845845) (xy 161.235406 -91.795263) (xy 161.206838 -91.740841)
			(xy 161.185039 -91.683372) (xy 161.170324 -91.623695) (xy 161.16291 -91.56268) (xy 161.162492 -91.531948)
			(xy 161.162642 -91.514941) (xy 161.164927 -91.481003) (xy 161.167064 -91.46413) (xy 161.168588 -91.452446)
			(xy 161.164778 -91.44127) (xy 161.162719 -91.435828) (xy 161.156563 -91.425959) (xy 161.152586 -91.421712)
			(xy 158.541212 -88.810338) (xy 158.537402 -88.80602) (xy 158.522704 -88.789396) (xy 158.497772 -88.752689)
			(xy 158.478415 -88.712759) (xy 158.471362 -88.69172) (xy 158.463765 -88.66562) (xy 158.456872 -88.611705)
			(xy 158.457646 -88.584532) (xy 158.457646 -88.581992) (xy 158.457354 -88.574118) (xy 158.452572 -88.559115)
			(xy 158.448248 -88.552528) (xy 158.435548 -88.535002) (xy 158.433107 -88.531756) (xy 158.427365 -88.526012)
			(xy 158.424118 -88.523572) (xy 158.40202 -88.508332) (xy 158.398972 -88.50757) (xy 158.393892 -88.5063)
			(xy 158.36246 -88.497057) (xy 158.302094 -88.471591) (xy 158.245498 -88.438586) (xy 158.193607 -88.398588)
			(xy 158.147282 -88.352258) (xy 158.107288 -88.300363) (xy 158.074288 -88.243764) (xy 158.048828 -88.183396)
			(xy 158.039562 -88.15197) (xy 158.038292 -88.14689) (xy 158.03753 -88.143842) (xy 158.02229 -88.121744)
			(xy 158.019847 -88.118499) (xy 158.014105 -88.112756) (xy 158.01086 -88.110314) (xy 157.993334 -88.097614)
			(xy 157.98675 -88.093283) (xy 157.971746 -88.088487) (xy 157.96387 -88.088216) (xy 157.96133 -88.088216)
			(xy 157.937226 -88.088987) (xy 157.889278 -88.083828) (xy 157.842742 -88.071181) (xy 157.798778 -88.051362)
			(xy 157.758485 -88.024866) (xy 157.74035 -88.008968) (xy 157.73527 -88.004396) (xy 152.027128 -82.296254)
			(xy 152.012781 -82.281405) (xy 151.987803 -82.248526) (xy 151.977344 -82.230722) (xy 151.972772 -82.222594)
			(xy 151.958548 -82.210656) (xy 151.947372 -82.2071) (xy 151.884634 -82.186272) (xy 151.880441 -82.184966)
			(xy 151.871753 -82.18368) (xy 151.867362 -82.183732) (xy 151.857202 -82.18424) (xy 151.848312 -82.18805)
			(xy 151.847804 -82.188304) (xy 151.823555 -82.19843) (xy 151.772974 -82.212684) (xy 151.720917 -82.219867)
			(xy 151.694642 -82.220308) (xy 151.689562 -82.220308) (xy 151.67133 -82.219867) (xy 151.635072 -82.215926)
			(xy 151.617172 -82.212434) (xy 151.592893 -82.20697) (xy 151.545902 -82.190582) (xy 151.501438 -82.168229)
			(xy 151.460254 -82.140289) (xy 151.441404 -82.124042) (xy 151.434292 -82.117946) (xy 151.422608 -82.113374)
			(xy 151.408638 -82.111342) (xy 151.33955 -82.111342) (xy 151.339296 -82.111342) (xy 151.325326 -82.113374)
			(xy 151.313642 -82.117946) (xy 151.30653 -82.124042) (xy 151.285485 -82.142073) (xy 151.239165 -82.172493)
			(xy 151.188928 -82.195887) (xy 151.135833 -82.211762) (xy 151.081 -82.219784) (xy 151.053292 -82.220308)
			(xy 151.026041 -82.219822) (xy 150.972094 -82.212064) (xy 150.9198 -82.196708) (xy 150.870224 -82.174067)
			(xy 150.824375 -82.1446) (xy 150.783186 -82.108909) (xy 150.747495 -82.067719) (xy 150.718029 -82.021869)
			(xy 150.695389 -81.972292) (xy 150.680034 -81.919998) (xy 150.672278 -81.866051) (xy 150.672278 -81.811549)
			(xy 150.680034 -81.757602) (xy 150.695389 -81.705308) (xy 150.718029 -81.655731) (xy 150.747495 -81.609881)
			(xy 150.783186 -81.568691) (xy 150.824375 -81.533) (xy 150.870224 -81.503533) (xy 150.9198 -81.480892)
			(xy 150.972094 -81.465536) (xy 151.026041 -81.457778) (xy 151.053292 -81.457292) (xy 151.081002 -81.457789)
			(xy 151.135837 -81.465812) (xy 151.188933 -81.481692) (xy 151.23917 -81.505092) (xy 151.285489 -81.53552)
			(xy 151.30653 -81.553558) (xy 151.313642 -81.559654) (xy 151.325326 -81.564226) (xy 151.339296 -81.566258)
			(xy 151.408384 -81.566258) (xy 151.408638 -81.566258) (xy 151.422608 -81.564226) (xy 151.434292 -81.559654)
			(xy 151.441404 -81.553558) (xy 151.462447 -81.535523) (xy 151.508767 -81.505095) (xy 151.559003 -81.481692)
			(xy 151.612097 -81.465808) (xy 151.666932 -81.457777) (xy 151.694642 -81.457292) (xy 151.723013 -81.457813)
			(xy 151.779126 -81.466235) (xy 151.806402 -81.474056) (xy 151.806656 -81.474056) (xy 151.807926 -81.474564)
			(xy 151.810466 -81.475326) (xy 151.814863 -81.476162) (xy 151.82381 -81.476425) (xy 151.828246 -81.475834)
			(xy 151.82977 -81.47558) (xy 151.835601 -81.474383) (xy 151.846513 -81.469636) (xy 151.85136 -81.466182)
			(xy 151.917654 -81.41716) (xy 151.926597 -81.409615) (xy 151.93705 -81.388709) (xy 151.93772 -81.377028)
			(xy 151.93772 -80.254602) (xy 151.93708 -80.242913) (xy 151.926616 -80.222003) (xy 151.917654 -80.21447)
			(xy 151.875236 -80.182974) (xy 151.84882 -80.163162) (xy 151.844405 -80.160563) (xy 151.834807 -80.156984)
			(xy 151.82977 -80.15605) (xy 151.829008 -80.155796) (xy 151.81834 -80.154018) (xy 151.806656 -80.157574)
			(xy 151.806402 -80.157574) (xy 151.779124 -80.165384) (xy 151.723011 -80.173796) (xy 151.694642 -80.174338)
			(xy 151.666932 -80.173843) (xy 151.612095 -80.165823) (xy 151.558998 -80.149945) (xy 151.50876 -80.126544)
			(xy 151.462441 -80.096114) (xy 151.441404 -80.078072) (xy 151.434292 -80.071976) (xy 151.422608 -80.067404)
			(xy 151.408638 -80.065372) (xy 151.33955 -80.065372) (xy 151.339296 -80.065372) (xy 151.325326 -80.067404)
			(xy 151.313642 -80.071976) (xy 151.30653 -80.078072) (xy 151.285485 -80.096102) (xy 151.239163 -80.12652)
			(xy 151.188926 -80.149912) (xy 151.135833 -80.165786) (xy 151.081 -80.173806) (xy 151.053292 -80.174338)
			(xy 151.026039 -80.173852) (xy 150.972088 -80.166094) (xy 150.91979 -80.150737) (xy 150.87021 -80.128093)
			(xy 150.824357 -80.098624) (xy 150.783164 -80.06293) (xy 150.747471 -80.021737) (xy 150.718003 -79.975883)
			(xy 150.695361 -79.926303) (xy 150.680005 -79.874004) (xy 150.672248 -79.820053) (xy 150.672248 -79.765547)
			(xy 150.680005 -79.711596) (xy 150.695361 -79.659297) (xy 150.718003 -79.609717) (xy 150.747471 -79.563863)
			(xy 150.783164 -79.52267) (xy 150.824357 -79.486976) (xy 150.87021 -79.457507) (xy 150.91979 -79.434863)
			(xy 150.972088 -79.419506) (xy 151.026039 -79.411748) (xy 151.053292 -79.411322) (xy 151.081002 -79.411819)
			(xy 151.135837 -79.419843) (xy 151.188932 -79.435723) (xy 151.239168 -79.459125) (xy 151.285485 -79.489555)
			(xy 151.30653 -79.507588) (xy 151.313642 -79.513684) (xy 151.325326 -79.518256) (xy 151.339296 -79.520288)
			(xy 151.408384 -79.520288) (xy 151.408638 -79.520288) (xy 151.422608 -79.518256) (xy 151.434292 -79.513684)
			(xy 151.441404 -79.507588) (xy 151.462447 -79.489552) (xy 151.508765 -79.459121) (xy 151.559001 -79.435717)
			(xy 151.612096 -79.419831) (xy 151.666932 -79.4118) (xy 151.694642 -79.411322) (xy 151.723013 -79.411842)
			(xy 151.779126 -79.420263) (xy 151.806402 -79.428086) (xy 151.806656 -79.428086) (xy 151.807926 -79.428594)
			(xy 151.810466 -79.429356) (xy 151.814864 -79.430186) (xy 151.823809 -79.430449) (xy 151.828246 -79.429864)
			(xy 151.82977 -79.42961) (xy 151.835601 -79.428414) (xy 151.846515 -79.423669) (xy 151.85136 -79.420212)
			(xy 151.917654 -79.37119) (xy 151.926602 -79.363647) (xy 151.937067 -79.342742) (xy 151.93772 -79.331058)
			(xy 151.93772 -78.208632) (xy 151.937086 -78.19694) (xy 151.926629 -78.176019) (xy 151.917654 -78.1685)
			(xy 151.875236 -78.137004) (xy 151.84882 -78.117192) (xy 151.844406 -78.114591) (xy 151.834808 -78.111011)
			(xy 151.82977 -78.11008) (xy 151.829008 -78.109826) (xy 151.81834 -78.108048) (xy 151.806656 -78.111604)
			(xy 151.806402 -78.111604) (xy 151.779124 -78.119415) (xy 151.723011 -78.127829) (xy 151.694642 -78.128368)
			(xy 151.666932 -78.127874) (xy 151.612094 -78.119854) (xy 151.558996 -78.103977) (xy 151.508757 -78.080578)
			(xy 151.462437 -78.05015) (xy 151.441404 -78.032102) (xy 151.434292 -78.026006) (xy 151.422608 -78.021434)
			(xy 151.408638 -78.019402) (xy 151.33955 -78.019402) (xy 151.339296 -78.019402) (xy 151.325326 -78.021434)
			(xy 151.313642 -78.026006) (xy 151.30653 -78.032102) (xy 151.285484 -78.050131) (xy 151.239162 -78.080546)
			(xy 151.188925 -78.103936) (xy 151.135832 -78.119809) (xy 151.081 -78.127829) (xy 151.053292 -78.128368)
			(xy 151.026044 -78.127881) (xy 150.972103 -78.120125) (xy 150.919815 -78.10477) (xy 150.870244 -78.082131)
			(xy 150.824399 -78.052668) (xy 150.783214 -78.01698) (xy 150.747527 -77.975794) (xy 150.718065 -77.929949)
			(xy 150.695427 -77.880378) (xy 150.680074 -77.828089) (xy 150.672318 -77.774148) (xy 150.672318 -77.719652)
			(xy 150.680074 -77.665711) (xy 150.695427 -77.613422) (xy 150.718065 -77.563851) (xy 150.747527 -77.518006)
			(xy 150.783214 -77.47682) (xy 150.824399 -77.441132) (xy 150.870244 -77.411669) (xy 150.919815 -77.38903)
			(xy 150.972103 -77.373675) (xy 151.026044 -77.365919) (xy 151.053292 -77.365352) (xy 151.081001 -77.365849)
			(xy 151.135836 -77.373873) (xy 151.188931 -77.389755) (xy 151.239165 -77.413158) (xy 151.285481 -77.44359)
			(xy 151.30653 -77.461618) (xy 151.313642 -77.467714) (xy 151.325326 -77.472286) (xy 151.339296 -77.474318)
			(xy 151.408384 -77.474318) (xy 151.408638 -77.474318) (xy 151.422608 -77.472286) (xy 151.434292 -77.467714)
			(xy 151.441404 -77.461618) (xy 151.462448 -77.443585) (xy 151.508768 -77.41316) (xy 151.559004 -77.389759)
			(xy 151.612099 -77.373877) (xy 151.666933 -77.365847) (xy 151.694642 -77.365352) (xy 151.723013 -77.365872)
			(xy 151.779126 -77.374293) (xy 151.806402 -77.382116) (xy 151.806656 -77.382116) (xy 151.807926 -77.382624)
			(xy 151.810466 -77.383386) (xy 151.814864 -77.384216) (xy 151.823809 -77.384479) (xy 151.828246 -77.383894)
			(xy 151.82977 -77.38364) (xy 151.8356 -77.382441) (xy 151.84651 -77.377692) (xy 151.85136 -77.374242)
			(xy 151.917654 -77.32522) (xy 151.92659 -77.317672) (xy 151.937027 -77.296766) (xy 151.93772 -77.285088)
			(xy 151.93772 -76.162662) (xy 151.937071 -76.150978) (xy 151.926598 -76.130081) (xy 151.917654 -76.12253)
			(xy 151.875236 -76.091034) (xy 151.84882 -76.071222) (xy 151.844406 -76.06862) (xy 151.834809 -76.065037)
			(xy 151.82977 -76.06411) (xy 151.829008 -76.063856) (xy 151.81834 -76.062078) (xy 151.806656 -76.065634)
			(xy 151.806402 -76.065634) (xy 151.779124 -76.073444) (xy 151.723011 -76.081858) (xy 151.694642 -76.082398)
			(xy 151.666931 -76.081904) (xy 151.612094 -76.073884) (xy 151.558995 -76.058008) (xy 151.508755 -76.034611)
			(xy 151.462433 -76.004184) (xy 151.441404 -75.986132) (xy 151.434292 -75.980036) (xy 151.422608 -75.975464)
			(xy 151.408638 -75.973432) (xy 151.33955 -75.973432) (xy 151.339296 -75.973432) (xy 151.325326 -75.975464)
			(xy 151.313642 -75.980036) (xy 151.30653 -75.986132) (xy 151.285486 -76.004164) (xy 151.239165 -76.034585)
			(xy 151.188928 -76.057979) (xy 151.135834 -76.073855) (xy 151.081 -76.081876) (xy 151.053292 -76.082398)
			(xy 151.026042 -76.081911) (xy 150.972096 -76.074154) (xy 150.919804 -76.058799) (xy 150.870229 -76.036158)
			(xy 150.824381 -76.006692) (xy 150.783193 -75.971001) (xy 150.747503 -75.929812) (xy 150.718039 -75.883964)
			(xy 150.695399 -75.834388) (xy 150.680044 -75.782096) (xy 150.672288 -75.72815) (xy 150.672288 -75.67365)
			(xy 150.680044 -75.619704) (xy 150.695399 -75.567412) (xy 150.718039 -75.517836) (xy 150.747503 -75.471988)
			(xy 150.783193 -75.430799) (xy 150.824381 -75.395108) (xy 150.870229 -75.365642) (xy 150.919804 -75.343001)
			(xy 150.972096 -75.327646) (xy 151.026042 -75.319889) (xy 151.053292 -75.319382) (xy 151.081002 -75.319878)
			(xy 151.135838 -75.327902) (xy 151.188934 -75.343781) (xy 151.239171 -75.367181) (xy 151.285491 -75.397609)
			(xy 151.30653 -75.415648) (xy 151.313642 -75.421744) (xy 151.325326 -75.426316) (xy 151.339296 -75.428348)
			(xy 151.408384 -75.428348) (xy 151.408638 -75.428348) (xy 151.422608 -75.426316) (xy 151.434292 -75.421744)
			(xy 151.441404 -75.415648) (xy 151.462448 -75.397613) (xy 151.508767 -75.367186) (xy 151.559003 -75.343784)
			(xy 151.612098 -75.3279) (xy 151.666932 -75.31987) (xy 151.694642 -75.319382) (xy 151.723013 -75.319903)
			(xy 151.779126 -75.328324) (xy 151.806402 -75.336146) (xy 151.806656 -75.336146) (xy 151.807926 -75.336654)
			(xy 151.810466 -75.337416) (xy 151.814863 -75.338252) (xy 151.82381 -75.338516) (xy 151.828246 -75.337924)
			(xy 151.82977 -75.33767) (xy 151.8356 -75.336472) (xy 151.846512 -75.331725) (xy 151.85136 -75.328272)
			(xy 151.917654 -75.27925) (xy 151.926595 -75.271704) (xy 151.937044 -75.250799) (xy 151.93772 -75.239118)
			(xy 151.93772 -72.196452) (xy 151.937032 -72.185005) (xy 151.927017 -72.16441) (xy 151.918416 -72.156828)
			(xy 151.851106 -72.107552) (xy 151.850852 -72.107298) (xy 151.848312 -72.10552) (xy 151.843812 -72.102735)
			(xy 151.833951 -72.098898) (xy 151.828754 -72.0979) (xy 151.827992 -72.097646) (xy 151.817324 -72.095868)
			(xy 151.815292 -72.096376) (xy 151.805386 -72.099678) (xy 151.76771 -72.110939) (xy 151.690016 -72.123061)
			(xy 151.6507 -72.123808) (xy 151.618739 -72.123306) (xy 151.555321 -72.115295) (xy 151.493407 -72.099398)
			(xy 151.433974 -72.075866) (xy 151.377959 -72.045072) (xy 151.326244 -72.007499) (xy 151.279647 -71.963742)
			(xy 151.238902 -71.914489) (xy 151.204651 -71.860518) (xy 151.177434 -71.802679) (xy 151.157681 -71.741886)
			(xy 151.145703 -71.679096) (xy 151.14169 -71.6153) (xy 151.145703 -71.551504) (xy 151.157681 -71.488714)
			(xy 151.177434 -71.427921) (xy 151.204651 -71.370082) (xy 151.238902 -71.316111) (xy 151.279647 -71.266858)
			(xy 151.326244 -71.223101) (xy 151.377959 -71.185528) (xy 151.433974 -71.154734) (xy 151.493407 -71.131202)
			(xy 151.555321 -71.115305) (xy 151.618739 -71.107294) (xy 151.6507 -71.106792) (xy 151.663422 -71.10687)
			(xy 151.688834 -71.10814) (xy 151.7015 -71.109332) (xy 151.706326 -71.10984) (xy 151.706834 -71.10984)
			(xy 151.741054 -71.114222) (xy 151.807959 -71.131049) (xy 151.840184 -71.143368) (xy 151.842216 -71.14413)
			(xy 151.857202 -71.147178) (xy 151.861012 -71.14794) (xy 151.868269 -71.147637) (xy 151.882188 -71.143505)
			(xy 151.888444 -71.139812) (xy 151.896318 -71.134732) (xy 151.915876 -71.122286) (xy 151.925551 -71.114676)
			(xy 151.936975 -71.092915) (xy 151.93772 -71.08063) (xy 151.93772 -71.000366) (xy 151.937811 -70.995347)
			(xy 151.939728 -70.985494) (xy 151.94153 -70.980808) (xy 151.957786 -70.941692) (xy 151.957786 -70.941438)
			(xy 151.958294 -70.940422) (xy 151.958294 -70.940168) (xy 151.966328 -70.920545) (xy 151.987027 -70.883537)
			(xy 152.012629 -70.849735) (xy 152.027382 -70.834504) (xy 152.028398 -70.833488) (xy 152.035164 -70.826128)
			(xy 152.042804 -70.80767) (xy 152.042797 -70.787693) (xy 152.035143 -70.769241) (xy 152.028398 -70.76186)
			(xy 152.022556 -70.755764) (xy 152.007824 -70.748652) (xy 151.999442 -70.747382) (xy 151.999188 -70.747382)
			(xy 151.953654 -70.740554) (xy 151.863848 -70.720214) (xy 151.776072 -70.692389) (xy 151.690949 -70.657274)
			(xy 151.609084 -70.61512) (xy 151.531057 -70.566226) (xy 151.457422 -70.510939) (xy 151.388701 -70.44965)
			(xy 151.325381 -70.382795) (xy 151.267913 -70.310848) (xy 151.216705 -70.234321) (xy 151.172118 -70.153754)
			(xy 151.13447 -70.069721) (xy 151.104028 -69.982818) (xy 151.081008 -69.893661) (xy 151.065573 -69.802883)
			(xy 151.057833 -69.711128) (xy 151.057356 -69.665088) (xy 151.057849 -69.618691) (xy 151.065718 -69.526232)
			(xy 151.0814 -69.434773) (xy 151.104782 -69.344974) (xy 151.135695 -69.257481) (xy 151.173917 -69.172925)
			(xy 151.219172 -69.091915) (xy 151.271134 -69.015035) (xy 151.329429 -68.942838) (xy 151.393636 -68.875845)
			(xy 151.463294 -68.814539) (xy 151.537899 -68.759361) (xy 151.616916 -68.710709) (xy 151.699773 -68.668933)
			(xy 151.785875 -68.634334) (xy 151.874601 -68.607162) (xy 151.965312 -68.587612) (xy 152.057354 -68.575826)
			(xy 152.150064 -68.571888) (xy 152.242774 -68.575826) (xy 152.334816 -68.587612) (xy 152.425527 -68.607162)
			(xy 152.514253 -68.634334) (xy 152.600355 -68.668933) (xy 152.683212 -68.710709) (xy 152.762229 -68.759361)
			(xy 152.836834 -68.814539) (xy 152.906492 -68.875845) (xy 152.970699 -68.942838) (xy 153.028994 -69.015035)
			(xy 153.080956 -69.091915) (xy 153.126211 -69.172925) (xy 153.164433 -69.257481) (xy 153.195346 -69.344974)
			(xy 153.218728 -69.434773) (xy 153.23441 -69.526232) (xy 153.242279 -69.618691) (xy 153.242772 -69.665088)
			(xy 153.242288 -69.711315) (xy 153.234477 -69.803438) (xy 153.218911 -69.894571) (xy 153.195701 -69.984064)
			(xy 153.165012 -70.071275) (xy 153.127065 -70.155582) (xy 153.08213 -70.236381) (xy 153.030529 -70.313095)
			(xy 152.972631 -70.385174) (xy 152.90885 -70.452104) (xy 152.839642 -70.513406) (xy 152.802844 -70.541388)
			(xy 152.80259 -70.541642) (xy 152.796514 -70.546602) (xy 152.787472 -70.559409) (xy 152.78481 -70.566788)
			(xy 152.78227 -70.574408) (xy 152.78227 -70.581774) (xy 152.784048 -70.59549) (xy 152.81529 -70.68947)
			(xy 152.819154 -70.699396) (xy 152.833455 -70.715147) (xy 152.852912 -70.72375) (xy 152.86355 -70.724268)
			(xy 167.283384 -70.724268) (xy 167.288402 -70.724363) (xy 167.298252 -70.726288) (xy 167.302942 -70.728078)
			(xy 167.342058 -70.744334) (xy 167.342312 -70.744334) (xy 167.343328 -70.744842) (xy 167.343582 -70.744842)
			(xy 167.363208 -70.752873) (xy 167.400222 -70.773564) (xy 167.434031 -70.799159) (xy 167.449246 -70.81393)
			(xy 169.381932 -72.746616) (xy 169.402246 -72.767866) (xy 169.435111 -72.816598) (xy 169.44721 -72.84339)
			(xy 169.45747 -72.868994) (xy 169.469605 -72.922795) (xy 169.47134 -72.950324) (xy 169.47134 -74.767948)
			(xy 173.354492 -74.767948) (xy 173.354492 -66.06794) (xy 173.354997 -65.962416) (xy 173.363081 -65.751522)
			(xy 173.379237 -65.541093) (xy 173.40344 -65.331436) (xy 173.435657 -65.122861) (xy 173.475839 -64.915673)
			(xy 173.523927 -64.710176) (xy 173.579851 -64.506672) (xy 173.643528 -64.305459) (xy 173.714866 -64.106832)
			(xy 173.79376 -63.911084) (xy 173.880093 -63.718502) (xy 173.97374 -63.529367) (xy 174.074562 -63.343958)
			(xy 174.182412 -63.162547) (xy 174.297131 -62.9854) (xy 174.418551 -62.812778) (xy 174.546494 -62.644932)
			(xy 174.680772 -62.48211) (xy 174.821188 -62.324551) (xy 174.967536 -62.172486) (xy 175.119601 -62.026138)
			(xy 175.27716 -61.885722) (xy 175.439982 -61.751444) (xy 175.607828 -61.623501) (xy 175.78045 -61.502081)
			(xy 175.957597 -61.387362) (xy 176.139008 -61.279512) (xy 176.324417 -61.17869) (xy 176.513552 -61.085043)
			(xy 176.706134 -60.99871) (xy 176.901882 -60.919816) (xy 177.100509 -60.848478) (xy 177.301722 -60.784801)
			(xy 177.505226 -60.728877) (xy 177.710723 -60.680789) (xy 177.917911 -60.640607) (xy 178.126486 -60.60839)
			(xy 178.336143 -60.584187) (xy 178.546572 -60.568031) (xy 178.757466 -60.559947) (xy 178.968514 -60.559947)
			(xy 179.179408 -60.568031) (xy 179.389837 -60.584187) (xy 179.599494 -60.60839) (xy 179.808069 -60.640607)
			(xy 180.015257 -60.680789) (xy 180.220754 -60.728877) (xy 180.424258 -60.784801) (xy 180.625471 -60.848478)
			(xy 180.824098 -60.919816) (xy 181.019846 -60.99871) (xy 181.212428 -61.085043) (xy 181.401563 -61.17869)
			(xy 181.586972 -61.279512) (xy 181.768383 -61.387362) (xy 181.94553 -61.502081) (xy 182.118152 -61.623501)
			(xy 182.285998 -61.751444) (xy 182.44882 -61.885722) (xy 182.606379 -62.026138) (xy 182.758444 -62.172486)
			(xy 182.904792 -62.324551) (xy 183.045208 -62.48211) (xy 183.049909 -62.48781) (xy 230.655114 -62.48781)
			(xy 230.65556 -62.457771) (xy 230.662628 -62.398112) (xy 230.676679 -62.339701) (xy 230.697516 -62.283353)
			(xy 230.72485 -62.229854) (xy 230.758298 -62.17995) (xy 230.797396 -62.134336) (xy 230.819198 -62.113668)
			(xy 230.826564 -62.10681) (xy 230.834946 -62.08903) (xy 230.839772 -61.997844) (xy 230.833168 -61.979302)
			(xy 230.826564 -61.971682) (xy 230.806605 -61.948408) (xy 230.771859 -61.897888) (xy 230.743439 -61.843558)
			(xy 230.721757 -61.786204) (xy 230.707129 -61.72666) (xy 230.699765 -61.665789) (xy 230.69931 -61.635132)
			(xy 230.699812 -61.603171) (xy 230.707823 -61.539753) (xy 230.72372 -61.477839) (xy 230.747252 -61.418406)
			(xy 230.778046 -61.362391) (xy 230.815619 -61.310676) (xy 230.859376 -61.264079) (xy 230.908629 -61.223334)
			(xy 230.9626 -61.189083) (xy 231.020439 -61.161866) (xy 231.081232 -61.142113) (xy 231.144022 -61.130135)
			(xy 231.207818 -61.126122) (xy 231.271614 -61.130135) (xy 231.334404 -61.142113) (xy 231.395197 -61.161866)
			(xy 231.453036 -61.189083) (xy 231.507007 -61.223334) (xy 231.55626 -61.264079) (xy 231.600017 -61.310676)
			(xy 231.63759 -61.362391) (xy 231.668384 -61.418406) (xy 231.691916 -61.477839) (xy 231.707813 -61.539753)
			(xy 231.715824 -61.603171) (xy 231.716326 -61.635132) (xy 231.715927 -61.665172) (xy 231.708854 -61.724834)
			(xy 231.694796 -61.783247) (xy 231.673952 -61.839595) (xy 231.646611 -61.893094) (xy 231.613154 -61.942997)
			(xy 231.591428 -61.968337) (xy 232.433379 -61.968337) (xy 232.433379 -61.881463) (xy 232.441394 -61.794959)
			(xy 232.457358 -61.709564) (xy 232.481132 -61.626006) (xy 232.512515 -61.544999) (xy 232.551239 -61.467232)
			(xy 232.596972 -61.393371) (xy 232.649326 -61.324044) (xy 232.707853 -61.259843) (xy 232.772055 -61.201317)
			(xy 232.841382 -61.148964) (xy 232.915245 -61.103232) (xy 232.993012 -61.064509) (xy 233.07402 -61.033128)
			(xy 233.157578 -61.009354) (xy 233.242973 -60.993392) (xy 233.329477 -60.985378) (xy 233.372914 -60.984892)
			(xy 233.450892 -60.984892) (xy 233.460914 -60.984474) (xy 233.479432 -60.976805) (xy 233.493605 -60.962632)
			(xy 233.501274 -60.944114) (xy 233.501692 -60.934092) (xy 233.501692 -60.926472) (xy 233.497374 -60.912502)
			(xy 233.49331 -60.906152) (xy 233.469391 -60.868917) (xy 233.42769 -60.790852) (xy 233.393305 -60.709298)
			(xy 233.366527 -60.624941) (xy 233.347578 -60.538488) (xy 233.336618 -60.450663) (xy 233.33374 -60.362205)
			(xy 233.338967 -60.273854) (xy 233.352255 -60.186351) (xy 233.373493 -60.100432) (xy 233.402502 -60.016816)
			(xy 233.43904 -59.936204) (xy 233.482801 -59.859274) (xy 233.533415 -59.78667) (xy 233.590461 -59.719001)
			(xy 233.653458 -59.656835) (xy 233.721878 -59.600694) (xy 233.795148 -59.551047) (xy 233.872653 -59.508313)
			(xy 233.953742 -59.472848) (xy 234.037736 -59.444952) (xy 234.12393 -59.424856) (xy 234.211601 -59.412732)
			(xy 234.300014 -59.408679) (xy 234.388427 -59.412732) (xy 234.476098 -59.424856) (xy 234.562292 -59.444952)
			(xy 234.646286 -59.472848) (xy 234.727375 -59.508313) (xy 234.80488 -59.551047) (xy 234.87815 -59.600694)
			(xy 234.94657 -59.656835) (xy 235.009567 -59.719001) (xy 235.066613 -59.78667) (xy 235.117227 -59.859274)
			(xy 235.160988 -59.936204) (xy 235.197526 -60.016816) (xy 235.226535 -60.100432) (xy 235.247773 -60.186351)
			(xy 235.261061 -60.273854) (xy 235.266288 -60.362205) (xy 235.26341 -60.450663) (xy 235.262361 -60.459069)
			(xy 260.525254 -60.459069) (xy 260.525254 -60.395147) (xy 260.533265 -60.331729) (xy 260.549162 -60.269815)
			(xy 260.572694 -60.210382) (xy 260.603488 -60.154367) (xy 260.641061 -60.102652) (xy 260.684818 -60.056055)
			(xy 260.734071 -60.01531) (xy 260.788042 -59.981059) (xy 260.845881 -59.953842) (xy 260.906674 -59.934089)
			(xy 260.969464 -59.922111) (xy 261.03326 -59.918098) (xy 261.097056 -59.922111) (xy 261.159846 -59.934089)
			(xy 261.220639 -59.953842) (xy 261.278478 -59.981059) (xy 261.332449 -60.01531) (xy 261.381702 -60.056055)
			(xy 261.425459 -60.102652) (xy 261.463032 -60.154367) (xy 261.493826 -60.210382) (xy 261.517358 -60.269815)
			(xy 261.533255 -60.331729) (xy 261.541266 -60.395147) (xy 261.541768 -60.427108) (xy 261.541266 -60.459069)
			(xy 261.533255 -60.522487) (xy 261.517358 -60.584401) (xy 261.493826 -60.643834) (xy 261.463032 -60.699849)
			(xy 261.425459 -60.751564) (xy 261.381702 -60.798161) (xy 261.332449 -60.838906) (xy 261.278478 -60.873157)
			(xy 261.220639 -60.900374) (xy 261.159846 -60.920127) (xy 261.097056 -60.932105) (xy 261.03326 -60.936119)
			(xy 260.969464 -60.932105) (xy 260.906674 -60.920127) (xy 260.845881 -60.900374) (xy 260.788042 -60.873157)
			(xy 260.734071 -60.838906) (xy 260.684818 -60.798161) (xy 260.641061 -60.751564) (xy 260.603488 -60.699849)
			(xy 260.572694 -60.643834) (xy 260.549162 -60.584401) (xy 260.533265 -60.522487) (xy 260.525254 -60.459069)
			(xy 235.262361 -60.459069) (xy 235.25245 -60.538488) (xy 235.233501 -60.624941) (xy 235.206723 -60.709298)
			(xy 235.172338 -60.790852) (xy 235.130637 -60.868917) (xy 235.106718 -60.906152) (xy 235.102654 -60.912502)
			(xy 235.098336 -60.926472) (xy 235.098336 -60.934092) (xy 235.098727 -60.944117) (xy 235.106401 -60.962641)
			(xy 235.120583 -60.976815) (xy 235.139111 -60.984479) (xy 235.149136 -60.984892) (xy 235.227114 -60.984892)
			(xy 235.272011 -60.985392) (xy 235.361396 -60.993953) (xy 235.449558 -61.010996) (xy 235.535694 -61.036366)
			(xy 235.619019 -61.069831) (xy 235.698775 -61.111087) (xy 235.774234 -61.159758) (xy 235.84471 -61.215401)
			(xy 235.909561 -61.277509) (xy 235.968196 -61.345516) (xy 236.020081 -61.418803) (xy 236.064743 -61.496702)
			(xy 236.101776 -61.578504) (xy 236.130842 -61.663463) (xy 236.141768 -61.707014) (xy 236.145324 -61.722)
			(xy 236.16793 -61.742828) (xy 236.27588 -61.7601) (xy 236.285851 -61.761274) (xy 236.305362 -61.756606)
			(xy 236.321593 -61.744814) (xy 236.327188 -61.736478) (xy 236.344629 -61.709096) (xy 236.385312 -61.658504)
			(xy 236.432103 -61.613502) (xy 236.484243 -61.574822) (xy 236.540882 -61.543094) (xy 236.601099 -61.518834)
			(xy 236.663914 -61.502437) (xy 236.728306 -61.494169) (xy 236.760766 -61.493654) (xy 236.792727 -61.494209)
			(xy 236.856146 -61.502217) (xy 236.918062 -61.51811) (xy 236.977497 -61.541638) (xy 237.033514 -61.572431)
			(xy 237.08523 -61.610002) (xy 237.131829 -61.653758) (xy 237.172576 -61.70301) (xy 237.206829 -61.756981)
			(xy 237.234047 -61.814819) (xy 237.253801 -61.875613) (xy 237.25542 -61.8841) (xy 255.832841 -61.8841)
			(xy 255.836855 -61.8203) (xy 255.848833 -61.757505) (xy 255.868587 -61.696707) (xy 255.895805 -61.638865)
			(xy 255.930058 -61.584889) (xy 255.970805 -61.535632) (xy 256.017405 -61.49187) (xy 256.069122 -61.454294)
			(xy 256.12514 -61.423496) (xy 256.184577 -61.399961) (xy 256.246495 -61.384061) (xy 256.309917 -61.376047)
			(xy 256.34188 -61.375544) (xy 256.374031 -61.376007) (xy 256.437822 -61.384106) (xy 256.50008 -61.400188)
			(xy 256.559812 -61.423998) (xy 256.616062 -61.455153) (xy 256.667932 -61.493158) (xy 256.714591 -61.537403)
			(xy 256.735326 -61.56198) (xy 256.741784 -61.569238) (xy 256.758768 -61.57864) (xy 256.768346 -61.580268)
			(xy 256.838196 -61.58865) (xy 256.847922 -61.589356) (xy 256.866729 -61.58426) (xy 256.874772 -61.578744)
			(xy 256.875026 -61.578744) (xy 256.89714 -61.562761) (xy 256.945023 -61.536604) (xy 256.996143 -61.51753)
			(xy 257.049457 -61.505927) (xy 257.10388 -61.502033) (xy 257.158303 -61.505927) (xy 257.211617 -61.51753)
			(xy 257.262737 -61.536604) (xy 257.31062 -61.562761) (xy 257.332734 -61.578744) (xy 257.332988 -61.578744)
			(xy 257.341005 -61.58431) (xy 257.359831 -61.589396) (xy 257.369564 -61.58865) (xy 257.439414 -61.580268)
			(xy 257.448979 -61.578601) (xy 257.465954 -61.56921) (xy 257.472434 -61.56198) (xy 257.493166 -61.537404)
			(xy 257.539837 -61.493176) (xy 257.591712 -61.455186) (xy 257.647963 -61.424039) (xy 257.707692 -61.400233)
			(xy 257.769946 -61.384147) (xy 257.833731 -61.376038) (xy 257.86588 -61.375544) (xy 257.866134 -61.375544)
			(xy 257.896343 -61.375946) (xy 257.956337 -61.38309) (xy 258.01506 -61.397298) (xy 258.071685 -61.418368)
			(xy 258.125411 -61.446004) (xy 258.175482 -61.479815) (xy 258.19862 -61.499242) (xy 258.205694 -61.504883)
			(xy 258.222604 -61.511273) (xy 258.23164 -61.511688) (xy 258.26212 -61.511688) (xy 258.271154 -61.511244)
			(xy 258.288071 -61.504882) (xy 258.29514 -61.499242) (xy 258.31829 -61.479834) (xy 258.368369 -61.446045)
			(xy 258.422097 -61.418422) (xy 258.478717 -61.397356) (xy 258.537434 -61.383142) (xy 258.59742 -61.37598)
			(xy 258.627626 -61.375544) (xy 258.62788 -61.375544) (xy 258.660031 -61.376007) (xy 258.723822 -61.384106)
			(xy 258.78608 -61.400188) (xy 258.845812 -61.423998) (xy 258.902062 -61.455153) (xy 258.953932 -61.493158)
			(xy 259.000591 -61.537403) (xy 259.021326 -61.56198) (xy 259.027784 -61.569238) (xy 259.044768 -61.57864)
			(xy 259.054346 -61.580268) (xy 259.124196 -61.58865) (xy 259.133922 -61.589356) (xy 259.152729 -61.58426)
			(xy 259.160772 -61.578744) (xy 259.161026 -61.578744) (xy 259.18314 -61.562761) (xy 259.231023 -61.536604)
			(xy 259.282143 -61.51753) (xy 259.335457 -61.505927) (xy 259.38988 -61.502033) (xy 259.444303 -61.505927)
			(xy 259.497617 -61.51753) (xy 259.548737 -61.536604) (xy 259.59662 -61.562761) (xy 259.618734 -61.578744)
			(xy 259.618988 -61.578744) (xy 259.627005 -61.58431) (xy 259.645831 -61.589396) (xy 259.655564 -61.58865)
			(xy 259.725414 -61.580268) (xy 259.734979 -61.578601) (xy 259.751954 -61.56921) (xy 259.758434 -61.56198)
			(xy 259.779166 -61.537404) (xy 259.825837 -61.493176) (xy 259.877712 -61.455186) (xy 259.933963 -61.424039)
			(xy 259.993692 -61.400233) (xy 260.055946 -61.384147) (xy 260.119731 -61.376038) (xy 260.15188 -61.375544)
			(xy 260.18384 -61.37612) (xy 260.247257 -61.384129) (xy 260.309169 -61.400023) (xy 260.368602 -61.423552)
			(xy 260.424616 -61.454344) (xy 260.47633 -61.491914) (xy 260.522926 -61.53567) (xy 260.563672 -61.584921)
			(xy 260.597923 -61.63889) (xy 260.625139 -61.696726) (xy 260.644892 -61.757518) (xy 260.65687 -61.820306)
			(xy 260.660884 -61.8841) (xy 260.65687 -61.947894) (xy 260.644892 -62.010682) (xy 260.625139 -62.071474)
			(xy 260.597923 -62.12931) (xy 260.563672 -62.183279) (xy 260.522926 -62.23253) (xy 260.47633 -62.276286)
			(xy 260.424616 -62.313856) (xy 260.368602 -62.344648) (xy 260.309169 -62.368177) (xy 260.247257 -62.384071)
			(xy 260.18384 -62.39208) (xy 260.15188 -62.39256) (xy 260.11973 -62.392053) (xy 260.055942 -62.383962)
			(xy 259.993684 -62.367887) (xy 259.933953 -62.344084) (xy 259.877702 -62.312935) (xy 259.825831 -62.274937)
			(xy 259.77917 -62.230698) (xy 259.758434 -62.206124) (xy 259.751989 -62.198852) (xy 259.734996 -62.189458)
			(xy 259.725414 -62.187836) (xy 259.655564 -62.179454) (xy 259.645838 -62.178726) (xy 259.627029 -62.183837)
			(xy 259.618988 -62.18936) (xy 259.618734 -62.18936) (xy 259.59662 -62.205343) (xy 259.548737 -62.2315)
			(xy 259.497617 -62.250574) (xy 259.444303 -62.262177) (xy 259.38988 -62.266071) (xy 259.335457 -62.262177)
			(xy 259.282143 -62.250574) (xy 259.231023 -62.2315) (xy 259.18314 -62.205343) (xy 259.161026 -62.18936)
			(xy 259.160772 -62.18936) (xy 259.152737 -62.183824) (xy 259.133925 -62.178719) (xy 259.124196 -62.179454)
			(xy 259.054346 -62.187836) (xy 259.044776 -62.189484) (xy 259.027803 -62.198889) (xy 259.021326 -62.206124)
			(xy 259.000562 -62.230672) (xy 258.953896 -62.274901) (xy 258.902027 -62.312893) (xy 258.845781 -62.344044)
			(xy 258.786058 -62.367855) (xy 258.723809 -62.383947) (xy 258.660028 -62.392062) (xy 258.62788 -62.39256)
			(xy 258.627626 -62.39256) (xy 258.597418 -62.392121) (xy 258.537426 -62.384984) (xy 258.478703 -62.370784)
			(xy 258.422078 -62.34972) (xy 258.368351 -62.322091) (xy 258.318279 -62.288286) (xy 258.29514 -62.268862)
			(xy 258.288078 -62.263205) (xy 258.271159 -62.256825) (xy 258.26212 -62.256416) (xy 258.23164 -62.256416)
			(xy 258.222604 -62.25684) (xy 258.205687 -62.263216) (xy 258.19862 -62.268862) (xy 258.175485 -62.288289)
			(xy 258.125403 -62.322077) (xy 258.071672 -62.349696) (xy 258.015048 -62.370759) (xy 257.956329 -62.384969)
			(xy 257.896341 -62.392126) (xy 257.866134 -62.39256) (xy 257.86588 -62.39256) (xy 257.83373 -62.392053)
			(xy 257.769942 -62.383962) (xy 257.707684 -62.367887) (xy 257.647953 -62.344084) (xy 257.591702 -62.312935)
			(xy 257.539831 -62.274937) (xy 257.49317 -62.230698) (xy 257.472434 -62.206124) (xy 257.465989 -62.198852)
			(xy 257.448996 -62.189458) (xy 257.439414 -62.187836) (xy 257.369564 -62.179454) (xy 257.359838 -62.178726)
			(xy 257.341029 -62.183837) (xy 257.332988 -62.18936) (xy 257.332734 -62.18936) (xy 257.31062 -62.205343)
			(xy 257.262737 -62.2315) (xy 257.211617 -62.250574) (xy 257.158303 -62.262177) (xy 257.10388 -62.266071)
			(xy 257.049457 -62.262177) (xy 256.996143 -62.250574) (xy 256.945023 -62.2315) (xy 256.89714 -62.205343)
			(xy 256.875026 -62.18936) (xy 256.874772 -62.18936) (xy 256.866737 -62.183824) (xy 256.847925 -62.178719)
			(xy 256.838196 -62.179454) (xy 256.768346 -62.187836) (xy 256.758776 -62.189484) (xy 256.741803 -62.198889)
			(xy 256.735326 -62.206124) (xy 256.714562 -62.230672) (xy 256.667896 -62.274901) (xy 256.616027 -62.312893)
			(xy 256.559781 -62.344044) (xy 256.500058 -62.367855) (xy 256.437809 -62.383947) (xy 256.374028 -62.392062)
			(xy 256.34188 -62.39256) (xy 256.309917 -62.392153) (xy 256.246495 -62.384139) (xy 256.184577 -62.368239)
			(xy 256.12514 -62.344704) (xy 256.069122 -62.313906) (xy 256.017405 -62.27633) (xy 255.970805 -62.232568)
			(xy 255.930058 -62.183311) (xy 255.895805 -62.129335) (xy 255.868587 -62.071493) (xy 255.848833 -62.010695)
			(xy 255.836855 -61.9479) (xy 255.832841 -61.8841) (xy 237.25542 -61.8841) (xy 237.26578 -61.938404)
			(xy 237.269794 -62.0022) (xy 237.26578 -62.065997) (xy 237.253801 -62.128787) (xy 237.234047 -62.189581)
			(xy 237.206829 -62.247419) (xy 237.172576 -62.30139) (xy 237.131829 -62.350642) (xy 237.08523 -62.394398)
			(xy 237.033514 -62.431969) (xy 236.977497 -62.462762) (xy 236.918062 -62.48629) (xy 236.856146 -62.502183)
			(xy 236.792727 -62.510191) (xy 236.760766 -62.51067) (xy 236.72906 -62.510193) (xy 236.666142 -62.502297)
			(xy 236.604692 -62.486646) (xy 236.545663 -62.463481) (xy 236.489969 -62.433162) (xy 236.438474 -62.396158)
			(xy 236.391975 -62.353042) (xy 236.351194 -62.304484) (xy 236.316761 -62.251235) (xy 236.30255 -62.222888)
			(xy 236.295946 -62.208918) (xy 236.269276 -62.19317) (xy 236.144562 -62.200536) (xy 236.120178 -62.218824)
			(xy 236.115098 -62.233556) (xy 236.099908 -62.275609) (xy 236.062663 -62.3569) (xy 236.017868 -62.434288)
			(xy 235.965927 -62.507073) (xy 235.907309 -62.574597) (xy 235.842545 -62.636249) (xy 235.772219 -62.691474)
			(xy 235.696967 -62.739771) (xy 235.617469 -62.780705) (xy 235.534444 -62.813905) (xy 235.448641 -62.839072)
			(xy 235.360836 -62.855977) (xy 235.271823 -62.864469) (xy 235.227114 -62.865) (xy 233.372914 -62.865)
			(xy 233.329477 -62.864422) (xy 233.242973 -62.856408) (xy 233.157578 -62.840446) (xy 233.07402 -62.816672)
			(xy 232.993012 -62.785291) (xy 232.915245 -62.746568) (xy 232.841382 -62.700836) (xy 232.772055 -62.648483)
			(xy 232.707853 -62.589957) (xy 232.649326 -62.525756) (xy 232.596972 -62.456429) (xy 232.551239 -62.382568)
			(xy 232.512515 -62.304801) (xy 232.481132 -62.223794) (xy 232.457358 -62.140236) (xy 232.441394 -62.054841)
			(xy 232.433379 -61.968337) (xy 231.591428 -61.968337) (xy 231.574048 -61.988608) (xy 231.552242 -62.009274)
			(xy 231.544876 -62.016132) (xy 231.536494 -62.033912) (xy 231.531668 -62.125098) (xy 231.538272 -62.14364)
			(xy 231.544876 -62.15126) (xy 231.564798 -62.174565) (xy 231.59955 -62.225077) (xy 231.627976 -62.279401)
			(xy 231.649665 -62.336748) (xy 231.6643 -62.396287) (xy 231.671671 -62.457154) (xy 231.67213 -62.48781)
			(xy 231.671628 -62.519771) (xy 231.663617 -62.583189) (xy 231.64772 -62.645103) (xy 231.624188 -62.704536)
			(xy 231.593394 -62.760551) (xy 231.555821 -62.812266) (xy 231.512064 -62.858863) (xy 231.462811 -62.899608)
			(xy 231.40884 -62.933859) (xy 231.351001 -62.961076) (xy 231.290208 -62.980829) (xy 231.227418 -62.992807)
			(xy 231.163622 -62.996821) (xy 231.099826 -62.992807) (xy 231.037036 -62.980829) (xy 230.976243 -62.961076)
			(xy 230.918404 -62.933859) (xy 230.864433 -62.899608) (xy 230.81518 -62.858863) (xy 230.771423 -62.812266)
			(xy 230.73385 -62.760551) (xy 230.703056 -62.704536) (xy 230.679524 -62.645103) (xy 230.663627 -62.583189)
			(xy 230.655616 -62.519771) (xy 230.655114 -62.48781) (xy 183.049909 -62.48781) (xy 183.179486 -62.644932)
			(xy 183.307429 -62.812778) (xy 183.428849 -62.9854) (xy 183.543568 -63.162547) (xy 183.651418 -63.343958)
			(xy 183.707542 -63.447168) (xy 196.07606 -63.447168) (xy 196.080131 -63.391546) (xy 196.092257 -63.337109)
			(xy 196.11218 -63.285018) (xy 196.139476 -63.236383) (xy 196.173562 -63.19224) (xy 196.213711 -63.153531)
			(xy 196.259069 -63.12108) (xy 196.308669 -63.095579) (xy 196.361453 -63.077572) (xy 196.416296 -63.067442)
			(xy 196.47203 -63.065405) (xy 196.527467 -63.071505) (xy 196.581424 -63.085611) (xy 196.632753 -63.107423)
			(xy 196.680359 -63.136477) (xy 196.723227 -63.172152) (xy 196.760444 -63.213689) (xy 196.791217 -63.260202)
			(xy 196.814889 -63.310699) (xy 196.830957 -63.364106) (xy 196.839077 -63.419282) (xy 196.839586 -63.447168)
			(xy 196.839077 -63.475054) (xy 196.830957 -63.53023) (xy 196.814889 -63.583637) (xy 196.791217 -63.634134)
			(xy 196.760444 -63.680647) (xy 196.723227 -63.722184) (xy 196.680359 -63.757859) (xy 196.632753 -63.786913)
			(xy 196.581424 -63.808725) (xy 196.527467 -63.822831) (xy 196.47203 -63.828931) (xy 196.416296 -63.826894)
			(xy 196.361453 -63.816764) (xy 196.308669 -63.798757) (xy 196.259069 -63.773256) (xy 196.213711 -63.740805)
			(xy 196.173562 -63.702096) (xy 196.139476 -63.657953) (xy 196.11218 -63.609318) (xy 196.092257 -63.557227)
			(xy 196.080131 -63.50279) (xy 196.07606 -63.447168) (xy 183.707542 -63.447168) (xy 183.75224 -63.529367)
			(xy 183.845887 -63.718502) (xy 183.93222 -63.911084) (xy 184.011114 -64.106832) (xy 184.082452 -64.305459)
			(xy 184.146129 -64.506672) (xy 184.202053 -64.710176) (xy 184.250141 -64.915673) (xy 184.290323 -65.122861)
			(xy 184.305413 -65.220553) (xy 196.953626 -65.220553) (xy 196.953626 -65.156631) (xy 196.961637 -65.093213)
			(xy 196.977534 -65.031299) (xy 197.001066 -64.971866) (xy 197.03186 -64.915851) (xy 197.069433 -64.864136)
			(xy 197.11319 -64.817539) (xy 197.162443 -64.776794) (xy 197.216414 -64.742543) (xy 197.274253 -64.715326)
			(xy 197.335046 -64.695573) (xy 197.397836 -64.683595) (xy 197.461632 -64.679582) (xy 197.525428 -64.683595)
			(xy 197.588218 -64.695573) (xy 197.649011 -64.715326) (xy 197.70685 -64.742543) (xy 197.760821 -64.776794)
			(xy 197.810074 -64.817539) (xy 197.853831 -64.864136) (xy 197.891404 -64.915851) (xy 197.922198 -64.971866)
			(xy 197.94573 -65.031299) (xy 197.961627 -65.093213) (xy 197.969638 -65.156631) (xy 197.97014 -65.188592)
			(xy 197.969638 -65.220553) (xy 197.961627 -65.283971) (xy 197.94573 -65.345885) (xy 197.922198 -65.405318)
			(xy 197.891404 -65.461333) (xy 197.853831 -65.513048) (xy 197.810074 -65.559645) (xy 197.775329 -65.588388)
			(xy 255.565908 -65.588388) (xy 255.569979 -65.532766) (xy 255.582105 -65.478329) (xy 255.602028 -65.426238)
			(xy 255.629324 -65.377603) (xy 255.66341 -65.33346) (xy 255.703559 -65.294751) (xy 255.748917 -65.2623)
			(xy 255.798517 -65.236799) (xy 255.851301 -65.218792) (xy 255.906144 -65.208662) (xy 255.961878 -65.206625)
			(xy 256.017315 -65.212725) (xy 256.071272 -65.226831) (xy 256.122601 -65.248643) (xy 256.170207 -65.277697)
			(xy 256.213075 -65.313372) (xy 256.250292 -65.354909) (xy 256.281065 -65.401422) (xy 256.304737 -65.451919)
			(xy 256.320805 -65.505326) (xy 256.328925 -65.560502) (xy 256.329434 -65.588388) (xy 256.328925 -65.616274)
			(xy 256.320805 -65.67145) (xy 256.304737 -65.724857) (xy 256.281065 -65.775354) (xy 256.251046 -65.820728)
			(xy 256.877308 -65.820728) (xy 256.877308 -65.736032) (xy 256.885359 -65.651718) (xy 256.901388 -65.568552)
			(xy 256.925249 -65.487285) (xy 256.956728 -65.408655) (xy 256.995539 -65.333374) (xy 257.041329 -65.262122)
			(xy 257.093685 -65.195546) (xy 257.152133 -65.134248) (xy 257.216143 -65.078783) (xy 257.285135 -65.029654)
			(xy 257.358485 -64.987305) (xy 257.435528 -64.952121) (xy 257.515567 -64.924419) (xy 257.597876 -64.904451)
			(xy 257.681711 -64.892398) (xy 257.766312 -64.888368) (xy 257.850913 -64.892398) (xy 257.934748 -64.904451)
			(xy 258.017057 -64.924419) (xy 258.097096 -64.952121) (xy 258.174139 -64.987305) (xy 258.247489 -65.029654)
			(xy 258.316481 -65.078783) (xy 258.380491 -65.134248) (xy 258.438939 -65.195546) (xy 258.491295 -65.262122)
			(xy 258.537085 -65.333374) (xy 258.575896 -65.408655) (xy 258.607375 -65.487285) (xy 258.631236 -65.568552)
			(xy 258.647265 -65.651718) (xy 258.655316 -65.736032) (xy 258.65582 -65.77838) (xy 258.655316 -65.820728)
			(xy 258.647265 -65.905042) (xy 258.631236 -65.988208) (xy 258.607375 -66.069475) (xy 258.575896 -66.148105)
			(xy 258.537085 -66.223386) (xy 258.491295 -66.294638) (xy 258.438939 -66.361214) (xy 258.380491 -66.422512)
			(xy 258.357027 -66.442844) (xy 267.363194 -66.442844) (xy 267.363718 -66.410164) (xy 267.372088 -66.345341)
			(xy 267.388695 -66.282126) (xy 267.413265 -66.221559) (xy 267.445393 -66.16464) (xy 267.48455 -66.112308)
			(xy 267.506958 -66.088514) (xy 267.513816 -66.081656) (xy 267.521182 -66.064638) (xy 267.524484 -65.97777)
			(xy 267.518642 -65.960244) (xy 267.512546 -65.952878) (xy 267.496009 -65.932254) (xy 267.468199 -65.887296)
			(xy 267.446863 -65.83893) (xy 267.432408 -65.788081) (xy 267.425111 -65.735724) (xy 267.424662 -65.709292)
			(xy 267.42517 -65.682042) (xy 267.432927 -65.628097) (xy 267.448282 -65.575804) (xy 267.470922 -65.526229)
			(xy 267.500386 -65.48038) (xy 267.536075 -65.439191) (xy 267.577262 -65.403499) (xy 267.623109 -65.374032)
			(xy 267.672683 -65.351389) (xy 267.724975 -65.336032) (xy 267.77892 -65.328272) (xy 267.80617 -65.327784)
			(xy 267.833809 -65.328256) (xy 267.888506 -65.336253) (xy 267.941477 -65.352056) (xy 267.991615 -65.375333)
			(xy 268.037872 -65.405599) (xy 268.0589 -65.423542) (xy 268.06568 -65.42908) (xy 268.081921 -65.435579)
			(xy 268.09065 -65.436242) (xy 268.120876 -65.437512) (xy 268.129748 -65.437552) (xy 268.14666 -65.432231)
			(xy 268.153896 -65.427098) (xy 268.180618 -65.407318) (xy 268.238214 -65.374108) (xy 268.299643 -65.34868)
			(xy 268.363861 -65.331467) (xy 268.429772 -65.322761) (xy 268.463014 -65.322196) (xy 268.493745 -65.322643)
			(xy 268.55476 -65.330053) (xy 268.614437 -65.344764) (xy 268.671905 -65.36656) (xy 268.726327 -65.395124)
			(xy 268.776909 -65.43004) (xy 268.822914 -65.470799) (xy 268.863671 -65.516805) (xy 268.898585 -65.567388)
			(xy 268.927147 -65.621812) (xy 268.948942 -65.679281) (xy 268.96365 -65.738958) (xy 268.971058 -65.799973)
			(xy 268.971522 -65.830704) (xy 268.971 -65.863341) (xy 268.962647 -65.928078) (xy 268.946079 -65.991214)
			(xy 268.921567 -66.051711) (xy 268.889516 -66.108574) (xy 268.850451 -66.160868) (xy 268.805017 -66.207734)
			(xy 268.753958 -66.2484) (xy 268.698116 -66.282198) (xy 268.638407 -66.308572) (xy 268.575815 -66.327089)
			(xy 268.511368 -66.337445) (xy 268.478762 -66.338958) (xy 268.478508 -66.338958) (xy 268.468729 -66.339718)
			(xy 268.450831 -66.347705) (xy 268.44371 -66.354452) (xy 268.394434 -66.405506) (xy 268.387983 -66.412878)
			(xy 268.380663 -66.431028) (xy 268.38021 -66.440812) (xy 268.38021 -66.442844) (xy 268.379708 -66.474805)
			(xy 268.371697 -66.538223) (xy 268.3558 -66.600137) (xy 268.332268 -66.65957) (xy 268.301474 -66.715585)
			(xy 268.263901 -66.7673) (xy 268.220144 -66.813897) (xy 268.170891 -66.854642) (xy 268.11692 -66.888893)
			(xy 268.059081 -66.91611) (xy 267.998288 -66.935863) (xy 267.935498 -66.947841) (xy 267.871702 -66.951855)
			(xy 267.807906 -66.947841) (xy 267.745116 -66.935863) (xy 267.684323 -66.91611) (xy 267.626484 -66.888893)
			(xy 267.572513 -66.854642) (xy 267.52326 -66.813897) (xy 267.479503 -66.7673) (xy 267.44193 -66.715585)
			(xy 267.411136 -66.65957) (xy 267.387604 -66.600137) (xy 267.371707 -66.538223) (xy 267.363696 -66.474805)
			(xy 267.363194 -66.442844) (xy 258.357027 -66.442844) (xy 258.316481 -66.477977) (xy 258.247489 -66.527106)
			(xy 258.174139 -66.569455) (xy 258.097096 -66.604639) (xy 258.017057 -66.632341) (xy 257.934748 -66.652309)
			(xy 257.850913 -66.664362) (xy 257.766312 -66.668393) (xy 257.681711 -66.664362) (xy 257.597876 -66.652309)
			(xy 257.515567 -66.632341) (xy 257.435528 -66.604639) (xy 257.358485 -66.569455) (xy 257.285135 -66.527106)
			(xy 257.216143 -66.477977) (xy 257.152133 -66.422512) (xy 257.093685 -66.361214) (xy 257.041329 -66.294638)
			(xy 256.995539 -66.223386) (xy 256.956728 -66.148105) (xy 256.925249 -66.069475) (xy 256.901388 -65.988208)
			(xy 256.885359 -65.905042) (xy 256.877308 -65.820728) (xy 256.251046 -65.820728) (xy 256.250292 -65.821867)
			(xy 256.213075 -65.863404) (xy 256.170207 -65.899079) (xy 256.122601 -65.928133) (xy 256.071272 -65.949945)
			(xy 256.017315 -65.964051) (xy 255.961878 -65.970151) (xy 255.906144 -65.968114) (xy 255.851301 -65.957984)
			(xy 255.798517 -65.939977) (xy 255.748917 -65.914476) (xy 255.703559 -65.882025) (xy 255.66341 -65.843316)
			(xy 255.629324 -65.799173) (xy 255.602028 -65.750538) (xy 255.582105 -65.698447) (xy 255.569979 -65.64401)
			(xy 255.565908 -65.588388) (xy 197.775329 -65.588388) (xy 197.760821 -65.60039) (xy 197.70685 -65.634641)
			(xy 197.649011 -65.661858) (xy 197.588218 -65.681611) (xy 197.525428 -65.693589) (xy 197.461632 -65.697603)
			(xy 197.397836 -65.693589) (xy 197.335046 -65.681611) (xy 197.274253 -65.661858) (xy 197.216414 -65.634641)
			(xy 197.162443 -65.60039) (xy 197.11319 -65.559645) (xy 197.069433 -65.513048) (xy 197.03186 -65.461333)
			(xy 197.001066 -65.405318) (xy 196.977534 -65.345885) (xy 196.961637 -65.283971) (xy 196.953626 -65.220553)
			(xy 184.305413 -65.220553) (xy 184.32254 -65.331436) (xy 184.346743 -65.541093) (xy 184.362899 -65.751522)
			(xy 184.370983 -65.962416) (xy 184.371488 -66.06794) (xy 184.371488 -66.190325) (xy 198.300842 -66.190325)
			(xy 198.300842 -66.126403) (xy 198.308853 -66.062985) (xy 198.32475 -66.001071) (xy 198.348282 -65.941638)
			(xy 198.379076 -65.885623) (xy 198.416649 -65.833908) (xy 198.460406 -65.787311) (xy 198.509659 -65.746566)
			(xy 198.56363 -65.712315) (xy 198.621469 -65.685098) (xy 198.682262 -65.665345) (xy 198.745052 -65.653367)
			(xy 198.808848 -65.649354) (xy 198.872644 -65.653367) (xy 198.935434 -65.665345) (xy 198.996227 -65.685098)
			(xy 199.054066 -65.712315) (xy 199.108037 -65.746566) (xy 199.15729 -65.787311) (xy 199.201047 -65.833908)
			(xy 199.23862 -65.885623) (xy 199.269414 -65.941638) (xy 199.292946 -66.001071) (xy 199.308843 -66.062985)
			(xy 199.316854 -66.126403) (xy 199.317356 -66.158364) (xy 199.316854 -66.190325) (xy 199.308843 -66.253743)
			(xy 199.292946 -66.315657) (xy 199.269414 -66.37509) (xy 199.23862 -66.431105) (xy 199.201047 -66.48282)
			(xy 199.15729 -66.529417) (xy 199.117326 -66.562478) (xy 216.364058 -66.562478) (xy 216.36456 -66.530517)
			(xy 216.372571 -66.467099) (xy 216.388468 -66.405185) (xy 216.412 -66.345752) (xy 216.442794 -66.289737)
			(xy 216.480367 -66.238022) (xy 216.524124 -66.191425) (xy 216.573377 -66.15068) (xy 216.627348 -66.116429)
			(xy 216.685187 -66.089212) (xy 216.74598 -66.069459) (xy 216.80877 -66.057481) (xy 216.872566 -66.053468)
			(xy 216.936362 -66.057481) (xy 216.999152 -66.069459) (xy 217.059945 -66.089212) (xy 217.117784 -66.116429)
			(xy 217.171755 -66.15068) (xy 217.221008 -66.191425) (xy 217.264765 -66.238022) (xy 217.302338 -66.289737)
			(xy 217.333132 -66.345752) (xy 217.356664 -66.405185) (xy 217.372561 -66.467099) (xy 217.380572 -66.530517)
			(xy 217.381074 -66.562478) (xy 217.380586 -66.594976) (xy 217.374154 -66.645028) (xy 217.684094 -66.645028)
			(xy 217.688165 -66.589406) (xy 217.700291 -66.534969) (xy 217.720214 -66.482878) (xy 217.74751 -66.434243)
			(xy 217.781596 -66.3901) (xy 217.821745 -66.351391) (xy 217.867103 -66.31894) (xy 217.916703 -66.293439)
			(xy 217.969487 -66.275432) (xy 218.02433 -66.265302) (xy 218.080064 -66.263265) (xy 218.135501 -66.269365)
			(xy 218.139211 -66.270335) (xy 249.035564 -66.270335) (xy 249.035564 -66.206413) (xy 249.043575 -66.142995)
			(xy 249.059472 -66.081081) (xy 249.083004 -66.021648) (xy 249.113798 -65.965633) (xy 249.151371 -65.913918)
			(xy 249.195128 -65.867321) (xy 249.244381 -65.826576) (xy 249.298352 -65.792325) (xy 249.356191 -65.765108)
			(xy 249.416984 -65.745355) (xy 249.479774 -65.733377) (xy 249.54357 -65.729364) (xy 249.607366 -65.733377)
			(xy 249.670156 -65.745355) (xy 249.730949 -65.765108) (xy 249.788788 -65.792325) (xy 249.842759 -65.826576)
			(xy 249.892012 -65.867321) (xy 249.935769 -65.913918) (xy 249.973342 -65.965633) (xy 250.004136 -66.021648)
			(xy 250.027668 -66.081081) (xy 250.043565 -66.142995) (xy 250.051576 -66.206413) (xy 250.052078 -66.238374)
			(xy 250.051576 -66.270335) (xy 250.043565 -66.333753) (xy 250.027668 -66.395667) (xy 250.004136 -66.4551)
			(xy 249.973342 -66.511115) (xy 249.935769 -66.56283) (xy 249.892012 -66.609427) (xy 249.842759 -66.650172)
			(xy 249.788788 -66.684423) (xy 249.730949 -66.71164) (xy 249.670156 -66.731393) (xy 249.607366 -66.743371)
			(xy 249.54357 -66.747385) (xy 249.479774 -66.743371) (xy 249.416984 -66.731393) (xy 249.356191 -66.71164)
			(xy 249.298352 -66.684423) (xy 249.244381 -66.650172) (xy 249.195128 -66.609427) (xy 249.151371 -66.56283)
			(xy 249.113798 -66.511115) (xy 249.083004 -66.4551) (xy 249.059472 -66.395667) (xy 249.043575 -66.333753)
			(xy 249.035564 -66.270335) (xy 218.139211 -66.270335) (xy 218.189458 -66.283471) (xy 218.240787 -66.305283)
			(xy 218.288393 -66.334337) (xy 218.331261 -66.370012) (xy 218.368478 -66.411549) (xy 218.399251 -66.458062)
			(xy 218.422923 -66.508559) (xy 218.438991 -66.561966) (xy 218.447111 -66.617142) (xy 218.44762 -66.645028)
			(xy 218.447111 -66.672914) (xy 218.438991 -66.72809) (xy 218.422923 -66.781497) (xy 218.399251 -66.831994)
			(xy 218.368478 -66.878507) (xy 218.331261 -66.920044) (xy 218.288393 -66.955719) (xy 218.240787 -66.984773)
			(xy 218.189458 -67.006585) (xy 218.135501 -67.020691) (xy 218.080064 -67.026791) (xy 218.02433 -67.024754)
			(xy 217.969487 -67.014624) (xy 217.916703 -66.996617) (xy 217.867103 -66.971116) (xy 217.821745 -66.938665)
			(xy 217.781596 -66.899956) (xy 217.74751 -66.855813) (xy 217.720214 -66.807178) (xy 217.700291 -66.755087)
			(xy 217.688165 -66.70065) (xy 217.684094 -66.645028) (xy 217.374154 -66.645028) (xy 217.372302 -66.659442)
			(xy 217.355866 -66.722325) (xy 217.331546 -66.782599) (xy 217.29974 -66.839281) (xy 217.260966 -66.891445)
			(xy 217.215858 -66.938239) (xy 217.190828 -66.958972) (xy 217.190574 -66.959226) (xy 217.183345 -66.965626)
			(xy 217.173953 -66.982481) (xy 217.172286 -66.991992) (xy 217.163901 -67.056211) (xy 233.766608 -67.056211)
			(xy 233.766608 -66.992289) (xy 233.774619 -66.928871) (xy 233.790516 -66.866957) (xy 233.814048 -66.807524)
			(xy 233.844842 -66.751509) (xy 233.882415 -66.699794) (xy 233.926172 -66.653197) (xy 233.975425 -66.612452)
			(xy 234.029396 -66.578201) (xy 234.087235 -66.550984) (xy 234.148028 -66.531231) (xy 234.210818 -66.519253)
			(xy 234.274614 -66.51524) (xy 234.33841 -66.519253) (xy 234.4012 -66.531231) (xy 234.461993 -66.550984)
			(xy 234.519832 -66.578201) (xy 234.573803 -66.612452) (xy 234.623056 -66.653197) (xy 234.666813 -66.699794)
			(xy 234.704386 -66.751509) (xy 234.73518 -66.807524) (xy 234.758712 -66.866957) (xy 234.774609 -66.928871)
			(xy 234.78262 -66.992289) (xy 234.783122 -67.02425) (xy 234.78262 -67.056211) (xy 234.780337 -67.074288)
			(xy 235.386878 -67.074288) (xy 235.390949 -67.018666) (xy 235.403075 -66.964229) (xy 235.422998 -66.912138)
			(xy 235.450294 -66.863503) (xy 235.48438 -66.81936) (xy 235.524529 -66.780651) (xy 235.569887 -66.7482)
			(xy 235.619487 -66.722699) (xy 235.672271 -66.704692) (xy 235.727114 -66.694562) (xy 235.782848 -66.692525)
			(xy 235.838285 -66.698625) (xy 235.892242 -66.712731) (xy 235.943571 -66.734543) (xy 235.991177 -66.763597)
			(xy 236.034045 -66.799272) (xy 236.071262 -66.840809) (xy 236.102035 -66.887322) (xy 236.125707 -66.937819)
			(xy 236.141775 -66.991226) (xy 236.149895 -67.046402) (xy 236.150404 -67.074288) (xy 236.149895 -67.102174)
			(xy 236.141775 -67.15735) (xy 236.125707 -67.210757) (xy 236.102035 -67.261254) (xy 236.071262 -67.307767)
			(xy 236.056783 -67.323927) (xy 247.97232 -67.323927) (xy 247.97232 -67.260005) (xy 247.980331 -67.196587)
			(xy 247.996228 -67.134673) (xy 248.01976 -67.07524) (xy 248.050554 -67.019225) (xy 248.088127 -66.96751)
			(xy 248.131884 -66.920913) (xy 248.181137 -66.880168) (xy 248.235108 -66.845917) (xy 248.292947 -66.8187)
			(xy 248.35374 -66.798947) (xy 248.41653 -66.786969) (xy 248.480326 -66.782956) (xy 248.544122 -66.786969)
			(xy 248.606912 -66.798947) (xy 248.667705 -66.8187) (xy 248.725544 -66.845917) (xy 248.779515 -66.880168)
			(xy 248.828768 -66.920913) (xy 248.872525 -66.96751) (xy 248.910098 -67.019225) (xy 248.940892 -67.07524)
			(xy 248.964424 -67.134673) (xy 248.980321 -67.196587) (xy 248.987621 -67.254374) (xy 249.161552 -67.254374)
			(xy 249.165623 -67.198752) (xy 249.177749 -67.144315) (xy 249.197672 -67.092224) (xy 249.224968 -67.043589)
			(xy 249.259054 -66.999446) (xy 249.299203 -66.960737) (xy 249.344561 -66.928286) (xy 249.394161 -66.902785)
			(xy 249.446945 -66.884778) (xy 249.501788 -66.874648) (xy 249.557522 -66.872611) (xy 249.612959 -66.878711)
			(xy 249.649867 -66.88836) (xy 252.395988 -66.88836) (xy 252.400059 -66.832738) (xy 252.412185 -66.778301)
			(xy 252.432108 -66.72621) (xy 252.459404 -66.677575) (xy 252.49349 -66.633432) (xy 252.533639 -66.594723)
			(xy 252.578997 -66.562272) (xy 252.628597 -66.536771) (xy 252.681381 -66.518764) (xy 252.736224 -66.508634)
			(xy 252.791958 -66.506597) (xy 252.847395 -66.512697) (xy 252.901352 -66.526803) (xy 252.952681 -66.548615)
			(xy 253.000287 -66.577669) (xy 253.043155 -66.613344) (xy 253.080372 -66.654881) (xy 253.111145 -66.701394)
			(xy 253.134817 -66.751891) (xy 253.150885 -66.805298) (xy 253.159005 -66.860474) (xy 253.159514 -66.88836)
			(xy 253.159005 -66.916246) (xy 253.150885 -66.971422) (xy 253.134817 -67.024829) (xy 253.111145 -67.075326)
			(xy 253.080372 -67.121839) (xy 253.043155 -67.163376) (xy 253.000287 -67.199051) (xy 252.952681 -67.228105)
			(xy 252.901352 -67.249917) (xy 252.847395 -67.264023) (xy 252.791958 -67.270123) (xy 252.736224 -67.268086)
			(xy 252.681381 -67.257956) (xy 252.628597 -67.239949) (xy 252.578997 -67.214448) (xy 252.533639 -67.181997)
			(xy 252.49349 -67.143288) (xy 252.459404 -67.099145) (xy 252.432108 -67.05051) (xy 252.412185 -66.998419)
			(xy 252.400059 -66.943982) (xy 252.395988 -66.88836) (xy 249.649867 -66.88836) (xy 249.666916 -66.892817)
			(xy 249.718245 -66.914629) (xy 249.765851 -66.943683) (xy 249.808719 -66.979358) (xy 249.845936 -67.020895)
			(xy 249.876709 -67.067408) (xy 249.900381 -67.117905) (xy 249.916449 -67.171312) (xy 249.924569 -67.226488)
			(xy 249.925078 -67.254374) (xy 249.924569 -67.28226) (xy 249.916449 -67.337436) (xy 249.900381 -67.390843)
			(xy 249.876709 -67.44134) (xy 249.845936 -67.487853) (xy 249.808719 -67.52939) (xy 249.765851 -67.565065)
			(xy 249.718245 -67.594119) (xy 249.666916 -67.615931) (xy 249.612959 -67.630037) (xy 249.557522 -67.636137)
			(xy 249.501788 -67.6341) (xy 249.446945 -67.62397) (xy 249.394161 -67.605963) (xy 249.344561 -67.580462)
			(xy 249.299203 -67.548011) (xy 249.259054 -67.509302) (xy 249.224968 -67.465159) (xy 249.197672 -67.416524)
			(xy 249.177749 -67.364433) (xy 249.165623 -67.309996) (xy 249.161552 -67.254374) (xy 248.987621 -67.254374)
			(xy 248.988332 -67.260005) (xy 248.988834 -67.291966) (xy 248.988332 -67.323927) (xy 248.980321 -67.387345)
			(xy 248.964424 -67.449259) (xy 248.940892 -67.508692) (xy 248.910098 -67.564707) (xy 248.872525 -67.616422)
			(xy 248.828768 -67.663019) (xy 248.779515 -67.703764) (xy 248.725544 -67.738015) (xy 248.667705 -67.765232)
			(xy 248.606912 -67.784985) (xy 248.544122 -67.796963) (xy 248.480326 -67.800977) (xy 248.41653 -67.796963)
			(xy 248.35374 -67.784985) (xy 248.292947 -67.765232) (xy 248.235108 -67.738015) (xy 248.181137 -67.703764)
			(xy 248.131884 -67.663019) (xy 248.088127 -67.616422) (xy 248.050554 -67.564707) (xy 248.01976 -67.508692)
			(xy 247.996228 -67.449259) (xy 247.980331 -67.387345) (xy 247.97232 -67.323927) (xy 236.056783 -67.323927)
			(xy 236.034045 -67.349304) (xy 235.991177 -67.384979) (xy 235.943571 -67.414033) (xy 235.892242 -67.435845)
			(xy 235.838285 -67.449951) (xy 235.782848 -67.456051) (xy 235.727114 -67.454014) (xy 235.672271 -67.443884)
			(xy 235.619487 -67.425877) (xy 235.569887 -67.400376) (xy 235.524529 -67.367925) (xy 235.48438 -67.329216)
			(xy 235.450294 -67.285073) (xy 235.422998 -67.236438) (xy 235.403075 -67.184347) (xy 235.390949 -67.12991)
			(xy 235.386878 -67.074288) (xy 234.780337 -67.074288) (xy 234.774609 -67.119629) (xy 234.758712 -67.181543)
			(xy 234.73518 -67.240976) (xy 234.704386 -67.296991) (xy 234.666813 -67.348706) (xy 234.623056 -67.395303)
			(xy 234.573803 -67.436048) (xy 234.519832 -67.470299) (xy 234.461993 -67.497516) (xy 234.4012 -67.517269)
			(xy 234.33841 -67.529247) (xy 234.274614 -67.533261) (xy 234.210818 -67.529247) (xy 234.148028 -67.517269)
			(xy 234.087235 -67.497516) (xy 234.029396 -67.470299) (xy 233.975425 -67.436048) (xy 233.926172 -67.395303)
			(xy 233.882415 -67.348706) (xy 233.844842 -67.296991) (xy 233.814048 -67.240976) (xy 233.790516 -67.181543)
			(xy 233.774619 -67.119629) (xy 233.766608 -67.056211) (xy 217.163901 -67.056211) (xy 217.161872 -67.071748)
			(xy 217.166698 -67.090544) (xy 217.17254 -67.098418) (xy 217.190005 -67.123137) (xy 217.217709 -67.176946)
			(xy 217.236574 -67.234453) (xy 217.246128 -67.294217) (xy 217.246708 -67.324478) (xy 217.246222 -67.351729)
			(xy 217.238466 -67.405677) (xy 217.223111 -67.457972) (xy 217.200469 -67.507549) (xy 217.171003 -67.553399)
			(xy 217.135312 -67.59459) (xy 217.094121 -67.630281) (xy 217.048271 -67.659747) (xy 216.998694 -67.682389)
			(xy 216.946399 -67.697744) (xy 216.892451 -67.7055) (xy 216.837949 -67.7055) (xy 216.784001 -67.697744)
			(xy 216.731706 -67.682389) (xy 216.682129 -67.659747) (xy 216.636279 -67.630281) (xy 216.595088 -67.59459)
			(xy 216.559397 -67.553399) (xy 216.529931 -67.507549) (xy 216.507289 -67.457972) (xy 216.491934 -67.405677)
			(xy 216.484178 -67.351729) (xy 216.483692 -67.324478) (xy 216.484091 -67.299546) (xy 216.490576 -67.250105)
			(xy 216.503445 -67.201931) (xy 216.522479 -67.155843) (xy 216.547354 -67.112626) (xy 216.562178 -67.092576)
			(xy 216.567771 -67.084566) (xy 216.57298 -67.06575) (xy 216.572338 -67.056) (xy 216.563702 -66.976498)
			(xy 216.554304 -66.958972) (xy 216.546684 -66.952876) (xy 216.522615 -66.932087) (xy 216.479257 -66.885558)
			(xy 216.442038 -66.833986) (xy 216.411539 -66.778176) (xy 216.388236 -66.719) (xy 216.372493 -66.65738)
			(xy 216.364554 -66.594278) (xy 216.364058 -66.562478) (xy 199.117326 -66.562478) (xy 199.108037 -66.570162)
			(xy 199.054066 -66.604413) (xy 198.996227 -66.63163) (xy 198.935434 -66.651383) (xy 198.872644 -66.663361)
			(xy 198.808848 -66.667375) (xy 198.745052 -66.663361) (xy 198.682262 -66.651383) (xy 198.621469 -66.63163)
			(xy 198.56363 -66.604413) (xy 198.509659 -66.570162) (xy 198.460406 -66.529417) (xy 198.416649 -66.48282)
			(xy 198.379076 -66.431105) (xy 198.348282 -66.37509) (xy 198.32475 -66.315657) (xy 198.308853 -66.253743)
			(xy 198.300842 -66.190325) (xy 184.371488 -66.190325) (xy 184.371488 -67.645026) (xy 191.207136 -67.645026)
			(xy 191.207622 -67.617775) (xy 191.215378 -67.563827) (xy 191.230733 -67.511532) (xy 191.253375 -67.461955)
			(xy 191.282841 -67.416105) (xy 191.318532 -67.374914) (xy 191.359723 -67.339223) (xy 191.405573 -67.309757)
			(xy 191.45515 -67.287115) (xy 191.507445 -67.27176) (xy 191.561393 -67.264004) (xy 191.615895 -67.264004)
			(xy 191.667283 -67.271392) (xy 200.618596 -67.271392) (xy 200.622667 -67.21577) (xy 200.634793 -67.161333)
			(xy 200.654716 -67.109242) (xy 200.682012 -67.060607) (xy 200.716098 -67.016464) (xy 200.756247 -66.977755)
			(xy 200.801605 -66.945304) (xy 200.851205 -66.919803) (xy 200.903989 -66.901796) (xy 200.958832 -66.891666)
			(xy 201.014566 -66.889629) (xy 201.070003 -66.895729) (xy 201.12396 -66.909835) (xy 201.175289 -66.931647)
			(xy 201.222895 -66.960701) (xy 201.265763 -66.996376) (xy 201.30298 -67.037913) (xy 201.333753 -67.084426)
			(xy 201.357425 -67.134923) (xy 201.373493 -67.18833) (xy 201.381613 -67.243506) (xy 201.382122 -67.271392)
			(xy 201.381613 -67.299278) (xy 201.373493 -67.354454) (xy 201.357425 -67.407861) (xy 201.333753 -67.458358)
			(xy 201.30298 -67.504871) (xy 201.284586 -67.5254) (xy 203.52966 -67.5254) (xy 203.533675 -67.4616)
			(xy 203.545653 -67.398806) (xy 203.565408 -67.338008) (xy 203.592627 -67.280166) (xy 203.62688 -67.226191)
			(xy 203.667629 -67.176936) (xy 203.714229 -67.133175) (xy 203.765947 -67.095601) (xy 203.821967 -67.064805)
			(xy 203.881404 -67.041273) (xy 203.943322 -67.025376) (xy 204.006745 -67.017364) (xy 204.038708 -67.016884)
			(xy 204.071852 -67.017416) (xy 204.137577 -67.026042) (xy 204.201625 -67.043133) (xy 204.262909 -67.0684)
			(xy 204.320392 -67.101415) (xy 204.373098 -67.141617) (xy 204.420135 -67.188326) (xy 204.460705 -67.24075)
			(xy 204.477874 -67.269106) (xy 204.485776 -67.281741) (xy 204.507591 -67.302032) (xy 204.534333 -67.315164)
			(xy 204.563727 -67.32002) (xy 204.593272 -67.316187) (xy 204.620454 -67.303991) (xy 204.64296 -67.28447)
			(xy 204.651356 -67.272154) (xy 204.666398 -67.249163) (xy 204.702099 -67.207402) (xy 204.74342 -67.171193)
			(xy 204.789508 -67.141286) (xy 204.839409 -67.118298) (xy 204.892091 -67.102705) (xy 204.946465 -67.09483)
			(xy 204.973936 -67.094354) (xy 205.001183 -67.094919) (xy 205.055121 -67.102679) (xy 205.107406 -67.118035)
			(xy 205.156974 -67.140676) (xy 205.202815 -67.17014) (xy 205.243997 -67.205828) (xy 205.279681 -67.247014)
			(xy 205.309141 -67.292858) (xy 205.331777 -67.342427) (xy 205.347129 -67.394714) (xy 205.354884 -67.448653)
			(xy 205.354884 -67.503147) (xy 205.347129 -67.557086) (xy 205.331777 -67.609373) (xy 205.330362 -67.612471)
			(xy 206.165698 -67.612471) (xy 206.165698 -67.548549) (xy 206.173709 -67.485131) (xy 206.189606 -67.423217)
			(xy 206.213138 -67.363784) (xy 206.243932 -67.307769) (xy 206.281505 -67.256054) (xy 206.325262 -67.209457)
			(xy 206.374515 -67.168712) (xy 206.428486 -67.134461) (xy 206.486325 -67.107244) (xy 206.547118 -67.087491)
			(xy 206.609908 -67.075513) (xy 206.673704 -67.0715) (xy 206.7375 -67.075513) (xy 206.80029 -67.087491)
			(xy 206.861083 -67.107244) (xy 206.918922 -67.134461) (xy 206.972893 -67.168712) (xy 207.022146 -67.209457)
			(xy 207.065903 -67.256054) (xy 207.103476 -67.307769) (xy 207.117549 -67.333368) (xy 214.994488 -67.333368)
			(xy 214.998559 -67.277746) (xy 215.010685 -67.223309) (xy 215.030608 -67.171218) (xy 215.057904 -67.122583)
			(xy 215.09199 -67.07844) (xy 215.132139 -67.039731) (xy 215.177497 -67.00728) (xy 215.227097 -66.981779)
			(xy 215.279881 -66.963772) (xy 215.334724 -66.953642) (xy 215.390458 -66.951605) (xy 215.445895 -66.957705)
			(xy 215.499852 -66.971811) (xy 215.551181 -66.993623) (xy 215.598787 -67.022677) (xy 215.641655 -67.058352)
			(xy 215.678872 -67.099889) (xy 215.709645 -67.146402) (xy 215.733317 -67.196899) (xy 215.749385 -67.250306)
			(xy 215.757505 -67.305482) (xy 215.758014 -67.333368) (xy 215.757505 -67.361254) (xy 215.749385 -67.41643)
			(xy 215.733317 -67.469837) (xy 215.709645 -67.520334) (xy 215.678872 -67.566847) (xy 215.641655 -67.608384)
			(xy 215.598787 -67.644059) (xy 215.551181 -67.673113) (xy 215.499852 -67.694925) (xy 215.445895 -67.709031)
			(xy 215.390458 -67.715131) (xy 215.334724 -67.713094) (xy 215.279881 -67.702964) (xy 215.227097 -67.684957)
			(xy 215.177497 -67.659456) (xy 215.132139 -67.627005) (xy 215.09199 -67.588296) (xy 215.057904 -67.544153)
			(xy 215.030608 -67.495518) (xy 215.010685 -67.443427) (xy 214.998559 -67.38899) (xy 214.994488 -67.333368)
			(xy 207.117549 -67.333368) (xy 207.13427 -67.363784) (xy 207.157802 -67.423217) (xy 207.173699 -67.485131)
			(xy 207.18171 -67.548549) (xy 207.182212 -67.58051) (xy 207.18171 -67.612471) (xy 207.173699 -67.675889)
			(xy 207.157802 -67.737803) (xy 207.13427 -67.797236) (xy 207.103476 -67.853251) (xy 207.065903 -67.904966)
			(xy 207.022146 -67.951563) (xy 206.972893 -67.992308) (xy 206.918922 -68.026559) (xy 206.861083 -68.053776)
			(xy 206.80029 -68.073529) (xy 206.7375 -68.085507) (xy 206.673704 -68.089521) (xy 206.609908 -68.085507)
			(xy 206.547118 -68.073529) (xy 206.486325 -68.053776) (xy 206.428486 -68.026559) (xy 206.374515 -67.992308)
			(xy 206.325262 -67.951563) (xy 206.281505 -67.904966) (xy 206.243932 -67.853251) (xy 206.213138 -67.797236)
			(xy 206.189606 -67.737803) (xy 206.173709 -67.675889) (xy 206.165698 -67.612471) (xy 205.330362 -67.612471)
			(xy 205.309141 -67.658942) (xy 205.279681 -67.704786) (xy 205.243997 -67.745972) (xy 205.202815 -67.78166)
			(xy 205.156974 -67.811124) (xy 205.107406 -67.833765) (xy 205.055121 -67.849121) (xy 205.001183 -67.856881)
			(xy 204.973936 -67.85737) (xy 204.945258 -67.856905) (xy 204.888547 -67.848323) (xy 204.833761 -67.831345)
			(xy 204.782134 -67.806356) (xy 204.734831 -67.773918) (xy 204.692918 -67.734764) (xy 204.674724 -67.71259)
			(xy 204.665113 -67.701188) (xy 204.640674 -67.684119) (xy 204.612345 -67.674842) (xy 204.582544 -67.67415)
			(xy 204.553815 -67.682101) (xy 204.52861 -67.698016) (xy 204.509081 -67.720537) (xy 204.502512 -67.733926)
			(xy 204.488758 -67.763322) (xy 204.45482 -67.818644) (xy 204.41412 -67.869199) (xy 204.367318 -67.914166)
			(xy 204.315177 -67.952813) (xy 204.258543 -67.984512) (xy 204.198335 -68.008749) (xy 204.135534 -68.02513)
			(xy 204.071159 -68.033388) (xy 204.038708 -68.0339) (xy 204.006745 -68.033436) (xy 203.943322 -68.025424)
			(xy 203.881404 -68.009527) (xy 203.821967 -67.985995) (xy 203.765947 -67.955199) (xy 203.714229 -67.917625)
			(xy 203.667629 -67.873864) (xy 203.62688 -67.824609) (xy 203.592627 -67.770634) (xy 203.565408 -67.712792)
			(xy 203.545653 -67.651994) (xy 203.533675 -67.5892) (xy 203.52966 -67.5254) (xy 201.284586 -67.5254)
			(xy 201.265763 -67.546408) (xy 201.222895 -67.582083) (xy 201.175289 -67.611137) (xy 201.12396 -67.632949)
			(xy 201.070003 -67.647055) (xy 201.014566 -67.653155) (xy 200.958832 -67.651118) (xy 200.903989 -67.640988)
			(xy 200.851205 -67.622981) (xy 200.801605 -67.59748) (xy 200.756247 -67.565029) (xy 200.716098 -67.52632)
			(xy 200.682012 -67.482177) (xy 200.654716 -67.433542) (xy 200.634793 -67.381451) (xy 200.622667 -67.327014)
			(xy 200.618596 -67.271392) (xy 191.667283 -67.271392) (xy 191.669843 -67.27176) (xy 191.722138 -67.287115)
			(xy 191.771715 -67.309757) (xy 191.817565 -67.339223) (xy 191.858756 -67.374914) (xy 191.894447 -67.416105)
			(xy 191.923913 -67.461955) (xy 191.946555 -67.511532) (xy 191.96191 -67.563827) (xy 191.969666 -67.617775)
			(xy 191.970152 -67.645026) (xy 191.969623 -67.67391) (xy 191.960899 -67.731016) (xy 191.943667 -67.786156)
			(xy 191.918322 -67.838068) (xy 191.885444 -67.885568) (xy 191.845782 -67.92757) (xy 191.82334 -67.945762)
			(xy 191.813942 -67.953128) (xy 191.803782 -67.973956) (xy 191.804036 -68.078096) (xy 191.814196 -68.098924)
			(xy 191.823594 -68.10629) (xy 191.846208 -68.124438) (xy 191.886134 -68.166485) (xy 191.919238 -68.214089)
			(xy 191.944758 -68.266154) (xy 191.962105 -68.321481) (xy 191.970881 -68.378796) (xy 191.971422 -68.407788)
			(xy 191.970936 -68.435039) (xy 191.96318 -68.488987) (xy 191.947825 -68.541282) (xy 191.925183 -68.590859)
			(xy 191.895717 -68.636709) (xy 191.860026 -68.6779) (xy 191.818835 -68.713591) (xy 191.795563 -68.728547)
			(xy 199.01636 -68.728547) (xy 199.01636 -68.664625) (xy 199.024371 -68.601207) (xy 199.040268 -68.539293)
			(xy 199.0638 -68.47986) (xy 199.094594 -68.423845) (xy 199.132167 -68.37213) (xy 199.175924 -68.325533)
			(xy 199.225177 -68.284788) (xy 199.279148 -68.250537) (xy 199.336987 -68.22332) (xy 199.39778 -68.203567)
			(xy 199.46057 -68.191589) (xy 199.524366 -68.187576) (xy 199.588162 -68.191589) (xy 199.650952 -68.203567)
			(xy 199.711745 -68.22332) (xy 199.760688 -68.246351) (xy 211.080344 -68.246351) (xy 211.080344 -68.191849)
			(xy 211.0881 -68.1379) (xy 211.103454 -68.085605) (xy 211.126093 -68.036027) (xy 211.155557 -67.990175)
			(xy 211.191247 -67.948982) (xy 211.232435 -67.913287) (xy 211.278283 -67.883817) (xy 211.327858 -67.861171)
			(xy 211.380152 -67.84581) (xy 211.434099 -67.838047) (xy 211.46135 -67.837558) (xy 211.48907 -67.838021)
			(xy 211.543927 -67.846045) (xy 211.597043 -67.861932) (xy 211.647296 -67.885346) (xy 211.693628 -67.915793)
			(xy 211.73506 -67.952631) (xy 211.770718 -67.995083) (xy 211.785708 -68.018406) (xy 211.793202 -68.029772)
			(xy 211.813121 -68.04832) (xy 211.837229 -68.060953) (xy 211.863816 -68.066777) (xy 211.890997 -68.065378)
			(xy 211.916846 -68.056856) (xy 211.93953 -68.041815) (xy 211.95744 -68.021321) (xy 211.963762 -68.009262)
			(xy 211.977967 -67.980959) (xy 212.012375 -67.927795) (xy 212.053121 -67.879317) (xy 212.099573 -67.836276)
			(xy 212.151012 -67.799338) (xy 212.206641 -67.769076) (xy 212.265598 -67.745958) (xy 212.32697 -67.730344)
			(xy 212.389806 -67.722474) (xy 212.42147 -67.721988) (xy 212.453433 -67.722475) (xy 212.516856 -67.730484)
			(xy 212.578775 -67.746379) (xy 212.638214 -67.769909) (xy 212.694234 -67.800704) (xy 212.745953 -67.838277)
			(xy 212.792555 -67.882036) (xy 212.833305 -67.931291) (xy 212.86756 -67.985266) (xy 212.868074 -67.986359)
			(xy 219.888048 -67.986359) (xy 219.888048 -67.922437) (xy 219.896059 -67.859019) (xy 219.911956 -67.797105)
			(xy 219.935488 -67.737672) (xy 219.966282 -67.681657) (xy 220.003855 -67.629942) (xy 220.047612 -67.583345)
			(xy 220.096865 -67.5426) (xy 220.150836 -67.508349) (xy 220.208675 -67.481132) (xy 220.269468 -67.461379)
			(xy 220.332258 -67.449401) (xy 220.396054 -67.445388) (xy 220.45985 -67.449401) (xy 220.52264 -67.461379)
			(xy 220.583433 -67.481132) (xy 220.641272 -67.508349) (xy 220.695243 -67.5426) (xy 220.744496 -67.583345)
			(xy 220.788253 -67.629942) (xy 220.825826 -67.681657) (xy 220.85662 -67.737672) (xy 220.880152 -67.797105)
			(xy 220.896049 -67.859019) (xy 220.90406 -67.922437) (xy 220.904545 -67.953339) (xy 223.35591 -67.953339)
			(xy 223.35591 -67.889417) (xy 223.363921 -67.825999) (xy 223.379818 -67.764085) (xy 223.40335 -67.704652)
			(xy 223.434144 -67.648637) (xy 223.471717 -67.596922) (xy 223.515474 -67.550325) (xy 223.564727 -67.50958)
			(xy 223.618698 -67.475329) (xy 223.676537 -67.448112) (xy 223.73733 -67.428359) (xy 223.80012 -67.416381)
			(xy 223.863916 -67.412368) (xy 223.927712 -67.416381) (xy 223.990502 -67.428359) (xy 224.051295 -67.448112)
			(xy 224.109134 -67.475329) (xy 224.163105 -67.50958) (xy 224.212358 -67.550325) (xy 224.256115 -67.596922)
			(xy 224.293688 -67.648637) (xy 224.324482 -67.704652) (xy 224.348014 -67.764085) (xy 224.363911 -67.825999)
			(xy 224.371922 -67.889417) (xy 224.372424 -67.921378) (xy 224.371922 -67.953339) (xy 224.363911 -68.016757)
			(xy 224.348014 -68.078671) (xy 224.324482 -68.138104) (xy 224.293688 -68.194119) (xy 224.256115 -68.245834)
			(xy 224.212358 -68.292431) (xy 224.163105 -68.333176) (xy 224.109134 -68.367427) (xy 224.051295 -68.394644)
			(xy 223.990502 -68.414397) (xy 223.927712 -68.426375) (xy 223.863916 -68.430389) (xy 223.80012 -68.426375)
			(xy 223.73733 -68.414397) (xy 223.676537 -68.394644) (xy 223.618698 -68.367427) (xy 223.564727 -68.333176)
			(xy 223.515474 -68.292431) (xy 223.471717 -68.245834) (xy 223.434144 -68.194119) (xy 223.40335 -68.138104)
			(xy 223.379818 -68.078671) (xy 223.363921 -68.016757) (xy 223.35591 -67.953339) (xy 220.904545 -67.953339)
			(xy 220.904562 -67.954398) (xy 220.90406 -67.986359) (xy 220.896049 -68.049777) (xy 220.880152 -68.111691)
			(xy 220.85662 -68.171124) (xy 220.825826 -68.227139) (xy 220.788253 -68.278854) (xy 220.744496 -68.325451)
			(xy 220.695243 -68.366196) (xy 220.641272 -68.400447) (xy 220.583433 -68.427664) (xy 220.52264 -68.447417)
			(xy 220.45985 -68.459395) (xy 220.396054 -68.463409) (xy 220.332258 -68.459395) (xy 220.269468 -68.447417)
			(xy 220.208675 -68.427664) (xy 220.150836 -68.400447) (xy 220.096865 -68.366196) (xy 220.047612 -68.325451)
			(xy 220.003855 -68.278854) (xy 219.966282 -68.227139) (xy 219.935488 -68.171124) (xy 219.911956 -68.111691)
			(xy 219.896059 -68.049777) (xy 219.888048 -67.986359) (xy 212.868074 -67.986359) (xy 212.894779 -68.043108)
			(xy 212.914534 -68.103905) (xy 212.926513 -68.1667) (xy 212.930528 -68.2305) (xy 212.926513 -68.2943)
			(xy 212.914534 -68.357095) (xy 212.894779 -68.417892) (xy 212.86756 -68.475734) (xy 212.833305 -68.529709)
			(xy 212.792555 -68.578964) (xy 212.745953 -68.622723) (xy 212.694234 -68.660296) (xy 212.638214 -68.691091)
			(xy 212.578775 -68.714621) (xy 212.516856 -68.730516) (xy 212.453433 -68.738525) (xy 212.42147 -68.739004)
			(xy 212.389125 -68.738473) (xy 212.324955 -68.730288) (xy 212.262342 -68.714028) (xy 212.202298 -68.689957)
			(xy 212.145793 -68.658462) (xy 212.093739 -68.620054) (xy 212.046979 -68.575353) (xy 212.006268 -68.52508)
			(xy 211.972263 -68.470049) (xy 211.958428 -68.440808) (xy 211.952477 -68.428582) (xy 211.935082 -68.407691)
			(xy 211.912791 -68.392129) (xy 211.887184 -68.383) (xy 211.860076 -68.380951) (xy 211.833388 -68.386126)
			(xy 211.80901 -68.39816) (xy 211.788672 -68.416199) (xy 211.780882 -68.427346) (xy 211.765698 -68.449764)
			(xy 211.730028 -68.490499) (xy 211.688956 -68.525779) (xy 211.643306 -68.554896) (xy 211.593998 -68.577263)
			(xy 211.542021 -68.592432) (xy 211.488422 -68.600097) (xy 211.46135 -68.600574) (xy 211.434099 -68.600153)
			(xy 211.380152 -68.59239) (xy 211.327858 -68.577029) (xy 211.278283 -68.554383) (xy 211.232435 -68.524913)
			(xy 211.191247 -68.489218) (xy 211.155557 -68.448025) (xy 211.126093 -68.402173) (xy 211.103454 -68.352595)
			(xy 211.0881 -68.3003) (xy 211.080344 -68.246351) (xy 199.760688 -68.246351) (xy 199.769584 -68.250537)
			(xy 199.823555 -68.284788) (xy 199.872808 -68.325533) (xy 199.916565 -68.37213) (xy 199.954138 -68.423845)
			(xy 199.984932 -68.47986) (xy 200.008464 -68.539293) (xy 200.024361 -68.601207) (xy 200.032372 -68.664625)
			(xy 200.032874 -68.696586) (xy 200.032372 -68.728547) (xy 200.024361 -68.791965) (xy 200.008464 -68.853879)
			(xy 199.984932 -68.913312) (xy 199.963044 -68.953126) (xy 202.168758 -68.953126) (xy 202.172829 -68.897504)
			(xy 202.184955 -68.843067) (xy 202.204878 -68.790976) (xy 202.232174 -68.742341) (xy 202.26626 -68.698198)
			(xy 202.306409 -68.659489) (xy 202.351767 -68.627038) (xy 202.401367 -68.601537) (xy 202.454151 -68.58353)
			(xy 202.508994 -68.5734) (xy 202.564728 -68.571363) (xy 202.620165 -68.577463) (xy 202.674122 -68.591569)
			(xy 202.725451 -68.613381) (xy 202.773057 -68.642435) (xy 202.815925 -68.67811) (xy 202.853142 -68.719647)
			(xy 202.883915 -68.76616) (xy 202.907587 -68.816657) (xy 202.923655 -68.870064) (xy 202.931775 -68.92524)
			(xy 202.932284 -68.953126) (xy 202.931775 -68.981012) (xy 202.923655 -69.036188) (xy 202.907587 -69.089595)
			(xy 202.883915 -69.140092) (xy 202.853142 -69.186605) (xy 202.815925 -69.228142) (xy 202.773057 -69.263817)
			(xy 202.725451 -69.292871) (xy 202.674122 -69.314683) (xy 202.620165 -69.328789) (xy 202.564728 -69.334889)
			(xy 202.508994 -69.332852) (xy 202.454151 -69.322722) (xy 202.401367 -69.304715) (xy 202.351767 -69.279214)
			(xy 202.306409 -69.246763) (xy 202.26626 -69.208054) (xy 202.232174 -69.163911) (xy 202.204878 -69.115276)
			(xy 202.184955 -69.063185) (xy 202.172829 -69.008748) (xy 202.168758 -68.953126) (xy 199.963044 -68.953126)
			(xy 199.954138 -68.969327) (xy 199.916565 -69.021042) (xy 199.872808 -69.067639) (xy 199.823555 -69.108384)
			(xy 199.769584 -69.142635) (xy 199.711745 -69.169852) (xy 199.650952 -69.189605) (xy 199.588162 -69.201583)
			(xy 199.524366 -69.205597) (xy 199.46057 -69.201583) (xy 199.39778 -69.189605) (xy 199.336987 -69.169852)
			(xy 199.279148 -69.142635) (xy 199.225177 -69.108384) (xy 199.175924 -69.067639) (xy 199.132167 -69.021042)
			(xy 199.094594 -68.969327) (xy 199.0638 -68.913312) (xy 199.040268 -68.853879) (xy 199.024371 -68.791965)
			(xy 199.01636 -68.728547) (xy 191.795563 -68.728547) (xy 191.772985 -68.743057) (xy 191.723408 -68.765699)
			(xy 191.671113 -68.781054) (xy 191.617165 -68.78881) (xy 191.562663 -68.78881) (xy 191.508715 -68.781054)
			(xy 191.45642 -68.765699) (xy 191.406843 -68.743057) (xy 191.360993 -68.713591) (xy 191.319802 -68.6779)
			(xy 191.284111 -68.636709) (xy 191.254645 -68.590859) (xy 191.232003 -68.541282) (xy 191.216648 -68.488987)
			(xy 191.208892 -68.435039) (xy 191.208406 -68.407788) (xy 191.208922 -68.378903) (xy 191.217647 -68.321795)
			(xy 191.234879 -68.266655) (xy 191.260226 -68.214742) (xy 191.293108 -68.167243) (xy 191.332773 -68.125242)
			(xy 191.355218 -68.107052) (xy 191.364616 -68.099686) (xy 191.374776 -68.078858) (xy 191.374522 -67.974718)
			(xy 191.364362 -67.95389) (xy 191.354964 -67.946524) (xy 191.332369 -67.928353) (xy 191.292439 -67.886313)
			(xy 191.259331 -67.838714) (xy 191.233807 -67.786653) (xy 191.216457 -67.731329) (xy 191.207678 -67.674016)
			(xy 191.207136 -67.645026) (xy 184.371488 -67.645026) (xy 184.371488 -69.652853) (xy 205.2673 -69.652853)
			(xy 205.2673 -69.588931) (xy 205.275311 -69.525513) (xy 205.291208 -69.463599) (xy 205.31474 -69.404166)
			(xy 205.345534 -69.348151) (xy 205.383107 -69.296436) (xy 205.426864 -69.249839) (xy 205.476117 -69.209094)
			(xy 205.530088 -69.174843) (xy 205.587927 -69.147626) (xy 205.64872 -69.127873) (xy 205.71151 -69.115895)
			(xy 205.775306 -69.111882) (xy 205.839102 -69.115895) (xy 205.901892 -69.127873) (xy 205.962685 -69.147626)
			(xy 206.020524 -69.174843) (xy 206.074495 -69.209094) (xy 206.123748 -69.249839) (xy 206.167505 -69.296436)
			(xy 206.205078 -69.348151) (xy 206.235872 -69.404166) (xy 206.259404 -69.463599) (xy 206.275301 -69.525513)
			(xy 206.283312 -69.588931) (xy 206.283814 -69.620892) (xy 206.283312 -69.652853) (xy 206.275301 -69.716271)
			(xy 206.259404 -69.778185) (xy 206.235872 -69.837618) (xy 206.205078 -69.893633) (xy 206.167505 -69.945348)
			(xy 206.123748 -69.991945) (xy 206.074495 -70.03269) (xy 206.020524 -70.066941) (xy 205.962685 -70.094158)
			(xy 205.901892 -70.113911) (xy 205.839102 -70.125889) (xy 205.775306 -70.129903) (xy 205.71151 -70.125889)
			(xy 205.64872 -70.113911) (xy 205.587927 -70.094158) (xy 205.530088 -70.066941) (xy 205.476117 -70.03269)
			(xy 205.426864 -69.991945) (xy 205.383107 -69.945348) (xy 205.345534 -69.893633) (xy 205.31474 -69.837618)
			(xy 205.291208 -69.778185) (xy 205.275311 -69.716271) (xy 205.2673 -69.652853) (xy 184.371488 -69.652853)
			(xy 184.371488 -70.198996) (xy 194.000372 -70.198996) (xy 194.004443 -70.143374) (xy 194.016569 -70.088937)
			(xy 194.036492 -70.036846) (xy 194.063788 -69.988211) (xy 194.097874 -69.944068) (xy 194.138023 -69.905359)
			(xy 194.183381 -69.872908) (xy 194.232981 -69.847407) (xy 194.285765 -69.8294) (xy 194.340608 -69.81927)
			(xy 194.396342 -69.817233) (xy 194.451779 -69.823333) (xy 194.505736 -69.837439) (xy 194.557065 -69.859251)
			(xy 194.604671 -69.888305) (xy 194.647539 -69.92398) (xy 194.684756 -69.965517) (xy 194.715529 -70.01203)
			(xy 194.739201 -70.062527) (xy 194.755269 -70.115934) (xy 194.763389 -70.17111) (xy 194.763898 -70.198996)
			(xy 194.763389 -70.226882) (xy 194.755269 -70.282058) (xy 194.739201 -70.335465) (xy 194.715529 -70.385962)
			(xy 194.684756 -70.432475) (xy 194.647539 -70.474012) (xy 194.604671 -70.509687) (xy 194.557065 -70.538741)
			(xy 194.505736 -70.560553) (xy 194.451779 -70.574659) (xy 194.396342 -70.580759) (xy 194.340608 -70.578722)
			(xy 194.285765 -70.568592) (xy 194.232981 -70.550585) (xy 194.183381 -70.525084) (xy 194.138023 -70.492633)
			(xy 194.097874 -70.453924) (xy 194.063788 -70.409781) (xy 194.036492 -70.361146) (xy 194.016569 -70.309055)
			(xy 194.004443 -70.254618) (xy 194.000372 -70.198996) (xy 184.371488 -70.198996) (xy 184.371488 -71.376032)
			(xy 191.200278 -71.376032) (xy 191.200278 -71.375778) (xy 191.200735 -71.345057) (xy 191.208141 -71.284062)
			(xy 191.222842 -71.224405) (xy 191.244625 -71.166953) (xy 191.273171 -71.112545) (xy 191.308066 -71.061973)
			(xy 191.348799 -71.015974) (xy 191.394779 -70.975218) (xy 191.445334 -70.940299) (xy 191.499729 -70.911726)
			(xy 191.55717 -70.889916) (xy 191.61682 -70.875185) (xy 191.677811 -70.86775) (xy 191.708532 -70.86727)
			(xy 191.70904 -70.86727) (xy 191.72174 -70.867524) (xy 191.730884 -70.867778) (xy 191.747902 -70.861936)
			(xy 191.813688 -70.808342) (xy 191.822832 -70.792848) (xy 191.824356 -70.783958) (xy 191.829475 -70.757864)
			(xy 191.846029 -70.707331) (xy 191.869442 -70.659588) (xy 191.899259 -70.615559) (xy 191.934902 -70.576098)
			(xy 191.975681 -70.541971) (xy 192.020805 -70.513839) (xy 192.069399 -70.492247) (xy 192.120521 -70.477614)
			(xy 192.17318 -70.470223) (xy 192.199768 -70.46976) (xy 192.227017 -70.470308) (xy 192.280961 -70.478059)
			(xy 192.333252 -70.493409) (xy 192.382827 -70.516044) (xy 192.428676 -70.545504) (xy 192.469866 -70.581189)
			(xy 192.505558 -70.622372) (xy 192.513231 -70.634309) (xy 196.956928 -70.634309) (xy 196.956928 -70.570387)
			(xy 196.964939 -70.506969) (xy 196.980836 -70.445055) (xy 197.004368 -70.385622) (xy 197.035162 -70.329607)
			(xy 197.072735 -70.277892) (xy 197.116492 -70.231295) (xy 197.165745 -70.19055) (xy 197.219716 -70.156299)
			(xy 197.277555 -70.129082) (xy 197.338348 -70.109329) (xy 197.401138 -70.097351) (xy 197.464934 -70.093338)
			(xy 197.52873 -70.097351) (xy 197.59152 -70.109329) (xy 197.652313 -70.129082) (xy 197.710152 -70.156299)
			(xy 197.748214 -70.180454) (xy 208.543144 -70.180454) (xy 208.543656 -70.148873) (xy 208.551483 -70.086199)
			(xy 208.567021 -70.024979) (xy 208.590032 -69.966158) (xy 208.620159 -69.910645) (xy 208.656939 -69.859297)
			(xy 208.678018 -69.835776) (xy 208.684036 -69.828563) (xy 208.690949 -69.811117) (xy 208.69148 -69.80174)
			(xy 208.69148 -69.771006) (xy 208.691121 -69.761691) (xy 208.684615 -69.744239) (xy 208.67878 -69.73697)
			(xy 208.658652 -69.713659) (xy 208.623636 -69.662991) (xy 208.594989 -69.608467) (xy 208.573131 -69.550886)
			(xy 208.558381 -69.491087) (xy 208.550955 -69.429945) (xy 208.55051 -69.39915) (xy 208.551012 -69.367189)
			(xy 208.559023 -69.303771) (xy 208.57492 -69.241857) (xy 208.598452 -69.182424) (xy 208.629246 -69.126409)
			(xy 208.666819 -69.074694) (xy 208.710576 -69.028097) (xy 208.759829 -68.987352) (xy 208.8138 -68.953101)
			(xy 208.871639 -68.925884) (xy 208.932432 -68.906131) (xy 208.995222 -68.894153) (xy 209.059018 -68.89014)
			(xy 209.122814 -68.894153) (xy 209.185604 -68.906131) (xy 209.246397 -68.925884) (xy 209.304236 -68.953101)
			(xy 209.358207 -68.987352) (xy 209.40746 -69.028097) (xy 209.451217 -69.074694) (xy 209.48879 -69.126409)
			(xy 209.519584 -69.182424) (xy 209.543116 -69.241857) (xy 209.559013 -69.303771) (xy 209.567024 -69.367189)
			(xy 209.567526 -69.39915) (xy 209.567024 -69.430731) (xy 209.559197 -69.493406) (xy 209.543657 -69.554627)
			(xy 209.520644 -69.613448) (xy 209.490514 -69.66896) (xy 209.453733 -69.720308) (xy 209.432652 -69.743828)
			(xy 209.426629 -69.751036) (xy 209.41972 -69.768486) (xy 209.41919 -69.777864) (xy 209.41919 -69.808598)
			(xy 209.419531 -69.817915) (xy 209.426048 -69.835367) (xy 209.43189 -69.842634) (xy 209.452015 -69.865948)
			(xy 209.487033 -69.916615) (xy 209.51568 -69.971138) (xy 209.53584 -70.024244) (xy 211.881466 -70.024244)
			(xy 211.881968 -69.992283) (xy 211.889979 -69.928865) (xy 211.905876 -69.866951) (xy 211.929408 -69.807518)
			(xy 211.960202 -69.751503) (xy 211.997775 -69.699788) (xy 212.041532 -69.653191) (xy 212.090785 -69.612446)
			(xy 212.144756 -69.578195) (xy 212.202595 -69.550978) (xy 212.263388 -69.531225) (xy 212.326178 -69.519247)
			(xy 212.389974 -69.515234) (xy 212.45377 -69.519247) (xy 212.51656 -69.531225) (xy 212.577353 -69.550978)
			(xy 212.635192 -69.578195) (xy 212.689163 -69.612446) (xy 212.738416 -69.653191) (xy 212.782173 -69.699788)
			(xy 212.819746 -69.751503) (xy 212.85054 -69.807518) (xy 212.874072 -69.866951) (xy 212.889969 -69.928865)
			(xy 212.89798 -69.992283) (xy 212.898482 -70.024244) (xy 212.898003 -70.055139) (xy 212.890511 -70.116472)
			(xy 212.879484 -70.160953) (xy 216.619773 -70.160953) (xy 216.619773 -70.106447) (xy 216.627531 -70.052495)
			(xy 216.642888 -70.000197) (xy 216.665532 -69.950617) (xy 216.695002 -69.904764) (xy 216.730698 -69.863572)
			(xy 216.771893 -69.82788) (xy 216.817748 -69.798415) (xy 216.867331 -69.775775) (xy 216.91963 -69.760423)
			(xy 216.973583 -69.752671) (xy 217.000836 -69.75221) (xy 217.029751 -69.75277) (xy 217.086921 -69.76149)
			(xy 217.142119 -69.778739) (xy 217.194081 -69.804123) (xy 217.241616 -69.837059) (xy 217.283635 -69.876794)
			(xy 217.301826 -69.899276) (xy 217.309419 -69.908098) (xy 217.330331 -69.91827) (xy 217.341958 -69.918834)
			(xy 217.421714 -69.918834) (xy 217.433349 -69.918312) (xy 217.45426 -69.908113) (xy 217.461846 -69.899276)
			(xy 217.480061 -69.876813) (xy 217.522077 -69.837078) (xy 217.569607 -69.804137) (xy 217.621563 -69.778746)
			(xy 217.676756 -69.761484) (xy 217.733922 -69.752749) (xy 217.762836 -69.75221) (xy 217.790087 -69.752662)
			(xy 217.844033 -69.760423) (xy 217.896326 -69.775782) (xy 217.945901 -69.798427) (xy 217.991749 -69.827895)
			(xy 218.032937 -69.863588) (xy 218.068626 -69.90478) (xy 218.098091 -69.95063) (xy 218.12073 -70.000208)
			(xy 218.136084 -70.052502) (xy 218.14384 -70.106449) (xy 218.14384 -70.160951) (xy 218.136084 -70.214898)
			(xy 218.12073 -70.267192) (xy 218.098091 -70.31677) (xy 218.083964 -70.338753) (xy 218.270773 -70.338753)
			(xy 218.270773 -70.284247) (xy 218.278531 -70.230295) (xy 218.293888 -70.177997) (xy 218.316532 -70.128417)
			(xy 218.346002 -70.082564) (xy 218.381698 -70.041372) (xy 218.422893 -70.00568) (xy 218.468748 -69.976215)
			(xy 218.518331 -69.953575) (xy 218.57063 -69.938223) (xy 218.624583 -69.930471) (xy 218.651836 -69.93001)
			(xy 218.678703 -69.930431) (xy 218.731907 -69.937964) (xy 218.783528 -69.95289) (xy 218.832542 -69.974912)
			(xy 218.87798 -70.003596) (xy 218.918943 -70.038374) (xy 218.954619 -70.078556) (xy 218.969844 -70.100698)
			(xy 218.977146 -70.11043) (xy 218.998365 -70.122251) (xy 219.010484 -70.123304) (xy 219.105734 -70.126606)
			(xy 219.128086 -70.115938) (xy 219.135452 -70.106032) (xy 219.148067 -70.089951) (xy 219.176193 -70.060295)
			(xy 219.191586 -70.04685) (xy 219.19184 -70.04685) (xy 219.198787 -70.040223) (xy 219.207654 -70.023212)
			(xy 219.209718 -70.00414) (xy 219.207588 -69.99478) (xy 219.183204 -69.90588) (xy 219.18023 -69.896724)
			(xy 219.168641 -69.881373) (xy 219.152224 -69.871352) (xy 219.142818 -69.869304) (xy 219.142564 -69.869304)
			(xy 219.110716 -69.863345) (xy 219.048757 -69.844393) (xy 218.989709 -69.817721) (xy 218.934528 -69.783763)
			(xy 218.884108 -69.743069) (xy 218.839268 -69.696299) (xy 218.800734 -69.644211) (xy 218.76913 -69.587648)
			(xy 218.744969 -69.527529) (xy 218.728642 -69.464827) (xy 218.720414 -69.400558) (xy 218.719908 -69.368162)
			(xy 218.72041 -69.336201) (xy 218.728421 -69.272783) (xy 218.744318 -69.210869) (xy 218.76785 -69.151436)
			(xy 218.798644 -69.095421) (xy 218.836217 -69.043706) (xy 218.879974 -68.997109) (xy 218.929227 -68.956364)
			(xy 218.983198 -68.922113) (xy 219.041037 -68.894896) (xy 219.10183 -68.875143) (xy 219.16462 -68.863165)
			(xy 219.228416 -68.859152) (xy 219.292212 -68.863165) (xy 219.355002 -68.875143) (xy 219.415795 -68.894896)
			(xy 219.473634 -68.922113) (xy 219.527605 -68.956364) (xy 219.576858 -68.997109) (xy 219.620615 -69.043706)
			(xy 219.658188 -69.095421) (xy 219.688982 -69.151436) (xy 219.712514 -69.210869) (xy 219.728411 -69.272783)
			(xy 219.736422 -69.336201) (xy 219.736924 -69.368162) (xy 219.736483 -69.399095) (xy 219.736357 -69.400123)
			(xy 219.99041 -69.400123) (xy 219.99041 -69.336201) (xy 219.998421 -69.272783) (xy 220.014318 -69.210869)
			(xy 220.03785 -69.151436) (xy 220.068644 -69.095421) (xy 220.106217 -69.043706) (xy 220.149974 -68.997109)
			(xy 220.199227 -68.956364) (xy 220.253198 -68.922113) (xy 220.311037 -68.894896) (xy 220.37183 -68.875143)
			(xy 220.43462 -68.863165) (xy 220.498416 -68.859152) (xy 220.562212 -68.863165) (xy 220.625002 -68.875143)
			(xy 220.685795 -68.894896) (xy 220.743634 -68.922113) (xy 220.788032 -68.950289) (xy 224.02901 -68.950289)
			(xy 224.02901 -68.886367) (xy 224.037021 -68.822949) (xy 224.052918 -68.761035) (xy 224.07645 -68.701602)
			(xy 224.107244 -68.645587) (xy 224.144817 -68.593872) (xy 224.188574 -68.547275) (xy 224.237827 -68.50653)
			(xy 224.291798 -68.472279) (xy 224.349637 -68.445062) (xy 224.41043 -68.425309) (xy 224.47322 -68.413331)
			(xy 224.537016 -68.409318) (xy 224.600812 -68.413331) (xy 224.663602 -68.425309) (xy 224.724395 -68.445062)
			(xy 224.782234 -68.472279) (xy 224.836205 -68.50653) (xy 224.885458 -68.547275) (xy 224.91257 -68.576147)
			(xy 232.224066 -68.576147) (xy 232.224066 -68.512225) (xy 232.232077 -68.448807) (xy 232.247974 -68.386893)
			(xy 232.271506 -68.32746) (xy 232.3023 -68.271445) (xy 232.339873 -68.21973) (xy 232.38363 -68.173133)
			(xy 232.432883 -68.132388) (xy 232.486854 -68.098137) (xy 232.544693 -68.07092) (xy 232.605486 -68.051167)
			(xy 232.668276 -68.039189) (xy 232.732072 -68.035176) (xy 232.795868 -68.039189) (xy 232.858658 -68.051167)
			(xy 232.919451 -68.07092) (xy 232.97729 -68.098137) (xy 233.031261 -68.132388) (xy 233.080514 -68.173133)
			(xy 233.124271 -68.21973) (xy 233.161844 -68.271445) (xy 233.175638 -68.296536) (xy 255.565908 -68.296536)
			(xy 255.569979 -68.240914) (xy 255.582105 -68.186477) (xy 255.602028 -68.134386) (xy 255.629324 -68.085751)
			(xy 255.66341 -68.041608) (xy 255.703559 -68.002899) (xy 255.748917 -67.970448) (xy 255.798517 -67.944947)
			(xy 255.851301 -67.92694) (xy 255.906144 -67.91681) (xy 255.961878 -67.914773) (xy 256.017315 -67.920873)
			(xy 256.071272 -67.934979) (xy 256.122601 -67.956791) (xy 256.170207 -67.985845) (xy 256.213075 -68.02152)
			(xy 256.250292 -68.063057) (xy 256.281065 -68.10957) (xy 256.304737 -68.160067) (xy 256.320805 -68.213474)
			(xy 256.322178 -68.222806) (xy 256.877308 -68.222806) (xy 256.877308 -68.13811) (xy 256.885359 -68.053796)
			(xy 256.901388 -67.97063) (xy 256.925249 -67.889363) (xy 256.956728 -67.810733) (xy 256.995539 -67.735452)
			(xy 257.041329 -67.6642) (xy 257.093685 -67.597624) (xy 257.152133 -67.536326) (xy 257.216143 -67.480861)
			(xy 257.285135 -67.431732) (xy 257.358485 -67.389383) (xy 257.435528 -67.354199) (xy 257.515567 -67.326497)
			(xy 257.597876 -67.306529) (xy 257.681711 -67.294476) (xy 257.766312 -67.290446) (xy 257.850913 -67.294476)
			(xy 257.934748 -67.306529) (xy 258.017057 -67.326497) (xy 258.097096 -67.354199) (xy 258.174139 -67.389383)
			(xy 258.247489 -67.431732) (xy 258.316481 -67.480861) (xy 258.380491 -67.536326) (xy 258.438939 -67.597624)
			(xy 258.491295 -67.6642) (xy 258.537085 -67.735452) (xy 258.575896 -67.810733) (xy 258.607375 -67.889363)
			(xy 258.631236 -67.97063) (xy 258.647265 -68.053796) (xy 258.655316 -68.13811) (xy 258.65582 -68.180458)
			(xy 258.655316 -68.222806) (xy 258.651129 -68.266656) (xy 264.797941 -68.266656) (xy 264.797941 -68.212144)
			(xy 264.8057 -68.158187) (xy 264.821059 -68.105883) (xy 264.843705 -68.056298) (xy 264.873179 -68.010441)
			(xy 264.908879 -67.969245) (xy 264.950079 -67.93355) (xy 264.99594 -67.904082) (xy 265.045528 -67.881442)
			(xy 265.097834 -67.866089) (xy 265.151792 -67.858338) (xy 265.179048 -67.857878) (xy 265.206278 -67.858398)
			(xy 265.260186 -67.866136) (xy 265.312446 -67.881461) (xy 265.361995 -67.904063) (xy 265.407825 -67.933482)
			(xy 265.449007 -67.969119) (xy 265.484701 -68.010251) (xy 265.49985 -68.032884) (xy 265.504906 -68.040039)
			(xy 265.518805 -68.050687) (xy 265.527028 -68.053712) (xy 265.55573 -68.062856) (xy 265.564268 -68.065182)
			(xy 265.581936 -68.064548) (xy 265.590274 -68.061586) (xy 265.620753 -68.049747) (xy 265.683993 -68.033127)
			(xy 265.748842 -68.024751) (xy 265.781536 -68.024248) (xy 265.782044 -68.024248) (xy 265.810886 -68.024666)
			(xy 265.868197 -68.031207) (xy 265.924398 -68.0442) (xy 265.951716 -68.053458) (xy 265.965686 -68.058538)
			(xy 265.994134 -68.052188) (xy 266.079986 -67.966336) (xy 266.086336 -67.937888) (xy 266.081256 -67.923918)
			(xy 266.072013 -67.896595) (xy 266.059023 -67.840395) (xy 266.052466 -67.783087) (xy 266.052046 -67.754246)
			(xy 266.052046 -67.753738) (xy 266.052592 -67.72301) (xy 266.059995 -67.662) (xy 266.074698 -67.602328)
			(xy 266.096486 -67.544863) (xy 266.125042 -67.490444) (xy 266.15995 -67.439863) (xy 266.200699 -67.393859)
			(xy 266.246697 -67.353101) (xy 266.297272 -67.318186) (xy 266.351687 -67.289621) (xy 266.409148 -67.267823)
			(xy 266.468818 -67.25311) (xy 266.529826 -67.245697) (xy 266.560554 -67.24523) (xy 266.58122 -67.245408)
			(xy 266.62242 -67.248711) (xy 266.64285 -67.251834) (xy 266.651569 -67.252921) (xy 266.668847 -67.249809)
			(xy 266.676632 -67.245738) (xy 266.702286 -67.230752) (xy 266.709526 -67.226173) (xy 266.720693 -67.213198)
			(xy 266.72413 -67.205352) (xy 266.735035 -67.178886) (xy 266.763538 -67.129248) (xy 266.799136 -67.084426)
			(xy 266.841031 -67.045425) (xy 266.888281 -67.013119) (xy 266.939828 -66.988235) (xy 266.994513 -66.97133)
			(xy 267.051111 -66.962784) (xy 267.07973 -66.962274) (xy 267.106981 -66.96275) (xy 267.160928 -66.97051)
			(xy 267.213222 -66.985868) (xy 267.262798 -67.008511) (xy 267.308648 -67.037979) (xy 267.349837 -67.073671)
			(xy 267.385528 -67.114862) (xy 267.414994 -67.160712) (xy 267.437636 -67.210289) (xy 267.452993 -67.262583)
			(xy 267.460751 -67.316531) (xy 267.461238 -67.343782) (xy 267.460768 -67.371138) (xy 267.452968 -67.42529)
			(xy 267.43751 -67.477772) (xy 267.414713 -67.527507) (xy 267.385044 -67.573475) (xy 267.349111 -67.614732)
			(xy 267.307652 -67.650432) (xy 267.261518 -67.679842) (xy 267.211655 -67.702358) (xy 267.159087 -67.71752)
			(xy 267.132054 -67.721734) (xy 267.123558 -67.723262) (xy 267.108232 -67.731172) (xy 267.102082 -67.737228)
			(xy 267.081762 -67.758818) (xy 267.075953 -67.765376) (xy 267.06881 -67.781358) (xy 267.067792 -67.79006)
			(xy 267.064984 -67.821717) (xy 267.052577 -67.884047) (xy 267.032501 -67.944346) (xy 267.005067 -68.001673)
			(xy 266.970704 -68.055135) (xy 266.929947 -68.103899) (xy 266.883432 -68.147204) (xy 266.831883 -68.184376)
			(xy 266.776105 -68.214834) (xy 266.716966 -68.238106) (xy 266.655388 -68.253827) (xy 266.592331 -68.261752)
			(xy 266.560554 -68.262246) (xy 266.560046 -68.262246) (xy 266.531204 -68.261831) (xy 266.473893 -68.255289)
			(xy 266.417692 -68.242295) (xy 266.390374 -68.233036) (xy 266.376404 -68.227956) (xy 266.347956 -68.234306)
			(xy 266.262104 -68.320158) (xy 266.255754 -68.348606) (xy 266.260834 -68.362576) (xy 266.270075 -68.389899)
			(xy 266.283066 -68.446099) (xy 266.289623 -68.503407) (xy 266.290044 -68.532248) (xy 266.290044 -68.532756)
			(xy 266.289521 -68.563486) (xy 266.282118 -68.624498) (xy 266.267415 -68.684173) (xy 266.245626 -68.74164)
			(xy 266.217069 -68.796062) (xy 266.212833 -68.8022) (xy 269.417818 -68.8022) (xy 269.421832 -68.738406)
			(xy 269.43381 -68.675619) (xy 269.453562 -68.614828) (xy 269.480779 -68.556992) (xy 269.515029 -68.503023)
			(xy 269.555774 -68.453773) (xy 269.60237 -68.410017) (xy 269.654083 -68.372447) (xy 269.710097 -68.341655)
			(xy 269.769528 -68.318126) (xy 269.83144 -68.302231) (xy 269.894856 -68.294222) (xy 269.926816 -68.293742)
			(xy 269.960438 -68.294308) (xy 270.027095 -68.303173) (xy 270.092003 -68.320745) (xy 270.154028 -68.346719)
			(xy 270.212089 -68.38064) (xy 270.265173 -68.421918) (xy 270.312354 -68.469832) (xy 270.352808 -68.523546)
			(xy 270.369792 -68.552568) (xy 270.374783 -68.560485) (xy 270.389243 -68.572341) (xy 270.397986 -68.575682)
			(xy 270.471392 -68.600574) (xy 270.489934 -68.599812) (xy 270.49857 -68.596002) (xy 270.522609 -68.586081)
			(xy 270.572689 -68.572068) (xy 270.624207 -68.564969) (xy 270.650208 -68.564506) (xy 270.67746 -68.564964)
			(xy 270.731409 -68.572722) (xy 270.783704 -68.588078) (xy 270.833282 -68.610721) (xy 270.879134 -68.640188)
			(xy 270.920324 -68.675881) (xy 270.956016 -68.717073) (xy 270.985483 -68.762925) (xy 270.99797 -68.790269)
			(xy 271.703286 -68.790269) (xy 271.703286 -68.726347) (xy 271.711297 -68.662929) (xy 271.727194 -68.601015)
			(xy 271.750726 -68.541582) (xy 271.78152 -68.485567) (xy 271.819093 -68.433852) (xy 271.86285 -68.387255)
			(xy 271.912103 -68.34651) (xy 271.966074 -68.312259) (xy 272.023913 -68.285042) (xy 272.084706 -68.265289)
			(xy 272.147496 -68.253311) (xy 272.211292 -68.249298) (xy 272.275088 -68.253311) (xy 272.337878 -68.265289)
			(xy 272.398671 -68.285042) (xy 272.45651 -68.312259) (xy 272.510481 -68.34651) (xy 272.559734 -68.387255)
			(xy 272.59762 -68.4276) (xy 273.511968 -68.4276) (xy 273.515983 -68.363798) (xy 273.527962 -68.301002)
			(xy 273.547718 -68.240204) (xy 273.574939 -68.18236) (xy 273.609195 -68.128385) (xy 273.649946 -68.079129)
			(xy 273.696549 -68.035369) (xy 273.74827 -67.997796) (xy 273.804292 -67.967002) (xy 273.863733 -67.943472)
			(xy 273.925653 -67.927578) (xy 273.989078 -67.91957) (xy 274.021042 -67.919092) (xy 274.054468 -67.919655)
			(xy 274.120745 -67.928397) (xy 274.185305 -67.945751) (xy 274.247033 -67.971417) (xy 274.304865 -68.004952)
			(xy 274.357802 -68.045778) (xy 274.404932 -68.09319) (xy 274.44544 -68.146371) (xy 274.462494 -68.175124)
			(xy 274.467574 -68.184014) (xy 274.483322 -68.196206) (xy 274.57273 -68.22059) (xy 274.592542 -68.217796)
			(xy 274.601432 -68.212716) (xy 274.623214 -68.200634) (xy 274.669258 -68.181633) (xy 274.717384 -68.168787)
			(xy 274.766773 -68.162314) (xy 274.791678 -68.161916) (xy 274.818934 -68.162329) (xy 274.87289 -68.170084)
			(xy 274.925194 -68.185439) (xy 274.97478 -68.208082) (xy 275.020639 -68.237551) (xy 275.061837 -68.273247)
			(xy 275.097535 -68.314443) (xy 275.127007 -68.3603) (xy 275.149653 -68.409885) (xy 275.165011 -68.462188)
			(xy 275.172769 -68.516144) (xy 275.172769 -68.570656) (xy 275.165011 -68.624612) (xy 275.149653 -68.676915)
			(xy 275.127007 -68.7265) (xy 275.097535 -68.772357) (xy 275.061837 -68.813553) (xy 275.020639 -68.849249)
			(xy 274.97478 -68.878718) (xy 274.925194 -68.901361) (xy 274.87289 -68.916716) (xy 274.818934 -68.924471)
			(xy 274.791678 -68.924932) (xy 274.765571 -68.92454) (xy 274.713845 -68.917427) (xy 274.663572 -68.903324)
			(xy 274.615694 -68.882495) (xy 274.571104 -68.855328) (xy 274.530638 -68.822332) (xy 274.512532 -68.80352)
			(xy 274.505674 -68.796154) (xy 274.487386 -68.787772) (xy 274.405344 -68.784978) (xy 274.395328 -68.785081)
			(xy 274.376604 -68.792149) (xy 274.369022 -68.798694) (xy 274.368768 -68.798694) (xy 274.345148 -68.820166)
			(xy 274.293464 -68.85763) (xy 274.237498 -68.888332) (xy 274.17813 -68.911789) (xy 274.116293 -68.927632)
			(xy 274.052959 -68.935613) (xy 274.021042 -68.936108) (xy 273.989078 -68.93563) (xy 273.925653 -68.927622)
			(xy 273.863733 -68.911728) (xy 273.804292 -68.888198) (xy 273.74827 -68.857404) (xy 273.696549 -68.819831)
			(xy 273.649946 -68.776071) (xy 273.609195 -68.726815) (xy 273.574939 -68.67284) (xy 273.547718 -68.614996)
			(xy 273.527962 -68.554198) (xy 273.515983 -68.491402) (xy 273.511968 -68.4276) (xy 272.59762 -68.4276)
			(xy 272.603491 -68.433852) (xy 272.641064 -68.485567) (xy 272.671858 -68.541582) (xy 272.69539 -68.601015)
			(xy 272.711287 -68.662929) (xy 272.719298 -68.726347) (xy 272.7198 -68.758308) (xy 272.719298 -68.790269)
			(xy 272.711287 -68.853687) (xy 272.69539 -68.915601) (xy 272.671858 -68.975034) (xy 272.641064 -69.031049)
			(xy 272.603491 -69.082764) (xy 272.559734 -69.129361) (xy 272.510481 -69.170106) (xy 272.45651 -69.204357)
			(xy 272.398671 -69.231574) (xy 272.337878 -69.251327) (xy 272.275088 -69.263305) (xy 272.211292 -69.267319)
			(xy 272.147496 -69.263305) (xy 272.084706 -69.251327) (xy 272.023913 -69.231574) (xy 271.966074 -69.204357)
			(xy 271.912103 -69.170106) (xy 271.86285 -69.129361) (xy 271.819093 -69.082764) (xy 271.78152 -69.031049)
			(xy 271.750726 -68.975034) (xy 271.727194 -68.915601) (xy 271.711297 -68.853687) (xy 271.703286 -68.790269)
			(xy 270.99797 -68.790269) (xy 271.008124 -68.812503) (xy 271.02348 -68.864799) (xy 271.031236 -68.918748)
			(xy 271.031236 -68.973252) (xy 271.02348 -69.027201) (xy 271.008124 -69.079497) (xy 270.985483 -69.129075)
			(xy 270.956016 -69.174927) (xy 270.920324 -69.216119) (xy 270.879134 -69.251812) (xy 270.833282 -69.281279)
			(xy 270.783704 -69.303922) (xy 270.731409 -69.319278) (xy 270.67746 -69.327036) (xy 270.650208 -69.327522)
			(xy 270.62475 -69.327072) (xy 270.574285 -69.320311) (xy 270.525168 -69.306896) (xy 270.478272 -69.287065)
			(xy 270.434433 -69.261171) (xy 270.394428 -69.229674) (xy 270.376396 -69.211698) (xy 270.369622 -69.205124)
			(xy 270.352513 -69.197176) (xy 270.343122 -69.196204) (xy 270.265906 -69.191124) (xy 270.248126 -69.196458)
			(xy 270.24076 -69.2023) (xy 270.213786 -69.222756) (xy 270.155452 -69.257106) (xy 270.093077 -69.283415)
			(xy 270.027763 -69.301218) (xy 269.960664 -69.3102) (xy 269.926816 -69.310758) (xy 269.894856 -69.310178)
			(xy 269.83144 -69.302169) (xy 269.769528 -69.286274) (xy 269.710097 -69.262745) (xy 269.654083 -69.231953)
			(xy 269.60237 -69.194383) (xy 269.555774 -69.150627) (xy 269.515029 -69.101377) (xy 269.480779 -69.047408)
			(xy 269.453562 -68.989572) (xy 269.43381 -68.928781) (xy 269.421832 -68.865994) (xy 269.417818 -68.8022)
			(xy 266.212833 -68.8022) (xy 266.18216 -68.846645) (xy 266.141408 -68.892652) (xy 266.095408 -68.93341)
			(xy 266.044831 -68.968327) (xy 265.990413 -68.996893) (xy 265.932949 -69.018691) (xy 265.873277 -69.033404)
			(xy 265.812266 -69.040816) (xy 265.781536 -69.041264) (xy 265.748668 -69.040807) (xy 265.683477 -69.032352)
			(xy 265.61992 -69.015565) (xy 265.559057 -68.990726) (xy 265.501903 -68.95825) (xy 265.449412 -68.918678)
			(xy 265.402458 -68.872671) (xy 265.361826 -68.820995) (xy 265.328194 -68.764514) (xy 265.302121 -68.704169)
			(xy 265.292586 -68.67271) (xy 265.289863 -68.664229) (xy 265.279443 -68.649794) (xy 265.272266 -68.644516)
			(xy 265.24712 -68.627752) (xy 265.239702 -68.623166) (xy 265.222808 -68.618886) (xy 265.2141 -68.61937)
			(xy 265.179048 -68.620894) (xy 265.151792 -68.620462) (xy 265.097834 -68.612711) (xy 265.045528 -68.597358)
			(xy 264.99594 -68.574718) (xy 264.950079 -68.54525) (xy 264.908879 -68.509555) (xy 264.873179 -68.468359)
			(xy 264.843705 -68.422502) (xy 264.821059 -68.372917) (xy 264.8057 -68.320613) (xy 264.797941 -68.266656)
			(xy 258.651129 -68.266656) (xy 258.647265 -68.30712) (xy 258.631236 -68.390286) (xy 258.607375 -68.471553)
			(xy 258.575896 -68.550183) (xy 258.537085 -68.625464) (xy 258.491295 -68.696716) (xy 258.438939 -68.763292)
			(xy 258.380491 -68.82459) (xy 258.316481 -68.880055) (xy 258.247489 -68.929184) (xy 258.174139 -68.971533)
			(xy 258.097096 -69.006717) (xy 258.017057 -69.034419) (xy 257.934748 -69.054387) (xy 257.850913 -69.06644)
			(xy 257.766312 -69.070471) (xy 257.681711 -69.06644) (xy 257.597876 -69.054387) (xy 257.515567 -69.034419)
			(xy 257.435528 -69.006717) (xy 257.358485 -68.971533) (xy 257.285135 -68.929184) (xy 257.216143 -68.880055)
			(xy 257.152133 -68.82459) (xy 257.093685 -68.763292) (xy 257.041329 -68.696716) (xy 256.995539 -68.625464)
			(xy 256.956728 -68.550183) (xy 256.925249 -68.471553) (xy 256.901388 -68.390286) (xy 256.885359 -68.30712)
			(xy 256.877308 -68.222806) (xy 256.322178 -68.222806) (xy 256.328925 -68.26865) (xy 256.329434 -68.296536)
			(xy 256.328925 -68.324422) (xy 256.320805 -68.379598) (xy 256.304737 -68.433005) (xy 256.281065 -68.483502)
			(xy 256.250292 -68.530015) (xy 256.213075 -68.571552) (xy 256.170207 -68.607227) (xy 256.122601 -68.636281)
			(xy 256.071272 -68.658093) (xy 256.017315 -68.672199) (xy 255.961878 -68.678299) (xy 255.906144 -68.676262)
			(xy 255.851301 -68.666132) (xy 255.798517 -68.648125) (xy 255.748917 -68.622624) (xy 255.703559 -68.590173)
			(xy 255.66341 -68.551464) (xy 255.629324 -68.507321) (xy 255.602028 -68.458686) (xy 255.582105 -68.406595)
			(xy 255.569979 -68.352158) (xy 255.565908 -68.296536) (xy 233.175638 -68.296536) (xy 233.192638 -68.32746)
			(xy 233.21617 -68.386893) (xy 233.232067 -68.448807) (xy 233.240078 -68.512225) (xy 233.24058 -68.544186)
			(xy 233.240078 -68.576147) (xy 233.232067 -68.639565) (xy 233.21617 -68.701479) (xy 233.192638 -68.760912)
			(xy 233.161844 -68.816927) (xy 233.124271 -68.868642) (xy 233.080514 -68.915239) (xy 233.031261 -68.955984)
			(xy 232.97729 -68.990235) (xy 232.919451 -69.017452) (xy 232.858658 -69.037205) (xy 232.795868 -69.049183)
			(xy 232.732072 -69.053197) (xy 232.668276 -69.049183) (xy 232.605486 -69.037205) (xy 232.544693 -69.017452)
			(xy 232.486854 -68.990235) (xy 232.432883 -68.955984) (xy 232.38363 -68.915239) (xy 232.339873 -68.868642)
			(xy 232.3023 -68.816927) (xy 232.271506 -68.760912) (xy 232.247974 -68.701479) (xy 232.232077 -68.639565)
			(xy 232.224066 -68.576147) (xy 224.91257 -68.576147) (xy 224.929215 -68.593872) (xy 224.966788 -68.645587)
			(xy 224.997582 -68.701602) (xy 225.021114 -68.761035) (xy 225.037011 -68.822949) (xy 225.045022 -68.886367)
			(xy 225.045524 -68.918328) (xy 225.045022 -68.950289) (xy 225.037011 -69.013707) (xy 225.021114 -69.075621)
			(xy 224.997582 -69.135054) (xy 224.975974 -69.17436) (xy 239.079784 -69.17436) (xy 239.083855 -69.118738)
			(xy 239.095981 -69.064301) (xy 239.115904 -69.01221) (xy 239.1432 -68.963575) (xy 239.177286 -68.919432)
			(xy 239.217435 -68.880723) (xy 239.262793 -68.848272) (xy 239.312393 -68.822771) (xy 239.365177 -68.804764)
			(xy 239.42002 -68.794634) (xy 239.475754 -68.792597) (xy 239.531191 -68.798697) (xy 239.585148 -68.812803)
			(xy 239.636477 -68.834615) (xy 239.684083 -68.863669) (xy 239.726951 -68.899344) (xy 239.764168 -68.940881)
			(xy 239.789045 -68.978483) (xy 249.035564 -68.978483) (xy 249.035564 -68.914561) (xy 249.043575 -68.851143)
			(xy 249.059472 -68.789229) (xy 249.083004 -68.729796) (xy 249.113798 -68.673781) (xy 249.151371 -68.622066)
			(xy 249.195128 -68.575469) (xy 249.244381 -68.534724) (xy 249.298352 -68.500473) (xy 249.356191 -68.473256)
			(xy 249.416984 -68.453503) (xy 249.479774 -68.441525) (xy 249.54357 -68.437512) (xy 249.607366 -68.441525)
			(xy 249.670156 -68.453503) (xy 249.730949 -68.473256) (xy 249.788788 -68.500473) (xy 249.842759 -68.534724)
			(xy 249.892012 -68.575469) (xy 249.935769 -68.622066) (xy 249.973342 -68.673781) (xy 250.004136 -68.729796)
			(xy 250.027668 -68.789229) (xy 250.043565 -68.851143) (xy 250.051576 -68.914561) (xy 250.052078 -68.946522)
			(xy 250.051576 -68.978483) (xy 250.043565 -69.041901) (xy 250.027668 -69.103815) (xy 250.004136 -69.163248)
			(xy 249.973342 -69.219263) (xy 249.935769 -69.270978) (xy 249.892012 -69.317575) (xy 249.842759 -69.35832)
			(xy 249.788788 -69.392571) (xy 249.730949 -69.419788) (xy 249.670156 -69.439541) (xy 249.607366 -69.451519)
			(xy 249.54357 -69.455533) (xy 249.479774 -69.451519) (xy 249.416984 -69.439541) (xy 249.356191 -69.419788)
			(xy 249.298352 -69.392571) (xy 249.244381 -69.35832) (xy 249.195128 -69.317575) (xy 249.151371 -69.270978)
			(xy 249.113798 -69.219263) (xy 249.083004 -69.163248) (xy 249.059472 -69.103815) (xy 249.043575 -69.041901)
			(xy 249.035564 -68.978483) (xy 239.789045 -68.978483) (xy 239.794941 -68.987394) (xy 239.818613 -69.037891)
			(xy 239.834681 -69.091298) (xy 239.842801 -69.146474) (xy 239.84331 -69.17436) (xy 239.842801 -69.202246)
			(xy 239.834681 -69.257422) (xy 239.818613 -69.310829) (xy 239.794941 -69.361326) (xy 239.764168 -69.407839)
			(xy 239.726951 -69.449376) (xy 239.684083 -69.485051) (xy 239.636477 -69.514105) (xy 239.585148 -69.535917)
			(xy 239.531191 -69.550023) (xy 239.475754 -69.556123) (xy 239.42002 -69.554086) (xy 239.365177 -69.543956)
			(xy 239.312393 -69.525949) (xy 239.262793 -69.500448) (xy 239.217435 -69.467997) (xy 239.177286 -69.429288)
			(xy 239.1432 -69.385145) (xy 239.115904 -69.33651) (xy 239.095981 -69.284419) (xy 239.083855 -69.229982)
			(xy 239.079784 -69.17436) (xy 224.975974 -69.17436) (xy 224.966788 -69.191069) (xy 224.929215 -69.242784)
			(xy 224.885458 -69.289381) (xy 224.836205 -69.330126) (xy 224.782234 -69.364377) (xy 224.724395 -69.391594)
			(xy 224.663602 -69.411347) (xy 224.600812 -69.423325) (xy 224.537016 -69.427339) (xy 224.47322 -69.423325)
			(xy 224.41043 -69.411347) (xy 224.349637 -69.391594) (xy 224.291798 -69.364377) (xy 224.237827 -69.330126)
			(xy 224.188574 -69.289381) (xy 224.144817 -69.242784) (xy 224.107244 -69.191069) (xy 224.07645 -69.135054)
			(xy 224.052918 -69.075621) (xy 224.037021 -69.013707) (xy 224.02901 -68.950289) (xy 220.788032 -68.950289)
			(xy 220.797605 -68.956364) (xy 220.846858 -68.997109) (xy 220.890615 -69.043706) (xy 220.928188 -69.095421)
			(xy 220.958982 -69.151436) (xy 220.982514 -69.210869) (xy 220.998411 -69.272783) (xy 221.006422 -69.336201)
			(xy 221.006924 -69.368162) (xy 221.006422 -69.400123) (xy 220.998411 -69.463541) (xy 220.982514 -69.525455)
			(xy 220.958982 -69.584888) (xy 220.928188 -69.640903) (xy 220.890615 -69.692618) (xy 220.846858 -69.739215)
			(xy 220.797605 -69.77996) (xy 220.743634 -69.814211) (xy 220.685795 -69.841428) (xy 220.625002 -69.861181)
			(xy 220.562212 -69.873159) (xy 220.498416 -69.877173) (xy 220.43462 -69.873159) (xy 220.37183 -69.861181)
			(xy 220.311037 -69.841428) (xy 220.253198 -69.814211) (xy 220.199227 -69.77996) (xy 220.149974 -69.739215)
			(xy 220.106217 -69.692618) (xy 220.068644 -69.640903) (xy 220.03785 -69.584888) (xy 220.014318 -69.525455)
			(xy 219.998421 -69.463541) (xy 219.99041 -69.400123) (xy 219.736357 -69.400123) (xy 219.728964 -69.460504)
			(xy 219.714056 -69.520548) (xy 219.69198 -69.578343) (xy 219.663061 -69.633035) (xy 219.627725 -69.683818)
			(xy 219.586495 -69.729944) (xy 219.539976 -69.770731) (xy 219.514674 -69.788532) (xy 219.502482 -69.79666)
			(xy 219.490798 -69.823838) (xy 219.510102 -69.944234) (xy 219.526263 -69.962522) (xy 249.161552 -69.962522)
			(xy 249.165623 -69.9069) (xy 249.177749 -69.852463) (xy 249.197672 -69.800372) (xy 249.224968 -69.751737)
			(xy 249.259054 -69.707594) (xy 249.299203 -69.668885) (xy 249.344561 -69.636434) (xy 249.394161 -69.610933)
			(xy 249.446945 -69.592926) (xy 249.501788 -69.582796) (xy 249.557522 -69.580759) (xy 249.612959 -69.586859)
			(xy 249.649867 -69.596508) (xy 252.395988 -69.596508) (xy 252.400059 -69.540886) (xy 252.412185 -69.486449)
			(xy 252.432108 -69.434358) (xy 252.459404 -69.385723) (xy 252.49349 -69.34158) (xy 252.533639 -69.302871)
			(xy 252.578997 -69.27042) (xy 252.628597 -69.244919) (xy 252.681381 -69.226912) (xy 252.736224 -69.216782)
			(xy 252.791958 -69.214745) (xy 252.847395 -69.220845) (xy 252.901352 -69.234951) (xy 252.952681 -69.256763)
			(xy 253.000287 -69.285817) (xy 253.043155 -69.321492) (xy 253.080372 -69.363029) (xy 253.111145 -69.409542)
			(xy 253.134817 -69.460039) (xy 253.150885 -69.513446) (xy 253.159005 -69.568622) (xy 253.159514 -69.596508)
			(xy 253.159005 -69.624394) (xy 253.150885 -69.67957) (xy 253.134817 -69.732977) (xy 253.111145 -69.783474)
			(xy 253.080372 -69.829987) (xy 253.043155 -69.871524) (xy 253.000287 -69.907199) (xy 252.952681 -69.936253)
			(xy 252.901352 -69.958065) (xy 252.847395 -69.972171) (xy 252.791958 -69.978271) (xy 252.736224 -69.976234)
			(xy 252.681381 -69.966104) (xy 252.628597 -69.948097) (xy 252.578997 -69.922596) (xy 252.533639 -69.890145)
			(xy 252.49349 -69.851436) (xy 252.459404 -69.807293) (xy 252.432108 -69.758658) (xy 252.412185 -69.706567)
			(xy 252.400059 -69.65213) (xy 252.395988 -69.596508) (xy 249.649867 -69.596508) (xy 249.666916 -69.600965)
			(xy 249.718245 -69.622777) (xy 249.765851 -69.651831) (xy 249.808719 -69.687506) (xy 249.845936 -69.729043)
			(xy 249.876709 -69.775556) (xy 249.900381 -69.826053) (xy 249.916449 -69.87946) (xy 249.924569 -69.934636)
			(xy 249.925078 -69.962522) (xy 249.924569 -69.990408) (xy 249.916449 -70.045584) (xy 249.900381 -70.098991)
			(xy 249.876709 -70.149488) (xy 249.845936 -70.196001) (xy 249.808719 -70.237538) (xy 249.765851 -70.273213)
			(xy 249.718245 -70.302267) (xy 249.666916 -70.324079) (xy 249.612959 -70.338185) (xy 249.557522 -70.344285)
			(xy 249.501788 -70.342248) (xy 249.446945 -70.332118) (xy 249.394161 -70.314111) (xy 249.344561 -70.28861)
			(xy 249.299203 -70.256159) (xy 249.259054 -70.21745) (xy 249.224968 -70.173307) (xy 249.197672 -70.124672)
			(xy 249.177749 -70.072581) (xy 249.165623 -70.018144) (xy 249.161552 -69.962522) (xy 219.526263 -69.962522)
			(xy 219.529406 -69.966078) (xy 219.543884 -69.970142) (xy 219.570106 -69.978143) (xy 219.620132 -70.000565)
			(xy 219.666433 -70.029918) (xy 219.708055 -70.065597) (xy 219.74414 -70.106867) (xy 219.773946 -70.152878)
			(xy 219.796858 -70.202682) (xy 219.812403 -70.255253) (xy 219.820263 -70.309507) (xy 219.820744 -70.336918)
			(xy 219.820167 -70.366679) (xy 219.810908 -70.425477) (xy 219.792633 -70.482124) (xy 219.765785 -70.535247)
			(xy 219.736322 -70.576186) (xy 232.350054 -70.576186) (xy 232.354125 -70.520564) (xy 232.366251 -70.466127)
			(xy 232.386174 -70.414036) (xy 232.41347 -70.365401) (xy 232.447556 -70.321258) (xy 232.487705 -70.282549)
			(xy 232.533063 -70.250098) (xy 232.582663 -70.224597) (xy 232.635447 -70.20659) (xy 232.69029 -70.19646)
			(xy 232.746024 -70.194423) (xy 232.801461 -70.200523) (xy 232.855418 -70.214629) (xy 232.906747 -70.236441)
			(xy 232.954353 -70.265495) (xy 232.997221 -70.30117) (xy 233.034438 -70.342707) (xy 233.065211 -70.38922)
			(xy 233.088883 -70.439717) (xy 233.104951 -70.493124) (xy 233.11239 -70.543674) (xy 239.083848 -70.543674)
			(xy 239.087919 -70.488052) (xy 239.100045 -70.433615) (xy 239.119968 -70.381524) (xy 239.147264 -70.332889)
			(xy 239.18135 -70.288746) (xy 239.221499 -70.250037) (xy 239.266857 -70.217586) (xy 239.316457 -70.192085)
			(xy 239.369241 -70.174078) (xy 239.424084 -70.163948) (xy 239.479818 -70.161911) (xy 239.535255 -70.168011)
			(xy 239.589212 -70.182117) (xy 239.640541 -70.203929) (xy 239.688147 -70.232983) (xy 239.731015 -70.268658)
			(xy 239.768232 -70.310195) (xy 239.799005 -70.356708) (xy 239.822677 -70.407205) (xy 239.838745 -70.460612)
			(xy 239.846865 -70.515788) (xy 239.847374 -70.543674) (xy 239.846865 -70.57156) (xy 239.838745 -70.626736)
			(xy 239.822677 -70.680143) (xy 239.799005 -70.73064) (xy 239.768232 -70.777153) (xy 239.731015 -70.81869)
			(xy 239.688147 -70.854365) (xy 239.640541 -70.883419) (xy 239.589212 -70.905231) (xy 239.535255 -70.919337)
			(xy 239.479818 -70.925437) (xy 239.424084 -70.9234) (xy 239.369241 -70.91327) (xy 239.316457 -70.895263)
			(xy 239.266857 -70.869762) (xy 239.221499 -70.837311) (xy 239.18135 -70.798602) (xy 239.147264 -70.754459)
			(xy 239.119968 -70.705824) (xy 239.100045 -70.653733) (xy 239.087919 -70.599296) (xy 239.083848 -70.543674)
			(xy 233.11239 -70.543674) (xy 233.113071 -70.5483) (xy 233.11358 -70.576186) (xy 233.113071 -70.604072)
			(xy 233.104951 -70.659248) (xy 233.088883 -70.712655) (xy 233.065211 -70.763152) (xy 233.034438 -70.809665)
			(xy 232.997221 -70.851202) (xy 232.954353 -70.886877) (xy 232.906747 -70.915931) (xy 232.855418 -70.937743)
			(xy 232.801461 -70.951849) (xy 232.746024 -70.957949) (xy 232.69029 -70.955912) (xy 232.635447 -70.945782)
			(xy 232.582663 -70.927775) (xy 232.533063 -70.902274) (xy 232.487705 -70.869823) (xy 232.447556 -70.831114)
			(xy 232.41347 -70.786971) (xy 232.386174 -70.738336) (xy 232.366251 -70.686245) (xy 232.354125 -70.631808)
			(xy 232.350054 -70.576186) (xy 219.736322 -70.576186) (xy 219.731016 -70.583559) (xy 219.689168 -70.625886)
			(xy 219.66555 -70.644004) (xy 219.665296 -70.644004) (xy 219.657211 -70.650616) (xy 219.646861 -70.668737)
			(xy 219.64523 -70.679056) (xy 219.636594 -70.75297) (xy 219.635931 -70.763283) (xy 219.641806 -70.783072)
			(xy 219.648024 -70.791324) (xy 219.648278 -70.791324) (xy 219.648278 -70.791832) (xy 219.667223 -70.814805)
			(xy 219.700151 -70.86442) (xy 219.727064 -70.917539) (xy 219.747594 -70.973436) (xy 219.76146 -71.031347)
			(xy 219.768473 -71.090481) (xy 219.768928 -71.120254) (xy 219.768426 -71.152215) (xy 219.764255 -71.185235)
			(xy 240.583968 -71.185235) (xy 240.583968 -71.121313) (xy 240.591979 -71.057895) (xy 240.607876 -70.995981)
			(xy 240.631408 -70.936548) (xy 240.662202 -70.880533) (xy 240.699775 -70.828818) (xy 240.743532 -70.782221)
			(xy 240.792785 -70.741476) (xy 240.846756 -70.707225) (xy 240.904595 -70.680008) (xy 240.965388 -70.660255)
			(xy 241.028178 -70.648277) (xy 241.091974 -70.644264) (xy 241.15577 -70.648277) (xy 241.21856 -70.660255)
			(xy 241.279353 -70.680008) (xy 241.337192 -70.707225) (xy 241.391163 -70.741476) (xy 241.440416 -70.782221)
			(xy 241.484173 -70.828818) (xy 241.521746 -70.880533) (xy 241.55254 -70.936548) (xy 241.576072 -70.995981)
			(xy 241.591969 -71.057895) (xy 241.59998 -71.121313) (xy 241.600482 -71.153274) (xy 241.59998 -71.185235)
			(xy 241.595739 -71.218806) (xy 251.818392 -71.218806) (xy 251.822463 -71.163184) (xy 251.834589 -71.108747)
			(xy 251.854512 -71.056656) (xy 251.881808 -71.008021) (xy 251.915894 -70.963878) (xy 251.956043 -70.925169)
			(xy 252.001401 -70.892718) (xy 252.051001 -70.867217) (xy 252.103785 -70.84921) (xy 252.158628 -70.83908)
			(xy 252.214362 -70.837043) (xy 252.269799 -70.843143) (xy 252.323756 -70.857249) (xy 252.375085 -70.879061)
			(xy 252.422691 -70.908115) (xy 252.465559 -70.94379) (xy 252.502776 -70.985327) (xy 252.533549 -71.03184)
			(xy 252.557221 -71.082337) (xy 252.573289 -71.135744) (xy 252.581409 -71.19092) (xy 252.581918 -71.218806)
			(xy 252.581409 -71.246692) (xy 252.573289 -71.301868) (xy 252.557221 -71.355275) (xy 252.533549 -71.405772)
			(xy 252.502776 -71.452285) (xy 252.465559 -71.493822) (xy 252.422691 -71.529497) (xy 252.375085 -71.558551)
			(xy 252.323756 -71.580363) (xy 252.269799 -71.594469) (xy 252.214362 -71.600569) (xy 252.158628 -71.598532)
			(xy 252.103785 -71.588402) (xy 252.051001 -71.570395) (xy 252.001401 -71.544894) (xy 251.956043 -71.512443)
			(xy 251.915894 -71.473734) (xy 251.881808 -71.429591) (xy 251.854512 -71.380956) (xy 251.834589 -71.328865)
			(xy 251.822463 -71.274428) (xy 251.818392 -71.218806) (xy 241.595739 -71.218806) (xy 241.591969 -71.248653)
			(xy 241.576072 -71.310567) (xy 241.55254 -71.37) (xy 241.521746 -71.426015) (xy 241.484173 -71.47773)
			(xy 241.440416 -71.524327) (xy 241.391163 -71.565072) (xy 241.337192 -71.599323) (xy 241.279353 -71.62654)
			(xy 241.21856 -71.646293) (xy 241.15577 -71.658271) (xy 241.091974 -71.662285) (xy 241.028178 -71.658271)
			(xy 240.965388 -71.646293) (xy 240.904595 -71.62654) (xy 240.846756 -71.599323) (xy 240.792785 -71.565072)
			(xy 240.743532 -71.524327) (xy 240.699775 -71.47773) (xy 240.662202 -71.426015) (xy 240.631408 -71.37)
			(xy 240.607876 -71.310567) (xy 240.591979 -71.248653) (xy 240.583968 -71.185235) (xy 219.764255 -71.185235)
			(xy 219.760415 -71.215633) (xy 219.744518 -71.277547) (xy 219.720986 -71.33698) (xy 219.690192 -71.392995)
			(xy 219.652619 -71.44471) (xy 219.608862 -71.491307) (xy 219.559609 -71.532052) (xy 219.505638 -71.566303)
			(xy 219.447799 -71.59352) (xy 219.387006 -71.613273) (xy 219.324216 -71.625251) (xy 219.26042 -71.629265)
			(xy 219.196624 -71.625251) (xy 219.133834 -71.613273) (xy 219.073041 -71.59352) (xy 219.015202 -71.566303)
			(xy 218.961231 -71.532052) (xy 218.911978 -71.491307) (xy 218.868221 -71.44471) (xy 218.830648 -71.392995)
			(xy 218.799854 -71.33698) (xy 218.776322 -71.277547) (xy 218.760425 -71.215633) (xy 218.752414 -71.152215)
			(xy 218.751912 -71.120254) (xy 218.75239 -71.087695) (xy 218.760709 -71.023112) (xy 218.777204 -70.960118)
			(xy 218.801605 -70.899746) (xy 218.833514 -70.842983) (xy 218.872408 -70.790757) (xy 218.91765 -70.743923)
			(xy 218.968501 -70.703249) (xy 219.024128 -70.669398) (xy 219.053664 -70.655688) (xy 219.063316 -70.65137)
			(xy 219.07754 -70.635876) (xy 219.108528 -70.545706) (xy 219.107004 -70.524624) (xy 219.101924 -70.51548)
			(xy 219.086684 -70.482714) (xy 219.082512 -70.473904) (xy 219.068891 -70.459992) (xy 219.05106 -70.452174)
			(xy 219.031599 -70.451582) (xy 219.013324 -70.458301) (xy 218.998882 -70.471358) (xy 218.994228 -70.47992)
			(xy 218.982109 -70.503567) (xy 218.952251 -70.54752) (xy 218.916585 -70.586908) (xy 218.875801 -70.620968)
			(xy 218.830687 -70.649043) (xy 218.782116 -70.670589) (xy 218.731026 -70.68519) (xy 218.678404 -70.692565)
			(xy 218.651836 -70.693026) (xy 218.624583 -70.692529) (xy 218.57063 -70.684777) (xy 218.518331 -70.669425)
			(xy 218.468748 -70.646785) (xy 218.422893 -70.61732) (xy 218.381698 -70.581628) (xy 218.346002 -70.540436)
			(xy 218.316532 -70.494583) (xy 218.293888 -70.445003) (xy 218.278531 -70.392705) (xy 218.270773 -70.338753)
			(xy 218.083964 -70.338753) (xy 218.068626 -70.36262) (xy 218.032937 -70.403812) (xy 217.991749 -70.439505)
			(xy 217.945901 -70.468973) (xy 217.896326 -70.491618) (xy 217.844033 -70.506977) (xy 217.790087 -70.514738)
			(xy 217.762836 -70.515226) (xy 217.733919 -70.51471) (xy 217.676746 -70.505985) (xy 217.621546 -70.488728)
			(xy 217.569584 -70.463336) (xy 217.52205 -70.430391) (xy 217.480035 -70.390647) (xy 217.461846 -70.36816)
			(xy 217.454216 -70.359377) (xy 217.433332 -70.349182) (xy 217.421714 -70.348602) (xy 217.341958 -70.348602)
			(xy 217.330325 -70.34913) (xy 217.309415 -70.359327) (xy 217.301826 -70.36816) (xy 217.28361 -70.390623)
			(xy 217.241597 -70.430361) (xy 217.194067 -70.463304) (xy 217.142111 -70.488696) (xy 217.086917 -70.505956)
			(xy 217.029751 -70.514689) (xy 217.000836 -70.515226) (xy 216.973583 -70.514729) (xy 216.91963 -70.506977)
			(xy 216.867331 -70.491625) (xy 216.817748 -70.468985) (xy 216.771893 -70.43952) (xy 216.730698 -70.403828)
			(xy 216.695002 -70.362636) (xy 216.665532 -70.316783) (xy 216.642888 -70.267203) (xy 216.627531 -70.214905)
			(xy 216.619773 -70.160953) (xy 212.879484 -70.160953) (xy 212.875643 -70.176446) (xy 212.853619 -70.234177)
			(xy 212.824762 -70.288814) (xy 212.789498 -70.339553) (xy 212.748346 -70.385644) (xy 212.701913 -70.426411)
			(xy 212.650882 -70.461251) (xy 212.623654 -70.475856) (xy 212.610715 -70.483029) (xy 212.589442 -70.503578)
			(xy 212.574948 -70.529359) (xy 212.568448 -70.558213) (xy 212.570486 -70.587719) (xy 212.580892 -70.615404)
			(xy 212.598794 -70.638948) (xy 212.610446 -70.648068) (xy 212.634236 -70.666187) (xy 212.676425 -70.708565)
			(xy 212.711487 -70.757004) (xy 212.738565 -70.81032) (xy 212.756995 -70.867206) (xy 212.766326 -70.926271)
			(xy 212.76691 -70.95617) (xy 212.766424 -70.983421) (xy 212.758668 -71.037369) (xy 212.743313 -71.089664)
			(xy 212.720671 -71.139241) (xy 212.691205 -71.185091) (xy 212.655514 -71.226282) (xy 212.614323 -71.261973)
			(xy 212.568473 -71.291439) (xy 212.518896 -71.314081) (xy 212.466601 -71.329436) (xy 212.412653 -71.337192)
			(xy 212.358151 -71.337192) (xy 212.304203 -71.329436) (xy 212.251908 -71.314081) (xy 212.202331 -71.291439)
			(xy 212.156481 -71.261973) (xy 212.11529 -71.226282) (xy 212.079599 -71.185091) (xy 212.050133 -71.139241)
			(xy 212.027491 -71.089664) (xy 212.012136 -71.037369) (xy 212.00438 -70.983421) (xy 212.003894 -70.95617)
			(xy 212.004329 -70.930287) (xy 212.011336 -70.878997) (xy 212.025218 -70.829128) (xy 212.045719 -70.781594)
			(xy 212.072463 -70.737271) (xy 212.104957 -70.696974) (xy 212.142604 -70.661444) (xy 212.163406 -70.646036)
			(xy 212.175136 -70.637003) (xy 212.193261 -70.61361) (xy 212.20392 -70.586004) (xy 212.206219 -70.556501)
			(xy 212.199965 -70.527577) (xy 212.185683 -70.50166) (xy 212.164572 -70.480923) (xy 212.151722 -70.47357)
			(xy 212.124897 -70.458811) (xy 212.074642 -70.423836) (xy 212.028951 -70.38308) (xy 211.988483 -70.337132)
			(xy 211.953826 -70.286658) (xy 211.92548 -70.232388) (xy 211.903855 -70.175106) (xy 211.889265 -70.115643)
			(xy 211.88192 -70.054858) (xy 211.881466 -70.024244) (xy 209.53584 -70.024244) (xy 209.537539 -70.028719)
			(xy 209.552289 -70.088517) (xy 209.559715 -70.149659) (xy 209.56016 -70.180454) (xy 209.559658 -70.212415)
			(xy 209.551647 -70.275833) (xy 209.53575 -70.337747) (xy 209.512218 -70.39718) (xy 209.481424 -70.453195)
			(xy 209.443851 -70.50491) (xy 209.400094 -70.551507) (xy 209.350841 -70.592252) (xy 209.29687 -70.626503)
			(xy 209.239031 -70.65372) (xy 209.178238 -70.673473) (xy 209.115448 -70.685451) (xy 209.051652 -70.689465)
			(xy 208.987856 -70.685451) (xy 208.925066 -70.673473) (xy 208.864273 -70.65372) (xy 208.806434 -70.626503)
			(xy 208.752463 -70.592252) (xy 208.70321 -70.551507) (xy 208.659453 -70.50491) (xy 208.62188 -70.453195)
			(xy 208.591086 -70.39718) (xy 208.567554 -70.337747) (xy 208.551657 -70.275833) (xy 208.543646 -70.212415)
			(xy 208.543144 -70.180454) (xy 197.748214 -70.180454) (xy 197.764123 -70.19055) (xy 197.813376 -70.231295)
			(xy 197.857133 -70.277892) (xy 197.894706 -70.329607) (xy 197.9255 -70.385622) (xy 197.949032 -70.445055)
			(xy 197.964929 -70.506969) (xy 197.97294 -70.570387) (xy 197.973442 -70.602348) (xy 197.97294 -70.634309)
			(xy 197.964929 -70.697727) (xy 197.949032 -70.759641) (xy 197.9255 -70.819074) (xy 197.894706 -70.875089)
			(xy 197.857133 -70.926804) (xy 197.813376 -70.973401) (xy 197.764123 -71.014146) (xy 197.710152 -71.048397)
			(xy 197.652313 -71.075614) (xy 197.59152 -71.095367) (xy 197.52873 -71.107345) (xy 197.464934 -71.111359)
			(xy 197.401138 -71.107345) (xy 197.338348 -71.095367) (xy 197.277555 -71.075614) (xy 197.219716 -71.048397)
			(xy 197.165745 -71.014146) (xy 197.116492 -70.973401) (xy 197.072735 -70.926804) (xy 197.035162 -70.875089)
			(xy 197.004368 -70.819074) (xy 196.980836 -70.759641) (xy 196.964939 -70.697727) (xy 196.956928 -70.634309)
			(xy 192.513231 -70.634309) (xy 192.535026 -70.668216) (xy 192.557669 -70.717788) (xy 192.573027 -70.770077)
			(xy 192.580788 -70.824019) (xy 192.581276 -70.851268) (xy 192.580822 -70.879423) (xy 192.572562 -70.935123)
			(xy 192.556203 -70.989003) (xy 192.5321 -71.039893) (xy 192.500777 -71.086686) (xy 192.462915 -71.128366)
			(xy 192.419336 -71.164025) (xy 192.370988 -71.19289) (xy 192.318921 -71.214333) (xy 192.291716 -71.2216)
			(xy 192.28308 -71.223632) (xy 192.268094 -71.233792) (xy 192.219072 -71.30288) (xy 192.2145 -71.320406)
			(xy 192.215262 -71.329296) (xy 192.216234 -71.340892) (xy 192.217251 -71.364142) (xy 192.217294 -71.375778)
			(xy 192.216803 -71.407421) (xy 192.208955 -71.470219) (xy 192.193365 -71.531555) (xy 192.172411 -71.585031)
			(xy 197.58253 -71.585031) (xy 197.58253 -71.521109) (xy 197.590541 -71.457691) (xy 197.606438 -71.395777)
			(xy 197.62997 -71.336344) (xy 197.660764 -71.280329) (xy 197.698337 -71.228614) (xy 197.742094 -71.182017)
			(xy 197.791347 -71.141272) (xy 197.845318 -71.107021) (xy 197.903157 -71.079804) (xy 197.96395 -71.060051)
			(xy 198.02674 -71.048073) (xy 198.090536 -71.04406) (xy 198.154332 -71.048073) (xy 198.217122 -71.060051)
			(xy 198.277915 -71.079804) (xy 198.335754 -71.107021) (xy 198.389725 -71.141272) (xy 198.438978 -71.182017)
			(xy 198.482735 -71.228614) (xy 198.520308 -71.280329) (xy 198.551102 -71.336344) (xy 198.574634 -71.395777)
			(xy 198.590531 -71.457691) (xy 198.598542 -71.521109) (xy 198.599044 -71.55307) (xy 198.598542 -71.585031)
			(xy 198.590531 -71.648449) (xy 198.580586 -71.687182) (xy 202.207368 -71.687182) (xy 202.207854 -71.658566)
			(xy 202.216398 -71.601976) (xy 202.233308 -71.547299) (xy 202.258202 -71.495765) (xy 202.290521 -71.448532)
			(xy 202.329539 -71.406663) (xy 202.35164 -71.388478) (xy 202.351894 -71.388224) (xy 202.359528 -71.381401)
			(xy 202.369097 -71.363322) (xy 202.370436 -71.353172) (xy 202.37704 -71.279258) (xy 202.377467 -71.268974)
			(xy 202.371035 -71.249441) (xy 202.364594 -71.241412) (xy 202.36434 -71.240904) (xy 202.344161 -71.217614)
			(xy 202.309034 -71.166979) (xy 202.280286 -71.112469) (xy 202.258339 -71.054883) (xy 202.243514 -70.995067)
			(xy 202.23603 -70.933897) (xy 202.235562 -70.903084) (xy 202.236041 -70.872354) (xy 202.243451 -70.811342)
			(xy 202.25816 -70.751668) (xy 202.279955 -70.694201) (xy 202.308517 -70.639781) (xy 202.343431 -70.5892)
			(xy 202.384186 -70.543196) (xy 202.430189 -70.502439) (xy 202.480769 -70.467524) (xy 202.535189 -70.438961)
			(xy 202.592654 -70.417164) (xy 202.652328 -70.402453) (xy 202.71334 -70.395042) (xy 202.74407 -70.394576)
			(xy 202.775957 -70.395059) (xy 202.839229 -70.403037) (xy 202.901009 -70.418859) (xy 202.960327 -70.442277)
			(xy 203.016254 -70.472924) (xy 203.067913 -70.51032) (xy 203.091542 -70.531736) (xy 203.098794 -70.537958)
			(xy 203.116541 -70.545004) (xy 203.126086 -70.545452) (xy 203.157074 -70.545452) (xy 203.166758 -70.545129)
			(xy 203.184784 -70.538061) (xy 203.192126 -70.531736) (xy 203.215784 -70.510162) (xy 203.267524 -70.472449)
			(xy 203.323588 -70.441528) (xy 203.38309 -70.417885) (xy 203.445087 -70.401897) (xy 203.508601 -70.393814)
			(xy 203.540614 -70.393306) (xy 203.57312 -70.393783) (xy 203.637605 -70.402047) (xy 203.70051 -70.418464)
			(xy 203.760808 -70.442766) (xy 203.817518 -70.474556) (xy 203.869711 -70.513317) (xy 203.916538 -70.558414)
			(xy 203.957234 -70.609113) (xy 203.991135 -70.664586) (xy 204.017687 -70.723929) (xy 204.036459 -70.786172)
			(xy 204.047142 -70.8503) (xy 204.047785 -70.862401) (xy 205.960212 -70.862401) (xy 205.960212 -70.798479)
			(xy 205.968223 -70.735061) (xy 205.98412 -70.673147) (xy 206.007652 -70.613714) (xy 206.038446 -70.557699)
			(xy 206.076019 -70.505984) (xy 206.119776 -70.459387) (xy 206.169029 -70.418642) (xy 206.223 -70.384391)
			(xy 206.280839 -70.357174) (xy 206.341632 -70.337421) (xy 206.404422 -70.325443) (xy 206.468218 -70.32143)
			(xy 206.532014 -70.325443) (xy 206.594804 -70.337421) (xy 206.655597 -70.357174) (xy 206.713436 -70.384391)
			(xy 206.767407 -70.418642) (xy 206.81666 -70.459387) (xy 206.860417 -70.505984) (xy 206.89799 -70.557699)
			(xy 206.928784 -70.613714) (xy 206.952316 -70.673147) (xy 206.968213 -70.735061) (xy 206.976224 -70.798479)
			(xy 206.976726 -70.83044) (xy 206.976224 -70.862401) (xy 206.968213 -70.925819) (xy 206.952316 -70.987733)
			(xy 206.928784 -71.047166) (xy 206.89799 -71.103181) (xy 206.860417 -71.154896) (xy 206.81666 -71.201493)
			(xy 206.767407 -71.242238) (xy 206.713436 -71.276489) (xy 206.655597 -71.303706) (xy 206.594804 -71.323459)
			(xy 206.532014 -71.335437) (xy 206.468218 -71.339451) (xy 206.404422 -71.335437) (xy 206.341632 -71.323459)
			(xy 206.280839 -71.303706) (xy 206.223 -71.276489) (xy 206.169029 -71.242238) (xy 206.119776 -71.201493)
			(xy 206.076019 -71.154896) (xy 206.038446 -71.103181) (xy 206.007652 -71.047166) (xy 205.98412 -70.987733)
			(xy 205.968223 -70.925819) (xy 205.960212 -70.862401) (xy 204.047785 -70.862401) (xy 204.048868 -70.882764)
			(xy 204.049122 -70.894448) (xy 204.05979 -70.914768) (xy 204.141832 -70.975982) (xy 204.16393 -70.9803)
			(xy 204.175106 -70.977506) (xy 204.205709 -70.970257) (xy 204.26812 -70.962483) (xy 204.299566 -70.962012)
			(xy 204.29982 -70.962012) (xy 204.331781 -70.962475) (xy 204.3952 -70.970489) (xy 204.457114 -70.986388)
			(xy 204.516548 -71.009922) (xy 204.572563 -71.040718) (xy 204.624277 -71.078292) (xy 204.670874 -71.122052)
			(xy 204.711619 -71.171306) (xy 204.74587 -71.225278) (xy 204.773086 -71.283118) (xy 204.792839 -71.343912)
			(xy 204.804817 -71.406703) (xy 204.808831 -71.4705) (xy 204.806196 -71.512387) (xy 214.424 -71.512387)
			(xy 214.424 -71.448465) (xy 214.432011 -71.385047) (xy 214.447908 -71.323133) (xy 214.47144 -71.2637)
			(xy 214.502234 -71.207685) (xy 214.539807 -71.15597) (xy 214.583564 -71.109373) (xy 214.632817 -71.068628)
			(xy 214.686788 -71.034377) (xy 214.744627 -71.00716) (xy 214.80542 -70.987407) (xy 214.86821 -70.975429)
			(xy 214.932006 -70.971416) (xy 214.995802 -70.975429) (xy 215.058592 -70.987407) (xy 215.119385 -71.00716)
			(xy 215.177224 -71.034377) (xy 215.231195 -71.068628) (xy 215.280448 -71.109373) (xy 215.296867 -71.126858)
			(xy 216.591132 -71.126858) (xy 216.595203 -71.071236) (xy 216.607329 -71.016799) (xy 216.627252 -70.964708)
			(xy 216.654548 -70.916073) (xy 216.688634 -70.87193) (xy 216.728783 -70.833221) (xy 216.774141 -70.80077)
			(xy 216.823741 -70.775269) (xy 216.876525 -70.757262) (xy 216.931368 -70.747132) (xy 216.987102 -70.745095)
			(xy 217.042539 -70.751195) (xy 217.096496 -70.765301) (xy 217.147825 -70.787113) (xy 217.195431 -70.816167)
			(xy 217.238299 -70.851842) (xy 217.275516 -70.893379) (xy 217.306289 -70.939892) (xy 217.329961 -70.990389)
			(xy 217.346029 -71.043796) (xy 217.354149 -71.098972) (xy 217.354658 -71.126858) (xy 217.354149 -71.154744)
			(xy 217.346029 -71.20992) (xy 217.329961 -71.263327) (xy 217.306289 -71.313824) (xy 217.275516 -71.360337)
			(xy 217.238299 -71.401874) (xy 217.195431 -71.437549) (xy 217.147825 -71.466603) (xy 217.096496 -71.488415)
			(xy 217.042539 -71.502521) (xy 216.987102 -71.508621) (xy 216.931368 -71.506584) (xy 216.876525 -71.496454)
			(xy 216.823741 -71.478447) (xy 216.774141 -71.452946) (xy 216.728783 -71.420495) (xy 216.688634 -71.381786)
			(xy 216.654548 -71.337643) (xy 216.627252 -71.289008) (xy 216.607329 -71.236917) (xy 216.595203 -71.18248)
			(xy 216.591132 -71.126858) (xy 215.296867 -71.126858) (xy 215.324205 -71.15597) (xy 215.361778 -71.207685)
			(xy 215.392572 -71.2637) (xy 215.416104 -71.323133) (xy 215.432001 -71.385047) (xy 215.440012 -71.448465)
			(xy 215.440514 -71.480426) (xy 215.440012 -71.512387) (xy 215.432001 -71.575805) (xy 215.416104 -71.637719)
			(xy 215.392572 -71.697152) (xy 215.361778 -71.753167) (xy 215.324205 -71.804882) (xy 215.280448 -71.851479)
			(xy 215.231195 -71.892224) (xy 215.177224 -71.926475) (xy 215.119385 -71.953692) (xy 215.058592 -71.973445)
			(xy 214.995802 -71.985423) (xy 214.932006 -71.989437) (xy 214.86821 -71.985423) (xy 214.80542 -71.973445)
			(xy 214.744627 -71.953692) (xy 214.686788 -71.926475) (xy 214.632817 -71.892224) (xy 214.583564 -71.851479)
			(xy 214.539807 -71.804882) (xy 214.502234 -71.753167) (xy 214.47144 -71.697152) (xy 214.447908 -71.637719)
			(xy 214.432011 -71.575805) (xy 214.424 -71.512387) (xy 204.806196 -71.512387) (xy 204.804817 -71.534297)
			(xy 204.792839 -71.597088) (xy 204.773086 -71.657882) (xy 204.74587 -71.715722) (xy 204.711619 -71.769694)
			(xy 204.670874 -71.818948) (xy 204.624277 -71.862708) (xy 204.572563 -71.900282) (xy 204.516548 -71.931078)
			(xy 204.457114 -71.954612) (xy 204.3952 -71.970511) (xy 204.331781 -71.978525) (xy 204.29982 -71.979028)
			(xy 204.267316 -71.978487) (xy 204.202835 -71.970227) (xy 204.139933 -71.953816) (xy 204.079637 -71.929519)
			(xy 204.022929 -71.897735) (xy 203.970736 -71.858981) (xy 203.923909 -71.813889) (xy 203.883213 -71.763196)
			(xy 203.84931 -71.707729) (xy 203.822755 -71.648393) (xy 203.803981 -71.586155) (xy 203.793294 -71.522032)
			(xy 203.791566 -71.48957) (xy 203.791312 -71.477886) (xy 203.780644 -71.457566) (xy 203.698602 -71.396352)
			(xy 203.676504 -71.392034) (xy 203.665328 -71.394828) (xy 203.634727 -71.40209) (xy 203.572315 -71.409856)
			(xy 203.540868 -71.410322) (xy 203.540614 -71.410322) (xy 203.508727 -71.409849) (xy 203.445454 -71.401869)
			(xy 203.383674 -71.386045) (xy 203.324356 -71.362625) (xy 203.268429 -71.331977) (xy 203.216771 -71.294579)
			(xy 203.193142 -71.273162) (xy 203.185895 -71.266933) (xy 203.168144 -71.259891) (xy 203.158598 -71.259446)
			(xy 203.12761 -71.259446) (xy 203.117925 -71.259761) (xy 203.099899 -71.266835) (xy 203.092558 -71.273162)
			(xy 203.064044 -71.299113) (xy 203.00065 -71.342989) (xy 202.96632 -71.360538) (xy 202.957176 -71.36511)
			(xy 202.94346 -71.380858) (xy 202.914758 -71.471282) (xy 202.917044 -71.49211) (xy 202.922124 -71.501254)
			(xy 202.933593 -71.522623) (xy 202.951653 -71.567634) (xy 202.963857 -71.614572) (xy 202.970007 -71.662679)
			(xy 202.970384 -71.686928) (xy 202.970384 -71.687182) (xy 202.969898 -71.714433) (xy 202.962142 -71.768381)
			(xy 202.946787 -71.820676) (xy 202.924145 -71.870253) (xy 202.894679 -71.916103) (xy 202.858988 -71.957294)
			(xy 202.817797 -71.992985) (xy 202.771947 -72.022451) (xy 202.72237 -72.045093) (xy 202.670075 -72.060448)
			(xy 202.616127 -72.068204) (xy 202.561625 -72.068204) (xy 202.507677 -72.060448) (xy 202.455382 -72.045093)
			(xy 202.405805 -72.022451) (xy 202.359955 -71.992985) (xy 202.318764 -71.957294) (xy 202.283073 -71.916103)
			(xy 202.253607 -71.870253) (xy 202.230965 -71.820676) (xy 202.21561 -71.768381) (xy 202.207854 -71.714433)
			(xy 202.207368 -71.687182) (xy 198.580586 -71.687182) (xy 198.574634 -71.710363) (xy 198.551102 -71.769796)
			(xy 198.520308 -71.825811) (xy 198.482735 -71.877526) (xy 198.438978 -71.924123) (xy 198.389725 -71.964868)
			(xy 198.335754 -71.999119) (xy 198.277915 -72.026336) (xy 198.217122 -72.046089) (xy 198.154332 -72.058067)
			(xy 198.090536 -72.062081) (xy 198.02674 -72.058067) (xy 197.96395 -72.046089) (xy 197.903157 -72.026336)
			(xy 197.845318 -71.999119) (xy 197.791347 -71.964868) (xy 197.742094 -71.924123) (xy 197.698337 -71.877526)
			(xy 197.660764 -71.825811) (xy 197.62997 -71.769796) (xy 197.606438 -71.710363) (xy 197.590541 -71.648449)
			(xy 197.58253 -71.585031) (xy 192.172411 -71.585031) (xy 192.170276 -71.590479) (xy 192.140045 -71.646077)
			(xy 192.10314 -71.697489) (xy 192.060134 -71.743917) (xy 192.011692 -71.784642) (xy 191.985392 -71.802244)
			(xy 191.976911 -71.80838) (xy 191.96537 -71.82582) (xy 191.96304 -71.836026) (xy 191.953388 -71.88962)
			(xy 191.958214 -71.895462) (xy 191.965072 -71.904352) (xy 191.985138 -71.914766) (xy 192.074292 -71.918068)
			(xy 192.085283 -71.917923) (xy 192.105561 -71.909507) (xy 192.113408 -71.901812) (xy 192.113916 -71.901304)
			(xy 192.132087 -71.88207) (xy 192.17277 -71.848239) (xy 192.217736 -71.820351) (xy 192.266123 -71.798942)
			(xy 192.317003 -71.78442) (xy 192.369401 -71.777065) (xy 192.395856 -71.77659) (xy 192.423111 -71.777054)
			(xy 192.477066 -71.784806) (xy 192.529369 -71.800158) (xy 192.578954 -71.822798) (xy 192.624813 -71.852265)
			(xy 192.666011 -71.887958) (xy 192.701709 -71.929152) (xy 192.731181 -71.975007) (xy 192.753826 -72.02459)
			(xy 192.769184 -72.076891) (xy 192.776943 -72.130845) (xy 192.776943 -72.185355) (xy 192.770562 -72.229726)
			(xy 206.96377 -72.229726) (xy 206.967841 -72.174104) (xy 206.979967 -72.119667) (xy 206.99989 -72.067576)
			(xy 207.027186 -72.018941) (xy 207.061272 -71.974798) (xy 207.101421 -71.936089) (xy 207.146779 -71.903638)
			(xy 207.196379 -71.878137) (xy 207.249163 -71.86013) (xy 207.304006 -71.85) (xy 207.35974 -71.847963)
			(xy 207.415177 -71.854063) (xy 207.469134 -71.868169) (xy 207.520463 -71.889981) (xy 207.568069 -71.919035)
			(xy 207.610937 -71.95471) (xy 207.648154 -71.996247) (xy 207.661129 -72.015858) (xy 216.591642 -72.015858)
			(xy 216.592128 -71.988607) (xy 216.599884 -71.934659) (xy 216.615239 -71.882364) (xy 216.637881 -71.832787)
			(xy 216.667347 -71.786937) (xy 216.703038 -71.745746) (xy 216.744229 -71.710055) (xy 216.790079 -71.680589)
			(xy 216.839656 -71.657947) (xy 216.891951 -71.642592) (xy 216.945899 -71.634836) (xy 217.000401 -71.634836)
			(xy 217.054349 -71.642592) (xy 217.106644 -71.657947) (xy 217.156221 -71.680589) (xy 217.202071 -71.710055)
			(xy 217.243262 -71.745746) (xy 217.278953 -71.786937) (xy 217.308419 -71.832787) (xy 217.331061 -71.882364)
			(xy 217.346416 -71.934659) (xy 217.354172 -71.988607) (xy 217.354658 -72.015858) (xy 217.354174 -72.042574)
			(xy 217.346657 -72.095477) (xy 217.339672 -72.121268) (xy 217.336306 -72.134902) (xy 217.336232 -72.16297)
			(xy 217.343797 -72.189999) (xy 217.35843 -72.213951) (xy 217.379027 -72.233019) (xy 217.404034 -72.245765)
			(xy 217.431565 -72.251227) (xy 217.44559 -72.250554) (xy 217.485976 -72.24903) (xy 217.517518 -72.249442)
			(xy 217.580119 -72.257242) (xy 217.641274 -72.272726) (xy 217.700044 -72.295655) (xy 217.755527 -72.325677)
			(xy 217.80687 -72.362331) (xy 217.853285 -72.405055) (xy 217.89406 -72.453192) (xy 217.928566 -72.506002)
			(xy 217.956276 -72.562675) (xy 217.976763 -72.622341) (xy 217.989712 -72.684082) (xy 217.994925 -72.746951)
			(xy 217.992322 -72.809982) (xy 217.981942 -72.872207) (xy 217.979797 -72.879415) (xy 219.61322 -72.879415)
			(xy 219.61322 -72.815493) (xy 219.621231 -72.752075) (xy 219.637128 -72.690161) (xy 219.66066 -72.630728)
			(xy 219.691454 -72.574713) (xy 219.729027 -72.522998) (xy 219.772784 -72.476401) (xy 219.822037 -72.435656)
			(xy 219.876008 -72.401405) (xy 219.933847 -72.374188) (xy 219.99464 -72.354435) (xy 220.05743 -72.342457)
			(xy 220.121226 -72.338444) (xy 220.185022 -72.342457) (xy 220.200974 -72.3455) (xy 222.362839 -72.3455)
			(xy 222.366853 -72.281711) (xy 222.378829 -72.218928) (xy 222.39858 -72.158141) (xy 222.425793 -72.100309)
			(xy 222.46004 -72.046343) (xy 222.500781 -71.997095) (xy 222.547373 -71.953342) (xy 222.599081 -71.915773)
			(xy 222.65509 -71.884981) (xy 222.714516 -71.861452) (xy 222.776423 -71.845556) (xy 222.839834 -71.837544)
			(xy 222.871792 -71.837042) (xy 222.903105 -71.837537) (xy 222.965257 -71.845237) (xy 223.025994 -71.86051)
			(xy 223.084395 -71.883124) (xy 223.139579 -71.912737) (xy 223.190709 -71.948901) (xy 223.214184 -71.96963)
			(xy 223.224598 -71.979028) (xy 223.251776 -71.984616) (xy 223.349566 -71.950326) (xy 223.358078 -71.946963)
			(xy 223.37215 -71.93528) (xy 223.381241 -71.919411) (xy 223.383094 -71.910448) (xy 223.387705 -71.883866)
			(xy 223.403567 -71.832299) (xy 223.426537 -71.783481) (xy 223.456156 -71.738386) (xy 223.491833 -71.697915)
			(xy 223.532856 -71.662874) (xy 223.578408 -71.633963) (xy 223.627578 -71.611759) (xy 223.679387 -71.596704)
			(xy 223.7328 -71.589098) (xy 223.759776 -71.58863) (xy 223.78703 -71.589078) (xy 223.840983 -71.596832)
			(xy 223.893284 -71.612187) (xy 223.942866 -71.63483) (xy 223.988722 -71.664299) (xy 224.029916 -71.699994)
			(xy 224.06561 -71.74119) (xy 224.095077 -71.787046) (xy 224.117718 -71.836629) (xy 224.133071 -71.88893)
			(xy 224.140823 -71.942884) (xy 224.141284 -71.970138) (xy 224.140727 -71.999054) (xy 224.132007 -72.056223)
			(xy 224.114757 -72.111422) (xy 224.089373 -72.163384) (xy 224.056436 -72.210918) (xy 224.016701 -72.252937)
			(xy 224.008398 -72.259655) (xy 224.47605 -72.259655) (xy 224.47605 -72.195733) (xy 224.484061 -72.132315)
			(xy 224.499958 -72.070401) (xy 224.52349 -72.010968) (xy 224.554284 -71.954953) (xy 224.591857 -71.903238)
			(xy 224.635614 -71.856641) (xy 224.684867 -71.815896) (xy 224.738838 -71.781645) (xy 224.796677 -71.754428)
			(xy 224.85747 -71.734675) (xy 224.92026 -71.722697) (xy 224.984056 -71.718684) (xy 225.047852 -71.722697)
			(xy 225.110642 -71.734675) (xy 225.171435 -71.754428) (xy 225.229274 -71.781645) (xy 225.283245 -71.815896)
			(xy 225.332498 -71.856641) (xy 225.376255 -71.903238) (xy 225.413828 -71.954953) (xy 225.444622 -72.010968)
			(xy 225.468154 -72.070401) (xy 225.484051 -72.132315) (xy 225.492062 -72.195733) (xy 225.492564 -72.227694)
			(xy 225.492062 -72.259655) (xy 225.484051 -72.323073) (xy 225.468154 -72.384987) (xy 225.444622 -72.44442)
			(xy 225.413828 -72.500435) (xy 225.376255 -72.55215) (xy 225.332498 -72.598747) (xy 225.283245 -72.639492)
			(xy 225.229274 -72.673743) (xy 225.171435 -72.70096) (xy 225.13815 -72.711775) (xy 230.823002 -72.711775)
			(xy 230.823002 -72.647853) (xy 230.831013 -72.584435) (xy 230.84691 -72.522521) (xy 230.870442 -72.463088)
			(xy 230.901236 -72.407073) (xy 230.938809 -72.355358) (xy 230.982566 -72.308761) (xy 231.031819 -72.268016)
			(xy 231.08579 -72.233765) (xy 231.143629 -72.206548) (xy 231.204422 -72.186795) (xy 231.267212 -72.174817)
			(xy 231.331008 -72.170804) (xy 231.394804 -72.174817) (xy 231.457594 -72.186795) (xy 231.518387 -72.206548)
			(xy 231.576226 -72.233765) (xy 231.630197 -72.268016) (xy 231.67945 -72.308761) (xy 231.705131 -72.336109)
			(xy 241.033294 -72.336109) (xy 241.033294 -72.272187) (xy 241.041305 -72.208769) (xy 241.057202 -72.146855)
			(xy 241.080734 -72.087422) (xy 241.111528 -72.031407) (xy 241.149101 -71.979692) (xy 241.192858 -71.933095)
			(xy 241.242111 -71.89235) (xy 241.296082 -71.858099) (xy 241.353921 -71.830882) (xy 241.414714 -71.811129)
			(xy 241.477504 -71.799151) (xy 241.5413 -71.795138) (xy 241.605096 -71.799151) (xy 241.667886 -71.811129)
			(xy 241.728679 -71.830882) (xy 241.777395 -71.853806) (xy 256.392934 -71.853806) (xy 256.393443 -71.820671)
			(xy 256.402052 -71.754961) (xy 256.419124 -71.690927) (xy 256.44437 -71.629654) (xy 256.477363 -71.57218)
			(xy 256.517542 -71.519478) (xy 256.564228 -71.472444) (xy 256.616628 -71.431873) (xy 256.673855 -71.398453)
			(xy 256.734939 -71.372751) (xy 256.798844 -71.355202) (xy 256.831592 -71.350124) (xy 256.840145 -71.348603)
			(xy 256.855595 -71.34069) (xy 256.861818 -71.33463) (xy 256.882138 -71.31304) (xy 256.887724 -71.306584)
			(xy 256.894719 -71.291022) (xy 256.895854 -71.28256) (xy 256.898952 -71.251176) (xy 256.91191 -71.189456)
			(xy 256.932402 -71.129813) (xy 256.960112 -71.073162) (xy 256.994615 -71.020372) (xy 257.035382 -70.972254)
			(xy 257.081786 -70.929547) (xy 257.133116 -70.892907) (xy 257.188582 -70.862895) (xy 257.247334 -70.839973)
			(xy 257.30847 -70.824493) (xy 257.371051 -70.816692) (xy 257.402584 -70.816216) (xy 257.433317 -70.816653)
			(xy 257.494334 -70.82406) (xy 257.554014 -70.838768) (xy 257.611485 -70.860564) (xy 257.66591 -70.889128)
			(xy 257.716495 -70.924044) (xy 257.762503 -70.964803) (xy 257.803261 -71.010811) (xy 257.838177 -71.061397)
			(xy 257.86674 -71.115822) (xy 257.888534 -71.173294) (xy 257.903241 -71.232974) (xy 257.910648 -71.293991)
			(xy 257.911092 -71.324724) (xy 257.910588 -71.357859) (xy 257.901976 -71.423568) (xy 257.884902 -71.487601)
			(xy 257.859654 -71.548873) (xy 257.82666 -71.606346) (xy 257.78648 -71.659047) (xy 257.739795 -71.706081)
			(xy 257.687395 -71.746652) (xy 257.630169 -71.780072) (xy 257.569086 -71.805776) (xy 257.505182 -71.823327)
			(xy 257.472434 -71.828406) (xy 257.463882 -71.82993) (xy 257.44843 -71.83784) (xy 257.442208 -71.8439)
			(xy 257.421888 -71.86549) (xy 257.416331 -71.871969) (xy 257.409318 -71.887513) (xy 257.408172 -71.89597)
			(xy 257.405087 -71.927356) (xy 257.392135 -71.98908) (xy 257.371647 -72.048728) (xy 257.343939 -72.105383)
			(xy 257.309436 -72.158177) (xy 257.268668 -72.206297) (xy 257.222261 -72.249005) (xy 257.170928 -72.285646)
			(xy 257.115458 -72.315656) (xy 257.056701 -72.338574) (xy 256.995561 -72.354049) (xy 256.932976 -72.361842)
			(xy 256.901442 -72.362314) (xy 256.870711 -72.361823) (xy 256.809697 -72.354419) (xy 256.75002 -72.339715)
			(xy 256.69255 -72.317924) (xy 256.638127 -72.289364) (xy 256.587543 -72.254453) (xy 256.541536 -72.213698)
			(xy 256.500777 -72.167695) (xy 256.465861 -72.117114) (xy 256.437296 -72.062694) (xy 256.4155 -72.005226)
			(xy 256.400789 -71.945551) (xy 256.39338 -71.884537) (xy 256.392934 -71.853806) (xy 241.777395 -71.853806)
			(xy 241.786518 -71.858099) (xy 241.840489 -71.89235) (xy 241.889742 -71.933095) (xy 241.933499 -71.979692)
			(xy 241.971072 -72.031407) (xy 242.001866 -72.087422) (xy 242.025398 -72.146855) (xy 242.041295 -72.208769)
			(xy 242.049306 -72.272187) (xy 242.049808 -72.304148) (xy 242.049306 -72.336109) (xy 242.041295 -72.399527)
			(xy 242.025398 -72.461441) (xy 242.001866 -72.520874) (xy 241.971072 -72.576889) (xy 241.933499 -72.628604)
			(xy 241.889742 -72.675201) (xy 241.840489 -72.715946) (xy 241.786518 -72.750197) (xy 241.728679 -72.777414)
			(xy 241.667886 -72.797167) (xy 241.605096 -72.809145) (xy 241.5413 -72.813159) (xy 241.477504 -72.809145)
			(xy 241.414714 -72.797167) (xy 241.353921 -72.777414) (xy 241.296082 -72.750197) (xy 241.242111 -72.715946)
			(xy 241.192858 -72.675201) (xy 241.149101 -72.628604) (xy 241.111528 -72.576889) (xy 241.080734 -72.520874)
			(xy 241.057202 -72.461441) (xy 241.041305 -72.399527) (xy 241.033294 -72.336109) (xy 231.705131 -72.336109)
			(xy 231.723207 -72.355358) (xy 231.76078 -72.407073) (xy 231.791574 -72.463088) (xy 231.815106 -72.522521)
			(xy 231.831003 -72.584435) (xy 231.839014 -72.647853) (xy 231.839516 -72.679814) (xy 231.839014 -72.711775)
			(xy 231.831003 -72.775193) (xy 231.815106 -72.837107) (xy 231.791574 -72.89654) (xy 231.76078 -72.952555)
			(xy 231.723207 -73.00427) (xy 231.718808 -73.008955) (xy 259.361934 -73.008955) (xy 259.361934 -72.945033)
			(xy 259.369945 -72.881615) (xy 259.385842 -72.819701) (xy 259.409374 -72.760268) (xy 259.440168 -72.704253)
			(xy 259.477741 -72.652538) (xy 259.521498 -72.605941) (xy 259.570751 -72.565196) (xy 259.624722 -72.530945)
			(xy 259.682561 -72.503728) (xy 259.743354 -72.483975) (xy 259.806144 -72.471997) (xy 259.86994 -72.467984)
			(xy 259.933736 -72.471997) (xy 259.996526 -72.483975) (xy 260.057319 -72.503728) (xy 260.115158 -72.530945)
			(xy 260.169129 -72.565196) (xy 260.218382 -72.605941) (xy 260.262139 -72.652538) (xy 260.299712 -72.704253)
			(xy 260.330506 -72.760268) (xy 260.354038 -72.819701) (xy 260.369935 -72.881615) (xy 260.377946 -72.945033)
			(xy 260.378448 -72.976994) (xy 260.377946 -73.008955) (xy 260.369935 -73.072373) (xy 260.354038 -73.134287)
			(xy 260.330506 -73.19372) (xy 260.299712 -73.249735) (xy 260.262139 -73.30145) (xy 260.218382 -73.348047)
			(xy 260.169129 -73.388792) (xy 260.115158 -73.423043) (xy 260.057319 -73.45026) (xy 259.996526 -73.470013)
			(xy 259.933736 -73.481991) (xy 259.86994 -73.486005) (xy 259.806144 -73.481991) (xy 259.743354 -73.470013)
			(xy 259.682561 -73.45026) (xy 259.624722 -73.423043) (xy 259.570751 -73.388792) (xy 259.521498 -73.348047)
			(xy 259.477741 -73.30145) (xy 259.440168 -73.249735) (xy 259.409374 -73.19372) (xy 259.385842 -73.134287)
			(xy 259.369945 -73.072373) (xy 259.361934 -73.008955) (xy 231.718808 -73.008955) (xy 231.67945 -73.050867)
			(xy 231.630197 -73.091612) (xy 231.576226 -73.125863) (xy 231.518387 -73.15308) (xy 231.457594 -73.172833)
			(xy 231.394804 -73.184811) (xy 231.331008 -73.188825) (xy 231.267212 -73.184811) (xy 231.204422 -73.172833)
			(xy 231.143629 -73.15308) (xy 231.08579 -73.125863) (xy 231.031819 -73.091612) (xy 230.982566 -73.050867)
			(xy 230.938809 -73.00427) (xy 230.901236 -72.952555) (xy 230.870442 -72.89654) (xy 230.84691 -72.837107)
			(xy 230.831013 -72.775193) (xy 230.823002 -72.711775) (xy 225.13815 -72.711775) (xy 225.110642 -72.720713)
			(xy 225.047852 -72.732691) (xy 224.984056 -72.736705) (xy 224.92026 -72.732691) (xy 224.85747 -72.720713)
			(xy 224.796677 -72.70096) (xy 224.738838 -72.673743) (xy 224.684867 -72.639492) (xy 224.635614 -72.598747)
			(xy 224.591857 -72.55215) (xy 224.554284 -72.500435) (xy 224.52349 -72.44442) (xy 224.499958 -72.384987)
			(xy 224.484061 -72.323073) (xy 224.47605 -72.259655) (xy 224.008398 -72.259655) (xy 223.994218 -72.271128)
			(xy 223.985394 -72.278719) (xy 223.975223 -72.299632) (xy 223.97466 -72.31126) (xy 223.97466 -72.391016)
			(xy 223.975183 -72.40265) (xy 223.985381 -72.423561) (xy 223.994218 -72.431148) (xy 224.01668 -72.449364)
			(xy 224.056416 -72.491379) (xy 224.089357 -72.538909) (xy 224.114749 -72.590865) (xy 224.13201 -72.646058)
			(xy 224.140745 -72.703224) (xy 224.141284 -72.732138) (xy 224.140857 -72.759391) (xy 224.133095 -72.813342)
			(xy 224.117734 -72.86564) (xy 224.095087 -72.915219) (xy 224.065614 -72.96107) (xy 224.029917 -73.00226)
			(xy 223.98872 -73.037951) (xy 223.942864 -73.067416) (xy 223.893282 -73.090056) (xy 223.840982 -73.105408)
			(xy 223.787029 -73.113162) (xy 223.759776 -73.113646) (xy 223.732401 -73.113142) (xy 223.678213 -73.105313)
			(xy 223.625701 -73.089817) (xy 223.575943 -73.066974) (xy 223.529961 -73.037253) (xy 223.488701 -73.001264)
			(xy 223.453008 -72.959746) (xy 223.423617 -72.913553) (xy 223.401131 -72.863633) (xy 223.386012 -72.811011)
			(xy 223.381824 -72.783954) (xy 223.380046 -72.769984) (xy 223.362266 -72.74814) (xy 223.264476 -72.712326)
			(xy 223.25572 -72.709533) (xy 223.237357 -72.709702) (xy 223.220249 -72.716374) (xy 223.213168 -72.722232)
			(xy 223.212914 -72.722486) (xy 223.189486 -72.743059) (xy 223.138493 -72.778938) (xy 223.083498 -72.808316)
			(xy 223.025325 -72.830753) (xy 222.964845 -72.845913) (xy 222.902967 -72.853568) (xy 222.871792 -72.854058)
			(xy 222.839834 -72.853456) (xy 222.776423 -72.845444) (xy 222.714516 -72.829548) (xy 222.65509 -72.806019)
			(xy 222.599081 -72.775227) (xy 222.547373 -72.737658) (xy 222.500781 -72.693905) (xy 222.46004 -72.644657)
			(xy 222.425793 -72.590691) (xy 222.39858 -72.532859) (xy 222.378829 -72.472072) (xy 222.366853 -72.409289)
			(xy 222.362839 -72.3455) (xy 220.200974 -72.3455) (xy 220.247812 -72.354435) (xy 220.308605 -72.374188)
			(xy 220.366444 -72.401405) (xy 220.420415 -72.435656) (xy 220.469668 -72.476401) (xy 220.513425 -72.522998)
			(xy 220.550998 -72.574713) (xy 220.581792 -72.630728) (xy 220.605324 -72.690161) (xy 220.621221 -72.752075)
			(xy 220.629232 -72.815493) (xy 220.629734 -72.847454) (xy 220.629232 -72.879415) (xy 220.621221 -72.942833)
			(xy 220.605324 -73.004747) (xy 220.581792 -73.06418) (xy 220.550998 -73.120195) (xy 220.513425 -73.17191)
			(xy 220.469668 -73.218507) (xy 220.420415 -73.259252) (xy 220.366444 -73.293503) (xy 220.308605 -73.32072)
			(xy 220.247812 -73.340473) (xy 220.185022 -73.352451) (xy 220.121226 -73.356465) (xy 220.05743 -73.352451)
			(xy 219.99464 -73.340473) (xy 219.933847 -73.32072) (xy 219.876008 -73.293503) (xy 219.822037 -73.259252)
			(xy 219.772784 -73.218507) (xy 219.729027 -73.17191) (xy 219.691454 -73.120195) (xy 219.66066 -73.06418)
			(xy 219.637128 -73.004747) (xy 219.621231 -72.942833) (xy 219.61322 -72.879415) (xy 217.979797 -72.879415)
			(xy 217.963945 -72.93267) (xy 217.938608 -72.990443) (xy 217.906319 -73.044638) (xy 217.867574 -73.094423)
			(xy 217.82297 -73.139033) (xy 217.773189 -73.177784) (xy 217.718998 -73.210079) (xy 217.661228 -73.235424)
			(xy 217.600767 -73.253428) (xy 217.538544 -73.263815) (xy 217.475513 -73.266426) (xy 217.412644 -73.261221)
			(xy 217.350901 -73.248279) (xy 217.291233 -73.2278) (xy 217.234556 -73.200097) (xy 217.181741 -73.165597)
			(xy 217.1336 -73.124828) (xy 217.09087 -73.078419) (xy 217.05421 -73.02708) (xy 217.024181 -72.971601)
			(xy 217.001245 -72.912833) (xy 216.985754 -72.85168) (xy 216.977946 -72.78908) (xy 216.977468 -72.757538)
			(xy 216.977468 -72.757284) (xy 216.977853 -72.729299) (xy 216.984025 -72.673669) (xy 216.996258 -72.619051)
			(xy 217.014405 -72.566104) (xy 217.025982 -72.540622) (xy 217.031524 -72.527733) (xy 217.036129 -72.50007)
			(xy 217.033032 -72.472198) (xy 217.022466 -72.446221) (xy 217.00523 -72.4241) (xy 216.982624 -72.407505)
			(xy 216.956354 -72.397689) (xy 216.942416 -72.396096) (xy 216.914109 -72.393311) (xy 216.858723 -72.380367)
			(xy 216.805872 -72.359344) (xy 216.756729 -72.330705) (xy 216.712384 -72.295087) (xy 216.673818 -72.25328)
			(xy 216.641888 -72.206209) (xy 216.617302 -72.154919) (xy 216.600603 -72.100546) (xy 216.592164 -72.044297)
			(xy 216.591642 -72.015858) (xy 207.661129 -72.015858) (xy 207.678927 -72.04276) (xy 207.702599 -72.093257)
			(xy 207.718667 -72.146664) (xy 207.726787 -72.20184) (xy 207.727296 -72.229726) (xy 207.726787 -72.257612)
			(xy 207.718667 -72.312788) (xy 207.702599 -72.366195) (xy 207.678927 -72.416692) (xy 207.648154 -72.463205)
			(xy 207.610937 -72.504742) (xy 207.568069 -72.540417) (xy 207.520463 -72.569471) (xy 207.469134 -72.591283)
			(xy 207.415177 -72.605389) (xy 207.35974 -72.611489) (xy 207.304006 -72.609452) (xy 207.249163 -72.599322)
			(xy 207.196379 -72.581315) (xy 207.146779 -72.555814) (xy 207.101421 -72.523363) (xy 207.061272 -72.484654)
			(xy 207.027186 -72.440511) (xy 206.99989 -72.391876) (xy 206.979967 -72.339785) (xy 206.967841 -72.285348)
			(xy 206.96377 -72.229726) (xy 192.770562 -72.229726) (xy 192.769184 -72.239309) (xy 192.753826 -72.29161)
			(xy 192.731181 -72.341193) (xy 192.701709 -72.387048) (xy 192.666011 -72.428242) (xy 192.624813 -72.463935)
			(xy 192.578954 -72.493402) (xy 192.529369 -72.516042) (xy 192.477066 -72.531394) (xy 192.423111 -72.539146)
			(xy 192.395856 -72.539606) (xy 192.366939 -72.539083) (xy 192.309766 -72.53036) (xy 192.254566 -72.513105)
			(xy 192.202603 -72.487715) (xy 192.15507 -72.45477) (xy 192.113055 -72.415027) (xy 192.094866 -72.39254)
			(xy 192.088008 -72.38365) (xy 192.067942 -72.373236) (xy 191.978788 -72.369934) (xy 191.967796 -72.370067)
			(xy 191.947518 -72.378491) (xy 191.939672 -72.38619) (xy 191.939164 -72.386698) (xy 191.921003 -72.405942)
			(xy 191.880318 -72.439772) (xy 191.83535 -72.467658) (xy 191.786961 -72.489066) (xy 191.736079 -72.503586)
			(xy 191.68368 -72.510939) (xy 191.657224 -72.511412) (xy 191.629972 -72.510922) (xy 191.576022 -72.503169)
			(xy 191.523725 -72.487816) (xy 191.474145 -72.465177) (xy 191.428292 -72.435711) (xy 191.387099 -72.40002)
			(xy 191.351405 -72.35883) (xy 191.321937 -72.312979) (xy 191.299294 -72.263401) (xy 191.283937 -72.211105)
			(xy 191.27618 -72.157156) (xy 191.275716 -72.129904) (xy 191.276159 -72.10311) (xy 191.283664 -72.050049)
			(xy 191.298513 -71.998558) (xy 191.320414 -71.949649) (xy 191.348938 -71.904283) (xy 191.365886 -71.883524)
			(xy 191.371926 -71.87588) (xy 191.378191 -71.857452) (xy 191.378078 -71.84771) (xy 191.374014 -71.778368)
			(xy 191.373047 -71.768771) (xy 191.364957 -71.751278) (xy 191.358266 -71.744332) (xy 191.333769 -71.720256)
			(xy 191.290823 -71.666653) (xy 191.255489 -71.607753) (xy 191.228411 -71.54463) (xy 191.210084 -71.478435)
			(xy 191.20084 -71.410375) (xy 191.200278 -71.376032) (xy 184.371488 -71.376032) (xy 184.371488 -72.867266)
			(xy 196.337172 -72.867266) (xy 196.341243 -72.811644) (xy 196.353369 -72.757207) (xy 196.373292 -72.705116)
			(xy 196.400588 -72.656481) (xy 196.434674 -72.612338) (xy 196.474823 -72.573629) (xy 196.520181 -72.541178)
			(xy 196.569781 -72.515677) (xy 196.622565 -72.49767) (xy 196.677408 -72.48754) (xy 196.733142 -72.485503)
			(xy 196.788579 -72.491603) (xy 196.842536 -72.505709) (xy 196.893865 -72.527521) (xy 196.941471 -72.556575)
			(xy 196.984339 -72.59225) (xy 197.021556 -72.633787) (xy 197.052329 -72.6803) (xy 197.076001 -72.730797)
			(xy 197.092069 -72.784204) (xy 197.100189 -72.83938) (xy 197.100698 -72.867266) (xy 197.100374 -72.885003)
			(xy 202.675484 -72.885003) (xy 202.675484 -72.821081) (xy 202.683495 -72.757663) (xy 202.699392 -72.695749)
			(xy 202.722924 -72.636316) (xy 202.753718 -72.580301) (xy 202.791291 -72.528586) (xy 202.835048 -72.481989)
			(xy 202.884301 -72.441244) (xy 202.938272 -72.406993) (xy 202.996111 -72.379776) (xy 203.056904 -72.360023)
			(xy 203.119694 -72.348045) (xy 203.18349 -72.344032) (xy 203.247286 -72.348045) (xy 203.310076 -72.360023)
			(xy 203.370869 -72.379776) (xy 203.428708 -72.406993) (xy 203.482679 -72.441244) (xy 203.531932 -72.481989)
			(xy 203.575689 -72.528586) (xy 203.613262 -72.580301) (xy 203.644056 -72.636316) (xy 203.667588 -72.695749)
			(xy 203.683485 -72.757663) (xy 203.691496 -72.821081) (xy 203.691998 -72.853042) (xy 203.691496 -72.885003)
			(xy 203.683485 -72.948421) (xy 203.667588 -73.010335) (xy 203.644056 -73.069768) (xy 203.613262 -73.125783)
			(xy 203.582588 -73.168002) (xy 210.2264 -73.168002) (xy 210.230471 -73.11238) (xy 210.242597 -73.057943)
			(xy 210.26252 -73.005852) (xy 210.289816 -72.957217) (xy 210.323902 -72.913074) (xy 210.364051 -72.874365)
			(xy 210.409409 -72.841914) (xy 210.459009 -72.816413) (xy 210.511793 -72.798406) (xy 210.566636 -72.788276)
			(xy 210.62237 -72.786239) (xy 210.677807 -72.792339) (xy 210.731764 -72.806445) (xy 210.783093 -72.828257)
			(xy 210.830699 -72.857311) (xy 210.873567 -72.892986) (xy 210.910784 -72.934523) (xy 210.941557 -72.981036)
			(xy 210.965229 -73.031533) (xy 210.978561 -73.075847) (xy 213.0522 -73.075847) (xy 213.0522 -73.021353)
			(xy 213.059955 -72.967412) (xy 213.075307 -72.915124) (xy 213.097943 -72.865553) (xy 213.127403 -72.819708)
			(xy 213.163087 -72.778521) (xy 213.204269 -72.742832) (xy 213.250111 -72.713366) (xy 213.299679 -72.690723)
			(xy 213.351965 -72.675365) (xy 213.405905 -72.667603) (xy 213.433152 -72.667114) (xy 213.461263 -72.667617)
			(xy 213.516878 -72.675858) (xy 213.570683 -72.692168) (xy 213.621513 -72.716195) (xy 213.668268 -72.747418)
			(xy 213.689438 -72.76592) (xy 213.697757 -72.772683) (xy 213.718099 -72.779378) (xy 213.728808 -72.778874)
			(xy 213.81466 -72.770238) (xy 213.833202 -72.75957) (xy 213.839552 -72.75068) (xy 213.860172 -72.723477)
			(xy 213.907487 -72.674275) (xy 213.960956 -72.631843) (xy 214.01962 -72.596942) (xy 214.082424 -72.570199)
			(xy 214.14824 -72.552096) (xy 214.215886 -72.542956) (xy 214.250016 -72.5424) (xy 214.281977 -72.542887)
			(xy 214.345394 -72.5509) (xy 214.407308 -72.566799) (xy 214.46674 -72.590331) (xy 214.522754 -72.621127)
			(xy 214.574468 -72.6587) (xy 214.621064 -72.702458) (xy 214.661808 -72.751712) (xy 214.696059 -72.805683)
			(xy 214.723275 -72.863521) (xy 214.743027 -72.924315) (xy 214.755005 -72.987104) (xy 214.759019 -73.0509)
			(xy 214.755005 -73.114696) (xy 214.743027 -73.177485) (xy 214.723275 -73.238279) (xy 214.696059 -73.296117)
			(xy 214.661808 -73.350088) (xy 214.621064 -73.399342) (xy 214.574468 -73.4431) (xy 214.522754 -73.480673)
			(xy 214.46674 -73.511469) (xy 214.407308 -73.535001) (xy 214.345394 -73.5509) (xy 214.281977 -73.558913)
			(xy 214.250016 -73.559416) (xy 214.219984 -73.558975) (xy 214.160338 -73.551907) (xy 214.101941 -73.537856)
			(xy 214.045607 -73.517018) (xy 213.992124 -73.489684) (xy 213.942236 -73.456235) (xy 213.89664 -73.417137)
			(xy 213.855972 -73.372936) (xy 213.838028 -73.34885) (xy 213.837774 -73.348596) (xy 213.831108 -73.340439)
			(xy 213.812869 -73.329946) (xy 213.802468 -73.328276) (xy 213.716362 -73.318878) (xy 213.696042 -73.325482)
			(xy 213.687914 -73.332594) (xy 213.666826 -73.350886) (xy 213.620284 -73.381712) (xy 213.569747 -73.405424)
			(xy 213.516293 -73.421517) (xy 213.461064 -73.429647) (xy 213.433152 -73.43013) (xy 213.405905 -73.429597)
			(xy 213.351965 -73.421835) (xy 213.299679 -73.406477) (xy 213.250111 -73.383834) (xy 213.204269 -73.354368)
			(xy 213.163087 -73.318679) (xy 213.127403 -73.277492) (xy 213.097943 -73.231647) (xy 213.075307 -73.182076)
			(xy 213.059955 -73.129788) (xy 213.0522 -73.075847) (xy 210.978561 -73.075847) (xy 210.981297 -73.08494)
			(xy 210.989417 -73.140116) (xy 210.989926 -73.168002) (xy 210.989417 -73.195888) (xy 210.981297 -73.251064)
			(xy 210.965229 -73.304471) (xy 210.941557 -73.354968) (xy 210.910784 -73.401481) (xy 210.873567 -73.443018)
			(xy 210.830699 -73.478693) (xy 210.783093 -73.507747) (xy 210.731764 -73.529559) (xy 210.677807 -73.543665)
			(xy 210.62237 -73.549765) (xy 210.566636 -73.547728) (xy 210.511793 -73.537598) (xy 210.459009 -73.519591)
			(xy 210.409409 -73.49409) (xy 210.364051 -73.461639) (xy 210.323902 -73.42293) (xy 210.289816 -73.378787)
			(xy 210.26252 -73.330152) (xy 210.242597 -73.278061) (xy 210.230471 -73.223624) (xy 210.2264 -73.168002)
			(xy 203.582588 -73.168002) (xy 203.575689 -73.177498) (xy 203.531932 -73.224095) (xy 203.482679 -73.26484)
			(xy 203.428708 -73.299091) (xy 203.370869 -73.326308) (xy 203.310076 -73.346061) (xy 203.247286 -73.358039)
			(xy 203.18349 -73.362053) (xy 203.119694 -73.358039) (xy 203.056904 -73.346061) (xy 202.996111 -73.326308)
			(xy 202.938272 -73.299091) (xy 202.884301 -73.26484) (xy 202.835048 -73.224095) (xy 202.791291 -73.177498)
			(xy 202.753718 -73.125783) (xy 202.722924 -73.069768) (xy 202.699392 -73.010335) (xy 202.683495 -72.948421)
			(xy 202.675484 -72.885003) (xy 197.100374 -72.885003) (xy 197.100189 -72.895152) (xy 197.092069 -72.950328)
			(xy 197.076001 -73.003735) (xy 197.052329 -73.054232) (xy 197.021556 -73.100745) (xy 196.984339 -73.142282)
			(xy 196.941471 -73.177957) (xy 196.893865 -73.207011) (xy 196.842536 -73.228823) (xy 196.788579 -73.242929)
			(xy 196.733142 -73.249029) (xy 196.677408 -73.246992) (xy 196.622565 -73.236862) (xy 196.569781 -73.218855)
			(xy 196.520181 -73.193354) (xy 196.474823 -73.160903) (xy 196.434674 -73.122194) (xy 196.400588 -73.078051)
			(xy 196.373292 -73.029416) (xy 196.353369 -72.977325) (xy 196.341243 -72.922888) (xy 196.337172 -72.867266)
			(xy 184.371488 -72.867266) (xy 184.371488 -74.055986) (xy 216.224612 -74.055986) (xy 216.225174 -74.026904)
			(xy 216.233999 -73.969413) (xy 216.251442 -73.913927) (xy 216.2771 -73.861728) (xy 216.31038 -73.814025)
			(xy 216.35051 -73.771923) (xy 216.373202 -73.753726) (xy 216.3826 -73.746614) (xy 216.393014 -73.725532)
			(xy 216.393776 -73.6219) (xy 216.383616 -73.600818) (xy 216.374472 -73.593706) (xy 216.35232 -73.575537)
			(xy 216.313249 -73.533634) (xy 216.280884 -73.486359) (xy 216.255953 -73.434775) (xy 216.239017 -73.380043)
			(xy 216.230456 -73.323394) (xy 216.229946 -73.294748) (xy 216.230432 -73.267497) (xy 216.238188 -73.213549)
			(xy 216.253543 -73.161254) (xy 216.276185 -73.111677) (xy 216.305651 -73.065827) (xy 216.341342 -73.024636)
			(xy 216.382533 -72.988945) (xy 216.428383 -72.959479) (xy 216.47796 -72.936837) (xy 216.530255 -72.921482)
			(xy 216.584203 -72.913726) (xy 216.638705 -72.913726) (xy 216.692653 -72.921482) (xy 216.744948 -72.936837)
			(xy 216.794525 -72.959479) (xy 216.840375 -72.988945) (xy 216.881566 -73.024636) (xy 216.917257 -73.065827)
			(xy 216.946723 -73.111677) (xy 216.969365 -73.161254) (xy 216.98472 -73.213549) (xy 216.992476 -73.267497)
			(xy 216.992962 -73.294748) (xy 216.992396 -73.323829) (xy 216.983568 -73.381319) (xy 216.966124 -73.436804)
			(xy 216.940466 -73.489002) (xy 216.907189 -73.536705) (xy 216.867063 -73.57881) (xy 216.844372 -73.597008)
			(xy 216.834974 -73.60412) (xy 216.82456 -73.625202) (xy 216.824216 -73.671938) (xy 218.577158 -73.671938)
			(xy 218.581229 -73.616316) (xy 218.593355 -73.561879) (xy 218.613278 -73.509788) (xy 218.640574 -73.461153)
			(xy 218.67466 -73.41701) (xy 218.714809 -73.378301) (xy 218.760167 -73.34585) (xy 218.809767 -73.320349)
			(xy 218.862551 -73.302342) (xy 218.917394 -73.292212) (xy 218.973128 -73.290175) (xy 219.028565 -73.296275)
			(xy 219.082522 -73.310381) (xy 219.133851 -73.332193) (xy 219.181457 -73.361247) (xy 219.224325 -73.396922)
			(xy 219.261542 -73.438459) (xy 219.292315 -73.484972) (xy 219.315987 -73.535469) (xy 219.332055 -73.588876)
			(xy 219.340175 -73.644052) (xy 219.340684 -73.671938) (xy 219.340175 -73.699824) (xy 219.332055 -73.755)
			(xy 219.315987 -73.808407) (xy 219.292315 -73.858904) (xy 219.261542 -73.905417) (xy 219.224325 -73.946954)
			(xy 219.181457 -73.982629) (xy 219.133851 -74.011683) (xy 219.082522 -74.033495) (xy 219.028565 -74.047601)
			(xy 218.973128 -74.053701) (xy 218.917394 -74.051664) (xy 218.862551 -74.041534) (xy 218.809767 -74.023527)
			(xy 218.760167 -73.998026) (xy 218.714809 -73.965575) (xy 218.67466 -73.926866) (xy 218.640574 -73.882723)
			(xy 218.613278 -73.834088) (xy 218.593355 -73.781997) (xy 218.581229 -73.72756) (xy 218.577158 -73.671938)
			(xy 216.824216 -73.671938) (xy 216.823798 -73.728834) (xy 216.833958 -73.749916) (xy 216.843102 -73.757028)
			(xy 216.865217 -73.775241) (xy 216.904291 -73.817134) (xy 216.936662 -73.864399) (xy 216.961599 -73.915975)
			(xy 216.978543 -73.970699) (xy 216.987112 -74.027342) (xy 216.987628 -74.055986) (xy 216.987142 -74.083237)
			(xy 216.979386 -74.137185) (xy 216.964031 -74.18948) (xy 216.941389 -74.239057) (xy 216.911923 -74.284907)
			(xy 216.876232 -74.326098) (xy 216.835041 -74.361789) (xy 216.789191 -74.391255) (xy 216.739614 -74.413897)
			(xy 216.687319 -74.429252) (xy 216.633371 -74.437008) (xy 216.578869 -74.437008) (xy 216.524921 -74.429252)
			(xy 216.472626 -74.413897) (xy 216.423049 -74.391255) (xy 216.377199 -74.361789) (xy 216.336008 -74.326098)
			(xy 216.300317 -74.284907) (xy 216.270851 -74.239057) (xy 216.248209 -74.18948) (xy 216.232854 -74.137185)
			(xy 216.225098 -74.083237) (xy 216.224612 -74.055986) (xy 184.371488 -74.055986) (xy 184.371488 -74.453961)
			(xy 225.043994 -74.453961) (xy 225.043994 -74.390039) (xy 225.052005 -74.326621) (xy 225.067902 -74.264707)
			(xy 225.091434 -74.205274) (xy 225.122228 -74.149259) (xy 225.159801 -74.097544) (xy 225.203558 -74.050947)
			(xy 225.252811 -74.010202) (xy 225.306782 -73.975951) (xy 225.364621 -73.948734) (xy 225.425414 -73.928981)
			(xy 225.488204 -73.917003) (xy 225.552 -73.91299) (xy 225.615796 -73.917003) (xy 225.678586 -73.928981)
			(xy 225.739379 -73.948734) (xy 225.797218 -73.975951) (xy 225.851189 -74.010202) (xy 225.900442 -74.050947)
			(xy 225.944199 -74.097544) (xy 225.981772 -74.149259) (xy 226.012566 -74.205274) (xy 226.036098 -74.264707)
			(xy 226.051995 -74.326621) (xy 226.060006 -74.390039) (xy 226.060508 -74.422) (xy 226.060006 -74.453961)
			(xy 226.051995 -74.517379) (xy 226.036098 -74.579293) (xy 226.012566 -74.638726) (xy 225.981772 -74.694741)
			(xy 225.944199 -74.746456) (xy 225.900442 -74.793053) (xy 225.851189 -74.833798) (xy 225.797218 -74.868049)
			(xy 225.741226 -74.894397) (xy 230.383836 -74.894397) (xy 230.383836 -74.830475) (xy 230.391847 -74.767057)
			(xy 230.407744 -74.705143) (xy 230.431276 -74.64571) (xy 230.46207 -74.589695) (xy 230.499643 -74.53798)
			(xy 230.5434 -74.491383) (xy 230.592653 -74.450638) (xy 230.646624 -74.416387) (xy 230.704463 -74.38917)
			(xy 230.765256 -74.369417) (xy 230.828046 -74.357439) (xy 230.891842 -74.353426) (xy 230.955638 -74.357439)
			(xy 231.018428 -74.369417) (xy 231.079221 -74.38917) (xy 231.13706 -74.416387) (xy 231.191031 -74.450638)
			(xy 231.240284 -74.491383) (xy 231.284041 -74.53798) (xy 231.321614 -74.589695) (xy 231.352408 -74.64571)
			(xy 231.37594 -74.705143) (xy 231.391837 -74.767057) (xy 231.39272 -74.774044) (xy 258.156962 -74.774044)
			(xy 258.161033 -74.718422) (xy 258.173159 -74.663985) (xy 258.193082 -74.611894) (xy 258.220378 -74.563259)
			(xy 258.254464 -74.519116) (xy 258.294613 -74.480407) (xy 258.339971 -74.447956) (xy 258.389571 -74.422455)
			(xy 258.442355 -74.404448) (xy 258.497198 -74.394318) (xy 258.552932 -74.392281) (xy 258.608369 -74.398381)
			(xy 258.662326 -74.412487) (xy 258.713655 -74.434299) (xy 258.761261 -74.463353) (xy 258.804129 -74.499028)
			(xy 258.841346 -74.540565) (xy 258.872119 -74.587078) (xy 258.895791 -74.637575) (xy 258.911859 -74.690982)
			(xy 258.919979 -74.746158) (xy 258.920488 -74.774044) (xy 258.919979 -74.80193) (xy 258.911859 -74.857106)
			(xy 258.895791 -74.910513) (xy 258.872119 -74.96101) (xy 258.862583 -74.975423) (xy 269.474436 -74.975423)
			(xy 269.474436 -74.911501) (xy 269.482447 -74.848083) (xy 269.498344 -74.786169) (xy 269.521876 -74.726736)
			(xy 269.55267 -74.670721) (xy 269.590243 -74.619006) (xy 269.634 -74.572409) (xy 269.683253 -74.531664)
			(xy 269.737224 -74.497413) (xy 269.795063 -74.470196) (xy 269.855856 -74.450443) (xy 269.918646 -74.438465)
			(xy 269.982442 -74.434452) (xy 270.046238 -74.438465) (xy 270.109028 -74.450443) (xy 270.169821 -74.470196)
			(xy 270.22766 -74.497413) (xy 270.281631 -74.531664) (xy 270.330884 -74.572409) (xy 270.374641 -74.619006)
			(xy 270.412214 -74.670721) (xy 270.443008 -74.726736) (xy 270.45651 -74.760836) (xy 287.494472 -74.760836)
			(xy 287.494472 -66.060828) (xy 287.494977 -65.955304) (xy 287.503061 -65.74441) (xy 287.519217 -65.533981)
			(xy 287.54342 -65.324324) (xy 287.575637 -65.115749) (xy 287.615819 -64.908561) (xy 287.663907 -64.703064)
			(xy 287.719831 -64.49956) (xy 287.783508 -64.298347) (xy 287.854846 -64.09972) (xy 287.93374 -63.903972)
			(xy 288.020073 -63.71139) (xy 288.11372 -63.522255) (xy 288.214542 -63.336846) (xy 288.322392 -63.155435)
			(xy 288.437111 -62.978288) (xy 288.558531 -62.805666) (xy 288.686474 -62.63782) (xy 288.820752 -62.474998)
			(xy 288.961168 -62.317439) (xy 289.107516 -62.165374) (xy 289.259581 -62.019026) (xy 289.41714 -61.87861)
			(xy 289.579962 -61.744332) (xy 289.747808 -61.616389) (xy 289.92043 -61.494969) (xy 290.097577 -61.38025)
			(xy 290.278988 -61.2724) (xy 290.464397 -61.171578) (xy 290.653532 -61.077931) (xy 290.846114 -60.991598)
			(xy 291.041862 -60.912704) (xy 291.240489 -60.841366) (xy 291.441702 -60.777689) (xy 291.645206 -60.721765)
			(xy 291.850703 -60.673677) (xy 292.057891 -60.633495) (xy 292.266466 -60.601278) (xy 292.476123 -60.577075)
			(xy 292.686552 -60.560919) (xy 292.897446 -60.552835) (xy 293.108494 -60.552835) (xy 293.319388 -60.560919)
			(xy 293.529817 -60.577075) (xy 293.739474 -60.601278) (xy 293.948049 -60.633495) (xy 294.155237 -60.673677)
			(xy 294.360734 -60.721765) (xy 294.564238 -60.777689) (xy 294.765451 -60.841366) (xy 294.964078 -60.912704)
			(xy 295.159826 -60.991598) (xy 295.352408 -61.077931) (xy 295.541543 -61.171578) (xy 295.726952 -61.2724)
			(xy 295.908363 -61.38025) (xy 295.933976 -61.396837) (xy 316.754504 -61.396837) (xy 316.754504 -61.332915)
			(xy 316.762515 -61.269497) (xy 316.778412 -61.207583) (xy 316.801944 -61.14815) (xy 316.832738 -61.092135)
			(xy 316.870311 -61.04042) (xy 316.914068 -60.993823) (xy 316.963321 -60.953078) (xy 317.017292 -60.918827)
			(xy 317.075131 -60.89161) (xy 317.135924 -60.871857) (xy 317.198714 -60.859879) (xy 317.26251 -60.855866)
			(xy 317.326306 -60.859879) (xy 317.389096 -60.871857) (xy 317.449889 -60.89161) (xy 317.507728 -60.918827)
			(xy 317.561699 -60.953078) (xy 317.610952 -60.993823) (xy 317.654709 -61.04042) (xy 317.692282 -61.092135)
			(xy 317.723076 -61.14815) (xy 317.746608 -61.207583) (xy 317.762505 -61.269497) (xy 317.770516 -61.332915)
			(xy 317.771018 -61.364876) (xy 324.16191 -61.364876) (xy 324.165981 -61.309254) (xy 324.178107 -61.254817)
			(xy 324.19803 -61.202726) (xy 324.225326 -61.154091) (xy 324.259412 -61.109948) (xy 324.299561 -61.071239)
			(xy 324.344919 -61.038788) (xy 324.394519 -61.013287) (xy 324.447303 -60.99528) (xy 324.502146 -60.98515)
			(xy 324.55788 -60.983113) (xy 324.613317 -60.989213) (xy 324.667274 -61.003319) (xy 324.718603 -61.025131)
			(xy 324.766209 -61.054185) (xy 324.809077 -61.08986) (xy 324.846294 -61.131397) (xy 324.877067 -61.17791)
			(xy 324.900739 -61.228407) (xy 324.916807 -61.281814) (xy 324.924927 -61.33699) (xy 324.925436 -61.364876)
			(xy 338.774022 -61.364876) (xy 338.778093 -61.309254) (xy 338.790219 -61.254817) (xy 338.810142 -61.202726)
			(xy 338.837438 -61.154091) (xy 338.871524 -61.109948) (xy 338.911673 -61.071239) (xy 338.957031 -61.038788)
			(xy 339.006631 -61.013287) (xy 339.059415 -60.99528) (xy 339.114258 -60.98515) (xy 339.169992 -60.983113)
			(xy 339.225429 -60.989213) (xy 339.279386 -61.003319) (xy 339.330715 -61.025131) (xy 339.378321 -61.054185)
			(xy 339.421189 -61.08986) (xy 339.458406 -61.131397) (xy 339.489179 -61.17791) (xy 339.512851 -61.228407)
			(xy 339.528919 -61.281814) (xy 339.537039 -61.33699) (xy 339.537548 -61.364876) (xy 339.537039 -61.392762)
			(xy 339.536439 -61.396837) (xy 350.955604 -61.396837) (xy 350.955604 -61.332915) (xy 350.963615 -61.269497)
			(xy 350.979512 -61.207583) (xy 351.003044 -61.14815) (xy 351.033838 -61.092135) (xy 351.071411 -61.04042)
			(xy 351.115168 -60.993823) (xy 351.164421 -60.953078) (xy 351.218392 -60.918827) (xy 351.276231 -60.89161)
			(xy 351.337024 -60.871857) (xy 351.399814 -60.859879) (xy 351.46361 -60.855866) (xy 351.527406 -60.859879)
			(xy 351.590196 -60.871857) (xy 351.650989 -60.89161) (xy 351.708828 -60.918827) (xy 351.762799 -60.953078)
			(xy 351.812052 -60.993823) (xy 351.855809 -61.04042) (xy 351.893382 -61.092135) (xy 351.924176 -61.14815)
			(xy 351.947708 -61.207583) (xy 351.963605 -61.269497) (xy 351.971616 -61.332915) (xy 351.972118 -61.364876)
			(xy 351.971616 -61.396837) (xy 351.963605 -61.460255) (xy 351.947708 -61.522169) (xy 351.924176 -61.581602)
			(xy 351.893382 -61.637617) (xy 351.855809 -61.689332) (xy 351.812052 -61.735929) (xy 351.762799 -61.776674)
			(xy 351.708828 -61.810925) (xy 351.650989 -61.838142) (xy 351.590196 -61.857895) (xy 351.527406 -61.869873)
			(xy 351.46361 -61.873887) (xy 351.399814 -61.869873) (xy 351.337024 -61.857895) (xy 351.276231 -61.838142)
			(xy 351.218392 -61.810925) (xy 351.164421 -61.776674) (xy 351.115168 -61.735929) (xy 351.071411 -61.689332)
			(xy 351.033838 -61.637617) (xy 351.003044 -61.581602) (xy 350.979512 -61.522169) (xy 350.963615 -61.460255)
			(xy 350.955604 -61.396837) (xy 339.536439 -61.396837) (xy 339.528919 -61.447938) (xy 339.512851 -61.501345)
			(xy 339.489179 -61.551842) (xy 339.458406 -61.598355) (xy 339.421189 -61.639892) (xy 339.378321 -61.675567)
			(xy 339.330715 -61.704621) (xy 339.279386 -61.726433) (xy 339.225429 -61.740539) (xy 339.169992 -61.746639)
			(xy 339.114258 -61.744602) (xy 339.059415 -61.734472) (xy 339.006631 -61.716465) (xy 338.957031 -61.690964)
			(xy 338.911673 -61.658513) (xy 338.871524 -61.619804) (xy 338.837438 -61.575661) (xy 338.810142 -61.527026)
			(xy 338.790219 -61.474935) (xy 338.778093 -61.420498) (xy 338.774022 -61.364876) (xy 324.925436 -61.364876)
			(xy 324.924927 -61.392762) (xy 324.916807 -61.447938) (xy 324.900739 -61.501345) (xy 324.877067 -61.551842)
			(xy 324.846294 -61.598355) (xy 324.809077 -61.639892) (xy 324.766209 -61.675567) (xy 324.718603 -61.704621)
			(xy 324.667274 -61.726433) (xy 324.613317 -61.740539) (xy 324.55788 -61.746639) (xy 324.502146 -61.744602)
			(xy 324.447303 -61.734472) (xy 324.394519 -61.716465) (xy 324.344919 -61.690964) (xy 324.299561 -61.658513)
			(xy 324.259412 -61.619804) (xy 324.225326 -61.575661) (xy 324.19803 -61.527026) (xy 324.178107 -61.474935)
			(xy 324.165981 -61.420498) (xy 324.16191 -61.364876) (xy 317.771018 -61.364876) (xy 317.770516 -61.396837)
			(xy 317.762505 -61.460255) (xy 317.746608 -61.522169) (xy 317.723076 -61.581602) (xy 317.692282 -61.637617)
			(xy 317.654709 -61.689332) (xy 317.610952 -61.735929) (xy 317.561699 -61.776674) (xy 317.507728 -61.810925)
			(xy 317.449889 -61.838142) (xy 317.389096 -61.857895) (xy 317.326306 -61.869873) (xy 317.26251 -61.873887)
			(xy 317.198714 -61.869873) (xy 317.135924 -61.857895) (xy 317.075131 -61.838142) (xy 317.017292 -61.810925)
			(xy 316.963321 -61.776674) (xy 316.914068 -61.735929) (xy 316.870311 -61.689332) (xy 316.832738 -61.637617)
			(xy 316.801944 -61.581602) (xy 316.778412 -61.522169) (xy 316.762515 -61.460255) (xy 316.754504 -61.396837)
			(xy 295.933976 -61.396837) (xy 296.08551 -61.494969) (xy 296.258132 -61.616389) (xy 296.425978 -61.744332)
			(xy 296.5888 -61.87861) (xy 296.746359 -62.019026) (xy 296.855538 -62.1241) (xy 357.821472 -62.1241)
			(xy 357.825485 -62.060302) (xy 357.837464 -61.99751) (xy 357.857217 -61.936714) (xy 357.884435 -61.878874)
			(xy 357.918687 -61.824901) (xy 357.959434 -61.775646) (xy 358.006033 -61.731887) (xy 358.057749 -61.694313)
			(xy 358.113766 -61.663517) (xy 358.173202 -61.639985) (xy 358.235118 -61.624088) (xy 358.298538 -61.616076)
			(xy 358.3305 -61.615574) (xy 358.36265 -61.616109) (xy 358.426435 -61.624226) (xy 358.488689 -61.640318)
			(xy 358.548418 -61.664129) (xy 358.604669 -61.695279) (xy 358.656545 -61.73327) (xy 358.703219 -61.777497)
			(xy 358.743946 -61.827254) (xy 358.778076 -61.881748) (xy 358.792018 -61.910722) (xy 358.798403 -61.923394)
			(xy 358.816948 -61.944855) (xy 358.84068 -61.960388) (xy 358.867769 -61.968795) (xy 358.896126 -61.969427)
			(xy 358.923562 -61.962235) (xy 358.947963 -61.947774) (xy 358.967445 -61.92716) (xy 358.97439 -61.914786)
			(xy 358.986791 -61.891849) (xy 359.016865 -61.849255) (xy 359.052459 -61.811152) (xy 359.092909 -61.77825)
			(xy 359.137463 -61.751163) (xy 359.18529 -61.730394) (xy 359.235499 -61.716331) (xy 359.287155 -61.709235)
			(xy 359.313226 -61.708792) (xy 359.340476 -61.70928) (xy 359.394421 -61.717039) (xy 359.446713 -61.732396)
			(xy 359.496287 -61.755039) (xy 359.542134 -61.784506) (xy 359.583321 -61.820198) (xy 359.61901 -61.861387)
			(xy 359.648473 -61.907236) (xy 359.671113 -61.956812) (xy 359.686466 -62.009104) (xy 359.690836 -62.0395)
			(xy 404.190454 -62.0395) (xy 404.190956 -62.007539) (xy 404.198967 -61.944121) (xy 404.214864 -61.882207)
			(xy 404.238396 -61.822774) (xy 404.26919 -61.766759) (xy 404.306763 -61.715044) (xy 404.35052 -61.668447)
			(xy 404.399773 -61.627702) (xy 404.453744 -61.593451) (xy 404.511583 -61.566234) (xy 404.572376 -61.546481)
			(xy 404.635166 -61.534503) (xy 404.698962 -61.53049) (xy 404.762758 -61.534503) (xy 404.825548 -61.546481)
			(xy 404.886341 -61.566234) (xy 404.94418 -61.593451) (xy 404.998151 -61.627702) (xy 405.047404 -61.668447)
			(xy 405.091161 -61.715044) (xy 405.128734 -61.766759) (xy 405.159528 -61.822774) (xy 405.18306 -61.882207)
			(xy 405.198957 -61.944121) (xy 405.206968 -62.007539) (xy 405.20747 -62.0395) (xy 405.206937 -62.073633)
			(xy 405.197815 -62.141288) (xy 405.179721 -62.207113) (xy 405.152981 -62.269924) (xy 405.118075 -62.328592)
			(xy 405.075633 -62.382062) (xy 405.026417 -62.42937) (xy 404.99919 -62.449964) (xy 404.989806 -62.457717)
			(xy 404.978936 -62.479461) (xy 404.978362 -62.49162) (xy 404.979378 -62.57417) (xy 404.980199 -62.586325)
			(xy 404.991627 -62.607807) (xy 405.001222 -62.615318) (xy 405.026051 -62.633211) (xy 405.071715 -62.673958)
			(xy 405.11216 -62.71989) (xy 405.146799 -62.770344) (xy 405.175133 -62.824591) (xy 405.196752 -62.881846)
			(xy 405.211343 -62.941282) (xy 405.218695 -63.00204) (xy 405.219154 -63.03264) (xy 405.218663 -63.063665)
			(xy 405.211105 -63.125253) (xy 405.196107 -63.185464) (xy 405.173891 -63.243401) (xy 405.144788 -63.298203)
			(xy 405.10923 -63.349054) (xy 405.067747 -63.3952) (xy 405.044656 -63.415926) (xy 405.035512 -63.4238)
			(xy 405.026368 -63.446152) (xy 405.035004 -63.551816) (xy 405.04745 -63.57239) (xy 405.057864 -63.57874)
			(xy 405.084977 -63.596199) (xy 405.134971 -63.636934) (xy 405.179415 -63.683661) (xy 405.217596 -63.735631)
			(xy 405.248902 -63.792011) (xy 405.272831 -63.851896) (xy 405.288998 -63.914324) (xy 405.297144 -63.978296)
			(xy 405.29764 -64.01054) (xy 405.297138 -64.042501) (xy 405.289127 -64.105919) (xy 405.27323 -64.167833)
			(xy 405.249698 -64.227266) (xy 405.218904 -64.283281) (xy 405.181331 -64.334996) (xy 405.137574 -64.381593)
			(xy 405.088321 -64.422338) (xy 405.03435 -64.456589) (xy 404.976511 -64.483806) (xy 404.915718 -64.503559)
			(xy 404.852928 -64.515537) (xy 404.789132 -64.519551) (xy 404.725336 -64.515537) (xy 404.662546 -64.503559)
			(xy 404.601753 -64.483806) (xy 404.543914 -64.456589) (xy 404.489943 -64.422338) (xy 404.44069 -64.381593)
			(xy 404.396933 -64.334996) (xy 404.35936 -64.283281) (xy 404.328566 -64.227266) (xy 404.305034 -64.167833)
			(xy 404.289137 -64.105919) (xy 404.281126 -64.042501) (xy 404.280624 -64.01054) (xy 404.281109 -63.979515)
			(xy 404.288669 -63.917926) (xy 404.303669 -63.857716) (xy 404.325886 -63.79978) (xy 404.35499 -63.744978)
			(xy 404.390548 -63.694126) (xy 404.432031 -63.64798) (xy 404.455122 -63.627254) (xy 404.464266 -63.61938)
			(xy 404.47341 -63.597028) (xy 404.464774 -63.491364) (xy 404.452328 -63.47079) (xy 404.441914 -63.46444)
			(xy 404.414787 -63.447002) (xy 404.364794 -63.406264) (xy 404.320351 -63.359533) (xy 404.282172 -63.307559)
			(xy 404.250868 -63.251177) (xy 404.226941 -63.19129) (xy 404.210777 -63.128858) (xy 404.202633 -63.064885)
			(xy 404.202138 -63.03264) (xy 404.202697 -62.998507) (xy 404.211814 -62.930854) (xy 404.229904 -62.865029)
			(xy 404.256639 -62.802218) (xy 404.291541 -62.743549) (xy 404.33398 -62.69008) (xy 404.383193 -62.64277)
			(xy 404.410418 -62.622176) (xy 404.419785 -62.614406) (xy 404.430664 -62.592675) (xy 404.431246 -62.58052)
			(xy 404.43023 -62.49797) (xy 404.429382 -62.485819) (xy 404.417973 -62.464337) (xy 404.408386 -62.456822)
			(xy 404.383531 -62.438964) (xy 404.337867 -62.398213) (xy 404.297423 -62.352275) (xy 404.262786 -62.301816)
			(xy 404.234455 -62.247564) (xy 404.212841 -62.190304) (xy 404.198256 -62.130863) (xy 404.19091 -62.070102)
			(xy 404.190454 -62.0395) (xy 359.690836 -62.0395) (xy 359.694222 -62.06305) (xy 359.694222 -62.11755)
			(xy 359.686466 -62.171496) (xy 359.671113 -62.223788) (xy 359.648473 -62.273364) (xy 359.61901 -62.319213)
			(xy 359.583321 -62.360402) (xy 359.542134 -62.396094) (xy 359.496287 -62.425561) (xy 359.446713 -62.448204)
			(xy 359.394421 -62.463561) (xy 359.340476 -62.47132) (xy 359.313226 -62.471808) (xy 359.285308 -62.471305)
			(xy 359.230068 -62.46317) (xy 359.176604 -62.447069) (xy 359.126058 -62.423348) (xy 359.07951 -62.392511)
			(xy 359.037953 -62.355219) (xy 359.002277 -62.312268) (xy 358.987344 -62.288674) (xy 358.979546 -62.276838)
			(xy 358.958699 -62.257653) (xy 358.933385 -62.244929) (xy 358.905551 -62.239646) (xy 358.877335 -62.24221)
			(xy 358.850909 -62.252424) (xy 358.828303 -62.269502) (xy 358.811256 -62.292131) (xy 358.805734 -62.305184)
			(xy 358.79433 -62.333681) (xy 358.765715 -62.387982) (xy 358.730775 -62.438446) (xy 358.690016 -62.484338)
			(xy 358.64403 -62.524992) (xy 358.593487 -62.559818) (xy 358.53912 -62.588308) (xy 358.48172 -62.610049)
			(xy 358.422121 -62.624725) (xy 358.36119 -62.632123) (xy 358.3305 -62.63259) (xy 358.298538 -62.632124)
			(xy 358.235118 -62.624112) (xy 358.173202 -62.608215) (xy 358.113766 -62.584683) (xy 358.057749 -62.553887)
			(xy 358.006033 -62.516313) (xy 357.959434 -62.472554) (xy 357.918687 -62.423299) (xy 357.884435 -62.369326)
			(xy 357.857217 -62.311486) (xy 357.837464 -62.25069) (xy 357.825485 -62.187898) (xy 357.821472 -62.1241)
			(xy 296.855538 -62.1241) (xy 296.898424 -62.165374) (xy 297.044772 -62.317439) (xy 297.185188 -62.474998)
			(xy 297.319466 -62.63782) (xy 297.341585 -62.666837) (xy 316.754504 -62.666837) (xy 316.754504 -62.602915)
			(xy 316.762515 -62.539497) (xy 316.778412 -62.477583) (xy 316.801944 -62.41815) (xy 316.832738 -62.362135)
			(xy 316.870311 -62.31042) (xy 316.914068 -62.263823) (xy 316.963321 -62.223078) (xy 317.017292 -62.188827)
			(xy 317.075131 -62.16161) (xy 317.135924 -62.141857) (xy 317.198714 -62.129879) (xy 317.26251 -62.125866)
			(xy 317.326306 -62.129879) (xy 317.389096 -62.141857) (xy 317.449889 -62.16161) (xy 317.507728 -62.188827)
			(xy 317.561699 -62.223078) (xy 317.610952 -62.263823) (xy 317.654709 -62.31042) (xy 317.692282 -62.362135)
			(xy 317.723076 -62.41815) (xy 317.746608 -62.477583) (xy 317.762505 -62.539497) (xy 317.770516 -62.602915)
			(xy 317.771018 -62.634876) (xy 324.16191 -62.634876) (xy 324.165981 -62.579254) (xy 324.178107 -62.524817)
			(xy 324.19803 -62.472726) (xy 324.225326 -62.424091) (xy 324.259412 -62.379948) (xy 324.299561 -62.341239)
			(xy 324.344919 -62.308788) (xy 324.394519 -62.283287) (xy 324.447303 -62.26528) (xy 324.502146 -62.25515)
			(xy 324.55788 -62.253113) (xy 324.613317 -62.259213) (xy 324.667274 -62.273319) (xy 324.718603 -62.295131)
			(xy 324.766209 -62.324185) (xy 324.809077 -62.35986) (xy 324.846294 -62.401397) (xy 324.877067 -62.44791)
			(xy 324.900739 -62.498407) (xy 324.916807 -62.551814) (xy 324.924927 -62.60699) (xy 324.925436 -62.634876)
			(xy 338.774022 -62.634876) (xy 338.778093 -62.579254) (xy 338.790219 -62.524817) (xy 338.810142 -62.472726)
			(xy 338.837438 -62.424091) (xy 338.871524 -62.379948) (xy 338.911673 -62.341239) (xy 338.957031 -62.308788)
			(xy 339.006631 -62.283287) (xy 339.059415 -62.26528) (xy 339.114258 -62.25515) (xy 339.169992 -62.253113)
			(xy 339.225429 -62.259213) (xy 339.279386 -62.273319) (xy 339.330715 -62.295131) (xy 339.378321 -62.324185)
			(xy 339.421189 -62.35986) (xy 339.458406 -62.401397) (xy 339.489179 -62.44791) (xy 339.512851 -62.498407)
			(xy 339.528919 -62.551814) (xy 339.537039 -62.60699) (xy 339.537548 -62.634876) (xy 339.537039 -62.662762)
			(xy 339.528919 -62.717938) (xy 339.512851 -62.771345) (xy 339.489179 -62.821842) (xy 339.458406 -62.868355)
			(xy 339.421189 -62.909892) (xy 339.378321 -62.945567) (xy 339.330715 -62.974621) (xy 339.279386 -62.996433)
			(xy 339.225429 -63.010539) (xy 339.169992 -63.016639) (xy 339.114258 -63.014602) (xy 339.059415 -63.004472)
			(xy 339.006631 -62.986465) (xy 338.957031 -62.960964) (xy 338.911673 -62.928513) (xy 338.871524 -62.889804)
			(xy 338.837438 -62.845661) (xy 338.810142 -62.797026) (xy 338.790219 -62.744935) (xy 338.778093 -62.690498)
			(xy 338.774022 -62.634876) (xy 324.925436 -62.634876) (xy 324.924927 -62.662762) (xy 324.916807 -62.717938)
			(xy 324.900739 -62.771345) (xy 324.877067 -62.821842) (xy 324.846294 -62.868355) (xy 324.809077 -62.909892)
			(xy 324.766209 -62.945567) (xy 324.718603 -62.974621) (xy 324.667274 -62.996433) (xy 324.613317 -63.010539)
			(xy 324.55788 -63.016639) (xy 324.502146 -63.014602) (xy 324.447303 -63.004472) (xy 324.394519 -62.986465)
			(xy 324.344919 -62.960964) (xy 324.299561 -62.928513) (xy 324.259412 -62.889804) (xy 324.225326 -62.845661)
			(xy 324.19803 -62.797026) (xy 324.178107 -62.744935) (xy 324.165981 -62.690498) (xy 324.16191 -62.634876)
			(xy 317.771018 -62.634876) (xy 317.770516 -62.666837) (xy 317.762505 -62.730255) (xy 317.746608 -62.792169)
			(xy 317.723076 -62.851602) (xy 317.692282 -62.907617) (xy 317.654709 -62.959332) (xy 317.610952 -63.005929)
			(xy 317.561699 -63.046674) (xy 317.507728 -63.080925) (xy 317.449889 -63.108142) (xy 317.389096 -63.127895)
			(xy 317.326306 -63.139873) (xy 317.26251 -63.143887) (xy 317.198714 -63.139873) (xy 317.135924 -63.127895)
			(xy 317.075131 -63.108142) (xy 317.017292 -63.080925) (xy 316.963321 -63.046674) (xy 316.914068 -63.005929)
			(xy 316.870311 -62.959332) (xy 316.832738 -62.907617) (xy 316.801944 -62.851602) (xy 316.778412 -62.792169)
			(xy 316.762515 -62.730255) (xy 316.754504 -62.666837) (xy 297.341585 -62.666837) (xy 297.447409 -62.805666)
			(xy 297.568829 -62.978288) (xy 297.683548 -63.155435) (xy 297.791398 -63.336846) (xy 297.89222 -63.522255)
			(xy 297.985867 -63.71139) (xy 298.0722 -63.903972) (xy 298.085446 -63.936837) (xy 316.754504 -63.936837)
			(xy 316.754504 -63.872915) (xy 316.762515 -63.809497) (xy 316.778412 -63.747583) (xy 316.801944 -63.68815)
			(xy 316.832738 -63.632135) (xy 316.870311 -63.58042) (xy 316.914068 -63.533823) (xy 316.963321 -63.493078)
			(xy 317.017292 -63.458827) (xy 317.075131 -63.43161) (xy 317.135924 -63.411857) (xy 317.198714 -63.399879)
			(xy 317.26251 -63.395866) (xy 317.326306 -63.399879) (xy 317.389096 -63.411857) (xy 317.449889 -63.43161)
			(xy 317.507728 -63.458827) (xy 317.561699 -63.493078) (xy 317.610952 -63.533823) (xy 317.654709 -63.58042)
			(xy 317.692282 -63.632135) (xy 317.723076 -63.68815) (xy 317.746608 -63.747583) (xy 317.762505 -63.809497)
			(xy 317.770516 -63.872915) (xy 317.771018 -63.904876) (xy 324.16191 -63.904876) (xy 324.165981 -63.849254)
			(xy 324.178107 -63.794817) (xy 324.19803 -63.742726) (xy 324.225326 -63.694091) (xy 324.259412 -63.649948)
			(xy 324.299561 -63.611239) (xy 324.344919 -63.578788) (xy 324.394519 -63.553287) (xy 324.447303 -63.53528)
			(xy 324.502146 -63.52515) (xy 324.55788 -63.523113) (xy 324.613317 -63.529213) (xy 324.667274 -63.543319)
			(xy 324.718603 -63.565131) (xy 324.766209 -63.594185) (xy 324.809077 -63.62986) (xy 324.846294 -63.671397)
			(xy 324.877067 -63.71791) (xy 324.900739 -63.768407) (xy 324.916807 -63.821814) (xy 324.924927 -63.87699)
			(xy 324.925436 -63.904876) (xy 338.774022 -63.904876) (xy 338.778093 -63.849254) (xy 338.790219 -63.794817)
			(xy 338.810142 -63.742726) (xy 338.837438 -63.694091) (xy 338.871524 -63.649948) (xy 338.911673 -63.611239)
			(xy 338.957031 -63.578788) (xy 339.006631 -63.553287) (xy 339.059415 -63.53528) (xy 339.114258 -63.52515)
			(xy 339.169992 -63.523113) (xy 339.225429 -63.529213) (xy 339.279386 -63.543319) (xy 339.330715 -63.565131)
			(xy 339.378321 -63.594185) (xy 339.421189 -63.62986) (xy 339.458406 -63.671397) (xy 339.489179 -63.71791)
			(xy 339.512851 -63.768407) (xy 339.528525 -63.820505) (xy 353.898702 -63.820505) (xy 353.898702 -63.756583)
			(xy 353.906713 -63.693165) (xy 353.92261 -63.631251) (xy 353.946142 -63.571818) (xy 353.976936 -63.515803)
			(xy 354.014509 -63.464088) (xy 354.058266 -63.417491) (xy 354.107519 -63.376746) (xy 354.16149 -63.342495)
			(xy 354.219329 -63.315278) (xy 354.280122 -63.295525) (xy 354.342912 -63.283547) (xy 354.406708 -63.279534)
			(xy 354.470504 -63.283547) (xy 354.533294 -63.295525) (xy 354.594087 -63.315278) (xy 354.651926 -63.342495)
			(xy 354.705897 -63.376746) (xy 354.75515 -63.417491) (xy 354.798907 -63.464088) (xy 354.83648 -63.515803)
			(xy 354.867274 -63.571818) (xy 354.890806 -63.631251) (xy 354.906703 -63.693165) (xy 354.914714 -63.756583)
			(xy 354.915216 -63.788544) (xy 354.914714 -63.820505) (xy 354.906703 -63.883923) (xy 354.890806 -63.945837)
			(xy 354.867274 -64.00527) (xy 354.83648 -64.061285) (xy 354.798907 -64.113) (xy 354.75515 -64.159597)
			(xy 354.705897 -64.200342) (xy 354.651926 -64.234593) (xy 354.594087 -64.26181) (xy 354.533294 -64.281563)
			(xy 354.470504 -64.293541) (xy 354.406708 -64.297555) (xy 354.342912 -64.293541) (xy 354.280122 -64.281563)
			(xy 354.219329 -64.26181) (xy 354.16149 -64.234593) (xy 354.107519 -64.200342) (xy 354.058266 -64.159597)
			(xy 354.014509 -64.113) (xy 353.976936 -64.061285) (xy 353.946142 -64.00527) (xy 353.92261 -63.945837)
			(xy 353.906713 -63.883923) (xy 353.898702 -63.820505) (xy 339.528525 -63.820505) (xy 339.528919 -63.821814)
			(xy 339.537039 -63.87699) (xy 339.537548 -63.904876) (xy 339.537039 -63.932762) (xy 339.528919 -63.987938)
			(xy 339.512851 -64.041345) (xy 339.489179 -64.091842) (xy 339.458406 -64.138355) (xy 339.421189 -64.179892)
			(xy 339.378321 -64.215567) (xy 339.330715 -64.244621) (xy 339.279386 -64.266433) (xy 339.225429 -64.280539)
			(xy 339.169992 -64.286639) (xy 339.114258 -64.284602) (xy 339.059415 -64.274472) (xy 339.006631 -64.256465)
			(xy 338.957031 -64.230964) (xy 338.911673 -64.198513) (xy 338.871524 -64.159804) (xy 338.837438 -64.115661)
			(xy 338.810142 -64.067026) (xy 338.790219 -64.014935) (xy 338.778093 -63.960498) (xy 338.774022 -63.904876)
			(xy 324.925436 -63.904876) (xy 324.924927 -63.932762) (xy 324.916807 -63.987938) (xy 324.900739 -64.041345)
			(xy 324.877067 -64.091842) (xy 324.846294 -64.138355) (xy 324.809077 -64.179892) (xy 324.766209 -64.215567)
			(xy 324.718603 -64.244621) (xy 324.667274 -64.266433) (xy 324.613317 -64.280539) (xy 324.55788 -64.286639)
			(xy 324.502146 -64.284602) (xy 324.447303 -64.274472) (xy 324.394519 -64.256465) (xy 324.344919 -64.230964)
			(xy 324.299561 -64.198513) (xy 324.259412 -64.159804) (xy 324.225326 -64.115661) (xy 324.19803 -64.067026)
			(xy 324.178107 -64.014935) (xy 324.165981 -63.960498) (xy 324.16191 -63.904876) (xy 317.771018 -63.904876)
			(xy 317.770516 -63.936837) (xy 317.762505 -64.000255) (xy 317.746608 -64.062169) (xy 317.723076 -64.121602)
			(xy 317.692282 -64.177617) (xy 317.654709 -64.229332) (xy 317.610952 -64.275929) (xy 317.561699 -64.316674)
			(xy 317.507728 -64.350925) (xy 317.449889 -64.378142) (xy 317.389096 -64.397895) (xy 317.326306 -64.409873)
			(xy 317.26251 -64.413887) (xy 317.198714 -64.409873) (xy 317.135924 -64.397895) (xy 317.075131 -64.378142)
			(xy 317.017292 -64.350925) (xy 316.963321 -64.316674) (xy 316.914068 -64.275929) (xy 316.870311 -64.229332)
			(xy 316.832738 -64.177617) (xy 316.801944 -64.121602) (xy 316.778412 -64.062169) (xy 316.762515 -64.000255)
			(xy 316.754504 -63.936837) (xy 298.085446 -63.936837) (xy 298.151094 -64.09972) (xy 298.222432 -64.298347)
			(xy 298.286109 -64.49956) (xy 298.287416 -64.504316) (xy 384.008884 -64.504316) (xy 384.009373 -64.477707)
			(xy 384.016742 -64.425001) (xy 384.031368 -64.373832) (xy 384.052966 -64.325193) (xy 384.081116 -64.28003)
			(xy 384.115273 -64.239219) (xy 384.154771 -64.203553) (xy 384.198845 -64.173726) (xy 384.246638 -64.150316)
			(xy 384.297221 -64.133778) (xy 384.323336 -64.12865) (xy 384.333242 -64.126872) (xy 384.349498 -64.116712)
			(xy 384.402584 -64.044322) (xy 384.40741 -64.025526) (xy 384.40614 -64.015874) (xy 384.4047 -64.003734)
			(xy 384.403176 -63.979331) (xy 384.403092 -63.967106) (xy 384.403565 -63.940496) (xy 384.410936 -63.887789)
			(xy 384.425563 -63.83662) (xy 384.447163 -63.78798) (xy 384.475315 -63.742817) (xy 384.509473 -63.702006)
			(xy 384.548974 -63.666341) (xy 384.593049 -63.636513) (xy 384.640844 -63.613104) (xy 384.691429 -63.596567)
			(xy 384.717544 -63.59144) (xy 384.72745 -63.589662) (xy 384.743706 -63.579502) (xy 384.796792 -63.507112)
			(xy 384.801618 -63.488316) (xy 384.800348 -63.478664) (xy 384.798907 -63.466524) (xy 384.797384 -63.442121)
			(xy 384.7973 -63.429896) (xy 384.797786 -63.402645) (xy 384.805542 -63.348697) (xy 384.820897 -63.296402)
			(xy 384.843539 -63.246825) (xy 384.873005 -63.200975) (xy 384.908696 -63.159784) (xy 384.949887 -63.124093)
			(xy 384.995737 -63.094627) (xy 385.045314 -63.071985) (xy 385.097609 -63.05663) (xy 385.151557 -63.048874)
			(xy 385.206059 -63.048874) (xy 385.260007 -63.05663) (xy 385.312302 -63.071985) (xy 385.361879 -63.094627)
			(xy 385.407729 -63.124093) (xy 385.44892 -63.159784) (xy 385.484611 -63.200975) (xy 385.514077 -63.246825)
			(xy 385.536719 -63.296402) (xy 385.552074 -63.348697) (xy 385.55983 -63.402645) (xy 385.560316 -63.429896)
			(xy 385.559838 -63.456506) (xy 385.552467 -63.509212) (xy 385.53784 -63.560381) (xy 385.516241 -63.60902)
			(xy 385.488089 -63.654183) (xy 385.453931 -63.694994) (xy 385.414432 -63.73066) (xy 385.370357 -63.760487)
			(xy 385.322563 -63.783897) (xy 385.271979 -63.800434) (xy 385.245864 -63.805562) (xy 385.235958 -63.80734)
			(xy 385.219702 -63.8175) (xy 385.166616 -63.88989) (xy 385.16179 -63.908686) (xy 385.16306 -63.918338)
			(xy 385.164501 -63.930478) (xy 385.166024 -63.954881) (xy 385.166108 -63.967106) (xy 385.165646 -63.993716)
			(xy 385.158273 -64.046423) (xy 385.143645 -64.097593) (xy 385.122044 -64.146233) (xy 385.09389 -64.191396)
			(xy 385.059731 -64.232207) (xy 385.020229 -64.267872) (xy 384.976153 -64.297699) (xy 384.928357 -64.321108)
			(xy 384.877772 -64.337645) (xy 384.851656 -64.342772) (xy 384.84175 -64.34455) (xy 384.825494 -64.35471)
			(xy 384.772408 -64.4271) (xy 384.767582 -64.445896) (xy 384.768852 -64.455548) (xy 384.770294 -64.467688)
			(xy 384.771816 -64.492091) (xy 384.7719 -64.504316) (xy 384.771414 -64.531567) (xy 384.764523 -64.5795)
			(xy 398.907 -64.5795) (xy 398.907438 -64.548768) (xy 398.914846 -64.487751) (xy 398.929556 -64.428072)
			(xy 398.951352 -64.370602) (xy 398.979916 -64.316177) (xy 399.014833 -64.265593) (xy 399.055592 -64.219586)
			(xy 399.101599 -64.178828) (xy 399.152184 -64.143912) (xy 399.206609 -64.115349) (xy 399.26408 -64.093554)
			(xy 399.323759 -64.078845) (xy 399.384776 -64.071437) (xy 399.415508 -64.070992) (xy 399.415762 -64.070992)
			(xy 399.427782 -64.071062) (xy 399.451796 -64.072206) (xy 399.463768 -64.073278) (xy 399.464022 -64.073278)
			(xy 399.476533 -64.073735) (xy 399.499576 -64.064028) (xy 399.507964 -64.054736) (xy 399.569432 -63.979044)
			(xy 399.574258 -63.954152) (xy 399.570448 -63.94196) (xy 399.562387 -63.914335) (xy 399.553717 -63.857448)
			(xy 399.553176 -63.828676) (xy 399.553662 -63.801425) (xy 399.561418 -63.747477) (xy 399.576773 -63.695182)
			(xy 399.599415 -63.645605) (xy 399.628881 -63.599755) (xy 399.664572 -63.558564) (xy 399.705763 -63.522873)
			(xy 399.751613 -63.493407) (xy 399.80119 -63.470765) (xy 399.853485 -63.45541) (xy 399.907433 -63.447654)
			(xy 399.961935 -63.447654) (xy 400.015883 -63.45541) (xy 400.068178 -63.470765) (xy 400.117755 -63.493407)
			(xy 400.163605 -63.522873) (xy 400.204796 -63.558564) (xy 400.240487 -63.599755) (xy 400.269953 -63.645605)
			(xy 400.292595 -63.695182) (xy 400.30795 -63.747477) (xy 400.315706 -63.801425) (xy 400.316192 -63.828676)
			(xy 400.315655 -63.857517) (xy 400.306947 -63.914539) (xy 400.289756 -63.969601) (xy 400.264473 -64.021448)
			(xy 400.231675 -64.068899) (xy 400.192108 -64.110874) (xy 400.146675 -64.146414) (xy 400.09641 -64.174712)
			(xy 400.042458 -64.195122) (xy 399.986049 -64.20718) (xy 399.95729 -64.209422) (xy 399.957036 -64.209422)
			(xy 399.944579 -64.210897) (xy 399.923269 -64.224075) (xy 399.916396 -64.234568) (xy 399.873724 -64.307466)
			(xy 399.867961 -64.318763) (xy 399.86717 -64.344083) (xy 399.8722 -64.355726) (xy 399.884581 -64.381886)
			(xy 399.903978 -64.436418) (xy 399.917046 -64.492802) (xy 399.923614 -64.550307) (xy 399.924016 -64.579246)
			(xy 399.924016 -64.5795) (xy 399.923558 -64.610275) (xy 399.916134 -64.671376) (xy 399.901384 -64.731133)
			(xy 399.879524 -64.78867) (xy 399.850872 -64.843146) (xy 399.81585 -64.893761) (xy 399.795746 -64.917066)
			(xy 399.789396 -64.924178) (xy 399.782792 -64.941958) (xy 399.784062 -65.02019) (xy 399.784603 -65.029511)
			(xy 399.791497 -65.046843) (xy 399.797524 -65.053972) (xy 399.797778 -65.054226) (xy 399.819368 -65.07786)
			(xy 399.857035 -65.129618) (xy 399.887909 -65.185694) (xy 399.911501 -65.245202) (xy 399.92744 -65.307199)
			(xy 399.935471 -65.370707) (xy 399.935954 -65.402714) (xy 399.935452 -65.434675) (xy 399.927441 -65.498093)
			(xy 399.911544 -65.560007) (xy 399.888012 -65.61944) (xy 399.857218 -65.675455) (xy 399.819645 -65.72717)
			(xy 399.775888 -65.773767) (xy 399.726635 -65.814512) (xy 399.672664 -65.848763) (xy 399.614825 -65.87598)
			(xy 399.554032 -65.895733) (xy 399.491242 -65.907711) (xy 399.427446 -65.911725) (xy 399.36365 -65.907711)
			(xy 399.30086 -65.895733) (xy 399.240067 -65.87598) (xy 399.182228 -65.848763) (xy 399.128257 -65.814512)
			(xy 399.079004 -65.773767) (xy 399.035247 -65.72717) (xy 398.997674 -65.675455) (xy 398.96688 -65.61944)
			(xy 398.943348 -65.560007) (xy 398.927451 -65.498093) (xy 398.91944 -65.434675) (xy 398.918938 -65.402714)
			(xy 398.919356 -65.371938) (xy 398.926789 -65.310835) (xy 398.941547 -65.251078) (xy 398.963416 -65.193541)
			(xy 398.992074 -65.139067) (xy 399.027101 -65.088453) (xy 399.047208 -65.065148) (xy 399.053558 -65.058036)
			(xy 399.060162 -65.040256) (xy 399.058892 -64.962024) (xy 399.058356 -64.952702) (xy 399.05146 -64.93537)
			(xy 399.04543 -64.928242) (xy 399.045176 -64.927988) (xy 399.023585 -64.904356) (xy 398.98592 -64.852596)
			(xy 398.955047 -64.796519) (xy 398.931455 -64.737012) (xy 398.915516 -64.675014) (xy 398.907484 -64.611507)
			(xy 398.907 -64.5795) (xy 384.764523 -64.5795) (xy 384.763658 -64.585515) (xy 384.748303 -64.63781)
			(xy 384.725661 -64.687387) (xy 384.696195 -64.733237) (xy 384.660504 -64.774428) (xy 384.619313 -64.810119)
			(xy 384.573463 -64.839585) (xy 384.523886 -64.862227) (xy 384.471591 -64.877582) (xy 384.417643 -64.885338)
			(xy 384.363141 -64.885338) (xy 384.309193 -64.877582) (xy 384.256898 -64.862227) (xy 384.207321 -64.839585)
			(xy 384.161471 -64.810119) (xy 384.12028 -64.774428) (xy 384.084589 -64.733237) (xy 384.055123 -64.687387)
			(xy 384.032481 -64.63781) (xy 384.017126 -64.585515) (xy 384.00937 -64.531567) (xy 384.008884 -64.504316)
			(xy 298.287416 -64.504316) (xy 298.342033 -64.703064) (xy 298.390121 -64.908561) (xy 298.425407 -65.090505)
			(xy 353.898702 -65.090505) (xy 353.898702 -65.026583) (xy 353.906713 -64.963165) (xy 353.92261 -64.901251)
			(xy 353.946142 -64.841818) (xy 353.976936 -64.785803) (xy 354.014509 -64.734088) (xy 354.058266 -64.687491)
			(xy 354.107519 -64.646746) (xy 354.16149 -64.612495) (xy 354.219329 -64.585278) (xy 354.280122 -64.565525)
			(xy 354.342912 -64.553547) (xy 354.406708 -64.549534) (xy 354.470504 -64.553547) (xy 354.533294 -64.565525)
			(xy 354.594087 -64.585278) (xy 354.651926 -64.612495) (xy 354.705897 -64.646746) (xy 354.75515 -64.687491)
			(xy 354.798907 -64.734088) (xy 354.83648 -64.785803) (xy 354.867274 -64.841818) (xy 354.890806 -64.901251)
			(xy 354.906703 -64.963165) (xy 354.914714 -65.026583) (xy 354.915216 -65.058544) (xy 354.914714 -65.090505)
			(xy 354.906703 -65.153923) (xy 354.890806 -65.215837) (xy 354.867274 -65.27527) (xy 354.83648 -65.331285)
			(xy 354.798907 -65.383) (xy 354.75515 -65.429597) (xy 354.705897 -65.470342) (xy 354.651926 -65.504593)
			(xy 354.594087 -65.53181) (xy 354.533294 -65.551563) (xy 354.470504 -65.563541) (xy 354.406708 -65.567555)
			(xy 354.342912 -65.563541) (xy 354.280122 -65.551563) (xy 354.219329 -65.53181) (xy 354.16149 -65.504593)
			(xy 354.107519 -65.470342) (xy 354.058266 -65.429597) (xy 354.014509 -65.383) (xy 353.976936 -65.331285)
			(xy 353.946142 -65.27527) (xy 353.92261 -65.215837) (xy 353.906713 -65.153923) (xy 353.898702 -65.090505)
			(xy 298.425407 -65.090505) (xy 298.430303 -65.115749) (xy 298.46252 -65.324324) (xy 298.486723 -65.533981)
			(xy 298.501369 -65.724743) (xy 313.96787 -65.724743) (xy 313.96787 -65.660821) (xy 313.975881 -65.597403)
			(xy 313.991778 -65.535489) (xy 314.01531 -65.476056) (xy 314.046104 -65.420041) (xy 314.083677 -65.368326)
			(xy 314.127434 -65.321729) (xy 314.176687 -65.280984) (xy 314.230658 -65.246733) (xy 314.288497 -65.219516)
			(xy 314.34929 -65.199763) (xy 314.41208 -65.187785) (xy 314.475876 -65.183772) (xy 314.539672 -65.187785)
			(xy 314.602462 -65.199763) (xy 314.663255 -65.219516) (xy 314.721094 -65.246733) (xy 314.775065 -65.280984)
			(xy 314.824318 -65.321729) (xy 314.868075 -65.368326) (xy 314.905648 -65.420041) (xy 314.936442 -65.476056)
			(xy 314.959974 -65.535489) (xy 314.975871 -65.597403) (xy 314.983882 -65.660821) (xy 314.984384 -65.692782)
			(xy 314.983882 -65.724743) (xy 315.99987 -65.724743) (xy 315.99987 -65.660821) (xy 316.007881 -65.597403)
			(xy 316.023778 -65.535489) (xy 316.04731 -65.476056) (xy 316.078104 -65.420041) (xy 316.115677 -65.368326)
			(xy 316.159434 -65.321729) (xy 316.208687 -65.280984) (xy 316.262658 -65.246733) (xy 316.320497 -65.219516)
			(xy 316.38129 -65.199763) (xy 316.44408 -65.187785) (xy 316.507876 -65.183772) (xy 316.571672 -65.187785)
			(xy 316.634462 -65.199763) (xy 316.695255 -65.219516) (xy 316.753094 -65.246733) (xy 316.807065 -65.280984)
			(xy 316.856318 -65.321729) (xy 316.900075 -65.368326) (xy 316.937648 -65.420041) (xy 316.968442 -65.476056)
			(xy 316.991974 -65.535489) (xy 317.007871 -65.597403) (xy 317.015882 -65.660821) (xy 317.016384 -65.692782)
			(xy 317.015882 -65.724743) (xy 317.007871 -65.788161) (xy 316.991974 -65.850075) (xy 316.968442 -65.909508)
			(xy 316.937648 -65.965523) (xy 316.900075 -66.017238) (xy 316.856318 -66.063835) (xy 316.807065 -66.10458)
			(xy 316.753094 -66.138831) (xy 316.695255 -66.166048) (xy 316.634462 -66.185801) (xy 316.571672 -66.197779)
			(xy 316.507876 -66.201793) (xy 316.44408 -66.197779) (xy 316.38129 -66.185801) (xy 316.320497 -66.166048)
			(xy 316.262658 -66.138831) (xy 316.208687 -66.10458) (xy 316.159434 -66.063835) (xy 316.115677 -66.017238)
			(xy 316.078104 -65.965523) (xy 316.04731 -65.909508) (xy 316.023778 -65.850075) (xy 316.007881 -65.788161)
			(xy 315.99987 -65.724743) (xy 314.983882 -65.724743) (xy 314.975871 -65.788161) (xy 314.959974 -65.850075)
			(xy 314.936442 -65.909508) (xy 314.905648 -65.965523) (xy 314.868075 -66.017238) (xy 314.824318 -66.063835)
			(xy 314.775065 -66.10458) (xy 314.721094 -66.138831) (xy 314.663255 -66.166048) (xy 314.602462 -66.185801)
			(xy 314.539672 -66.197779) (xy 314.475876 -66.201793) (xy 314.41208 -66.197779) (xy 314.34929 -66.185801)
			(xy 314.288497 -66.166048) (xy 314.230658 -66.138831) (xy 314.176687 -66.10458) (xy 314.127434 -66.063835)
			(xy 314.083677 -66.017238) (xy 314.046104 -65.965523) (xy 314.01531 -65.909508) (xy 313.991778 -65.850075)
			(xy 313.975881 -65.788161) (xy 313.96787 -65.724743) (xy 298.501369 -65.724743) (xy 298.502879 -65.74441)
			(xy 298.510963 -65.955304) (xy 298.511468 -66.060828) (xy 298.511468 -68.359993) (xy 307.87187 -68.359993)
			(xy 307.87187 -68.296071) (xy 307.879881 -68.232653) (xy 307.895778 -68.170739) (xy 307.91931 -68.111306)
			(xy 307.950104 -68.055291) (xy 307.987677 -68.003576) (xy 308.031434 -67.956979) (xy 308.080687 -67.916234)
			(xy 308.134658 -67.881983) (xy 308.192497 -67.854766) (xy 308.25329 -67.835013) (xy 308.31608 -67.823035)
			(xy 308.379876 -67.819022) (xy 308.443672 -67.823035) (xy 308.506462 -67.835013) (xy 308.567255 -67.854766)
			(xy 308.625094 -67.881983) (xy 308.679065 -67.916234) (xy 308.728318 -67.956979) (xy 308.772075 -68.003576)
			(xy 308.809648 -68.055291) (xy 308.840442 -68.111306) (xy 308.863974 -68.170739) (xy 308.879871 -68.232653)
			(xy 308.887882 -68.296071) (xy 308.888384 -68.328032) (xy 308.887882 -68.359993) (xy 309.90387 -68.359993)
			(xy 309.90387 -68.296071) (xy 309.911881 -68.232653) (xy 309.927778 -68.170739) (xy 309.95131 -68.111306)
			(xy 309.982104 -68.055291) (xy 310.019677 -68.003576) (xy 310.063434 -67.956979) (xy 310.112687 -67.916234)
			(xy 310.166658 -67.881983) (xy 310.224497 -67.854766) (xy 310.28529 -67.835013) (xy 310.34808 -67.823035)
			(xy 310.411876 -67.819022) (xy 310.475672 -67.823035) (xy 310.538462 -67.835013) (xy 310.599255 -67.854766)
			(xy 310.657094 -67.881983) (xy 310.711065 -67.916234) (xy 310.760318 -67.956979) (xy 310.804075 -68.003576)
			(xy 310.841648 -68.055291) (xy 310.872442 -68.111306) (xy 310.895974 -68.170739) (xy 310.911871 -68.232653)
			(xy 310.919882 -68.296071) (xy 310.920384 -68.328032) (xy 310.919882 -68.359993) (xy 311.93587 -68.359993)
			(xy 311.93587 -68.296071) (xy 311.943881 -68.232653) (xy 311.959778 -68.170739) (xy 311.98331 -68.111306)
			(xy 312.014104 -68.055291) (xy 312.051677 -68.003576) (xy 312.095434 -67.956979) (xy 312.144687 -67.916234)
			(xy 312.198658 -67.881983) (xy 312.256497 -67.854766) (xy 312.31729 -67.835013) (xy 312.38008 -67.823035)
			(xy 312.443876 -67.819022) (xy 312.507672 -67.823035) (xy 312.570462 -67.835013) (xy 312.631255 -67.854766)
			(xy 312.689094 -67.881983) (xy 312.743065 -67.916234) (xy 312.792318 -67.956979) (xy 312.836075 -68.003576)
			(xy 312.873648 -68.055291) (xy 312.904442 -68.111306) (xy 312.927974 -68.170739) (xy 312.943871 -68.232653)
			(xy 312.951882 -68.296071) (xy 312.952384 -68.328032) (xy 312.951882 -68.359993) (xy 313.96787 -68.359993)
			(xy 313.96787 -68.296071) (xy 313.975881 -68.232653) (xy 313.991778 -68.170739) (xy 314.01531 -68.111306)
			(xy 314.046104 -68.055291) (xy 314.083677 -68.003576) (xy 314.127434 -67.956979) (xy 314.176687 -67.916234)
			(xy 314.230658 -67.881983) (xy 314.288497 -67.854766) (xy 314.34929 -67.835013) (xy 314.41208 -67.823035)
			(xy 314.475876 -67.819022) (xy 314.539672 -67.823035) (xy 314.602462 -67.835013) (xy 314.663255 -67.854766)
			(xy 314.721094 -67.881983) (xy 314.775065 -67.916234) (xy 314.824318 -67.956979) (xy 314.868075 -68.003576)
			(xy 314.905648 -68.055291) (xy 314.936442 -68.111306) (xy 314.959974 -68.170739) (xy 314.975871 -68.232653)
			(xy 314.983882 -68.296071) (xy 314.984384 -68.328032) (xy 314.983882 -68.359993) (xy 315.99987 -68.359993)
			(xy 315.99987 -68.296071) (xy 316.007881 -68.232653) (xy 316.023778 -68.170739) (xy 316.04731 -68.111306)
			(xy 316.078104 -68.055291) (xy 316.115677 -68.003576) (xy 316.159434 -67.956979) (xy 316.208687 -67.916234)
			(xy 316.262658 -67.881983) (xy 316.320497 -67.854766) (xy 316.38129 -67.835013) (xy 316.44408 -67.823035)
			(xy 316.507876 -67.819022) (xy 316.571672 -67.823035) (xy 316.634462 -67.835013) (xy 316.695255 -67.854766)
			(xy 316.753094 -67.881983) (xy 316.807065 -67.916234) (xy 316.856318 -67.956979) (xy 316.900075 -68.003576)
			(xy 316.937648 -68.055291) (xy 316.968442 -68.111306) (xy 316.991974 -68.170739) (xy 317.007871 -68.232653)
			(xy 317.015882 -68.296071) (xy 317.016384 -68.328032) (xy 317.015882 -68.359993) (xy 318.03187 -68.359993)
			(xy 318.03187 -68.296071) (xy 318.039881 -68.232653) (xy 318.055778 -68.170739) (xy 318.07931 -68.111306)
			(xy 318.110104 -68.055291) (xy 318.147677 -68.003576) (xy 318.191434 -67.956979) (xy 318.240687 -67.916234)
			(xy 318.294658 -67.881983) (xy 318.352497 -67.854766) (xy 318.41329 -67.835013) (xy 318.47608 -67.823035)
			(xy 318.539876 -67.819022) (xy 318.603672 -67.823035) (xy 318.666462 -67.835013) (xy 318.727255 -67.854766)
			(xy 318.785094 -67.881983) (xy 318.839065 -67.916234) (xy 318.888318 -67.956979) (xy 318.932075 -68.003576)
			(xy 318.969648 -68.055291) (xy 319.000442 -68.111306) (xy 319.023974 -68.170739) (xy 319.039871 -68.232653)
			(xy 319.047882 -68.296071) (xy 319.048384 -68.328032) (xy 319.047882 -68.359993) (xy 320.06387 -68.359993)
			(xy 320.06387 -68.296071) (xy 320.071881 -68.232653) (xy 320.087778 -68.170739) (xy 320.11131 -68.111306)
			(xy 320.142104 -68.055291) (xy 320.179677 -68.003576) (xy 320.223434 -67.956979) (xy 320.272687 -67.916234)
			(xy 320.326658 -67.881983) (xy 320.384497 -67.854766) (xy 320.44529 -67.835013) (xy 320.50808 -67.823035)
			(xy 320.571876 -67.819022) (xy 320.635672 -67.823035) (xy 320.698462 -67.835013) (xy 320.759255 -67.854766)
			(xy 320.817094 -67.881983) (xy 320.871065 -67.916234) (xy 320.920318 -67.956979) (xy 320.964075 -68.003576)
			(xy 321.001648 -68.055291) (xy 321.032442 -68.111306) (xy 321.055974 -68.170739) (xy 321.071871 -68.232653)
			(xy 321.079882 -68.296071) (xy 321.080384 -68.328032) (xy 321.079882 -68.359993) (xy 322.09587 -68.359993)
			(xy 322.09587 -68.296071) (xy 322.103881 -68.232653) (xy 322.119778 -68.170739) (xy 322.14331 -68.111306)
			(xy 322.174104 -68.055291) (xy 322.211677 -68.003576) (xy 322.255434 -67.956979) (xy 322.304687 -67.916234)
			(xy 322.358658 -67.881983) (xy 322.416497 -67.854766) (xy 322.47729 -67.835013) (xy 322.54008 -67.823035)
			(xy 322.603876 -67.819022) (xy 322.667672 -67.823035) (xy 322.730462 -67.835013) (xy 322.791255 -67.854766)
			(xy 322.849094 -67.881983) (xy 322.903065 -67.916234) (xy 322.952318 -67.956979) (xy 322.996075 -68.003576)
			(xy 323.033648 -68.055291) (xy 323.064442 -68.111306) (xy 323.087974 -68.170739) (xy 323.103871 -68.232653)
			(xy 323.111882 -68.296071) (xy 323.112384 -68.328032) (xy 323.111882 -68.359993) (xy 324.12787 -68.359993)
			(xy 324.12787 -68.296071) (xy 324.135881 -68.232653) (xy 324.151778 -68.170739) (xy 324.17531 -68.111306)
			(xy 324.206104 -68.055291) (xy 324.243677 -68.003576) (xy 324.287434 -67.956979) (xy 324.336687 -67.916234)
			(xy 324.390658 -67.881983) (xy 324.448497 -67.854766) (xy 324.50929 -67.835013) (xy 324.57208 -67.823035)
			(xy 324.635876 -67.819022) (xy 324.699672 -67.823035) (xy 324.762462 -67.835013) (xy 324.823255 -67.854766)
			(xy 324.881094 -67.881983) (xy 324.935065 -67.916234) (xy 324.984318 -67.956979) (xy 325.028075 -68.003576)
			(xy 325.065648 -68.055291) (xy 325.096442 -68.111306) (xy 325.119974 -68.170739) (xy 325.135871 -68.232653)
			(xy 325.143882 -68.296071) (xy 325.144384 -68.328032) (xy 325.143882 -68.359993) (xy 326.15987 -68.359993)
			(xy 326.15987 -68.296071) (xy 326.167881 -68.232653) (xy 326.183778 -68.170739) (xy 326.20731 -68.111306)
			(xy 326.238104 -68.055291) (xy 326.275677 -68.003576) (xy 326.319434 -67.956979) (xy 326.368687 -67.916234)
			(xy 326.422658 -67.881983) (xy 326.480497 -67.854766) (xy 326.54129 -67.835013) (xy 326.60408 -67.823035)
			(xy 326.667876 -67.819022) (xy 326.731672 -67.823035) (xy 326.794462 -67.835013) (xy 326.855255 -67.854766)
			(xy 326.913094 -67.881983) (xy 326.967065 -67.916234) (xy 327.016318 -67.956979) (xy 327.060075 -68.003576)
			(xy 327.097648 -68.055291) (xy 327.128442 -68.111306) (xy 327.151974 -68.170739) (xy 327.167871 -68.232653)
			(xy 327.175882 -68.296071) (xy 327.176384 -68.328032) (xy 327.175882 -68.359993) (xy 328.19187 -68.359993)
			(xy 328.19187 -68.296071) (xy 328.199881 -68.232653) (xy 328.215778 -68.170739) (xy 328.23931 -68.111306)
			(xy 328.270104 -68.055291) (xy 328.307677 -68.003576) (xy 328.351434 -67.956979) (xy 328.400687 -67.916234)
			(xy 328.454658 -67.881983) (xy 328.512497 -67.854766) (xy 328.57329 -67.835013) (xy 328.63608 -67.823035)
			(xy 328.699876 -67.819022) (xy 328.763672 -67.823035) (xy 328.826462 -67.835013) (xy 328.887255 -67.854766)
			(xy 328.945094 -67.881983) (xy 328.999065 -67.916234) (xy 329.048318 -67.956979) (xy 329.092075 -68.003576)
			(xy 329.129648 -68.055291) (xy 329.160442 -68.111306) (xy 329.183974 -68.170739) (xy 329.199871 -68.232653)
			(xy 329.207882 -68.296071) (xy 329.208384 -68.328032) (xy 329.207882 -68.359993) (xy 330.22387 -68.359993)
			(xy 330.22387 -68.296071) (xy 330.231881 -68.232653) (xy 330.247778 -68.170739) (xy 330.27131 -68.111306)
			(xy 330.302104 -68.055291) (xy 330.339677 -68.003576) (xy 330.383434 -67.956979) (xy 330.432687 -67.916234)
			(xy 330.486658 -67.881983) (xy 330.544497 -67.854766) (xy 330.60529 -67.835013) (xy 330.66808 -67.823035)
			(xy 330.731876 -67.819022) (xy 330.795672 -67.823035) (xy 330.858462 -67.835013) (xy 330.919255 -67.854766)
			(xy 330.977094 -67.881983) (xy 331.031065 -67.916234) (xy 331.080318 -67.956979) (xy 331.124075 -68.003576)
			(xy 331.161648 -68.055291) (xy 331.192442 -68.111306) (xy 331.215974 -68.170739) (xy 331.231871 -68.232653)
			(xy 331.239882 -68.296071) (xy 331.240384 -68.328032) (xy 331.239882 -68.359993) (xy 332.25587 -68.359993)
			(xy 332.25587 -68.296071) (xy 332.263881 -68.232653) (xy 332.279778 -68.170739) (xy 332.30331 -68.111306)
			(xy 332.334104 -68.055291) (xy 332.371677 -68.003576) (xy 332.415434 -67.956979) (xy 332.464687 -67.916234)
			(xy 332.518658 -67.881983) (xy 332.576497 -67.854766) (xy 332.63729 -67.835013) (xy 332.70008 -67.823035)
			(xy 332.763876 -67.819022) (xy 332.827672 -67.823035) (xy 332.890462 -67.835013) (xy 332.951255 -67.854766)
			(xy 333.009094 -67.881983) (xy 333.063065 -67.916234) (xy 333.112318 -67.956979) (xy 333.156075 -68.003576)
			(xy 333.193648 -68.055291) (xy 333.224442 -68.111306) (xy 333.247974 -68.170739) (xy 333.263871 -68.232653)
			(xy 333.271882 -68.296071) (xy 333.272384 -68.328032) (xy 333.271882 -68.359993) (xy 334.28787 -68.359993)
			(xy 334.28787 -68.296071) (xy 334.295881 -68.232653) (xy 334.311778 -68.170739) (xy 334.33531 -68.111306)
			(xy 334.366104 -68.055291) (xy 334.403677 -68.003576) (xy 334.447434 -67.956979) (xy 334.496687 -67.916234)
			(xy 334.550658 -67.881983) (xy 334.608497 -67.854766) (xy 334.66929 -67.835013) (xy 334.73208 -67.823035)
			(xy 334.795876 -67.819022) (xy 334.859672 -67.823035) (xy 334.922462 -67.835013) (xy 334.983255 -67.854766)
			(xy 335.041094 -67.881983) (xy 335.095065 -67.916234) (xy 335.144318 -67.956979) (xy 335.188075 -68.003576)
			(xy 335.225648 -68.055291) (xy 335.256442 -68.111306) (xy 335.279974 -68.170739) (xy 335.295871 -68.232653)
			(xy 335.303882 -68.296071) (xy 335.304384 -68.328032) (xy 335.303882 -68.359993) (xy 336.31987 -68.359993)
			(xy 336.31987 -68.296071) (xy 336.327881 -68.232653) (xy 336.343778 -68.170739) (xy 336.36731 -68.111306)
			(xy 336.398104 -68.055291) (xy 336.435677 -68.003576) (xy 336.479434 -67.956979) (xy 336.528687 -67.916234)
			(xy 336.582658 -67.881983) (xy 336.640497 -67.854766) (xy 336.70129 -67.835013) (xy 336.76408 -67.823035)
			(xy 336.827876 -67.819022) (xy 336.891672 -67.823035) (xy 336.954462 -67.835013) (xy 337.015255 -67.854766)
			(xy 337.073094 -67.881983) (xy 337.127065 -67.916234) (xy 337.176318 -67.956979) (xy 337.220075 -68.003576)
			(xy 337.257648 -68.055291) (xy 337.288442 -68.111306) (xy 337.311974 -68.170739) (xy 337.327871 -68.232653)
			(xy 337.335882 -68.296071) (xy 337.336384 -68.328032) (xy 337.335882 -68.359993) (xy 338.35187 -68.359993)
			(xy 338.35187 -68.296071) (xy 338.359881 -68.232653) (xy 338.375778 -68.170739) (xy 338.39931 -68.111306)
			(xy 338.430104 -68.055291) (xy 338.467677 -68.003576) (xy 338.511434 -67.956979) (xy 338.560687 -67.916234)
			(xy 338.614658 -67.881983) (xy 338.672497 -67.854766) (xy 338.73329 -67.835013) (xy 338.79608 -67.823035)
			(xy 338.859876 -67.819022) (xy 338.923672 -67.823035) (xy 338.986462 -67.835013) (xy 339.047255 -67.854766)
			(xy 339.105094 -67.881983) (xy 339.159065 -67.916234) (xy 339.208318 -67.956979) (xy 339.252075 -68.003576)
			(xy 339.289648 -68.055291) (xy 339.320442 -68.111306) (xy 339.343974 -68.170739) (xy 339.359871 -68.232653)
			(xy 339.367882 -68.296071) (xy 339.368384 -68.328032) (xy 339.367882 -68.359993) (xy 340.38387 -68.359993)
			(xy 340.38387 -68.296071) (xy 340.391881 -68.232653) (xy 340.407778 -68.170739) (xy 340.43131 -68.111306)
			(xy 340.462104 -68.055291) (xy 340.499677 -68.003576) (xy 340.543434 -67.956979) (xy 340.592687 -67.916234)
			(xy 340.646658 -67.881983) (xy 340.704497 -67.854766) (xy 340.76529 -67.835013) (xy 340.82808 -67.823035)
			(xy 340.891876 -67.819022) (xy 340.955672 -67.823035) (xy 341.018462 -67.835013) (xy 341.079255 -67.854766)
			(xy 341.137094 -67.881983) (xy 341.191065 -67.916234) (xy 341.240318 -67.956979) (xy 341.284075 -68.003576)
			(xy 341.321648 -68.055291) (xy 341.352442 -68.111306) (xy 341.375974 -68.170739) (xy 341.391871 -68.232653)
			(xy 341.399882 -68.296071) (xy 341.400384 -68.328032) (xy 341.399882 -68.359993) (xy 342.41587 -68.359993)
			(xy 342.41587 -68.296071) (xy 342.423881 -68.232653) (xy 342.439778 -68.170739) (xy 342.46331 -68.111306)
			(xy 342.494104 -68.055291) (xy 342.531677 -68.003576) (xy 342.575434 -67.956979) (xy 342.624687 -67.916234)
			(xy 342.678658 -67.881983) (xy 342.736497 -67.854766) (xy 342.79729 -67.835013) (xy 342.86008 -67.823035)
			(xy 342.923876 -67.819022) (xy 342.987672 -67.823035) (xy 343.050462 -67.835013) (xy 343.111255 -67.854766)
			(xy 343.169094 -67.881983) (xy 343.223065 -67.916234) (xy 343.272318 -67.956979) (xy 343.316075 -68.003576)
			(xy 343.353648 -68.055291) (xy 343.384442 -68.111306) (xy 343.407974 -68.170739) (xy 343.423871 -68.232653)
			(xy 343.431882 -68.296071) (xy 343.432384 -68.328032) (xy 343.431882 -68.359993) (xy 344.44787 -68.359993)
			(xy 344.44787 -68.296071) (xy 344.455881 -68.232653) (xy 344.471778 -68.170739) (xy 344.49531 -68.111306)
			(xy 344.526104 -68.055291) (xy 344.563677 -68.003576) (xy 344.607434 -67.956979) (xy 344.656687 -67.916234)
			(xy 344.710658 -67.881983) (xy 344.768497 -67.854766) (xy 344.82929 -67.835013) (xy 344.89208 -67.823035)
			(xy 344.955876 -67.819022) (xy 345.019672 -67.823035) (xy 345.082462 -67.835013) (xy 345.143255 -67.854766)
			(xy 345.201094 -67.881983) (xy 345.255065 -67.916234) (xy 345.304318 -67.956979) (xy 345.348075 -68.003576)
			(xy 345.385648 -68.055291) (xy 345.416442 -68.111306) (xy 345.439974 -68.170739) (xy 345.455871 -68.232653)
			(xy 345.463882 -68.296071) (xy 345.464384 -68.328032) (xy 345.463882 -68.359993) (xy 346.47987 -68.359993)
			(xy 346.47987 -68.296071) (xy 346.487881 -68.232653) (xy 346.503778 -68.170739) (xy 346.52731 -68.111306)
			(xy 346.558104 -68.055291) (xy 346.595677 -68.003576) (xy 346.639434 -67.956979) (xy 346.688687 -67.916234)
			(xy 346.742658 -67.881983) (xy 346.800497 -67.854766) (xy 346.86129 -67.835013) (xy 346.92408 -67.823035)
			(xy 346.987876 -67.819022) (xy 347.051672 -67.823035) (xy 347.114462 -67.835013) (xy 347.175255 -67.854766)
			(xy 347.233094 -67.881983) (xy 347.287065 -67.916234) (xy 347.336318 -67.956979) (xy 347.380075 -68.003576)
			(xy 347.417648 -68.055291) (xy 347.448442 -68.111306) (xy 347.471974 -68.170739) (xy 347.487871 -68.232653)
			(xy 347.495882 -68.296071) (xy 347.496384 -68.328032) (xy 347.495882 -68.359993) (xy 347.487871 -68.423411)
			(xy 347.471974 -68.485325) (xy 347.448442 -68.544758) (xy 347.417648 -68.600773) (xy 347.380075 -68.652488)
			(xy 347.336318 -68.699085) (xy 347.287065 -68.73983) (xy 347.233094 -68.774081) (xy 347.175255 -68.801298)
			(xy 347.114462 -68.821051) (xy 347.051672 -68.833029) (xy 346.987876 -68.837043) (xy 346.92408 -68.833029)
			(xy 346.86129 -68.821051) (xy 346.800497 -68.801298) (xy 346.742658 -68.774081) (xy 346.688687 -68.73983)
			(xy 346.639434 -68.699085) (xy 346.595677 -68.652488) (xy 346.558104 -68.600773) (xy 346.52731 -68.544758)
			(xy 346.503778 -68.485325) (xy 346.487881 -68.423411) (xy 346.47987 -68.359993) (xy 345.463882 -68.359993)
			(xy 345.455871 -68.423411) (xy 345.439974 -68.485325) (xy 345.416442 -68.544758) (xy 345.385648 -68.600773)
			(xy 345.348075 -68.652488) (xy 345.304318 -68.699085) (xy 345.255065 -68.73983) (xy 345.201094 -68.774081)
			(xy 345.143255 -68.801298) (xy 345.082462 -68.821051) (xy 345.019672 -68.833029) (xy 344.955876 -68.837043)
			(xy 344.89208 -68.833029) (xy 344.82929 -68.821051) (xy 344.768497 -68.801298) (xy 344.710658 -68.774081)
			(xy 344.656687 -68.73983) (xy 344.607434 -68.699085) (xy 344.563677 -68.652488) (xy 344.526104 -68.600773)
			(xy 344.49531 -68.544758) (xy 344.471778 -68.485325) (xy 344.455881 -68.423411) (xy 344.44787 -68.359993)
			(xy 343.431882 -68.359993) (xy 343.423871 -68.423411) (xy 343.407974 -68.485325) (xy 343.384442 -68.544758)
			(xy 343.353648 -68.600773) (xy 343.316075 -68.652488) (xy 343.272318 -68.699085) (xy 343.223065 -68.73983)
			(xy 343.169094 -68.774081) (xy 343.111255 -68.801298) (xy 343.050462 -68.821051) (xy 342.987672 -68.833029)
			(xy 342.923876 -68.837043) (xy 342.86008 -68.833029) (xy 342.79729 -68.821051) (xy 342.736497 -68.801298)
			(xy 342.678658 -68.774081) (xy 342.624687 -68.73983) (xy 342.575434 -68.699085) (xy 342.531677 -68.652488)
			(xy 342.494104 -68.600773) (xy 342.46331 -68.544758) (xy 342.439778 -68.485325) (xy 342.423881 -68.423411)
			(xy 342.41587 -68.359993) (xy 341.399882 -68.359993) (xy 341.391871 -68.423411) (xy 341.375974 -68.485325)
			(xy 341.352442 -68.544758) (xy 341.321648 -68.600773) (xy 341.284075 -68.652488) (xy 341.240318 -68.699085)
			(xy 341.191065 -68.73983) (xy 341.137094 -68.774081) (xy 341.079255 -68.801298) (xy 341.018462 -68.821051)
			(xy 340.955672 -68.833029) (xy 340.891876 -68.837043) (xy 340.82808 -68.833029) (xy 340.76529 -68.821051)
			(xy 340.704497 -68.801298) (xy 340.646658 -68.774081) (xy 340.592687 -68.73983) (xy 340.543434 -68.699085)
			(xy 340.499677 -68.652488) (xy 340.462104 -68.600773) (xy 340.43131 -68.544758) (xy 340.407778 -68.485325)
			(xy 340.391881 -68.423411) (xy 340.38387 -68.359993) (xy 339.367882 -68.359993) (xy 339.359871 -68.423411)
			(xy 339.343974 -68.485325) (xy 339.320442 -68.544758) (xy 339.289648 -68.600773) (xy 339.252075 -68.652488)
			(xy 339.208318 -68.699085) (xy 339.159065 -68.73983) (xy 339.105094 -68.774081) (xy 339.047255 -68.801298)
			(xy 338.986462 -68.821051) (xy 338.923672 -68.833029) (xy 338.859876 -68.837043) (xy 338.79608 -68.833029)
			(xy 338.73329 -68.821051) (xy 338.672497 -68.801298) (xy 338.614658 -68.774081) (xy 338.560687 -68.73983)
			(xy 338.511434 -68.699085) (xy 338.467677 -68.652488) (xy 338.430104 -68.600773) (xy 338.39931 -68.544758)
			(xy 338.375778 -68.485325) (xy 338.359881 -68.423411) (xy 338.35187 -68.359993) (xy 337.335882 -68.359993)
			(xy 337.327871 -68.423411) (xy 337.311974 -68.485325) (xy 337.288442 -68.544758) (xy 337.257648 -68.600773)
			(xy 337.220075 -68.652488) (xy 337.176318 -68.699085) (xy 337.127065 -68.73983) (xy 337.073094 -68.774081)
			(xy 337.015255 -68.801298) (xy 336.954462 -68.821051) (xy 336.891672 -68.833029) (xy 336.827876 -68.837043)
			(xy 336.76408 -68.833029) (xy 336.70129 -68.821051) (xy 336.640497 -68.801298) (xy 336.582658 -68.774081)
			(xy 336.528687 -68.73983) (xy 336.479434 -68.699085) (xy 336.435677 -68.652488) (xy 336.398104 -68.600773)
			(xy 336.36731 -68.544758) (xy 336.343778 -68.485325) (xy 336.327881 -68.423411) (xy 336.31987 -68.359993)
			(xy 335.303882 -68.359993) (xy 335.295871 -68.423411) (xy 335.279974 -68.485325) (xy 335.256442 -68.544758)
			(xy 335.225648 -68.600773) (xy 335.188075 -68.652488) (xy 335.144318 -68.699085) (xy 335.095065 -68.73983)
			(xy 335.041094 -68.774081) (xy 334.983255 -68.801298) (xy 334.922462 -68.821051) (xy 334.859672 -68.833029)
			(xy 334.795876 -68.837043) (xy 334.73208 -68.833029) (xy 334.66929 -68.821051) (xy 334.608497 -68.801298)
			(xy 334.550658 -68.774081) (xy 334.496687 -68.73983) (xy 334.447434 -68.699085) (xy 334.403677 -68.652488)
			(xy 334.366104 -68.600773) (xy 334.33531 -68.544758) (xy 334.311778 -68.485325) (xy 334.295881 -68.423411)
			(xy 334.28787 -68.359993) (xy 333.271882 -68.359993) (xy 333.263871 -68.423411) (xy 333.247974 -68.485325)
			(xy 333.224442 -68.544758) (xy 333.193648 -68.600773) (xy 333.156075 -68.652488) (xy 333.112318 -68.699085)
			(xy 333.063065 -68.73983) (xy 333.009094 -68.774081) (xy 332.951255 -68.801298) (xy 332.890462 -68.821051)
			(xy 332.827672 -68.833029) (xy 332.763876 -68.837043) (xy 332.70008 -68.833029) (xy 332.63729 -68.821051)
			(xy 332.576497 -68.801298) (xy 332.518658 -68.774081) (xy 332.464687 -68.73983) (xy 332.415434 -68.699085)
			(xy 332.371677 -68.652488) (xy 332.334104 -68.600773) (xy 332.30331 -68.544758) (xy 332.279778 -68.485325)
			(xy 332.263881 -68.423411) (xy 332.25587 -68.359993) (xy 331.239882 -68.359993) (xy 331.231871 -68.423411)
			(xy 331.215974 -68.485325) (xy 331.192442 -68.544758) (xy 331.161648 -68.600773) (xy 331.124075 -68.652488)
			(xy 331.080318 -68.699085) (xy 331.031065 -68.73983) (xy 330.977094 -68.774081) (xy 330.919255 -68.801298)
			(xy 330.858462 -68.821051) (xy 330.795672 -68.833029) (xy 330.731876 -68.837043) (xy 330.66808 -68.833029)
			(xy 330.60529 -68.821051) (xy 330.544497 -68.801298) (xy 330.486658 -68.774081) (xy 330.432687 -68.73983)
			(xy 330.383434 -68.699085) (xy 330.339677 -68.652488) (xy 330.302104 -68.600773) (xy 330.27131 -68.544758)
			(xy 330.247778 -68.485325) (xy 330.231881 -68.423411) (xy 330.22387 -68.359993) (xy 329.207882 -68.359993)
			(xy 329.199871 -68.423411) (xy 329.183974 -68.485325) (xy 329.160442 -68.544758) (xy 329.129648 -68.600773)
			(xy 329.092075 -68.652488) (xy 329.048318 -68.699085) (xy 328.999065 -68.73983) (xy 328.945094 -68.774081)
			(xy 328.887255 -68.801298) (xy 328.826462 -68.821051) (xy 328.763672 -68.833029) (xy 328.699876 -68.837043)
			(xy 328.63608 -68.833029) (xy 328.57329 -68.821051) (xy 328.512497 -68.801298) (xy 328.454658 -68.774081)
			(xy 328.400687 -68.73983) (xy 328.351434 -68.699085) (xy 328.307677 -68.652488) (xy 328.270104 -68.600773)
			(xy 328.23931 -68.544758) (xy 328.215778 -68.485325) (xy 328.199881 -68.423411) (xy 328.19187 -68.359993)
			(xy 327.175882 -68.359993) (xy 327.167871 -68.423411) (xy 327.151974 -68.485325) (xy 327.128442 -68.544758)
			(xy 327.097648 -68.600773) (xy 327.060075 -68.652488) (xy 327.016318 -68.699085) (xy 326.967065 -68.73983)
			(xy 326.913094 -68.774081) (xy 326.855255 -68.801298) (xy 326.794462 -68.821051) (xy 326.731672 -68.833029)
			(xy 326.667876 -68.837043) (xy 326.60408 -68.833029) (xy 326.54129 -68.821051) (xy 326.480497 -68.801298)
			(xy 326.422658 -68.774081) (xy 326.368687 -68.73983) (xy 326.319434 -68.699085) (xy 326.275677 -68.652488)
			(xy 326.238104 -68.600773) (xy 326.20731 -68.544758) (xy 326.183778 -68.485325) (xy 326.167881 -68.423411)
			(xy 326.15987 -68.359993) (xy 325.143882 -68.359993) (xy 325.135871 -68.423411) (xy 325.119974 -68.485325)
			(xy 325.096442 -68.544758) (xy 325.065648 -68.600773) (xy 325.028075 -68.652488) (xy 324.984318 -68.699085)
			(xy 324.935065 -68.73983) (xy 324.881094 -68.774081) (xy 324.823255 -68.801298) (xy 324.762462 -68.821051)
			(xy 324.699672 -68.833029) (xy 324.635876 -68.837043) (xy 324.57208 -68.833029) (xy 324.50929 -68.821051)
			(xy 324.448497 -68.801298) (xy 324.390658 -68.774081) (xy 324.336687 -68.73983) (xy 324.287434 -68.699085)
			(xy 324.243677 -68.652488) (xy 324.206104 -68.600773) (xy 324.17531 -68.544758) (xy 324.151778 -68.485325)
			(xy 324.135881 -68.423411) (xy 324.12787 -68.359993) (xy 323.111882 -68.359993) (xy 323.103871 -68.423411)
			(xy 323.087974 -68.485325) (xy 323.064442 -68.544758) (xy 323.033648 -68.600773) (xy 322.996075 -68.652488)
			(xy 322.952318 -68.699085) (xy 322.903065 -68.73983) (xy 322.849094 -68.774081) (xy 322.791255 -68.801298)
			(xy 322.730462 -68.821051) (xy 322.667672 -68.833029) (xy 322.603876 -68.837043) (xy 322.54008 -68.833029)
			(xy 322.47729 -68.821051) (xy 322.416497 -68.801298) (xy 322.358658 -68.774081) (xy 322.304687 -68.73983)
			(xy 322.255434 -68.699085) (xy 322.211677 -68.652488) (xy 322.174104 -68.600773) (xy 322.14331 -68.544758)
			(xy 322.119778 -68.485325) (xy 322.103881 -68.423411) (xy 322.09587 -68.359993) (xy 321.079882 -68.359993)
			(xy 321.071871 -68.423411) (xy 321.055974 -68.485325) (xy 321.032442 -68.544758) (xy 321.001648 -68.600773)
			(xy 320.964075 -68.652488) (xy 320.920318 -68.699085) (xy 320.871065 -68.73983) (xy 320.817094 -68.774081)
			(xy 320.759255 -68.801298) (xy 320.698462 -68.821051) (xy 320.635672 -68.833029) (xy 320.571876 -68.837043)
			(xy 320.50808 -68.833029) (xy 320.44529 -68.821051) (xy 320.384497 -68.801298) (xy 320.326658 -68.774081)
			(xy 320.272687 -68.73983) (xy 320.223434 -68.699085) (xy 320.179677 -68.652488) (xy 320.142104 -68.600773)
			(xy 320.11131 -68.544758) (xy 320.087778 -68.485325) (xy 320.071881 -68.423411) (xy 320.06387 -68.359993)
			(xy 319.047882 -68.359993) (xy 319.039871 -68.423411) (xy 319.023974 -68.485325) (xy 319.000442 -68.544758)
			(xy 318.969648 -68.600773) (xy 318.932075 -68.652488) (xy 318.888318 -68.699085) (xy 318.839065 -68.73983)
			(xy 318.785094 -68.774081) (xy 318.727255 -68.801298) (xy 318.666462 -68.821051) (xy 318.603672 -68.833029)
			(xy 318.539876 -68.837043) (xy 318.47608 -68.833029) (xy 318.41329 -68.821051) (xy 318.352497 -68.801298)
			(xy 318.294658 -68.774081) (xy 318.240687 -68.73983) (xy 318.191434 -68.699085) (xy 318.147677 -68.652488)
			(xy 318.110104 -68.600773) (xy 318.07931 -68.544758) (xy 318.055778 -68.485325) (xy 318.039881 -68.423411)
			(xy 318.03187 -68.359993) (xy 317.015882 -68.359993) (xy 317.007871 -68.423411) (xy 316.991974 -68.485325)
			(xy 316.968442 -68.544758) (xy 316.937648 -68.600773) (xy 316.900075 -68.652488) (xy 316.856318 -68.699085)
			(xy 316.807065 -68.73983) (xy 316.753094 -68.774081) (xy 316.695255 -68.801298) (xy 316.634462 -68.821051)
			(xy 316.571672 -68.833029) (xy 316.507876 -68.837043) (xy 316.44408 -68.833029) (xy 316.38129 -68.821051)
			(xy 316.320497 -68.801298) (xy 316.262658 -68.774081) (xy 316.208687 -68.73983) (xy 316.159434 -68.699085)
			(xy 316.115677 -68.652488) (xy 316.078104 -68.600773) (xy 316.04731 -68.544758) (xy 316.023778 -68.485325)
			(xy 316.007881 -68.423411) (xy 315.99987 -68.359993) (xy 314.983882 -68.359993) (xy 314.975871 -68.423411)
			(xy 314.959974 -68.485325) (xy 314.936442 -68.544758) (xy 314.905648 -68.600773) (xy 314.868075 -68.652488)
			(xy 314.824318 -68.699085) (xy 314.775065 -68.73983) (xy 314.721094 -68.774081) (xy 314.663255 -68.801298)
			(xy 314.602462 -68.821051) (xy 314.539672 -68.833029) (xy 314.475876 -68.837043) (xy 314.41208 -68.833029)
			(xy 314.34929 -68.821051) (xy 314.288497 -68.801298) (xy 314.230658 -68.774081) (xy 314.176687 -68.73983)
			(xy 314.127434 -68.699085) (xy 314.083677 -68.652488) (xy 314.046104 -68.600773) (xy 314.01531 -68.544758)
			(xy 313.991778 -68.485325) (xy 313.975881 -68.423411) (xy 313.96787 -68.359993) (xy 312.951882 -68.359993)
			(xy 312.943871 -68.423411) (xy 312.927974 -68.485325) (xy 312.904442 -68.544758) (xy 312.873648 -68.600773)
			(xy 312.836075 -68.652488) (xy 312.792318 -68.699085) (xy 312.743065 -68.73983) (xy 312.689094 -68.774081)
			(xy 312.631255 -68.801298) (xy 312.570462 -68.821051) (xy 312.507672 -68.833029) (xy 312.443876 -68.837043)
			(xy 312.38008 -68.833029) (xy 312.31729 -68.821051) (xy 312.256497 -68.801298) (xy 312.198658 -68.774081)
			(xy 312.144687 -68.73983) (xy 312.095434 -68.699085) (xy 312.051677 -68.652488) (xy 312.014104 -68.600773)
			(xy 311.98331 -68.544758) (xy 311.959778 -68.485325) (xy 311.943881 -68.423411) (xy 311.93587 -68.359993)
			(xy 310.919882 -68.359993) (xy 310.911871 -68.423411) (xy 310.895974 -68.485325) (xy 310.872442 -68.544758)
			(xy 310.841648 -68.600773) (xy 310.804075 -68.652488) (xy 310.760318 -68.699085) (xy 310.711065 -68.73983)
			(xy 310.657094 -68.774081) (xy 310.599255 -68.801298) (xy 310.538462 -68.821051) (xy 310.475672 -68.833029)
			(xy 310.411876 -68.837043) (xy 310.34808 -68.833029) (xy 310.28529 -68.821051) (xy 310.224497 -68.801298)
			(xy 310.166658 -68.774081) (xy 310.112687 -68.73983) (xy 310.063434 -68.699085) (xy 310.019677 -68.652488)
			(xy 309.982104 -68.600773) (xy 309.95131 -68.544758) (xy 309.927778 -68.485325) (xy 309.911881 -68.423411)
			(xy 309.90387 -68.359993) (xy 308.887882 -68.359993) (xy 308.879871 -68.423411) (xy 308.863974 -68.485325)
			(xy 308.840442 -68.544758) (xy 308.809648 -68.600773) (xy 308.772075 -68.652488) (xy 308.728318 -68.699085)
			(xy 308.679065 -68.73983) (xy 308.625094 -68.774081) (xy 308.567255 -68.801298) (xy 308.506462 -68.821051)
			(xy 308.443672 -68.833029) (xy 308.379876 -68.837043) (xy 308.31608 -68.833029) (xy 308.25329 -68.821051)
			(xy 308.192497 -68.801298) (xy 308.134658 -68.774081) (xy 308.080687 -68.73983) (xy 308.031434 -68.699085)
			(xy 307.987677 -68.652488) (xy 307.950104 -68.600773) (xy 307.91931 -68.544758) (xy 307.895778 -68.485325)
			(xy 307.879881 -68.423411) (xy 307.87187 -68.359993) (xy 298.511468 -68.359993) (xy 298.511468 -69.117675)
			(xy 405.252168 -69.117675) (xy 405.252168 -69.053753) (xy 405.260179 -68.990335) (xy 405.276076 -68.928421)
			(xy 405.299608 -68.868988) (xy 405.330402 -68.812973) (xy 405.367975 -68.761258) (xy 405.411732 -68.714661)
			(xy 405.460985 -68.673916) (xy 405.514956 -68.639665) (xy 405.572795 -68.612448) (xy 405.633588 -68.592695)
			(xy 405.696378 -68.580717) (xy 405.760174 -68.576704) (xy 405.82397 -68.580717) (xy 405.88676 -68.592695)
			(xy 405.947553 -68.612448) (xy 406.005392 -68.639665) (xy 406.059363 -68.673916) (xy 406.108616 -68.714661)
			(xy 406.152373 -68.761258) (xy 406.189946 -68.812973) (xy 406.22074 -68.868988) (xy 406.244272 -68.928421)
			(xy 406.260169 -68.990335) (xy 406.26818 -69.053753) (xy 406.268682 -69.085714) (xy 406.26818 -69.117675)
			(xy 406.260169 -69.181093) (xy 406.244272 -69.243007) (xy 406.22074 -69.30244) (xy 406.189946 -69.358455)
			(xy 406.152373 -69.41017) (xy 406.108616 -69.456767) (xy 406.059363 -69.497512) (xy 406.005392 -69.531763)
			(xy 405.947553 -69.55898) (xy 405.88676 -69.578733) (xy 405.82397 -69.590711) (xy 405.760174 -69.594725)
			(xy 405.696378 -69.590711) (xy 405.633588 -69.578733) (xy 405.572795 -69.55898) (xy 405.514956 -69.531763)
			(xy 405.460985 -69.497512) (xy 405.411732 -69.456767) (xy 405.367975 -69.41017) (xy 405.330402 -69.358455)
			(xy 405.299608 -69.30244) (xy 405.276076 -69.243007) (xy 405.260179 -69.181093) (xy 405.252168 -69.117675)
			(xy 298.511468 -69.117675) (xy 298.511468 -71.265542) (xy 314.093858 -71.265542) (xy 314.097929 -71.20992)
			(xy 314.110055 -71.155483) (xy 314.129978 -71.103392) (xy 314.157274 -71.054757) (xy 314.19136 -71.010614)
			(xy 314.231509 -70.971905) (xy 314.276867 -70.939454) (xy 314.326467 -70.913953) (xy 314.379251 -70.895946)
			(xy 314.434094 -70.885816) (xy 314.489828 -70.883779) (xy 314.545265 -70.889879) (xy 314.599222 -70.903985)
			(xy 314.650551 -70.925797) (xy 314.698157 -70.954851) (xy 314.741025 -70.990526) (xy 314.778242 -71.032063)
			(xy 314.809015 -71.078576) (xy 314.832687 -71.129073) (xy 314.848755 -71.18248) (xy 314.856875 -71.237656)
			(xy 314.857384 -71.265542) (xy 316.125858 -71.265542) (xy 316.129929 -71.20992) (xy 316.142055 -71.155483)
			(xy 316.161978 -71.103392) (xy 316.189274 -71.054757) (xy 316.22336 -71.010614) (xy 316.263509 -70.971905)
			(xy 316.308867 -70.939454) (xy 316.358467 -70.913953) (xy 316.411251 -70.895946) (xy 316.466094 -70.885816)
			(xy 316.521828 -70.883779) (xy 316.577265 -70.889879) (xy 316.631222 -70.903985) (xy 316.682551 -70.925797)
			(xy 316.730157 -70.954851) (xy 316.773025 -70.990526) (xy 316.810242 -71.032063) (xy 316.841015 -71.078576)
			(xy 316.864687 -71.129073) (xy 316.880755 -71.18248) (xy 316.888875 -71.237656) (xy 316.889384 -71.265542)
			(xy 316.888875 -71.293428) (xy 316.880755 -71.348604) (xy 316.864687 -71.402011) (xy 316.841015 -71.452508)
			(xy 316.810242 -71.499021) (xy 316.773025 -71.540558) (xy 316.730157 -71.576233) (xy 316.682551 -71.605287)
			(xy 316.631222 -71.627099) (xy 316.577265 -71.641205) (xy 316.521828 -71.647305) (xy 316.466094 -71.645268)
			(xy 316.411251 -71.635138) (xy 316.358467 -71.617131) (xy 316.308867 -71.59163) (xy 316.263509 -71.559179)
			(xy 316.22336 -71.52047) (xy 316.189274 -71.476327) (xy 316.161978 -71.427692) (xy 316.142055 -71.375601)
			(xy 316.129929 -71.321164) (xy 316.125858 -71.265542) (xy 314.857384 -71.265542) (xy 314.856875 -71.293428)
			(xy 314.848755 -71.348604) (xy 314.832687 -71.402011) (xy 314.809015 -71.452508) (xy 314.778242 -71.499021)
			(xy 314.741025 -71.540558) (xy 314.698157 -71.576233) (xy 314.650551 -71.605287) (xy 314.599222 -71.627099)
			(xy 314.545265 -71.641205) (xy 314.489828 -71.647305) (xy 314.434094 -71.645268) (xy 314.379251 -71.635138)
			(xy 314.326467 -71.617131) (xy 314.276867 -71.59163) (xy 314.231509 -71.559179) (xy 314.19136 -71.52047)
			(xy 314.157274 -71.476327) (xy 314.129978 -71.427692) (xy 314.110055 -71.375601) (xy 314.097929 -71.321164)
			(xy 314.093858 -71.265542) (xy 298.511468 -71.265542) (xy 298.511468 -71.900753) (xy 307.87187 -71.900753)
			(xy 307.87187 -71.836831) (xy 307.879881 -71.773413) (xy 307.895778 -71.711499) (xy 307.91931 -71.652066)
			(xy 307.950104 -71.596051) (xy 307.987677 -71.544336) (xy 308.031434 -71.497739) (xy 308.080687 -71.456994)
			(xy 308.134658 -71.422743) (xy 308.192497 -71.395526) (xy 308.25329 -71.375773) (xy 308.31608 -71.363795)
			(xy 308.379876 -71.359782) (xy 308.443672 -71.363795) (xy 308.506462 -71.375773) (xy 308.567255 -71.395526)
			(xy 308.625094 -71.422743) (xy 308.679065 -71.456994) (xy 308.728318 -71.497739) (xy 308.772075 -71.544336)
			(xy 308.809648 -71.596051) (xy 308.840442 -71.652066) (xy 308.863974 -71.711499) (xy 308.879871 -71.773413)
			(xy 308.887882 -71.836831) (xy 308.888384 -71.868792) (xy 308.887882 -71.900753) (xy 309.90387 -71.900753)
			(xy 309.90387 -71.836831) (xy 309.911881 -71.773413) (xy 309.927778 -71.711499) (xy 309.95131 -71.652066)
			(xy 309.982104 -71.596051) (xy 310.019677 -71.544336) (xy 310.063434 -71.497739) (xy 310.112687 -71.456994)
			(xy 310.166658 -71.422743) (xy 310.224497 -71.395526) (xy 310.28529 -71.375773) (xy 310.34808 -71.363795)
			(xy 310.411876 -71.359782) (xy 310.475672 -71.363795) (xy 310.538462 -71.375773) (xy 310.599255 -71.395526)
			(xy 310.657094 -71.422743) (xy 310.711065 -71.456994) (xy 310.760318 -71.497739) (xy 310.804075 -71.544336)
			(xy 310.841648 -71.596051) (xy 310.872442 -71.652066) (xy 310.895974 -71.711499) (xy 310.911871 -71.773413)
			(xy 310.919882 -71.836831) (xy 310.920384 -71.868792) (xy 310.919882 -71.900753) (xy 311.93587 -71.900753)
			(xy 311.93587 -71.836831) (xy 311.943881 -71.773413) (xy 311.959778 -71.711499) (xy 311.98331 -71.652066)
			(xy 312.014104 -71.596051) (xy 312.051677 -71.544336) (xy 312.095434 -71.497739) (xy 312.144687 -71.456994)
			(xy 312.198658 -71.422743) (xy 312.256497 -71.395526) (xy 312.31729 -71.375773) (xy 312.38008 -71.363795)
			(xy 312.443876 -71.359782) (xy 312.507672 -71.363795) (xy 312.570462 -71.375773) (xy 312.631255 -71.395526)
			(xy 312.689094 -71.422743) (xy 312.743065 -71.456994) (xy 312.792318 -71.497739) (xy 312.836075 -71.544336)
			(xy 312.873648 -71.596051) (xy 312.904442 -71.652066) (xy 312.927974 -71.711499) (xy 312.943871 -71.773413)
			(xy 312.951882 -71.836831) (xy 312.952384 -71.868792) (xy 312.951882 -71.900753) (xy 318.03187 -71.900753)
			(xy 318.03187 -71.836831) (xy 318.039881 -71.773413) (xy 318.055778 -71.711499) (xy 318.07931 -71.652066)
			(xy 318.110104 -71.596051) (xy 318.147677 -71.544336) (xy 318.191434 -71.497739) (xy 318.240687 -71.456994)
			(xy 318.294658 -71.422743) (xy 318.352497 -71.395526) (xy 318.41329 -71.375773) (xy 318.47608 -71.363795)
			(xy 318.539876 -71.359782) (xy 318.603672 -71.363795) (xy 318.666462 -71.375773) (xy 318.727255 -71.395526)
			(xy 318.785094 -71.422743) (xy 318.839065 -71.456994) (xy 318.888318 -71.497739) (xy 318.932075 -71.544336)
			(xy 318.969648 -71.596051) (xy 319.000442 -71.652066) (xy 319.023974 -71.711499) (xy 319.039871 -71.773413)
			(xy 319.047882 -71.836831) (xy 319.048384 -71.868792) (xy 319.047882 -71.900753) (xy 320.06387 -71.900753)
			(xy 320.06387 -71.836831) (xy 320.071881 -71.773413) (xy 320.087778 -71.711499) (xy 320.11131 -71.652066)
			(xy 320.142104 -71.596051) (xy 320.179677 -71.544336) (xy 320.223434 -71.497739) (xy 320.272687 -71.456994)
			(xy 320.326658 -71.422743) (xy 320.384497 -71.395526) (xy 320.44529 -71.375773) (xy 320.50808 -71.363795)
			(xy 320.571876 -71.359782) (xy 320.635672 -71.363795) (xy 320.698462 -71.375773) (xy 320.759255 -71.395526)
			(xy 320.817094 -71.422743) (xy 320.871065 -71.456994) (xy 320.920318 -71.497739) (xy 320.964075 -71.544336)
			(xy 321.001648 -71.596051) (xy 321.032442 -71.652066) (xy 321.055974 -71.711499) (xy 321.071871 -71.773413)
			(xy 321.079882 -71.836831) (xy 321.080384 -71.868792) (xy 321.079882 -71.900753) (xy 322.09587 -71.900753)
			(xy 322.09587 -71.836831) (xy 322.103881 -71.773413) (xy 322.119778 -71.711499) (xy 322.14331 -71.652066)
			(xy 322.174104 -71.596051) (xy 322.211677 -71.544336) (xy 322.255434 -71.497739) (xy 322.304687 -71.456994)
			(xy 322.358658 -71.422743) (xy 322.416497 -71.395526) (xy 322.47729 -71.375773) (xy 322.54008 -71.363795)
			(xy 322.603876 -71.359782) (xy 322.667672 -71.363795) (xy 322.730462 -71.375773) (xy 322.791255 -71.395526)
			(xy 322.849094 -71.422743) (xy 322.903065 -71.456994) (xy 322.952318 -71.497739) (xy 322.996075 -71.544336)
			(xy 323.033648 -71.596051) (xy 323.064442 -71.652066) (xy 323.087974 -71.711499) (xy 323.103871 -71.773413)
			(xy 323.111882 -71.836831) (xy 323.112384 -71.868792) (xy 323.111882 -71.900753) (xy 324.12787 -71.900753)
			(xy 324.12787 -71.836831) (xy 324.135881 -71.773413) (xy 324.151778 -71.711499) (xy 324.17531 -71.652066)
			(xy 324.206104 -71.596051) (xy 324.243677 -71.544336) (xy 324.287434 -71.497739) (xy 324.336687 -71.456994)
			(xy 324.390658 -71.422743) (xy 324.448497 -71.395526) (xy 324.50929 -71.375773) (xy 324.57208 -71.363795)
			(xy 324.635876 -71.359782) (xy 324.699672 -71.363795) (xy 324.762462 -71.375773) (xy 324.823255 -71.395526)
			(xy 324.881094 -71.422743) (xy 324.935065 -71.456994) (xy 324.984318 -71.497739) (xy 325.028075 -71.544336)
			(xy 325.065648 -71.596051) (xy 325.096442 -71.652066) (xy 325.119974 -71.711499) (xy 325.135871 -71.773413)
			(xy 325.143882 -71.836831) (xy 325.144384 -71.868792) (xy 325.143882 -71.900753) (xy 326.15987 -71.900753)
			(xy 326.15987 -71.836831) (xy 326.167881 -71.773413) (xy 326.183778 -71.711499) (xy 326.20731 -71.652066)
			(xy 326.238104 -71.596051) (xy 326.275677 -71.544336) (xy 326.319434 -71.497739) (xy 326.368687 -71.456994)
			(xy 326.422658 -71.422743) (xy 326.480497 -71.395526) (xy 326.54129 -71.375773) (xy 326.60408 -71.363795)
			(xy 326.667876 -71.359782) (xy 326.731672 -71.363795) (xy 326.794462 -71.375773) (xy 326.855255 -71.395526)
			(xy 326.913094 -71.422743) (xy 326.967065 -71.456994) (xy 327.016318 -71.497739) (xy 327.060075 -71.544336)
			(xy 327.097648 -71.596051) (xy 327.128442 -71.652066) (xy 327.151974 -71.711499) (xy 327.167871 -71.773413)
			(xy 327.175882 -71.836831) (xy 327.176384 -71.868792) (xy 327.175882 -71.900753) (xy 328.19187 -71.900753)
			(xy 328.19187 -71.836831) (xy 328.199881 -71.773413) (xy 328.215778 -71.711499) (xy 328.23931 -71.652066)
			(xy 328.270104 -71.596051) (xy 328.307677 -71.544336) (xy 328.351434 -71.497739) (xy 328.400687 -71.456994)
			(xy 328.454658 -71.422743) (xy 328.512497 -71.395526) (xy 328.57329 -71.375773) (xy 328.63608 -71.363795)
			(xy 328.699876 -71.359782) (xy 328.763672 -71.363795) (xy 328.826462 -71.375773) (xy 328.887255 -71.395526)
			(xy 328.945094 -71.422743) (xy 328.999065 -71.456994) (xy 329.048318 -71.497739) (xy 329.092075 -71.544336)
			(xy 329.129648 -71.596051) (xy 329.160442 -71.652066) (xy 329.183974 -71.711499) (xy 329.199871 -71.773413)
			(xy 329.207882 -71.836831) (xy 329.208384 -71.868792) (xy 329.207882 -71.900753) (xy 330.22387 -71.900753)
			(xy 330.22387 -71.836831) (xy 330.231881 -71.773413) (xy 330.247778 -71.711499) (xy 330.27131 -71.652066)
			(xy 330.302104 -71.596051) (xy 330.339677 -71.544336) (xy 330.383434 -71.497739) (xy 330.432687 -71.456994)
			(xy 330.486658 -71.422743) (xy 330.544497 -71.395526) (xy 330.60529 -71.375773) (xy 330.66808 -71.363795)
			(xy 330.731876 -71.359782) (xy 330.795672 -71.363795) (xy 330.858462 -71.375773) (xy 330.919255 -71.395526)
			(xy 330.977094 -71.422743) (xy 331.031065 -71.456994) (xy 331.080318 -71.497739) (xy 331.124075 -71.544336)
			(xy 331.161648 -71.596051) (xy 331.192442 -71.652066) (xy 331.215974 -71.711499) (xy 331.231871 -71.773413)
			(xy 331.239882 -71.836831) (xy 331.240384 -71.868792) (xy 331.239882 -71.900753) (xy 332.25587 -71.900753)
			(xy 332.25587 -71.836831) (xy 332.263881 -71.773413) (xy 332.279778 -71.711499) (xy 332.30331 -71.652066)
			(xy 332.334104 -71.596051) (xy 332.371677 -71.544336) (xy 332.415434 -71.497739) (xy 332.464687 -71.456994)
			(xy 332.518658 -71.422743) (xy 332.576497 -71.395526) (xy 332.63729 -71.375773) (xy 332.70008 -71.363795)
			(xy 332.763876 -71.359782) (xy 332.827672 -71.363795) (xy 332.890462 -71.375773) (xy 332.951255 -71.395526)
			(xy 333.009094 -71.422743) (xy 333.063065 -71.456994) (xy 333.112318 -71.497739) (xy 333.156075 -71.544336)
			(xy 333.193648 -71.596051) (xy 333.224442 -71.652066) (xy 333.247974 -71.711499) (xy 333.263871 -71.773413)
			(xy 333.271882 -71.836831) (xy 333.272384 -71.868792) (xy 333.271882 -71.900753) (xy 334.28787 -71.900753)
			(xy 334.28787 -71.836831) (xy 334.295881 -71.773413) (xy 334.311778 -71.711499) (xy 334.33531 -71.652066)
			(xy 334.366104 -71.596051) (xy 334.403677 -71.544336) (xy 334.447434 -71.497739) (xy 334.496687 -71.456994)
			(xy 334.550658 -71.422743) (xy 334.608497 -71.395526) (xy 334.66929 -71.375773) (xy 334.73208 -71.363795)
			(xy 334.795876 -71.359782) (xy 334.859672 -71.363795) (xy 334.922462 -71.375773) (xy 334.983255 -71.395526)
			(xy 335.041094 -71.422743) (xy 335.095065 -71.456994) (xy 335.144318 -71.497739) (xy 335.188075 -71.544336)
			(xy 335.225648 -71.596051) (xy 335.256442 -71.652066) (xy 335.279974 -71.711499) (xy 335.295871 -71.773413)
			(xy 335.303882 -71.836831) (xy 335.304384 -71.868792) (xy 335.303882 -71.900753) (xy 336.31987 -71.900753)
			(xy 336.31987 -71.836831) (xy 336.327881 -71.773413) (xy 336.343778 -71.711499) (xy 336.36731 -71.652066)
			(xy 336.398104 -71.596051) (xy 336.435677 -71.544336) (xy 336.479434 -71.497739) (xy 336.528687 -71.456994)
			(xy 336.582658 -71.422743) (xy 336.640497 -71.395526) (xy 336.70129 -71.375773) (xy 336.76408 -71.363795)
			(xy 336.827876 -71.359782) (xy 336.891672 -71.363795) (xy 336.954462 -71.375773) (xy 337.015255 -71.395526)
			(xy 337.073094 -71.422743) (xy 337.127065 -71.456994) (xy 337.176318 -71.497739) (xy 337.220075 -71.544336)
			(xy 337.257648 -71.596051) (xy 337.288442 -71.652066) (xy 337.311974 -71.711499) (xy 337.327871 -71.773413)
			(xy 337.335882 -71.836831) (xy 337.336384 -71.868792) (xy 337.335882 -71.900753) (xy 338.35187 -71.900753)
			(xy 338.35187 -71.836831) (xy 338.359881 -71.773413) (xy 338.375778 -71.711499) (xy 338.39931 -71.652066)
			(xy 338.430104 -71.596051) (xy 338.467677 -71.544336) (xy 338.511434 -71.497739) (xy 338.560687 -71.456994)
			(xy 338.614658 -71.422743) (xy 338.672497 -71.395526) (xy 338.73329 -71.375773) (xy 338.79608 -71.363795)
			(xy 338.859876 -71.359782) (xy 338.923672 -71.363795) (xy 338.986462 -71.375773) (xy 339.047255 -71.395526)
			(xy 339.105094 -71.422743) (xy 339.159065 -71.456994) (xy 339.208318 -71.497739) (xy 339.252075 -71.544336)
			(xy 339.289648 -71.596051) (xy 339.320442 -71.652066) (xy 339.343974 -71.711499) (xy 339.359871 -71.773413)
			(xy 339.367882 -71.836831) (xy 339.368384 -71.868792) (xy 339.367882 -71.900753) (xy 340.38387 -71.900753)
			(xy 340.38387 -71.836831) (xy 340.391881 -71.773413) (xy 340.407778 -71.711499) (xy 340.43131 -71.652066)
			(xy 340.462104 -71.596051) (xy 340.499677 -71.544336) (xy 340.543434 -71.497739) (xy 340.592687 -71.456994)
			(xy 340.646658 -71.422743) (xy 340.704497 -71.395526) (xy 340.76529 -71.375773) (xy 340.82808 -71.363795)
			(xy 340.891876 -71.359782) (xy 340.955672 -71.363795) (xy 341.018462 -71.375773) (xy 341.079255 -71.395526)
			(xy 341.137094 -71.422743) (xy 341.191065 -71.456994) (xy 341.240318 -71.497739) (xy 341.284075 -71.544336)
			(xy 341.321648 -71.596051) (xy 341.352442 -71.652066) (xy 341.375974 -71.711499) (xy 341.391871 -71.773413)
			(xy 341.399882 -71.836831) (xy 341.400384 -71.868792) (xy 341.399882 -71.900753) (xy 342.41587 -71.900753)
			(xy 342.41587 -71.836831) (xy 342.423881 -71.773413) (xy 342.439778 -71.711499) (xy 342.46331 -71.652066)
			(xy 342.494104 -71.596051) (xy 342.531677 -71.544336) (xy 342.575434 -71.497739) (xy 342.624687 -71.456994)
			(xy 342.678658 -71.422743) (xy 342.736497 -71.395526) (xy 342.79729 -71.375773) (xy 342.86008 -71.363795)
			(xy 342.923876 -71.359782) (xy 342.987672 -71.363795) (xy 343.050462 -71.375773) (xy 343.111255 -71.395526)
			(xy 343.169094 -71.422743) (xy 343.223065 -71.456994) (xy 343.272318 -71.497739) (xy 343.316075 -71.544336)
			(xy 343.353648 -71.596051) (xy 343.384442 -71.652066) (xy 343.407974 -71.711499) (xy 343.423871 -71.773413)
			(xy 343.431882 -71.836831) (xy 343.432384 -71.868792) (xy 343.431882 -71.900753) (xy 344.44787 -71.900753)
			(xy 344.44787 -71.836831) (xy 344.455881 -71.773413) (xy 344.471778 -71.711499) (xy 344.49531 -71.652066)
			(xy 344.526104 -71.596051) (xy 344.563677 -71.544336) (xy 344.607434 -71.497739) (xy 344.656687 -71.456994)
			(xy 344.710658 -71.422743) (xy 344.768497 -71.395526) (xy 344.82929 -71.375773) (xy 344.89208 -71.363795)
			(xy 344.955876 -71.359782) (xy 345.019672 -71.363795) (xy 345.082462 -71.375773) (xy 345.143255 -71.395526)
			(xy 345.201094 -71.422743) (xy 345.255065 -71.456994) (xy 345.304318 -71.497739) (xy 345.348075 -71.544336)
			(xy 345.385648 -71.596051) (xy 345.416442 -71.652066) (xy 345.439974 -71.711499) (xy 345.455871 -71.773413)
			(xy 345.463882 -71.836831) (xy 345.464384 -71.868792) (xy 345.463882 -71.900753) (xy 346.47987 -71.900753)
			(xy 346.47987 -71.836831) (xy 346.487881 -71.773413) (xy 346.503778 -71.711499) (xy 346.52731 -71.652066)
			(xy 346.558104 -71.596051) (xy 346.595677 -71.544336) (xy 346.639434 -71.497739) (xy 346.688687 -71.456994)
			(xy 346.742658 -71.422743) (xy 346.800497 -71.395526) (xy 346.86129 -71.375773) (xy 346.92408 -71.363795)
			(xy 346.987876 -71.359782) (xy 347.051672 -71.363795) (xy 347.114462 -71.375773) (xy 347.175255 -71.395526)
			(xy 347.233094 -71.422743) (xy 347.287065 -71.456994) (xy 347.336318 -71.497739) (xy 347.380075 -71.544336)
			(xy 347.417648 -71.596051) (xy 347.448442 -71.652066) (xy 347.471974 -71.711499) (xy 347.487871 -71.773413)
			(xy 347.495882 -71.836831) (xy 347.496384 -71.868792) (xy 347.495882 -71.900753) (xy 347.487871 -71.964171)
			(xy 347.471974 -72.026085) (xy 347.448442 -72.085518) (xy 347.417648 -72.141533) (xy 347.380075 -72.193248)
			(xy 347.336318 -72.239845) (xy 347.287065 -72.28059) (xy 347.233094 -72.314841) (xy 347.175255 -72.342058)
			(xy 347.114462 -72.361811) (xy 347.051672 -72.373789) (xy 346.987876 -72.377803) (xy 346.92408 -72.373789)
			(xy 346.86129 -72.361811) (xy 346.800497 -72.342058) (xy 346.742658 -72.314841) (xy 346.688687 -72.28059)
			(xy 346.639434 -72.239845) (xy 346.595677 -72.193248) (xy 346.558104 -72.141533) (xy 346.52731 -72.085518)
			(xy 346.503778 -72.026085) (xy 346.487881 -71.964171) (xy 346.47987 -71.900753) (xy 345.463882 -71.900753)
			(xy 345.455871 -71.964171) (xy 345.439974 -72.026085) (xy 345.416442 -72.085518) (xy 345.385648 -72.141533)
			(xy 345.348075 -72.193248) (xy 345.304318 -72.239845) (xy 345.255065 -72.28059) (xy 345.201094 -72.314841)
			(xy 345.143255 -72.342058) (xy 345.082462 -72.361811) (xy 345.019672 -72.373789) (xy 344.955876 -72.377803)
			(xy 344.89208 -72.373789) (xy 344.82929 -72.361811) (xy 344.768497 -72.342058) (xy 344.710658 -72.314841)
			(xy 344.656687 -72.28059) (xy 344.607434 -72.239845) (xy 344.563677 -72.193248) (xy 344.526104 -72.141533)
			(xy 344.49531 -72.085518) (xy 344.471778 -72.026085) (xy 344.455881 -71.964171) (xy 344.44787 -71.900753)
			(xy 343.431882 -71.900753) (xy 343.423871 -71.964171) (xy 343.407974 -72.026085) (xy 343.384442 -72.085518)
			(xy 343.353648 -72.141533) (xy 343.316075 -72.193248) (xy 343.272318 -72.239845) (xy 343.223065 -72.28059)
			(xy 343.169094 -72.314841) (xy 343.111255 -72.342058) (xy 343.050462 -72.361811) (xy 342.987672 -72.373789)
			(xy 342.923876 -72.377803) (xy 342.86008 -72.373789) (xy 342.79729 -72.361811) (xy 342.736497 -72.342058)
			(xy 342.678658 -72.314841) (xy 342.624687 -72.28059) (xy 342.575434 -72.239845) (xy 342.531677 -72.193248)
			(xy 342.494104 -72.141533) (xy 342.46331 -72.085518) (xy 342.439778 -72.026085) (xy 342.423881 -71.964171)
			(xy 342.41587 -71.900753) (xy 341.399882 -71.900753) (xy 341.391871 -71.964171) (xy 341.375974 -72.026085)
			(xy 341.352442 -72.085518) (xy 341.321648 -72.141533) (xy 341.284075 -72.193248) (xy 341.240318 -72.239845)
			(xy 341.191065 -72.28059) (xy 341.137094 -72.314841) (xy 341.079255 -72.342058) (xy 341.018462 -72.361811)
			(xy 340.955672 -72.373789) (xy 340.891876 -72.377803) (xy 340.82808 -72.373789) (xy 340.76529 -72.361811)
			(xy 340.704497 -72.342058) (xy 340.646658 -72.314841) (xy 340.592687 -72.28059) (xy 340.543434 -72.239845)
			(xy 340.499677 -72.193248) (xy 340.462104 -72.141533) (xy 340.43131 -72.085518) (xy 340.407778 -72.026085)
			(xy 340.391881 -71.964171) (xy 340.38387 -71.900753) (xy 339.367882 -71.900753) (xy 339.359871 -71.964171)
			(xy 339.343974 -72.026085) (xy 339.320442 -72.085518) (xy 339.289648 -72.141533) (xy 339.252075 -72.193248)
			(xy 339.208318 -72.239845) (xy 339.159065 -72.28059) (xy 339.105094 -72.314841) (xy 339.047255 -72.342058)
			(xy 338.986462 -72.361811) (xy 338.923672 -72.373789) (xy 338.859876 -72.377803) (xy 338.79608 -72.373789)
			(xy 338.73329 -72.361811) (xy 338.672497 -72.342058) (xy 338.614658 -72.314841) (xy 338.560687 -72.28059)
			(xy 338.511434 -72.239845) (xy 338.467677 -72.193248) (xy 338.430104 -72.141533) (xy 338.39931 -72.085518)
			(xy 338.375778 -72.026085) (xy 338.359881 -71.964171) (xy 338.35187 -71.900753) (xy 337.335882 -71.900753)
			(xy 337.327871 -71.964171) (xy 337.311974 -72.026085) (xy 337.288442 -72.085518) (xy 337.257648 -72.141533)
			(xy 337.220075 -72.193248) (xy 337.176318 -72.239845) (xy 337.127065 -72.28059) (xy 337.073094 -72.314841)
			(xy 337.015255 -72.342058) (xy 336.954462 -72.361811) (xy 336.891672 -72.373789) (xy 336.827876 -72.377803)
			(xy 336.76408 -72.373789) (xy 336.70129 -72.361811) (xy 336.640497 -72.342058) (xy 336.582658 -72.314841)
			(xy 336.528687 -72.28059) (xy 336.479434 -72.239845) (xy 336.435677 -72.193248) (xy 336.398104 -72.141533)
			(xy 336.36731 -72.085518) (xy 336.343778 -72.026085) (xy 336.327881 -71.964171) (xy 336.31987 -71.900753)
			(xy 335.303882 -71.900753) (xy 335.295871 -71.964171) (xy 335.279974 -72.026085) (xy 335.256442 -72.085518)
			(xy 335.225648 -72.141533) (xy 335.188075 -72.193248) (xy 335.144318 -72.239845) (xy 335.095065 -72.28059)
			(xy 335.041094 -72.314841) (xy 334.983255 -72.342058) (xy 334.922462 -72.361811) (xy 334.859672 -72.373789)
			(xy 334.795876 -72.377803) (xy 334.73208 -72.373789) (xy 334.66929 -72.361811) (xy 334.608497 -72.342058)
			(xy 334.550658 -72.314841) (xy 334.496687 -72.28059) (xy 334.447434 -72.239845) (xy 334.403677 -72.193248)
			(xy 334.366104 -72.141533) (xy 334.33531 -72.085518) (xy 334.311778 -72.026085) (xy 334.295881 -71.964171)
			(xy 334.28787 -71.900753) (xy 333.271882 -71.900753) (xy 333.263871 -71.964171) (xy 333.247974 -72.026085)
			(xy 333.224442 -72.085518) (xy 333.193648 -72.141533) (xy 333.156075 -72.193248) (xy 333.112318 -72.239845)
			(xy 333.063065 -72.28059) (xy 333.009094 -72.314841) (xy 332.951255 -72.342058) (xy 332.890462 -72.361811)
			(xy 332.827672 -72.373789) (xy 332.763876 -72.377803) (xy 332.70008 -72.373789) (xy 332.63729 -72.361811)
			(xy 332.576497 -72.342058) (xy 332.518658 -72.314841) (xy 332.464687 -72.28059) (xy 332.415434 -72.239845)
			(xy 332.371677 -72.193248) (xy 332.334104 -72.141533) (xy 332.30331 -72.085518) (xy 332.279778 -72.026085)
			(xy 332.263881 -71.964171) (xy 332.25587 -71.900753) (xy 331.239882 -71.900753) (xy 331.231871 -71.964171)
			(xy 331.215974 -72.026085) (xy 331.192442 -72.085518) (xy 331.161648 -72.141533) (xy 331.124075 -72.193248)
			(xy 331.080318 -72.239845) (xy 331.031065 -72.28059) (xy 330.977094 -72.314841) (xy 330.919255 -72.342058)
			(xy 330.858462 -72.361811) (xy 330.795672 -72.373789) (xy 330.731876 -72.377803) (xy 330.66808 -72.373789)
			(xy 330.60529 -72.361811) (xy 330.544497 -72.342058) (xy 330.486658 -72.314841) (xy 330.432687 -72.28059)
			(xy 330.383434 -72.239845) (xy 330.339677 -72.193248) (xy 330.302104 -72.141533) (xy 330.27131 -72.085518)
			(xy 330.247778 -72.026085) (xy 330.231881 -71.964171) (xy 330.22387 -71.900753) (xy 329.207882 -71.900753)
			(xy 329.199871 -71.964171) (xy 329.183974 -72.026085) (xy 329.160442 -72.085518) (xy 329.129648 -72.141533)
			(xy 329.092075 -72.193248) (xy 329.048318 -72.239845) (xy 328.999065 -72.28059) (xy 328.945094 -72.314841)
			(xy 328.887255 -72.342058) (xy 328.826462 -72.361811) (xy 328.763672 -72.373789) (xy 328.699876 -72.377803)
			(xy 328.63608 -72.373789) (xy 328.57329 -72.361811) (xy 328.512497 -72.342058) (xy 328.454658 -72.314841)
			(xy 328.400687 -72.28059) (xy 328.351434 -72.239845) (xy 328.307677 -72.193248) (xy 328.270104 -72.141533)
			(xy 328.23931 -72.085518) (xy 328.215778 -72.026085) (xy 328.199881 -71.964171) (xy 328.19187 -71.900753)
			(xy 327.175882 -71.900753) (xy 327.167871 -71.964171) (xy 327.151974 -72.026085) (xy 327.128442 -72.085518)
			(xy 327.097648 -72.141533) (xy 327.060075 -72.193248) (xy 327.016318 -72.239845) (xy 326.967065 -72.28059)
			(xy 326.913094 -72.314841) (xy 326.855255 -72.342058) (xy 326.794462 -72.361811) (xy 326.731672 -72.373789)
			(xy 326.667876 -72.377803) (xy 326.60408 -72.373789) (xy 326.54129 -72.361811) (xy 326.480497 -72.342058)
			(xy 326.422658 -72.314841) (xy 326.368687 -72.28059) (xy 326.319434 -72.239845) (xy 326.275677 -72.193248)
			(xy 326.238104 -72.141533) (xy 326.20731 -72.085518) (xy 326.183778 -72.026085) (xy 326.167881 -71.964171)
			(xy 326.15987 -71.900753) (xy 325.143882 -71.900753) (xy 325.135871 -71.964171) (xy 325.119974 -72.026085)
			(xy 325.096442 -72.085518) (xy 325.065648 -72.141533) (xy 325.028075 -72.193248) (xy 324.984318 -72.239845)
			(xy 324.935065 -72.28059) (xy 324.881094 -72.314841) (xy 324.823255 -72.342058) (xy 324.762462 -72.361811)
			(xy 324.699672 -72.373789) (xy 324.635876 -72.377803) (xy 324.57208 -72.373789) (xy 324.50929 -72.361811)
			(xy 324.448497 -72.342058) (xy 324.390658 -72.314841) (xy 324.336687 -72.28059) (xy 324.287434 -72.239845)
			(xy 324.243677 -72.193248) (xy 324.206104 -72.141533) (xy 324.17531 -72.085518) (xy 324.151778 -72.026085)
			(xy 324.135881 -71.964171) (xy 324.12787 -71.900753) (xy 323.111882 -71.900753) (xy 323.103871 -71.964171)
			(xy 323.087974 -72.026085) (xy 323.064442 -72.085518) (xy 323.033648 -72.141533) (xy 322.996075 -72.193248)
			(xy 322.952318 -72.239845) (xy 322.903065 -72.28059) (xy 322.849094 -72.314841) (xy 322.791255 -72.342058)
			(xy 322.730462 -72.361811) (xy 322.667672 -72.373789) (xy 322.603876 -72.377803) (xy 322.54008 -72.373789)
			(xy 322.47729 -72.361811) (xy 322.416497 -72.342058) (xy 322.358658 -72.314841) (xy 322.304687 -72.28059)
			(xy 322.255434 -72.239845) (xy 322.211677 -72.193248) (xy 322.174104 -72.141533) (xy 322.14331 -72.085518)
			(xy 322.119778 -72.026085) (xy 322.103881 -71.964171) (xy 322.09587 -71.900753) (xy 321.079882 -71.900753)
			(xy 321.071871 -71.964171) (xy 321.055974 -72.026085) (xy 321.032442 -72.085518) (xy 321.001648 -72.141533)
			(xy 320.964075 -72.193248) (xy 320.920318 -72.239845) (xy 320.871065 -72.28059) (xy 320.817094 -72.314841)
			(xy 320.759255 -72.342058) (xy 320.698462 -72.361811) (xy 320.635672 -72.373789) (xy 320.571876 -72.377803)
			(xy 320.50808 -72.373789) (xy 320.44529 -72.361811) (xy 320.384497 -72.342058) (xy 320.326658 -72.314841)
			(xy 320.272687 -72.28059) (xy 320.223434 -72.239845) (xy 320.179677 -72.193248) (xy 320.142104 -72.141533)
			(xy 320.11131 -72.085518) (xy 320.087778 -72.026085) (xy 320.071881 -71.964171) (xy 320.06387 -71.900753)
			(xy 319.047882 -71.900753) (xy 319.039871 -71.964171) (xy 319.023974 -72.026085) (xy 319.000442 -72.085518)
			(xy 318.969648 -72.141533) (xy 318.932075 -72.193248) (xy 318.888318 -72.239845) (xy 318.839065 -72.28059)
			(xy 318.785094 -72.314841) (xy 318.727255 -72.342058) (xy 318.666462 -72.361811) (xy 318.603672 -72.373789)
			(xy 318.539876 -72.377803) (xy 318.47608 -72.373789) (xy 318.41329 -72.361811) (xy 318.352497 -72.342058)
			(xy 318.294658 -72.314841) (xy 318.240687 -72.28059) (xy 318.191434 -72.239845) (xy 318.147677 -72.193248)
			(xy 318.110104 -72.141533) (xy 318.07931 -72.085518) (xy 318.055778 -72.026085) (xy 318.039881 -71.964171)
			(xy 318.03187 -71.900753) (xy 312.951882 -71.900753) (xy 312.943871 -71.964171) (xy 312.927974 -72.026085)
			(xy 312.904442 -72.085518) (xy 312.873648 -72.141533) (xy 312.836075 -72.193248) (xy 312.792318 -72.239845)
			(xy 312.743065 -72.28059) (xy 312.689094 -72.314841) (xy 312.631255 -72.342058) (xy 312.570462 -72.361811)
			(xy 312.507672 -72.373789) (xy 312.443876 -72.377803) (xy 312.38008 -72.373789) (xy 312.31729 -72.361811)
			(xy 312.256497 -72.342058) (xy 312.198658 -72.314841) (xy 312.144687 -72.28059) (xy 312.095434 -72.239845)
			(xy 312.051677 -72.193248) (xy 312.014104 -72.141533) (xy 311.98331 -72.085518) (xy 311.959778 -72.026085)
			(xy 311.943881 -71.964171) (xy 311.93587 -71.900753) (xy 310.919882 -71.900753) (xy 310.911871 -71.964171)
			(xy 310.895974 -72.026085) (xy 310.872442 -72.085518) (xy 310.841648 -72.141533) (xy 310.804075 -72.193248)
			(xy 310.760318 -72.239845) (xy 310.711065 -72.28059) (xy 310.657094 -72.314841) (xy 310.599255 -72.342058)
			(xy 310.538462 -72.361811) (xy 310.475672 -72.373789) (xy 310.411876 -72.377803) (xy 310.34808 -72.373789)
			(xy 310.28529 -72.361811) (xy 310.224497 -72.342058) (xy 310.166658 -72.314841) (xy 310.112687 -72.28059)
			(xy 310.063434 -72.239845) (xy 310.019677 -72.193248) (xy 309.982104 -72.141533) (xy 309.95131 -72.085518)
			(xy 309.927778 -72.026085) (xy 309.911881 -71.964171) (xy 309.90387 -71.900753) (xy 308.887882 -71.900753)
			(xy 308.879871 -71.964171) (xy 308.863974 -72.026085) (xy 308.840442 -72.085518) (xy 308.809648 -72.141533)
			(xy 308.772075 -72.193248) (xy 308.728318 -72.239845) (xy 308.679065 -72.28059) (xy 308.625094 -72.314841)
			(xy 308.567255 -72.342058) (xy 308.506462 -72.361811) (xy 308.443672 -72.373789) (xy 308.379876 -72.377803)
			(xy 308.31608 -72.373789) (xy 308.25329 -72.361811) (xy 308.192497 -72.342058) (xy 308.134658 -72.314841)
			(xy 308.080687 -72.28059) (xy 308.031434 -72.239845) (xy 307.987677 -72.193248) (xy 307.950104 -72.141533)
			(xy 307.91931 -72.085518) (xy 307.895778 -72.026085) (xy 307.879881 -71.964171) (xy 307.87187 -71.900753)
			(xy 298.511468 -71.900753) (xy 298.511468 -73.170753) (xy 307.87187 -73.170753) (xy 307.87187 -73.106831)
			(xy 307.879881 -73.043413) (xy 307.895778 -72.981499) (xy 307.91931 -72.922066) (xy 307.950104 -72.866051)
			(xy 307.987677 -72.814336) (xy 308.031434 -72.767739) (xy 308.080687 -72.726994) (xy 308.134658 -72.692743)
			(xy 308.192497 -72.665526) (xy 308.25329 -72.645773) (xy 308.31608 -72.633795) (xy 308.379876 -72.629782)
			(xy 308.443672 -72.633795) (xy 308.506462 -72.645773) (xy 308.567255 -72.665526) (xy 308.625094 -72.692743)
			(xy 308.679065 -72.726994) (xy 308.728318 -72.767739) (xy 308.772075 -72.814336) (xy 308.809648 -72.866051)
			(xy 308.819951 -72.884792) (xy 310.029858 -72.884792) (xy 310.033929 -72.82917) (xy 310.046055 -72.774733)
			(xy 310.065978 -72.722642) (xy 310.093274 -72.674007) (xy 310.12736 -72.629864) (xy 310.167509 -72.591155)
			(xy 310.212867 -72.558704) (xy 310.262467 -72.533203) (xy 310.315251 -72.515196) (xy 310.370094 -72.505066)
			(xy 310.425828 -72.503029) (xy 310.481265 -72.509129) (xy 310.535222 -72.523235) (xy 310.586551 -72.545047)
			(xy 310.634157 -72.574101) (xy 310.677025 -72.609776) (xy 310.714242 -72.651313) (xy 310.745015 -72.697826)
			(xy 310.768687 -72.748323) (xy 310.784755 -72.80173) (xy 310.792875 -72.856906) (xy 310.793384 -72.884792)
			(xy 310.792875 -72.912678) (xy 310.784755 -72.967854) (xy 310.768687 -73.021261) (xy 310.745015 -73.071758)
			(xy 310.714242 -73.118271) (xy 310.677025 -73.159808) (xy 310.663873 -73.170753) (xy 311.93587 -73.170753)
			(xy 311.93587 -73.106831) (xy 311.943881 -73.043413) (xy 311.959778 -72.981499) (xy 311.98331 -72.922066)
			(xy 312.014104 -72.866051) (xy 312.051677 -72.814336) (xy 312.095434 -72.767739) (xy 312.144687 -72.726994)
			(xy 312.198658 -72.692743) (xy 312.256497 -72.665526) (xy 312.31729 -72.645773) (xy 312.38008 -72.633795)
			(xy 312.443876 -72.629782) (xy 312.507672 -72.633795) (xy 312.570462 -72.645773) (xy 312.631255 -72.665526)
			(xy 312.689094 -72.692743) (xy 312.743065 -72.726994) (xy 312.792318 -72.767739) (xy 312.836075 -72.814336)
			(xy 312.873648 -72.866051) (xy 312.883951 -72.884792) (xy 318.157858 -72.884792) (xy 318.161929 -72.82917)
			(xy 318.174055 -72.774733) (xy 318.193978 -72.722642) (xy 318.221274 -72.674007) (xy 318.25536 -72.629864)
			(xy 318.295509 -72.591155) (xy 318.340867 -72.558704) (xy 318.390467 -72.533203) (xy 318.443251 -72.515196)
			(xy 318.498094 -72.505066) (xy 318.553828 -72.503029) (xy 318.609265 -72.509129) (xy 318.663222 -72.523235)
			(xy 318.714551 -72.545047) (xy 318.762157 -72.574101) (xy 318.805025 -72.609776) (xy 318.842242 -72.651313)
			(xy 318.873015 -72.697826) (xy 318.896687 -72.748323) (xy 318.912755 -72.80173) (xy 318.920875 -72.856906)
			(xy 318.921384 -72.884792) (xy 318.920875 -72.912678) (xy 318.912755 -72.967854) (xy 318.896687 -73.021261)
			(xy 318.873015 -73.071758) (xy 318.842242 -73.118271) (xy 318.805025 -73.159808) (xy 318.791873 -73.170753)
			(xy 320.06387 -73.170753) (xy 320.06387 -73.106831) (xy 320.071881 -73.043413) (xy 320.087778 -72.981499)
			(xy 320.11131 -72.922066) (xy 320.142104 -72.866051) (xy 320.179677 -72.814336) (xy 320.223434 -72.767739)
			(xy 320.272687 -72.726994) (xy 320.326658 -72.692743) (xy 320.384497 -72.665526) (xy 320.44529 -72.645773)
			(xy 320.50808 -72.633795) (xy 320.571876 -72.629782) (xy 320.635672 -72.633795) (xy 320.698462 -72.645773)
			(xy 320.759255 -72.665526) (xy 320.817094 -72.692743) (xy 320.871065 -72.726994) (xy 320.920318 -72.767739)
			(xy 320.964075 -72.814336) (xy 321.001648 -72.866051) (xy 321.011951 -72.884792) (xy 322.221858 -72.884792)
			(xy 322.225929 -72.82917) (xy 322.238055 -72.774733) (xy 322.257978 -72.722642) (xy 322.285274 -72.674007)
			(xy 322.31936 -72.629864) (xy 322.359509 -72.591155) (xy 322.404867 -72.558704) (xy 322.454467 -72.533203)
			(xy 322.507251 -72.515196) (xy 322.562094 -72.505066) (xy 322.617828 -72.503029) (xy 322.673265 -72.509129)
			(xy 322.727222 -72.523235) (xy 322.778551 -72.545047) (xy 322.826157 -72.574101) (xy 322.869025 -72.609776)
			(xy 322.906242 -72.651313) (xy 322.937015 -72.697826) (xy 322.960687 -72.748323) (xy 322.976755 -72.80173)
			(xy 322.984875 -72.856906) (xy 322.985384 -72.884792) (xy 322.984875 -72.912678) (xy 322.976755 -72.967854)
			(xy 322.960687 -73.021261) (xy 322.937015 -73.071758) (xy 322.906242 -73.118271) (xy 322.869025 -73.159808)
			(xy 322.855873 -73.170753) (xy 324.12787 -73.170753) (xy 324.12787 -73.106831) (xy 324.135881 -73.043413)
			(xy 324.151778 -72.981499) (xy 324.17531 -72.922066) (xy 324.206104 -72.866051) (xy 324.243677 -72.814336)
			(xy 324.287434 -72.767739) (xy 324.336687 -72.726994) (xy 324.390658 -72.692743) (xy 324.448497 -72.665526)
			(xy 324.50929 -72.645773) (xy 324.57208 -72.633795) (xy 324.635876 -72.629782) (xy 324.699672 -72.633795)
			(xy 324.762462 -72.645773) (xy 324.823255 -72.665526) (xy 324.881094 -72.692743) (xy 324.935065 -72.726994)
			(xy 324.984318 -72.767739) (xy 325.028075 -72.814336) (xy 325.065648 -72.866051) (xy 325.075951 -72.884792)
			(xy 326.285858 -72.884792) (xy 326.289929 -72.82917) (xy 326.302055 -72.774733) (xy 326.321978 -72.722642)
			(xy 326.349274 -72.674007) (xy 326.38336 -72.629864) (xy 326.423509 -72.591155) (xy 326.468867 -72.558704)
			(xy 326.518467 -72.533203) (xy 326.571251 -72.515196) (xy 326.626094 -72.505066) (xy 326.681828 -72.503029)
			(xy 326.737265 -72.509129) (xy 326.791222 -72.523235) (xy 326.842551 -72.545047) (xy 326.890157 -72.574101)
			(xy 326.933025 -72.609776) (xy 326.970242 -72.651313) (xy 327.001015 -72.697826) (xy 327.024687 -72.748323)
			(xy 327.040755 -72.80173) (xy 327.048875 -72.856906) (xy 327.049384 -72.884792) (xy 327.048875 -72.912678)
			(xy 327.040755 -72.967854) (xy 327.024687 -73.021261) (xy 327.001015 -73.071758) (xy 326.970242 -73.118271)
			(xy 326.933025 -73.159808) (xy 326.919873 -73.170753) (xy 328.19187 -73.170753) (xy 328.19187 -73.106831)
			(xy 328.199881 -73.043413) (xy 328.215778 -72.981499) (xy 328.23931 -72.922066) (xy 328.270104 -72.866051)
			(xy 328.307677 -72.814336) (xy 328.351434 -72.767739) (xy 328.400687 -72.726994) (xy 328.454658 -72.692743)
			(xy 328.512497 -72.665526) (xy 328.57329 -72.645773) (xy 328.63608 -72.633795) (xy 328.699876 -72.629782)
			(xy 328.763672 -72.633795) (xy 328.826462 -72.645773) (xy 328.887255 -72.665526) (xy 328.945094 -72.692743)
			(xy 328.999065 -72.726994) (xy 329.048318 -72.767739) (xy 329.092075 -72.814336) (xy 329.129648 -72.866051)
			(xy 329.139951 -72.884792) (xy 330.349858 -72.884792) (xy 330.353929 -72.82917) (xy 330.366055 -72.774733)
			(xy 330.385978 -72.722642) (xy 330.413274 -72.674007) (xy 330.44736 -72.629864) (xy 330.487509 -72.591155)
			(xy 330.532867 -72.558704) (xy 330.582467 -72.533203) (xy 330.635251 -72.515196) (xy 330.690094 -72.505066)
			(xy 330.745828 -72.503029) (xy 330.801265 -72.509129) (xy 330.855222 -72.523235) (xy 330.906551 -72.545047)
			(xy 330.954157 -72.574101) (xy 330.997025 -72.609776) (xy 331.034242 -72.651313) (xy 331.065015 -72.697826)
			(xy 331.088687 -72.748323) (xy 331.104755 -72.80173) (xy 331.112875 -72.856906) (xy 331.113384 -72.884792)
			(xy 331.112875 -72.912678) (xy 331.104755 -72.967854) (xy 331.088687 -73.021261) (xy 331.065015 -73.071758)
			(xy 331.034242 -73.118271) (xy 330.997025 -73.159808) (xy 330.983873 -73.170753) (xy 332.25587 -73.170753)
			(xy 332.25587 -73.106831) (xy 332.263881 -73.043413) (xy 332.279778 -72.981499) (xy 332.30331 -72.922066)
			(xy 332.334104 -72.866051) (xy 332.371677 -72.814336) (xy 332.415434 -72.767739) (xy 332.464687 -72.726994)
			(xy 332.518658 -72.692743) (xy 332.576497 -72.665526) (xy 332.63729 -72.645773) (xy 332.70008 -72.633795)
			(xy 332.763876 -72.629782) (xy 332.827672 -72.633795) (xy 332.890462 -72.645773) (xy 332.951255 -72.665526)
			(xy 333.009094 -72.692743) (xy 333.063065 -72.726994) (xy 333.112318 -72.767739) (xy 333.156075 -72.814336)
			(xy 333.193648 -72.866051) (xy 333.203951 -72.884792) (xy 336.445858 -72.884792) (xy 336.449929 -72.82917)
			(xy 336.462055 -72.774733) (xy 336.481978 -72.722642) (xy 336.509274 -72.674007) (xy 336.54336 -72.629864)
			(xy 336.583509 -72.591155) (xy 336.628867 -72.558704) (xy 336.678467 -72.533203) (xy 336.731251 -72.515196)
			(xy 336.786094 -72.505066) (xy 336.841828 -72.503029) (xy 336.897265 -72.509129) (xy 336.951222 -72.523235)
			(xy 337.002551 -72.545047) (xy 337.050157 -72.574101) (xy 337.093025 -72.609776) (xy 337.130242 -72.651313)
			(xy 337.161015 -72.697826) (xy 337.184687 -72.748323) (xy 337.200755 -72.80173) (xy 337.208875 -72.856906)
			(xy 337.209384 -72.884792) (xy 337.208875 -72.912678) (xy 337.200755 -72.967854) (xy 337.184687 -73.021261)
			(xy 337.161015 -73.071758) (xy 337.130242 -73.118271) (xy 337.093025 -73.159808) (xy 337.079873 -73.170753)
			(xy 338.35187 -73.170753) (xy 338.35187 -73.106831) (xy 338.359881 -73.043413) (xy 338.375778 -72.981499)
			(xy 338.39931 -72.922066) (xy 338.430104 -72.866051) (xy 338.467677 -72.814336) (xy 338.511434 -72.767739)
			(xy 338.560687 -72.726994) (xy 338.614658 -72.692743) (xy 338.672497 -72.665526) (xy 338.73329 -72.645773)
			(xy 338.79608 -72.633795) (xy 338.859876 -72.629782) (xy 338.923672 -72.633795) (xy 338.986462 -72.645773)
			(xy 339.047255 -72.665526) (xy 339.105094 -72.692743) (xy 339.159065 -72.726994) (xy 339.208318 -72.767739)
			(xy 339.252075 -72.814336) (xy 339.289648 -72.866051) (xy 339.299951 -72.884792) (xy 340.509858 -72.884792)
			(xy 340.513929 -72.82917) (xy 340.526055 -72.774733) (xy 340.545978 -72.722642) (xy 340.573274 -72.674007)
			(xy 340.60736 -72.629864) (xy 340.647509 -72.591155) (xy 340.692867 -72.558704) (xy 340.742467 -72.533203)
			(xy 340.795251 -72.515196) (xy 340.850094 -72.505066) (xy 340.905828 -72.503029) (xy 340.961265 -72.509129)
			(xy 341.015222 -72.523235) (xy 341.066551 -72.545047) (xy 341.114157 -72.574101) (xy 341.157025 -72.609776)
			(xy 341.194242 -72.651313) (xy 341.225015 -72.697826) (xy 341.248687 -72.748323) (xy 341.264755 -72.80173)
			(xy 341.272875 -72.856906) (xy 341.273384 -72.884792) (xy 341.272875 -72.912678) (xy 341.264755 -72.967854)
			(xy 341.248687 -73.021261) (xy 341.225015 -73.071758) (xy 341.194242 -73.118271) (xy 341.157025 -73.159808)
			(xy 341.143873 -73.170753) (xy 342.41587 -73.170753) (xy 342.41587 -73.106831) (xy 342.423881 -73.043413)
			(xy 342.439778 -72.981499) (xy 342.46331 -72.922066) (xy 342.494104 -72.866051) (xy 342.531677 -72.814336)
			(xy 342.575434 -72.767739) (xy 342.624687 -72.726994) (xy 342.678658 -72.692743) (xy 342.736497 -72.665526)
			(xy 342.79729 -72.645773) (xy 342.86008 -72.633795) (xy 342.923876 -72.629782) (xy 342.987672 -72.633795)
			(xy 343.050462 -72.645773) (xy 343.111255 -72.665526) (xy 343.169094 -72.692743) (xy 343.223065 -72.726994)
			(xy 343.272318 -72.767739) (xy 343.316075 -72.814336) (xy 343.353648 -72.866051) (xy 343.363951 -72.884792)
			(xy 344.573858 -72.884792) (xy 344.577929 -72.82917) (xy 344.590055 -72.774733) (xy 344.609978 -72.722642)
			(xy 344.637274 -72.674007) (xy 344.67136 -72.629864) (xy 344.711509 -72.591155) (xy 344.756867 -72.558704)
			(xy 344.806467 -72.533203) (xy 344.859251 -72.515196) (xy 344.914094 -72.505066) (xy 344.969828 -72.503029)
			(xy 345.025265 -72.509129) (xy 345.079222 -72.523235) (xy 345.130551 -72.545047) (xy 345.178157 -72.574101)
			(xy 345.221025 -72.609776) (xy 345.258242 -72.651313) (xy 345.289015 -72.697826) (xy 345.312687 -72.748323)
			(xy 345.328755 -72.80173) (xy 345.336875 -72.856906) (xy 345.337384 -72.884792) (xy 345.336875 -72.912678)
			(xy 345.328755 -72.967854) (xy 345.312687 -73.021261) (xy 345.289015 -73.071758) (xy 345.258242 -73.118271)
			(xy 345.221025 -73.159808) (xy 345.207873 -73.170753) (xy 346.47987 -73.170753) (xy 346.47987 -73.106831)
			(xy 346.487881 -73.043413) (xy 346.503778 -72.981499) (xy 346.52731 -72.922066) (xy 346.558104 -72.866051)
			(xy 346.595677 -72.814336) (xy 346.639434 -72.767739) (xy 346.688687 -72.726994) (xy 346.742658 -72.692743)
			(xy 346.800497 -72.665526) (xy 346.86129 -72.645773) (xy 346.92408 -72.633795) (xy 346.987876 -72.629782)
			(xy 347.051672 -72.633795) (xy 347.114462 -72.645773) (xy 347.175255 -72.665526) (xy 347.233094 -72.692743)
			(xy 347.287065 -72.726994) (xy 347.336318 -72.767739) (xy 347.380075 -72.814336) (xy 347.417648 -72.866051)
			(xy 347.448442 -72.922066) (xy 347.463234 -72.959425) (xy 392.3764 -72.959425) (xy 392.3764 -72.895503)
			(xy 392.384411 -72.832085) (xy 392.400308 -72.770171) (xy 392.42384 -72.710738) (xy 392.454634 -72.654723)
			(xy 392.492207 -72.603008) (xy 392.535964 -72.556411) (xy 392.585217 -72.515666) (xy 392.639188 -72.481415)
			(xy 392.697027 -72.454198) (xy 392.75782 -72.434445) (xy 392.82061 -72.422467) (xy 392.884406 -72.418454)
			(xy 392.948202 -72.422467) (xy 393.010992 -72.434445) (xy 393.071785 -72.454198) (xy 393.129624 -72.481415)
			(xy 393.183595 -72.515666) (xy 393.232848 -72.556411) (xy 393.276605 -72.603008) (xy 393.314178 -72.654723)
			(xy 393.344972 -72.710738) (xy 393.368504 -72.770171) (xy 393.384401 -72.832085) (xy 393.392412 -72.895503)
			(xy 393.392914 -72.927464) (xy 393.392412 -72.959425) (xy 393.386893 -73.003113) (xy 393.674594 -73.003113)
			(xy 393.674594 -72.939191) (xy 393.682605 -72.875773) (xy 393.698502 -72.813859) (xy 393.722034 -72.754426)
			(xy 393.752828 -72.698411) (xy 393.790401 -72.646696) (xy 393.834158 -72.600099) (xy 393.883411 -72.559354)
			(xy 393.937382 -72.525103) (xy 393.995221 -72.497886) (xy 394.056014 -72.478133) (xy 394.118804 -72.466155)
			(xy 394.1826 -72.462142) (xy 394.246396 -72.466155) (xy 394.309186 -72.478133) (xy 394.369979 -72.497886)
			(xy 394.427818 -72.525103) (xy 394.481789 -72.559354) (xy 394.531042 -72.600099) (xy 394.574799 -72.646696)
			(xy 394.612372 -72.698411) (xy 394.643166 -72.754426) (xy 394.666698 -72.813859) (xy 394.682595 -72.875773)
			(xy 394.690606 -72.939191) (xy 394.691108 -72.971152) (xy 394.690606 -73.003113) (xy 394.68451 -73.051373)
			(xy 394.959834 -73.051373) (xy 394.959834 -72.987451) (xy 394.967845 -72.924033) (xy 394.983742 -72.862119)
			(xy 395.007274 -72.802686) (xy 395.038068 -72.746671) (xy 395.075641 -72.694956) (xy 395.119398 -72.648359)
			(xy 395.168651 -72.607614) (xy 395.222622 -72.573363) (xy 395.280461 -72.546146) (xy 395.341254 -72.526393)
			(xy 395.404044 -72.514415) (xy 395.46784 -72.510402) (xy 395.531636 -72.514415) (xy 395.594426 -72.526393)
			(xy 395.655219 -72.546146) (xy 395.713058 -72.573363) (xy 395.767029 -72.607614) (xy 395.816282 -72.648359)
			(xy 395.860039 -72.694956) (xy 395.897612 -72.746671) (xy 395.928406 -72.802686) (xy 395.951938 -72.862119)
			(xy 395.967835 -72.924033) (xy 395.975846 -72.987451) (xy 395.976348 -73.019412) (xy 395.975846 -73.051373)
			(xy 395.967835 -73.114791) (xy 395.951938 -73.176705) (xy 395.928406 -73.236138) (xy 395.897612 -73.292153)
			(xy 395.860039 -73.343868) (xy 395.816282 -73.390465) (xy 395.767029 -73.43121) (xy 395.713058 -73.465461)
			(xy 395.655219 -73.492678) (xy 395.594426 -73.512431) (xy 395.531636 -73.524409) (xy 395.46784 -73.528423)
			(xy 395.404044 -73.524409) (xy 395.341254 -73.512431) (xy 395.280461 -73.492678) (xy 395.222622 -73.465461)
			(xy 395.168651 -73.43121) (xy 395.119398 -73.390465) (xy 395.075641 -73.343868) (xy 395.038068 -73.292153)
			(xy 395.007274 -73.236138) (xy 394.983742 -73.176705) (xy 394.967845 -73.114791) (xy 394.959834 -73.051373)
			(xy 394.68451 -73.051373) (xy 394.682595 -73.066531) (xy 394.666698 -73.128445) (xy 394.643166 -73.187878)
			(xy 394.612372 -73.243893) (xy 394.574799 -73.295608) (xy 394.531042 -73.342205) (xy 394.481789 -73.38295)
			(xy 394.427818 -73.417201) (xy 394.369979 -73.444418) (xy 394.309186 -73.464171) (xy 394.246396 -73.476149)
			(xy 394.1826 -73.480163) (xy 394.118804 -73.476149) (xy 394.056014 -73.464171) (xy 393.995221 -73.444418)
			(xy 393.937382 -73.417201) (xy 393.883411 -73.38295) (xy 393.834158 -73.342205) (xy 393.790401 -73.295608)
			(xy 393.752828 -73.243893) (xy 393.722034 -73.187878) (xy 393.698502 -73.128445) (xy 393.682605 -73.066531)
			(xy 393.674594 -73.003113) (xy 393.386893 -73.003113) (xy 393.384401 -73.022843) (xy 393.368504 -73.084757)
			(xy 393.344972 -73.14419) (xy 393.314178 -73.200205) (xy 393.276605 -73.25192) (xy 393.232848 -73.298517)
			(xy 393.183595 -73.339262) (xy 393.129624 -73.373513) (xy 393.071785 -73.40073) (xy 393.010992 -73.420483)
			(xy 392.948202 -73.432461) (xy 392.884406 -73.436475) (xy 392.82061 -73.432461) (xy 392.75782 -73.420483)
			(xy 392.697027 -73.40073) (xy 392.639188 -73.373513) (xy 392.585217 -73.339262) (xy 392.535964 -73.298517)
			(xy 392.492207 -73.25192) (xy 392.454634 -73.200205) (xy 392.42384 -73.14419) (xy 392.400308 -73.084757)
			(xy 392.384411 -73.022843) (xy 392.3764 -72.959425) (xy 347.463234 -72.959425) (xy 347.471974 -72.981499)
			(xy 347.487871 -73.043413) (xy 347.495882 -73.106831) (xy 347.496384 -73.138792) (xy 347.495882 -73.170753)
			(xy 347.487871 -73.234171) (xy 347.471974 -73.296085) (xy 347.448442 -73.355518) (xy 347.417648 -73.411533)
			(xy 347.380075 -73.463248) (xy 347.336318 -73.509845) (xy 347.287065 -73.55059) (xy 347.233094 -73.584841)
			(xy 347.175255 -73.612058) (xy 347.114462 -73.631811) (xy 347.051672 -73.643789) (xy 346.987876 -73.647803)
			(xy 346.92408 -73.643789) (xy 346.86129 -73.631811) (xy 346.800497 -73.612058) (xy 346.742658 -73.584841)
			(xy 346.688687 -73.55059) (xy 346.639434 -73.509845) (xy 346.595677 -73.463248) (xy 346.558104 -73.411533)
			(xy 346.52731 -73.355518) (xy 346.503778 -73.296085) (xy 346.487881 -73.234171) (xy 346.47987 -73.170753)
			(xy 345.207873 -73.170753) (xy 345.178157 -73.195483) (xy 345.130551 -73.224537) (xy 345.079222 -73.246349)
			(xy 345.025265 -73.260455) (xy 344.969828 -73.266555) (xy 344.914094 -73.264518) (xy 344.859251 -73.254388)
			(xy 344.806467 -73.236381) (xy 344.756867 -73.21088) (xy 344.711509 -73.178429) (xy 344.67136 -73.13972)
			(xy 344.637274 -73.095577) (xy 344.609978 -73.046942) (xy 344.590055 -72.994851) (xy 344.577929 -72.940414)
			(xy 344.573858 -72.884792) (xy 343.363951 -72.884792) (xy 343.384442 -72.922066) (xy 343.407974 -72.981499)
			(xy 343.423871 -73.043413) (xy 343.431882 -73.106831) (xy 343.432384 -73.138792) (xy 343.431882 -73.170753)
			(xy 343.423871 -73.234171) (xy 343.407974 -73.296085) (xy 343.384442 -73.355518) (xy 343.353648 -73.411533)
			(xy 343.316075 -73.463248) (xy 343.272318 -73.509845) (xy 343.223065 -73.55059) (xy 343.169094 -73.584841)
			(xy 343.111255 -73.612058) (xy 343.050462 -73.631811) (xy 342.987672 -73.643789) (xy 342.923876 -73.647803)
			(xy 342.86008 -73.643789) (xy 342.79729 -73.631811) (xy 342.736497 -73.612058) (xy 342.678658 -73.584841)
			(xy 342.624687 -73.55059) (xy 342.575434 -73.509845) (xy 342.531677 -73.463248) (xy 342.494104 -73.411533)
			(xy 342.46331 -73.355518) (xy 342.439778 -73.296085) (xy 342.423881 -73.234171) (xy 342.41587 -73.170753)
			(xy 341.143873 -73.170753) (xy 341.114157 -73.195483) (xy 341.066551 -73.224537) (xy 341.015222 -73.246349)
			(xy 340.961265 -73.260455) (xy 340.905828 -73.266555) (xy 340.850094 -73.264518) (xy 340.795251 -73.254388)
			(xy 340.742467 -73.236381) (xy 340.692867 -73.21088) (xy 340.647509 -73.178429) (xy 340.60736 -73.13972)
			(xy 340.573274 -73.095577) (xy 340.545978 -73.046942) (xy 340.526055 -72.994851) (xy 340.513929 -72.940414)
			(xy 340.509858 -72.884792) (xy 339.299951 -72.884792) (xy 339.320442 -72.922066) (xy 339.343974 -72.981499)
			(xy 339.359871 -73.043413) (xy 339.367882 -73.106831) (xy 339.368384 -73.138792) (xy 339.367882 -73.170753)
			(xy 339.359871 -73.234171) (xy 339.343974 -73.296085) (xy 339.320442 -73.355518) (xy 339.289648 -73.411533)
			(xy 339.252075 -73.463248) (xy 339.208318 -73.509845) (xy 339.159065 -73.55059) (xy 339.105094 -73.584841)
			(xy 339.047255 -73.612058) (xy 338.986462 -73.631811) (xy 338.923672 -73.643789) (xy 338.859876 -73.647803)
			(xy 338.79608 -73.643789) (xy 338.73329 -73.631811) (xy 338.672497 -73.612058) (xy 338.614658 -73.584841)
			(xy 338.560687 -73.55059) (xy 338.511434 -73.509845) (xy 338.467677 -73.463248) (xy 338.430104 -73.411533)
			(xy 338.39931 -73.355518) (xy 338.375778 -73.296085) (xy 338.359881 -73.234171) (xy 338.35187 -73.170753)
			(xy 337.079873 -73.170753) (xy 337.050157 -73.195483) (xy 337.002551 -73.224537) (xy 336.951222 -73.246349)
			(xy 336.897265 -73.260455) (xy 336.841828 -73.266555) (xy 336.786094 -73.264518) (xy 336.731251 -73.254388)
			(xy 336.678467 -73.236381) (xy 336.628867 -73.21088) (xy 336.583509 -73.178429) (xy 336.54336 -73.13972)
			(xy 336.509274 -73.095577) (xy 336.481978 -73.046942) (xy 336.462055 -72.994851) (xy 336.449929 -72.940414)
			(xy 336.445858 -72.884792) (xy 333.203951 -72.884792) (xy 333.224442 -72.922066) (xy 333.247974 -72.981499)
			(xy 333.263871 -73.043413) (xy 333.271882 -73.106831) (xy 333.272384 -73.138792) (xy 333.271882 -73.170753)
			(xy 333.263871 -73.234171) (xy 333.247974 -73.296085) (xy 333.224442 -73.355518) (xy 333.193648 -73.411533)
			(xy 333.156075 -73.463248) (xy 333.112318 -73.509845) (xy 333.063065 -73.55059) (xy 333.009094 -73.584841)
			(xy 332.951255 -73.612058) (xy 332.890462 -73.631811) (xy 332.827672 -73.643789) (xy 332.763876 -73.647803)
			(xy 332.70008 -73.643789) (xy 332.63729 -73.631811) (xy 332.576497 -73.612058) (xy 332.518658 -73.584841)
			(xy 332.464687 -73.55059) (xy 332.415434 -73.509845) (xy 332.371677 -73.463248) (xy 332.334104 -73.411533)
			(xy 332.30331 -73.355518) (xy 332.279778 -73.296085) (xy 332.263881 -73.234171) (xy 332.25587 -73.170753)
			(xy 330.983873 -73.170753) (xy 330.954157 -73.195483) (xy 330.906551 -73.224537) (xy 330.855222 -73.246349)
			(xy 330.801265 -73.260455) (xy 330.745828 -73.266555) (xy 330.690094 -73.264518) (xy 330.635251 -73.254388)
			(xy 330.582467 -73.236381) (xy 330.532867 -73.21088) (xy 330.487509 -73.178429) (xy 330.44736 -73.13972)
			(xy 330.413274 -73.095577) (xy 330.385978 -73.046942) (xy 330.366055 -72.994851) (xy 330.353929 -72.940414)
			(xy 330.349858 -72.884792) (xy 329.139951 -72.884792) (xy 329.160442 -72.922066) (xy 329.183974 -72.981499)
			(xy 329.199871 -73.043413) (xy 329.207882 -73.106831) (xy 329.208384 -73.138792) (xy 329.207882 -73.170753)
			(xy 329.199871 -73.234171) (xy 329.183974 -73.296085) (xy 329.160442 -73.355518) (xy 329.129648 -73.411533)
			(xy 329.092075 -73.463248) (xy 329.048318 -73.509845) (xy 328.999065 -73.55059) (xy 328.945094 -73.584841)
			(xy 328.887255 -73.612058) (xy 328.826462 -73.631811) (xy 328.763672 -73.643789) (xy 328.699876 -73.647803)
			(xy 328.63608 -73.643789) (xy 328.57329 -73.631811) (xy 328.512497 -73.612058) (xy 328.454658 -73.584841)
			(xy 328.400687 -73.55059) (xy 328.351434 -73.509845) (xy 328.307677 -73.463248) (xy 328.270104 -73.411533)
			(xy 328.23931 -73.355518) (xy 328.215778 -73.296085) (xy 328.199881 -73.234171) (xy 328.19187 -73.170753)
			(xy 326.919873 -73.170753) (xy 326.890157 -73.195483) (xy 326.842551 -73.224537) (xy 326.791222 -73.246349)
			(xy 326.737265 -73.260455) (xy 326.681828 -73.266555) (xy 326.626094 -73.264518) (xy 326.571251 -73.254388)
			(xy 326.518467 -73.236381) (xy 326.468867 -73.21088) (xy 326.423509 -73.178429) (xy 326.38336 -73.13972)
			(xy 326.349274 -73.095577) (xy 326.321978 -73.046942) (xy 326.302055 -72.994851) (xy 326.289929 -72.940414)
			(xy 326.285858 -72.884792) (xy 325.075951 -72.884792) (xy 325.096442 -72.922066) (xy 325.119974 -72.981499)
			(xy 325.135871 -73.043413) (xy 325.143882 -73.106831) (xy 325.144384 -73.138792) (xy 325.143882 -73.170753)
			(xy 325.135871 -73.234171) (xy 325.119974 -73.296085) (xy 325.096442 -73.355518) (xy 325.065648 -73.411533)
			(xy 325.028075 -73.463248) (xy 324.984318 -73.509845) (xy 324.935065 -73.55059) (xy 324.881094 -73.584841)
			(xy 324.823255 -73.612058) (xy 324.762462 -73.631811) (xy 324.699672 -73.643789) (xy 324.635876 -73.647803)
			(xy 324.57208 -73.643789) (xy 324.50929 -73.631811) (xy 324.448497 -73.612058) (xy 324.390658 -73.584841)
			(xy 324.336687 -73.55059) (xy 324.287434 -73.509845) (xy 324.243677 -73.463248) (xy 324.206104 -73.411533)
			(xy 324.17531 -73.355518) (xy 324.151778 -73.296085) (xy 324.135881 -73.234171) (xy 324.12787 -73.170753)
			(xy 322.855873 -73.170753) (xy 322.826157 -73.195483) (xy 322.778551 -73.224537) (xy 322.727222 -73.246349)
			(xy 322.673265 -73.260455) (xy 322.617828 -73.266555) (xy 322.562094 -73.264518) (xy 322.507251 -73.254388)
			(xy 322.454467 -73.236381) (xy 322.404867 -73.21088) (xy 322.359509 -73.178429) (xy 322.31936 -73.13972)
			(xy 322.285274 -73.095577) (xy 322.257978 -73.046942) (xy 322.238055 -72.994851) (xy 322.225929 -72.940414)
			(xy 322.221858 -72.884792) (xy 321.011951 -72.884792) (xy 321.032442 -72.922066) (xy 321.055974 -72.981499)
			(xy 321.071871 -73.043413) (xy 321.079882 -73.106831) (xy 321.080384 -73.138792) (xy 321.079882 -73.170753)
			(xy 321.071871 -73.234171) (xy 321.055974 -73.296085) (xy 321.032442 -73.355518) (xy 321.001648 -73.411533)
			(xy 320.964075 -73.463248) (xy 320.920318 -73.509845) (xy 320.871065 -73.55059) (xy 320.817094 -73.584841)
			(xy 320.759255 -73.612058) (xy 320.698462 -73.631811) (xy 320.635672 -73.643789) (xy 320.571876 -73.647803)
			(xy 320.50808 -73.643789) (xy 320.44529 -73.631811) (xy 320.384497 -73.612058) (xy 320.326658 -73.584841)
			(xy 320.272687 -73.55059) (xy 320.223434 -73.509845) (xy 320.179677 -73.463248) (xy 320.142104 -73.411533)
			(xy 320.11131 -73.355518) (xy 320.087778 -73.296085) (xy 320.071881 -73.234171) (xy 320.06387 -73.170753)
			(xy 318.791873 -73.170753) (xy 318.762157 -73.195483) (xy 318.714551 -73.224537) (xy 318.663222 -73.246349)
			(xy 318.609265 -73.260455) (xy 318.553828 -73.266555) (xy 318.498094 -73.264518) (xy 318.443251 -73.254388)
			(xy 318.390467 -73.236381) (xy 318.340867 -73.21088) (xy 318.295509 -73.178429) (xy 318.25536 -73.13972)
			(xy 318.221274 -73.095577) (xy 318.193978 -73.046942) (xy 318.174055 -72.994851) (xy 318.161929 -72.940414)
			(xy 318.157858 -72.884792) (xy 312.883951 -72.884792) (xy 312.904442 -72.922066) (xy 312.927974 -72.981499)
			(xy 312.943871 -73.043413) (xy 312.951882 -73.106831) (xy 312.952384 -73.138792) (xy 312.951882 -73.170753)
			(xy 312.943871 -73.234171) (xy 312.927974 -73.296085) (xy 312.904442 -73.355518) (xy 312.873648 -73.411533)
			(xy 312.836075 -73.463248) (xy 312.792318 -73.509845) (xy 312.743065 -73.55059) (xy 312.689094 -73.584841)
			(xy 312.631255 -73.612058) (xy 312.570462 -73.631811) (xy 312.507672 -73.643789) (xy 312.443876 -73.647803)
			(xy 312.38008 -73.643789) (xy 312.31729 -73.631811) (xy 312.256497 -73.612058) (xy 312.198658 -73.584841)
			(xy 312.144687 -73.55059) (xy 312.095434 -73.509845) (xy 312.051677 -73.463248) (xy 312.014104 -73.411533)
			(xy 311.98331 -73.355518) (xy 311.959778 -73.296085) (xy 311.943881 -73.234171) (xy 311.93587 -73.170753)
			(xy 310.663873 -73.170753) (xy 310.634157 -73.195483) (xy 310.586551 -73.224537) (xy 310.535222 -73.246349)
			(xy 310.481265 -73.260455) (xy 310.425828 -73.266555) (xy 310.370094 -73.264518) (xy 310.315251 -73.254388)
			(xy 310.262467 -73.236381) (xy 310.212867 -73.21088) (xy 310.167509 -73.178429) (xy 310.12736 -73.13972)
			(xy 310.093274 -73.095577) (xy 310.065978 -73.046942) (xy 310.046055 -72.994851) (xy 310.033929 -72.940414)
			(xy 310.029858 -72.884792) (xy 308.819951 -72.884792) (xy 308.840442 -72.922066) (xy 308.863974 -72.981499)
			(xy 308.879871 -73.043413) (xy 308.887882 -73.106831) (xy 308.888384 -73.138792) (xy 308.887882 -73.170753)
			(xy 308.879871 -73.234171) (xy 308.863974 -73.296085) (xy 308.840442 -73.355518) (xy 308.809648 -73.411533)
			(xy 308.772075 -73.463248) (xy 308.728318 -73.509845) (xy 308.679065 -73.55059) (xy 308.625094 -73.584841)
			(xy 308.567255 -73.612058) (xy 308.506462 -73.631811) (xy 308.443672 -73.643789) (xy 308.379876 -73.647803)
			(xy 308.31608 -73.643789) (xy 308.25329 -73.631811) (xy 308.192497 -73.612058) (xy 308.134658 -73.584841)
			(xy 308.080687 -73.55059) (xy 308.031434 -73.509845) (xy 307.987677 -73.463248) (xy 307.950104 -73.411533)
			(xy 307.91931 -73.355518) (xy 307.895778 -73.296085) (xy 307.879881 -73.234171) (xy 307.87187 -73.170753)
			(xy 298.511468 -73.170753) (xy 298.511468 -74.184764) (xy 308.013606 -74.184764) (xy 308.017677 -74.129142)
			(xy 308.029803 -74.074705) (xy 308.049726 -74.022614) (xy 308.077022 -73.973979) (xy 308.111108 -73.929836)
			(xy 308.151257 -73.891127) (xy 308.196615 -73.858676) (xy 308.246215 -73.833175) (xy 308.298999 -73.815168)
			(xy 308.353842 -73.805038) (xy 308.409576 -73.803001) (xy 308.465013 -73.809101) (xy 308.51897 -73.823207)
			(xy 308.570299 -73.845019) (xy 308.617905 -73.874073) (xy 308.660773 -73.909748) (xy 308.69799 -73.951285)
			(xy 308.728763 -73.997798) (xy 308.752435 -74.048295) (xy 308.768503 -74.101702) (xy 308.776623 -74.156878)
			(xy 308.777132 -74.184764) (xy 308.776623 -74.21265) (xy 308.776023 -74.216725) (xy 309.90387 -74.216725)
			(xy 309.90387 -74.152803) (xy 309.911881 -74.089385) (xy 309.927778 -74.027471) (xy 309.95131 -73.968038)
			(xy 309.982104 -73.912023) (xy 310.019677 -73.860308) (xy 310.063434 -73.813711) (xy 310.112687 -73.772966)
			(xy 310.166658 -73.738715) (xy 310.224497 -73.711498) (xy 310.28529 -73.691745) (xy 310.34808 -73.679767)
			(xy 310.411876 -73.675754) (xy 310.475672 -73.679767) (xy 310.538462 -73.691745) (xy 310.599255 -73.711498)
			(xy 310.657094 -73.738715) (xy 310.711065 -73.772966) (xy 310.760318 -73.813711) (xy 310.804075 -73.860308)
			(xy 310.841648 -73.912023) (xy 310.872442 -73.968038) (xy 310.895974 -74.027471) (xy 310.911871 -74.089385)
			(xy 310.919882 -74.152803) (xy 310.920384 -74.184764) (xy 312.077606 -74.184764) (xy 312.081677 -74.129142)
			(xy 312.093803 -74.074705) (xy 312.113726 -74.022614) (xy 312.141022 -73.973979) (xy 312.175108 -73.929836)
			(xy 312.215257 -73.891127) (xy 312.260615 -73.858676) (xy 312.310215 -73.833175) (xy 312.362999 -73.815168)
			(xy 312.417842 -73.805038) (xy 312.473576 -73.803001) (xy 312.529013 -73.809101) (xy 312.58297 -73.823207)
			(xy 312.634299 -73.845019) (xy 312.681905 -73.874073) (xy 312.724773 -73.909748) (xy 312.76199 -73.951285)
			(xy 312.792763 -73.997798) (xy 312.816435 -74.048295) (xy 312.832503 -74.101702) (xy 312.840623 -74.156878)
			(xy 312.841132 -74.184764) (xy 320.205606 -74.184764) (xy 320.209677 -74.129142) (xy 320.221803 -74.074705)
			(xy 320.241726 -74.022614) (xy 320.269022 -73.973979) (xy 320.303108 -73.929836) (xy 320.343257 -73.891127)
			(xy 320.388615 -73.858676) (xy 320.438215 -73.833175) (xy 320.490999 -73.815168) (xy 320.545842 -73.805038)
			(xy 320.601576 -73.803001) (xy 320.657013 -73.809101) (xy 320.71097 -73.823207) (xy 320.762299 -73.845019)
			(xy 320.809905 -73.874073) (xy 320.852773 -73.909748) (xy 320.88999 -73.951285) (xy 320.920763 -73.997798)
			(xy 320.944435 -74.048295) (xy 320.960503 -74.101702) (xy 320.968623 -74.156878) (xy 320.969132 -74.184764)
			(xy 320.968623 -74.21265) (xy 320.968023 -74.216725) (xy 322.09587 -74.216725) (xy 322.09587 -74.152803)
			(xy 322.103881 -74.089385) (xy 322.119778 -74.027471) (xy 322.14331 -73.968038) (xy 322.174104 -73.912023)
			(xy 322.211677 -73.860308) (xy 322.255434 -73.813711) (xy 322.304687 -73.772966) (xy 322.358658 -73.738715)
			(xy 322.416497 -73.711498) (xy 322.47729 -73.691745) (xy 322.54008 -73.679767) (xy 322.603876 -73.675754)
			(xy 322.667672 -73.679767) (xy 322.730462 -73.691745) (xy 322.791255 -73.711498) (xy 322.849094 -73.738715)
			(xy 322.903065 -73.772966) (xy 322.952318 -73.813711) (xy 322.996075 -73.860308) (xy 323.033648 -73.912023)
			(xy 323.064442 -73.968038) (xy 323.087974 -74.027471) (xy 323.103871 -74.089385) (xy 323.111882 -74.152803)
			(xy 323.112384 -74.184764) (xy 324.269606 -74.184764) (xy 324.273677 -74.129142) (xy 324.285803 -74.074705)
			(xy 324.305726 -74.022614) (xy 324.333022 -73.973979) (xy 324.367108 -73.929836) (xy 324.407257 -73.891127)
			(xy 324.452615 -73.858676) (xy 324.502215 -73.833175) (xy 324.554999 -73.815168) (xy 324.609842 -73.805038)
			(xy 324.665576 -73.803001) (xy 324.721013 -73.809101) (xy 324.77497 -73.823207) (xy 324.826299 -73.845019)
			(xy 324.873905 -73.874073) (xy 324.916773 -73.909748) (xy 324.95399 -73.951285) (xy 324.984763 -73.997798)
			(xy 325.008435 -74.048295) (xy 325.024503 -74.101702) (xy 325.032623 -74.156878) (xy 325.033132 -74.184764)
			(xy 325.032623 -74.21265) (xy 325.032023 -74.216725) (xy 326.15987 -74.216725) (xy 326.15987 -74.152803)
			(xy 326.167881 -74.089385) (xy 326.183778 -74.027471) (xy 326.20731 -73.968038) (xy 326.238104 -73.912023)
			(xy 326.275677 -73.860308) (xy 326.319434 -73.813711) (xy 326.368687 -73.772966) (xy 326.422658 -73.738715)
			(xy 326.480497 -73.711498) (xy 326.54129 -73.691745) (xy 326.60408 -73.679767) (xy 326.667876 -73.675754)
			(xy 326.731672 -73.679767) (xy 326.794462 -73.691745) (xy 326.855255 -73.711498) (xy 326.913094 -73.738715)
			(xy 326.967065 -73.772966) (xy 327.016318 -73.813711) (xy 327.060075 -73.860308) (xy 327.097648 -73.912023)
			(xy 327.128442 -73.968038) (xy 327.151974 -74.027471) (xy 327.167871 -74.089385) (xy 327.175882 -74.152803)
			(xy 327.176384 -74.184764) (xy 328.333606 -74.184764) (xy 328.337677 -74.129142) (xy 328.349803 -74.074705)
			(xy 328.369726 -74.022614) (xy 328.397022 -73.973979) (xy 328.431108 -73.929836) (xy 328.471257 -73.891127)
			(xy 328.516615 -73.858676) (xy 328.566215 -73.833175) (xy 328.618999 -73.815168) (xy 328.673842 -73.805038)
			(xy 328.729576 -73.803001) (xy 328.785013 -73.809101) (xy 328.83897 -73.823207) (xy 328.890299 -73.845019)
			(xy 328.937905 -73.874073) (xy 328.980773 -73.909748) (xy 329.01799 -73.951285) (xy 329.048763 -73.997798)
			(xy 329.072435 -74.048295) (xy 329.088503 -74.101702) (xy 329.096623 -74.156878) (xy 329.097132 -74.184764)
			(xy 329.096623 -74.21265) (xy 329.096023 -74.216725) (xy 330.22387 -74.216725) (xy 330.22387 -74.152803)
			(xy 330.231881 -74.089385) (xy 330.247778 -74.027471) (xy 330.27131 -73.968038) (xy 330.302104 -73.912023)
			(xy 330.339677 -73.860308) (xy 330.383434 -73.813711) (xy 330.432687 -73.772966) (xy 330.486658 -73.738715)
			(xy 330.544497 -73.711498) (xy 330.60529 -73.691745) (xy 330.66808 -73.679767) (xy 330.731876 -73.675754)
			(xy 330.795672 -73.679767) (xy 330.858462 -73.691745) (xy 330.919255 -73.711498) (xy 330.977094 -73.738715)
			(xy 331.031065 -73.772966) (xy 331.080318 -73.813711) (xy 331.124075 -73.860308) (xy 331.161648 -73.912023)
			(xy 331.192442 -73.968038) (xy 331.215974 -74.027471) (xy 331.231871 -74.089385) (xy 331.239882 -74.152803)
			(xy 331.240384 -74.184764) (xy 332.397606 -74.184764) (xy 332.401677 -74.129142) (xy 332.413803 -74.074705)
			(xy 332.433726 -74.022614) (xy 332.461022 -73.973979) (xy 332.495108 -73.929836) (xy 332.535257 -73.891127)
			(xy 332.580615 -73.858676) (xy 332.630215 -73.833175) (xy 332.682999 -73.815168) (xy 332.737842 -73.805038)
			(xy 332.793576 -73.803001) (xy 332.849013 -73.809101) (xy 332.90297 -73.823207) (xy 332.954299 -73.845019)
			(xy 333.001905 -73.874073) (xy 333.044773 -73.909748) (xy 333.08199 -73.951285) (xy 333.112763 -73.997798)
			(xy 333.136435 -74.048295) (xy 333.152503 -74.101702) (xy 333.160623 -74.156878) (xy 333.161132 -74.184764)
			(xy 333.160623 -74.21265) (xy 333.160023 -74.216725) (xy 336.31987 -74.216725) (xy 336.31987 -74.152803)
			(xy 336.327881 -74.089385) (xy 336.343778 -74.027471) (xy 336.36731 -73.968038) (xy 336.398104 -73.912023)
			(xy 336.435677 -73.860308) (xy 336.479434 -73.813711) (xy 336.528687 -73.772966) (xy 336.582658 -73.738715)
			(xy 336.640497 -73.711498) (xy 336.70129 -73.691745) (xy 336.76408 -73.679767) (xy 336.827876 -73.675754)
			(xy 336.891672 -73.679767) (xy 336.954462 -73.691745) (xy 337.015255 -73.711498) (xy 337.073094 -73.738715)
			(xy 337.127065 -73.772966) (xy 337.176318 -73.813711) (xy 337.220075 -73.860308) (xy 337.257648 -73.912023)
			(xy 337.288442 -73.968038) (xy 337.311974 -74.027471) (xy 337.327871 -74.089385) (xy 337.335882 -74.152803)
			(xy 337.336384 -74.184764) (xy 338.493606 -74.184764) (xy 338.497677 -74.129142) (xy 338.509803 -74.074705)
			(xy 338.529726 -74.022614) (xy 338.557022 -73.973979) (xy 338.591108 -73.929836) (xy 338.631257 -73.891127)
			(xy 338.676615 -73.858676) (xy 338.726215 -73.833175) (xy 338.778999 -73.815168) (xy 338.833842 -73.805038)
			(xy 338.889576 -73.803001) (xy 338.945013 -73.809101) (xy 338.99897 -73.823207) (xy 339.050299 -73.845019)
			(xy 339.097905 -73.874073) (xy 339.140773 -73.909748) (xy 339.17799 -73.951285) (xy 339.208763 -73.997798)
			(xy 339.232435 -74.048295) (xy 339.248503 -74.101702) (xy 339.256623 -74.156878) (xy 339.257132 -74.184764)
			(xy 339.256623 -74.21265) (xy 339.256023 -74.216725) (xy 340.38387 -74.216725) (xy 340.38387 -74.152803)
			(xy 340.391881 -74.089385) (xy 340.407778 -74.027471) (xy 340.43131 -73.968038) (xy 340.462104 -73.912023)
			(xy 340.499677 -73.860308) (xy 340.543434 -73.813711) (xy 340.592687 -73.772966) (xy 340.646658 -73.738715)
			(xy 340.704497 -73.711498) (xy 340.76529 -73.691745) (xy 340.82808 -73.679767) (xy 340.891876 -73.675754)
			(xy 340.955672 -73.679767) (xy 341.018462 -73.691745) (xy 341.079255 -73.711498) (xy 341.137094 -73.738715)
			(xy 341.191065 -73.772966) (xy 341.240318 -73.813711) (xy 341.284075 -73.860308) (xy 341.321648 -73.912023)
			(xy 341.352442 -73.968038) (xy 341.375974 -74.027471) (xy 341.391871 -74.089385) (xy 341.399882 -74.152803)
			(xy 341.400384 -74.184764) (xy 342.557606 -74.184764) (xy 342.561677 -74.129142) (xy 342.573803 -74.074705)
			(xy 342.593726 -74.022614) (xy 342.621022 -73.973979) (xy 342.655108 -73.929836) (xy 342.695257 -73.891127)
			(xy 342.740615 -73.858676) (xy 342.790215 -73.833175) (xy 342.842999 -73.815168) (xy 342.897842 -73.805038)
			(xy 342.953576 -73.803001) (xy 343.009013 -73.809101) (xy 343.06297 -73.823207) (xy 343.114299 -73.845019)
			(xy 343.161905 -73.874073) (xy 343.204773 -73.909748) (xy 343.24199 -73.951285) (xy 343.272763 -73.997798)
			(xy 343.296435 -74.048295) (xy 343.312503 -74.101702) (xy 343.320623 -74.156878) (xy 343.321132 -74.184764)
			(xy 343.320623 -74.21265) (xy 343.320023 -74.216725) (xy 344.44787 -74.216725) (xy 344.44787 -74.152803)
			(xy 344.455881 -74.089385) (xy 344.471778 -74.027471) (xy 344.49531 -73.968038) (xy 344.526104 -73.912023)
			(xy 344.563677 -73.860308) (xy 344.607434 -73.813711) (xy 344.656687 -73.772966) (xy 344.710658 -73.738715)
			(xy 344.768497 -73.711498) (xy 344.82929 -73.691745) (xy 344.89208 -73.679767) (xy 344.955876 -73.675754)
			(xy 345.019672 -73.679767) (xy 345.082462 -73.691745) (xy 345.143255 -73.711498) (xy 345.201094 -73.738715)
			(xy 345.255065 -73.772966) (xy 345.304318 -73.813711) (xy 345.348075 -73.860308) (xy 345.385648 -73.912023)
			(xy 345.416442 -73.968038) (xy 345.439974 -74.027471) (xy 345.455871 -74.089385) (xy 345.463882 -74.152803)
			(xy 345.464384 -74.184764) (xy 346.621606 -74.184764) (xy 346.625677 -74.129142) (xy 346.637803 -74.074705)
			(xy 346.657726 -74.022614) (xy 346.685022 -73.973979) (xy 346.719108 -73.929836) (xy 346.759257 -73.891127)
			(xy 346.804615 -73.858676) (xy 346.854215 -73.833175) (xy 346.906999 -73.815168) (xy 346.961842 -73.805038)
			(xy 347.017576 -73.803001) (xy 347.073013 -73.809101) (xy 347.12697 -73.823207) (xy 347.178299 -73.845019)
			(xy 347.225905 -73.874073) (xy 347.268773 -73.909748) (xy 347.30599 -73.951285) (xy 347.336763 -73.997798)
			(xy 347.360435 -74.048295) (xy 347.376503 -74.101702) (xy 347.384623 -74.156878) (xy 347.385132 -74.184764)
			(xy 347.384623 -74.21265) (xy 347.376503 -74.267826) (xy 347.360435 -74.321233) (xy 347.336763 -74.37173)
			(xy 347.334425 -74.375264) (xy 389.74268 -74.375264) (xy 389.743182 -74.343303) (xy 389.751193 -74.279885)
			(xy 389.76709 -74.217971) (xy 389.790622 -74.158538) (xy 389.821416 -74.102523) (xy 389.858989 -74.050808)
			(xy 389.902746 -74.004211) (xy 389.951999 -73.963466) (xy 390.00597 -73.929215) (xy 390.063809 -73.901998)
			(xy 390.124602 -73.882245) (xy 390.187392 -73.870267) (xy 390.251188 -73.866254) (xy 390.314984 -73.870267)
			(xy 390.377774 -73.882245) (xy 390.438567 -73.901998) (xy 390.496406 -73.929215) (xy 390.550377 -73.963466)
			(xy 390.59963 -74.004211) (xy 390.643387 -74.050808) (xy 390.68096 -74.102523) (xy 390.711754 -74.158538)
			(xy 390.719707 -74.178625) (xy 392.880082 -74.178625) (xy 392.880082 -74.114703) (xy 392.888093 -74.051285)
			(xy 392.90399 -73.989371) (xy 392.927522 -73.929938) (xy 392.958316 -73.873923) (xy 392.995889 -73.822208)
			(xy 393.039646 -73.775611) (xy 393.088899 -73.734866) (xy 393.14287 -73.700615) (xy 393.200709 -73.673398)
			(xy 393.261502 -73.653645) (xy 393.324292 -73.641667) (xy 393.388088 -73.637654) (xy 393.451884 -73.641667)
			(xy 393.514674 -73.653645) (xy 393.575467 -73.673398) (xy 393.633306 -73.700615) (xy 393.687277 -73.734866)
			(xy 393.73653 -73.775611) (xy 393.780287 -73.822208) (xy 393.81786 -73.873923) (xy 393.848654 -73.929938)
			(xy 393.872186 -73.989371) (xy 393.888083 -74.051285) (xy 393.896094 -74.114703) (xy 393.896596 -74.146664)
			(xy 393.896094 -74.178625) (xy 393.888083 -74.242043) (xy 393.872186 -74.303957) (xy 393.848654 -74.36339)
			(xy 393.81786 -74.419405) (xy 393.780287 -74.47112) (xy 393.73653 -74.517717) (xy 393.687277 -74.558462)
			(xy 393.633306 -74.592713) (xy 393.575467 -74.61993) (xy 393.514674 -74.639683) (xy 393.451884 -74.651661)
			(xy 393.388088 -74.655675) (xy 393.324292 -74.651661) (xy 393.261502 -74.639683) (xy 393.200709 -74.61993)
			(xy 393.14287 -74.592713) (xy 393.088899 -74.558462) (xy 393.039646 -74.517717) (xy 392.995889 -74.47112)
			(xy 392.958316 -74.419405) (xy 392.927522 -74.36339) (xy 392.90399 -74.303957) (xy 392.888093 -74.242043)
			(xy 392.880082 -74.178625) (xy 390.719707 -74.178625) (xy 390.735286 -74.217971) (xy 390.751183 -74.279885)
			(xy 390.759194 -74.343303) (xy 390.759696 -74.375264) (xy 390.759242 -74.405672) (xy 390.751992 -74.466055)
			(xy 390.737592 -74.525141) (xy 390.716246 -74.582088) (xy 390.68826 -74.636083) (xy 390.654034 -74.686354)
			(xy 390.614055 -74.732183) (xy 390.568896 -74.772917) (xy 390.544304 -74.790808) (xy 390.532813 -74.79942)
			(xy 390.514834 -74.821797) (xy 390.503797 -74.848296) (xy 390.500576 -74.87682) (xy 390.50168 -74.883264)
			(xy 398.29435 -74.883264) (xy 398.298421 -74.827642) (xy 398.310547 -74.773205) (xy 398.33047 -74.721114)
			(xy 398.357766 -74.672479) (xy 398.391852 -74.628336) (xy 398.432001 -74.589627) (xy 398.477359 -74.557176)
			(xy 398.526959 -74.531675) (xy 398.579743 -74.513668) (xy 398.634586 -74.503538) (xy 398.69032 -74.501501)
			(xy 398.745757 -74.507601) (xy 398.799714 -74.521707) (xy 398.851043 -74.543519) (xy 398.898649 -74.572573)
			(xy 398.941517 -74.608248) (xy 398.978734 -74.649785) (xy 399.009507 -74.696298) (xy 399.033179 -74.746795)
			(xy 399.049247 -74.800202) (xy 399.057367 -74.855378) (xy 399.057876 -74.883264) (xy 399.057367 -74.91115)
			(xy 399.049247 -74.966326) (xy 399.035111 -75.013312) (xy 405.97658 -75.013312) (xy 405.980651 -74.95769)
			(xy 405.992777 -74.903253) (xy 406.0127 -74.851162) (xy 406.039996 -74.802527) (xy 406.074082 -74.758384)
			(xy 406.114231 -74.719675) (xy 406.159589 -74.687224) (xy 406.209189 -74.661723) (xy 406.261973 -74.643716)
			(xy 406.316816 -74.633586) (xy 406.37255 -74.631549) (xy 406.427987 -74.637649) (xy 406.446271 -74.642429)
			(xy 410.94888 -74.642429) (xy 410.94888 -74.578507) (xy 410.956891 -74.515089) (xy 410.972788 -74.453175)
			(xy 410.99632 -74.393742) (xy 411.027114 -74.337727) (xy 411.064687 -74.286012) (xy 411.108444 -74.239415)
			(xy 411.157697 -74.19867) (xy 411.211668 -74.164419) (xy 411.269507 -74.137202) (xy 411.3303 -74.117449)
			(xy 411.39309 -74.105471) (xy 411.456886 -74.101458) (xy 411.520682 -74.105471) (xy 411.583472 -74.117449)
			(xy 411.644265 -74.137202) (xy 411.702104 -74.164419) (xy 411.756075 -74.19867) (xy 411.805328 -74.239415)
			(xy 411.849085 -74.286012) (xy 411.886658 -74.337727) (xy 411.917452 -74.393742) (xy 411.940984 -74.453175)
			(xy 411.956881 -74.515089) (xy 411.964892 -74.578507) (xy 411.965394 -74.610468) (xy 411.964892 -74.642429)
			(xy 411.956881 -74.705847) (xy 411.940984 -74.767761) (xy 411.917452 -74.827194) (xy 411.886658 -74.883209)
			(xy 411.849085 -74.934924) (xy 411.805328 -74.981521) (xy 411.756075 -75.022266) (xy 411.702104 -75.056517)
			(xy 411.644265 -75.083734) (xy 411.583472 -75.103487) (xy 411.520682 -75.115465) (xy 411.456886 -75.119479)
			(xy 411.39309 -75.115465) (xy 411.3303 -75.103487) (xy 411.269507 -75.083734) (xy 411.211668 -75.056517)
			(xy 411.157697 -75.022266) (xy 411.108444 -74.981521) (xy 411.064687 -74.934924) (xy 411.027114 -74.883209)
			(xy 410.99632 -74.827194) (xy 410.972788 -74.767761) (xy 410.956891 -74.705847) (xy 410.94888 -74.642429)
			(xy 406.446271 -74.642429) (xy 406.481944 -74.651755) (xy 406.533273 -74.673567) (xy 406.580879 -74.702621)
			(xy 406.623747 -74.738296) (xy 406.660964 -74.779833) (xy 406.691737 -74.826346) (xy 406.715409 -74.876843)
			(xy 406.731477 -74.93025) (xy 406.739597 -74.985426) (xy 406.740106 -75.013312) (xy 406.739597 -75.041198)
			(xy 406.731477 -75.096374) (xy 406.715409 -75.149781) (xy 406.691737 -75.200278) (xy 406.660964 -75.246791)
			(xy 406.623747 -75.288328) (xy 406.580879 -75.324003) (xy 406.533273 -75.353057) (xy 406.481944 -75.374869)
			(xy 406.427987 -75.388975) (xy 406.37255 -75.395075) (xy 406.316816 -75.393038) (xy 406.261973 -75.382908)
			(xy 406.209189 -75.364901) (xy 406.159589 -75.3394) (xy 406.114231 -75.306949) (xy 406.074082 -75.26824)
			(xy 406.039996 -75.224097) (xy 406.0127 -75.175462) (xy 405.992777 -75.123371) (xy 405.980651 -75.068934)
			(xy 405.97658 -75.013312) (xy 399.035111 -75.013312) (xy 399.033179 -75.019733) (xy 399.009507 -75.07023)
			(xy 398.978734 -75.116743) (xy 398.941517 -75.15828) (xy 398.898649 -75.193955) (xy 398.851043 -75.223009)
			(xy 398.799714 -75.244821) (xy 398.745757 -75.258927) (xy 398.69032 -75.265027) (xy 398.634586 -75.26299)
			(xy 398.579743 -75.25286) (xy 398.526959 -75.234853) (xy 398.477359 -75.209352) (xy 398.432001 -75.176901)
			(xy 398.391852 -75.138192) (xy 398.357766 -75.094049) (xy 398.33047 -75.045414) (xy 398.310547 -74.993323)
			(xy 398.298421 -74.938886) (xy 398.29435 -74.883264) (xy 390.50168 -74.883264) (xy 390.505424 -74.905113)
			(xy 390.517958 -74.930937) (xy 390.537187 -74.95225) (xy 390.54913 -74.960226) (xy 390.576261 -74.977675)
			(xy 390.626304 -75.018383) (xy 390.670794 -75.065094) (xy 390.709017 -75.117059) (xy 390.740359 -75.173442)
			(xy 390.764317 -75.233337) (xy 390.780504 -75.295781) (xy 390.788662 -75.359772) (xy 390.78916 -75.392026)
			(xy 390.788658 -75.423987) (xy 390.780647 -75.487405) (xy 390.76475 -75.549319) (xy 390.741218 -75.608752)
			(xy 390.710424 -75.664767) (xy 390.672851 -75.716482) (xy 390.667457 -75.722226) (xy 394.311884 -75.722226)
			(xy 394.315955 -75.666604) (xy 394.328081 -75.612167) (xy 394.348004 -75.560076) (xy 394.3753 -75.511441)
			(xy 394.409386 -75.467298) (xy 394.449535 -75.428589) (xy 394.494893 -75.396138) (xy 394.544493 -75.370637)
			(xy 394.597277 -75.35263) (xy 394.65212 -75.3425) (xy 394.707854 -75.340463) (xy 394.763291 -75.346563)
			(xy 394.817248 -75.360669) (xy 394.868577 -75.382481) (xy 394.916183 -75.411535) (xy 394.959051 -75.44721)
			(xy 394.996268 -75.488747) (xy 395.027041 -75.53526) (xy 395.050713 -75.585757) (xy 395.066781 -75.639164)
			(xy 395.074901 -75.69434) (xy 395.07541 -75.722226) (xy 395.074901 -75.750112) (xy 395.066781 -75.805288)
			(xy 395.050713 -75.858695) (xy 395.027041 -75.909192) (xy 394.996268 -75.955705) (xy 394.959051 -75.997242)
			(xy 394.916183 -76.032917) (xy 394.878806 -76.055728) (xy 397.0053 -76.055728) (xy 397.009371 -76.000106)
			(xy 397.021497 -75.945669) (xy 397.04142 -75.893578) (xy 397.068716 -75.844943) (xy 397.102802 -75.8008)
			(xy 397.142951 -75.762091) (xy 397.188309 -75.72964) (xy 397.237909 -75.704139) (xy 397.290693 -75.686132)
			(xy 397.345536 -75.676002) (xy 397.40127 -75.673965) (xy 397.456707 -75.680065) (xy 397.510664 -75.694171)
			(xy 397.561993 -75.715983) (xy 397.609599 -75.745037) (xy 397.652467 -75.780712) (xy 397.689684 -75.822249)
			(xy 397.720457 -75.868762) (xy 397.740927 -75.912429) (xy 410.94888 -75.912429) (xy 410.94888 -75.848507)
			(xy 410.956891 -75.785089) (xy 410.972788 -75.723175) (xy 410.99632 -75.663742) (xy 411.027114 -75.607727)
			(xy 411.064687 -75.556012) (xy 411.108444 -75.509415) (xy 411.157697 -75.46867) (xy 411.211668 -75.434419)
			(xy 411.269507 -75.407202) (xy 411.3303 -75.387449) (xy 411.39309 -75.375471) (xy 411.456886 -75.371458)
			(xy 411.520682 -75.375471) (xy 411.583472 -75.387449) (xy 411.644265 -75.407202) (xy 411.702104 -75.434419)
			(xy 411.756075 -75.46867) (xy 411.805328 -75.509415) (xy 411.849085 -75.556012) (xy 411.886658 -75.607727)
			(xy 411.917452 -75.663742) (xy 411.940984 -75.723175) (xy 411.956881 -75.785089) (xy 411.964892 -75.848507)
			(xy 411.965394 -75.880468) (xy 411.964892 -75.912429) (xy 411.956881 -75.975847) (xy 411.940984 -76.037761)
			(xy 411.917452 -76.097194) (xy 411.886658 -76.153209) (xy 411.849085 -76.204924) (xy 411.805328 -76.251521)
			(xy 411.756075 -76.292266) (xy 411.702104 -76.326517) (xy 411.644265 -76.353734) (xy 411.583472 -76.373487)
			(xy 411.520682 -76.385465) (xy 411.456886 -76.389479) (xy 411.39309 -76.385465) (xy 411.3303 -76.373487)
			(xy 411.269507 -76.353734) (xy 411.211668 -76.326517) (xy 411.157697 -76.292266) (xy 411.108444 -76.251521)
			(xy 411.064687 -76.204924) (xy 411.027114 -76.153209) (xy 410.99632 -76.097194) (xy 410.972788 -76.037761)
			(xy 410.956891 -75.975847) (xy 410.94888 -75.912429) (xy 397.740927 -75.912429) (xy 397.744129 -75.919259)
			(xy 397.760197 -75.972666) (xy 397.768317 -76.027842) (xy 397.768826 -76.055728) (xy 397.768317 -76.083614)
			(xy 397.760197 -76.13879) (xy 397.744129 -76.192197) (xy 397.720457 -76.242694) (xy 397.689684 -76.289207)
			(xy 397.652467 -76.330744) (xy 397.609599 -76.366419) (xy 397.561993 -76.395473) (xy 397.510664 -76.417285)
			(xy 397.456707 -76.431391) (xy 397.40127 -76.437491) (xy 397.345536 -76.435454) (xy 397.290693 -76.425324)
			(xy 397.237909 -76.407317) (xy 397.188309 -76.381816) (xy 397.142951 -76.349365) (xy 397.102802 -76.310656)
			(xy 397.068716 -76.266513) (xy 397.04142 -76.217878) (xy 397.021497 -76.165787) (xy 397.009371 -76.11135)
			(xy 397.0053 -76.055728) (xy 394.878806 -76.055728) (xy 394.868577 -76.061971) (xy 394.817248 -76.083783)
			(xy 394.763291 -76.097889) (xy 394.707854 -76.103989) (xy 394.65212 -76.101952) (xy 394.597277 -76.091822)
			(xy 394.544493 -76.073815) (xy 394.494893 -76.048314) (xy 394.449535 -76.015863) (xy 394.409386 -75.977154)
			(xy 394.3753 -75.933011) (xy 394.348004 -75.884376) (xy 394.328081 -75.832285) (xy 394.315955 -75.777848)
			(xy 394.311884 -75.722226) (xy 390.667457 -75.722226) (xy 390.629094 -75.763079) (xy 390.579841 -75.803824)
			(xy 390.52587 -75.838075) (xy 390.468031 -75.865292) (xy 390.407238 -75.885045) (xy 390.344448 -75.897023)
			(xy 390.280652 -75.901037) (xy 390.216856 -75.897023) (xy 390.154066 -75.885045) (xy 390.093273 -75.865292)
			(xy 390.035434 -75.838075) (xy 389.981463 -75.803824) (xy 389.93221 -75.763079) (xy 389.888453 -75.716482)
			(xy 389.85088 -75.664767) (xy 389.820086 -75.608752) (xy 389.796554 -75.549319) (xy 389.780657 -75.487405)
			(xy 389.772646 -75.423987) (xy 389.772144 -75.392026) (xy 389.772573 -75.361617) (xy 389.779825 -75.301233)
			(xy 389.794228 -75.242145) (xy 389.815577 -75.185197) (xy 389.843566 -75.131202) (xy 389.877796 -75.080932)
			(xy 389.917779 -75.035104) (xy 389.962942 -74.994372) (xy 389.987536 -74.976482) (xy 389.999032 -74.967879)
			(xy 390.017004 -74.945497) (xy 390.028035 -74.918997) (xy 390.031254 -74.890474) (xy 390.026406 -74.862182)
			(xy 390.013874 -74.836358) (xy 389.99465 -74.815043) (xy 389.98271 -74.807064) (xy 389.955583 -74.789607)
			(xy 389.905539 -74.748902) (xy 389.861047 -74.702193) (xy 389.822823 -74.650229) (xy 389.79148 -74.593847)
			(xy 389.767522 -74.533953) (xy 389.751335 -74.471509) (xy 389.743177 -74.407518) (xy 389.74268 -74.375264)
			(xy 347.334425 -74.375264) (xy 347.30599 -74.418243) (xy 347.268773 -74.45978) (xy 347.225905 -74.495455)
			(xy 347.178299 -74.524509) (xy 347.12697 -74.546321) (xy 347.073013 -74.560427) (xy 347.017576 -74.566527)
			(xy 346.961842 -74.56449) (xy 346.906999 -74.55436) (xy 346.854215 -74.536353) (xy 346.804615 -74.510852)
			(xy 346.759257 -74.478401) (xy 346.719108 -74.439692) (xy 346.685022 -74.395549) (xy 346.657726 -74.346914)
			(xy 346.637803 -74.294823) (xy 346.625677 -74.240386) (xy 346.621606 -74.184764) (xy 345.464384 -74.184764)
			(xy 345.463882 -74.216725) (xy 345.455871 -74.280143) (xy 345.439974 -74.342057) (xy 345.416442 -74.40149)
			(xy 345.385648 -74.457505) (xy 345.348075 -74.50922) (xy 345.304318 -74.555817) (xy 345.255065 -74.596562)
			(xy 345.201094 -74.630813) (xy 345.143255 -74.65803) (xy 345.082462 -74.677783) (xy 345.019672 -74.689761)
			(xy 344.955876 -74.693775) (xy 344.89208 -74.689761) (xy 344.82929 -74.677783) (xy 344.768497 -74.65803)
			(xy 344.710658 -74.630813) (xy 344.656687 -74.596562) (xy 344.607434 -74.555817) (xy 344.563677 -74.50922)
			(xy 344.526104 -74.457505) (xy 344.49531 -74.40149) (xy 344.471778 -74.342057) (xy 344.455881 -74.280143)
			(xy 344.44787 -74.216725) (xy 343.320023 -74.216725) (xy 343.312503 -74.267826) (xy 343.296435 -74.321233)
			(xy 343.272763 -74.37173) (xy 343.24199 -74.418243) (xy 343.204773 -74.45978) (xy 343.161905 -74.495455)
			(xy 343.114299 -74.524509) (xy 343.06297 -74.546321) (xy 343.009013 -74.560427) (xy 342.953576 -74.566527)
			(xy 342.897842 -74.56449) (xy 342.842999 -74.55436) (xy 342.790215 -74.536353) (xy 342.740615 -74.510852)
			(xy 342.695257 -74.478401) (xy 342.655108 -74.439692) (xy 342.621022 -74.395549) (xy 342.593726 -74.346914)
			(xy 342.573803 -74.294823) (xy 342.561677 -74.240386) (xy 342.557606 -74.184764) (xy 341.400384 -74.184764)
			(xy 341.399882 -74.216725) (xy 341.391871 -74.280143) (xy 341.375974 -74.342057) (xy 341.352442 -74.40149)
			(xy 341.321648 -74.457505) (xy 341.284075 -74.50922) (xy 341.240318 -74.555817) (xy 341.191065 -74.596562)
			(xy 341.137094 -74.630813) (xy 341.079255 -74.65803) (xy 341.018462 -74.677783) (xy 340.955672 -74.689761)
			(xy 340.891876 -74.693775) (xy 340.82808 -74.689761) (xy 340.76529 -74.677783) (xy 340.704497 -74.65803)
			(xy 340.646658 -74.630813) (xy 340.592687 -74.596562) (xy 340.543434 -74.555817) (xy 340.499677 -74.50922)
			(xy 340.462104 -74.457505) (xy 340.43131 -74.40149) (xy 340.407778 -74.342057) (xy 340.391881 -74.280143)
			(xy 340.38387 -74.216725) (xy 339.256023 -74.216725) (xy 339.248503 -74.267826) (xy 339.232435 -74.321233)
			(xy 339.208763 -74.37173) (xy 339.17799 -74.418243) (xy 339.140773 -74.45978) (xy 339.097905 -74.495455)
			(xy 339.050299 -74.524509) (xy 338.99897 -74.546321) (xy 338.945013 -74.560427) (xy 338.889576 -74.566527)
			(xy 338.833842 -74.56449) (xy 338.778999 -74.55436) (xy 338.726215 -74.536353) (xy 338.676615 -74.510852)
			(xy 338.631257 -74.478401) (xy 338.591108 -74.439692) (xy 338.557022 -74.395549) (xy 338.529726 -74.346914)
			(xy 338.509803 -74.294823) (xy 338.497677 -74.240386) (xy 338.493606 -74.184764) (xy 337.336384 -74.184764)
			(xy 337.335882 -74.216725) (xy 337.327871 -74.280143) (xy 337.311974 -74.342057) (xy 337.288442 -74.40149)
			(xy 337.257648 -74.457505) (xy 337.220075 -74.50922) (xy 337.176318 -74.555817) (xy 337.127065 -74.596562)
			(xy 337.073094 -74.630813) (xy 337.015255 -74.65803) (xy 336.954462 -74.677783) (xy 336.891672 -74.689761)
			(xy 336.827876 -74.693775) (xy 336.76408 -74.689761) (xy 336.70129 -74.677783) (xy 336.640497 -74.65803)
			(xy 336.582658 -74.630813) (xy 336.528687 -74.596562) (xy 336.479434 -74.555817) (xy 336.435677 -74.50922)
			(xy 336.398104 -74.457505) (xy 336.36731 -74.40149) (xy 336.343778 -74.342057) (xy 336.327881 -74.280143)
			(xy 336.31987 -74.216725) (xy 333.160023 -74.216725) (xy 333.152503 -74.267826) (xy 333.136435 -74.321233)
			(xy 333.112763 -74.37173) (xy 333.08199 -74.418243) (xy 333.044773 -74.45978) (xy 333.001905 -74.495455)
			(xy 332.954299 -74.524509) (xy 332.90297 -74.546321) (xy 332.849013 -74.560427) (xy 332.793576 -74.566527)
			(xy 332.737842 -74.56449) (xy 332.682999 -74.55436) (xy 332.630215 -74.536353) (xy 332.580615 -74.510852)
			(xy 332.535257 -74.478401) (xy 332.495108 -74.439692) (xy 332.461022 -74.395549) (xy 332.433726 -74.346914)
			(xy 332.413803 -74.294823) (xy 332.401677 -74.240386) (xy 332.397606 -74.184764) (xy 331.240384 -74.184764)
			(xy 331.239882 -74.216725) (xy 331.231871 -74.280143) (xy 331.215974 -74.342057) (xy 331.192442 -74.40149)
			(xy 331.161648 -74.457505) (xy 331.124075 -74.50922) (xy 331.080318 -74.555817) (xy 331.031065 -74.596562)
			(xy 330.977094 -74.630813) (xy 330.919255 -74.65803) (xy 330.858462 -74.677783) (xy 330.795672 -74.689761)
			(xy 330.731876 -74.693775) (xy 330.66808 -74.689761) (xy 330.60529 -74.677783) (xy 330.544497 -74.65803)
			(xy 330.486658 -74.630813) (xy 330.432687 -74.596562) (xy 330.383434 -74.555817) (xy 330.339677 -74.50922)
			(xy 330.302104 -74.457505) (xy 330.27131 -74.40149) (xy 330.247778 -74.342057) (xy 330.231881 -74.280143)
			(xy 330.22387 -74.216725) (xy 329.096023 -74.216725) (xy 329.088503 -74.267826) (xy 329.072435 -74.321233)
			(xy 329.048763 -74.37173) (xy 329.01799 -74.418243) (xy 328.980773 -74.45978) (xy 328.937905 -74.495455)
			(xy 328.890299 -74.524509) (xy 328.83897 -74.546321) (xy 328.785013 -74.560427) (xy 328.729576 -74.566527)
			(xy 328.673842 -74.56449) (xy 328.618999 -74.55436) (xy 328.566215 -74.536353) (xy 328.516615 -74.510852)
			(xy 328.471257 -74.478401) (xy 328.431108 -74.439692) (xy 328.397022 -74.395549) (xy 328.369726 -74.346914)
			(xy 328.349803 -74.294823) (xy 328.337677 -74.240386) (xy 328.333606 -74.184764) (xy 327.176384 -74.184764)
			(xy 327.175882 -74.216725) (xy 327.167871 -74.280143) (xy 327.151974 -74.342057) (xy 327.128442 -74.40149)
			(xy 327.097648 -74.457505) (xy 327.060075 -74.50922) (xy 327.016318 -74.555817) (xy 326.967065 -74.596562)
			(xy 326.913094 -74.630813) (xy 326.855255 -74.65803) (xy 326.794462 -74.677783) (xy 326.731672 -74.689761)
			(xy 326.667876 -74.693775) (xy 326.60408 -74.689761) (xy 326.54129 -74.677783) (xy 326.480497 -74.65803)
			(xy 326.422658 -74.630813) (xy 326.368687 -74.596562) (xy 326.319434 -74.555817) (xy 326.275677 -74.50922)
			(xy 326.238104 -74.457505) (xy 326.20731 -74.40149) (xy 326.183778 -74.342057) (xy 326.167881 -74.280143)
			(xy 326.15987 -74.216725) (xy 325.032023 -74.216725) (xy 325.024503 -74.267826) (xy 325.008435 -74.321233)
			(xy 324.984763 -74.37173) (xy 324.95399 -74.418243) (xy 324.916773 -74.45978) (xy 324.873905 -74.495455)
			(xy 324.826299 -74.524509) (xy 324.77497 -74.546321) (xy 324.721013 -74.560427) (xy 324.665576 -74.566527)
			(xy 324.609842 -74.56449) (xy 324.554999 -74.55436) (xy 324.502215 -74.536353) (xy 324.452615 -74.510852)
			(xy 324.407257 -74.478401) (xy 324.367108 -74.439692) (xy 324.333022 -74.395549) (xy 324.305726 -74.346914)
			(xy 324.285803 -74.294823) (xy 324.273677 -74.240386) (xy 324.269606 -74.184764) (xy 323.112384 -74.184764)
			(xy 323.111882 -74.216725) (xy 323.103871 -74.280143) (xy 323.087974 -74.342057) (xy 323.064442 -74.40149)
			(xy 323.033648 -74.457505) (xy 322.996075 -74.50922) (xy 322.952318 -74.555817) (xy 322.903065 -74.596562)
			(xy 322.849094 -74.630813) (xy 322.791255 -74.65803) (xy 322.730462 -74.677783) (xy 322.667672 -74.689761)
			(xy 322.603876 -74.693775) (xy 322.54008 -74.689761) (xy 322.47729 -74.677783) (xy 322.416497 -74.65803)
			(xy 322.358658 -74.630813) (xy 322.304687 -74.596562) (xy 322.255434 -74.555817) (xy 322.211677 -74.50922)
			(xy 322.174104 -74.457505) (xy 322.14331 -74.40149) (xy 322.119778 -74.342057) (xy 322.103881 -74.280143)
			(xy 322.09587 -74.216725) (xy 320.968023 -74.216725) (xy 320.960503 -74.267826) (xy 320.944435 -74.321233)
			(xy 320.920763 -74.37173) (xy 320.88999 -74.418243) (xy 320.852773 -74.45978) (xy 320.809905 -74.495455)
			(xy 320.762299 -74.524509) (xy 320.71097 -74.546321) (xy 320.657013 -74.560427) (xy 320.601576 -74.566527)
			(xy 320.545842 -74.56449) (xy 320.490999 -74.55436) (xy 320.438215 -74.536353) (xy 320.388615 -74.510852)
			(xy 320.343257 -74.478401) (xy 320.303108 -74.439692) (xy 320.269022 -74.395549) (xy 320.241726 -74.346914)
			(xy 320.221803 -74.294823) (xy 320.209677 -74.240386) (xy 320.205606 -74.184764) (xy 312.841132 -74.184764)
			(xy 312.840623 -74.21265) (xy 312.832503 -74.267826) (xy 312.816435 -74.321233) (xy 312.792763 -74.37173)
			(xy 312.76199 -74.418243) (xy 312.724773 -74.45978) (xy 312.681905 -74.495455) (xy 312.634299 -74.524509)
			(xy 312.58297 -74.546321) (xy 312.529013 -74.560427) (xy 312.473576 -74.566527) (xy 312.417842 -74.56449)
			(xy 312.362999 -74.55436) (xy 312.310215 -74.536353) (xy 312.260615 -74.510852) (xy 312.215257 -74.478401)
			(xy 312.175108 -74.439692) (xy 312.141022 -74.395549) (xy 312.113726 -74.346914) (xy 312.093803 -74.294823)
			(xy 312.081677 -74.240386) (xy 312.077606 -74.184764) (xy 310.920384 -74.184764) (xy 310.919882 -74.216725)
			(xy 310.911871 -74.280143) (xy 310.895974 -74.342057) (xy 310.872442 -74.40149) (xy 310.841648 -74.457505)
			(xy 310.804075 -74.50922) (xy 310.760318 -74.555817) (xy 310.711065 -74.596562) (xy 310.657094 -74.630813)
			(xy 310.599255 -74.65803) (xy 310.538462 -74.677783) (xy 310.475672 -74.689761) (xy 310.411876 -74.693775)
			(xy 310.34808 -74.689761) (xy 310.28529 -74.677783) (xy 310.224497 -74.65803) (xy 310.166658 -74.630813)
			(xy 310.112687 -74.596562) (xy 310.063434 -74.555817) (xy 310.019677 -74.50922) (xy 309.982104 -74.457505)
			(xy 309.95131 -74.40149) (xy 309.927778 -74.342057) (xy 309.911881 -74.280143) (xy 309.90387 -74.216725)
			(xy 308.776023 -74.216725) (xy 308.768503 -74.267826) (xy 308.752435 -74.321233) (xy 308.728763 -74.37173)
			(xy 308.69799 -74.418243) (xy 308.660773 -74.45978) (xy 308.617905 -74.495455) (xy 308.570299 -74.524509)
			(xy 308.51897 -74.546321) (xy 308.465013 -74.560427) (xy 308.409576 -74.566527) (xy 308.353842 -74.56449)
			(xy 308.298999 -74.55436) (xy 308.246215 -74.536353) (xy 308.196615 -74.510852) (xy 308.151257 -74.478401)
			(xy 308.111108 -74.439692) (xy 308.077022 -74.395549) (xy 308.049726 -74.346914) (xy 308.029803 -74.294823)
			(xy 308.017677 -74.240386) (xy 308.013606 -74.184764) (xy 298.511468 -74.184764) (xy 298.511468 -74.760836)
			(xy 298.510963 -74.86636) (xy 298.502879 -75.077254) (xy 298.486723 -75.287683) (xy 298.463745 -75.486725)
			(xy 309.90387 -75.486725) (xy 309.90387 -75.422803) (xy 309.911881 -75.359385) (xy 309.927778 -75.297471)
			(xy 309.95131 -75.238038) (xy 309.982104 -75.182023) (xy 310.019677 -75.130308) (xy 310.063434 -75.083711)
			(xy 310.112687 -75.042966) (xy 310.166658 -75.008715) (xy 310.224497 -74.981498) (xy 310.28529 -74.961745)
			(xy 310.34808 -74.949767) (xy 310.411876 -74.945754) (xy 310.475672 -74.949767) (xy 310.538462 -74.961745)
			(xy 310.599255 -74.981498) (xy 310.657094 -75.008715) (xy 310.711065 -75.042966) (xy 310.760318 -75.083711)
			(xy 310.804075 -75.130308) (xy 310.841648 -75.182023) (xy 310.872442 -75.238038) (xy 310.895974 -75.297471)
			(xy 310.911871 -75.359385) (xy 310.919882 -75.422803) (xy 310.920384 -75.454764) (xy 311.045858 -75.454764)
			(xy 311.049929 -75.399142) (xy 311.062055 -75.344705) (xy 311.081978 -75.292614) (xy 311.109274 -75.243979)
			(xy 311.14336 -75.199836) (xy 311.183509 -75.161127) (xy 311.228867 -75.128676) (xy 311.278467 -75.103175)
			(xy 311.331251 -75.085168) (xy 311.386094 -75.075038) (xy 311.441828 -75.073001) (xy 311.497265 -75.079101)
			(xy 311.551222 -75.093207) (xy 311.602551 -75.115019) (xy 311.650157 -75.144073) (xy 311.693025 -75.179748)
			(xy 311.730242 -75.221285) (xy 311.761015 -75.267798) (xy 311.784687 -75.318295) (xy 311.800755 -75.371702)
			(xy 311.808875 -75.426878) (xy 311.809384 -75.454764) (xy 311.808875 -75.48265) (xy 311.800755 -75.537826)
			(xy 311.784687 -75.591233) (xy 311.761015 -75.64173) (xy 311.730242 -75.688243) (xy 311.711855 -75.708764)
			(xy 330.349858 -75.708764) (xy 330.353929 -75.653142) (xy 330.366055 -75.598705) (xy 330.385978 -75.546614)
			(xy 330.413274 -75.497979) (xy 330.44736 -75.453836) (xy 330.487509 -75.415127) (xy 330.532867 -75.382676)
			(xy 330.582467 -75.357175) (xy 330.635251 -75.339168) (xy 330.690094 -75.329038) (xy 330.745828 -75.327001)
			(xy 330.801265 -75.333101) (xy 330.855222 -75.347207) (xy 330.906551 -75.369019) (xy 330.954157 -75.398073)
			(xy 330.997025 -75.433748) (xy 331.034242 -75.475285) (xy 331.065015 -75.521798) (xy 331.088687 -75.572295)
			(xy 331.104755 -75.625702) (xy 331.112875 -75.680878) (xy 331.113384 -75.708764) (xy 331.112875 -75.73665)
			(xy 331.104755 -75.791826) (xy 331.088687 -75.845233) (xy 331.065015 -75.89573) (xy 331.034242 -75.942243)
			(xy 330.997025 -75.98378) (xy 330.954157 -76.019455) (xy 330.906551 -76.048509) (xy 330.855222 -76.070321)
			(xy 330.801265 -76.084427) (xy 330.745828 -76.090527) (xy 330.690094 -76.08849) (xy 330.635251 -76.07836)
			(xy 330.582467 -76.060353) (xy 330.532867 -76.034852) (xy 330.487509 -76.002401) (xy 330.44736 -75.963692)
			(xy 330.413274 -75.919549) (xy 330.385978 -75.870914) (xy 330.366055 -75.818823) (xy 330.353929 -75.764386)
			(xy 330.349858 -75.708764) (xy 311.711855 -75.708764) (xy 311.693025 -75.72978) (xy 311.650157 -75.765455)
			(xy 311.602551 -75.794509) (xy 311.551222 -75.816321) (xy 311.497265 -75.830427) (xy 311.441828 -75.836527)
			(xy 311.386094 -75.83449) (xy 311.331251 -75.82436) (xy 311.278467 -75.806353) (xy 311.228867 -75.780852)
			(xy 311.183509 -75.748401) (xy 311.14336 -75.709692) (xy 311.109274 -75.665549) (xy 311.081978 -75.616914)
			(xy 311.062055 -75.564823) (xy 311.049929 -75.510386) (xy 311.045858 -75.454764) (xy 310.920384 -75.454764)
			(xy 310.919882 -75.486725) (xy 310.911871 -75.550143) (xy 310.895974 -75.612057) (xy 310.872442 -75.67149)
			(xy 310.841648 -75.727505) (xy 310.804075 -75.77922) (xy 310.760318 -75.825817) (xy 310.711065 -75.866562)
			(xy 310.657094 -75.900813) (xy 310.599255 -75.92803) (xy 310.538462 -75.947783) (xy 310.475672 -75.959761)
			(xy 310.411876 -75.963775) (xy 310.34808 -75.959761) (xy 310.28529 -75.947783) (xy 310.224497 -75.92803)
			(xy 310.166658 -75.900813) (xy 310.112687 -75.866562) (xy 310.063434 -75.825817) (xy 310.019677 -75.77922)
			(xy 309.982104 -75.727505) (xy 309.95131 -75.67149) (xy 309.927778 -75.612057) (xy 309.911881 -75.550143)
			(xy 309.90387 -75.486725) (xy 298.463745 -75.486725) (xy 298.46252 -75.49734) (xy 298.430303 -75.705915)
			(xy 298.390121 -75.913103) (xy 298.342033 -76.1186) (xy 298.308705 -76.239878) (xy 312.887612 -76.239878)
			(xy 312.891683 -76.184256) (xy 312.903809 -76.129819) (xy 312.923732 -76.077728) (xy 312.951028 -76.029093)
			(xy 312.985114 -75.98495) (xy 313.025263 -75.946241) (xy 313.070621 -75.91379) (xy 313.120221 -75.888289)
			(xy 313.173005 -75.870282) (xy 313.227848 -75.860152) (xy 313.283582 -75.858115) (xy 313.339019 -75.864215)
			(xy 313.392976 -75.878321) (xy 313.444305 -75.900133) (xy 313.491911 -75.929187) (xy 313.534779 -75.964862)
			(xy 313.571996 -76.006399) (xy 313.602769 -76.052912) (xy 313.626441 -76.103409) (xy 313.642509 -76.156816)
			(xy 313.650629 -76.211992) (xy 313.651138 -76.239878) (xy 313.650629 -76.267764) (xy 313.642509 -76.32294)
			(xy 313.626441 -76.376347) (xy 313.611591 -76.408026) (xy 389.89965 -76.408026) (xy 389.903721 -76.352404)
			(xy 389.915847 -76.297967) (xy 389.93577 -76.245876) (xy 389.963066 -76.197241) (xy 389.997152 -76.153098)
			(xy 390.037301 -76.114389) (xy 390.082659 -76.081938) (xy 390.132259 -76.056437) (xy 390.185043 -76.03843)
			(xy 390.239886 -76.0283) (xy 390.29562 -76.026263) (xy 390.351057 -76.032363) (xy 390.405014 -76.046469)
			(xy 390.456343 -76.068281) (xy 390.503949 -76.097335) (xy 390.546817 -76.13301) (xy 390.584034 -76.174547)
			(xy 390.614807 -76.22106) (xy 390.638479 -76.271557) (xy 390.654547 -76.324964) (xy 390.662667 -76.38014)
			(xy 390.663176 -76.408026) (xy 390.662667 -76.435912) (xy 390.654547 -76.491088) (xy 390.638479 -76.544495)
			(xy 390.614807 -76.594992) (xy 390.584034 -76.641505) (xy 390.546817 -76.683042) (xy 390.503949 -76.718717)
			(xy 390.456343 -76.747771) (xy 390.405014 -76.769583) (xy 390.351057 -76.783689) (xy 390.29562 -76.789789)
			(xy 390.239886 -76.787752) (xy 390.185043 -76.777622) (xy 390.132259 -76.759615) (xy 390.082659 -76.734114)
			(xy 390.037301 -76.701663) (xy 389.997152 -76.662954) (xy 389.963066 -76.618811) (xy 389.93577 -76.570176)
			(xy 389.915847 -76.518085) (xy 389.903721 -76.463648) (xy 389.89965 -76.408026) (xy 313.611591 -76.408026)
			(xy 313.602769 -76.426844) (xy 313.571996 -76.473357) (xy 313.534779 -76.514894) (xy 313.491911 -76.550569)
			(xy 313.444305 -76.579623) (xy 313.392976 -76.601435) (xy 313.339019 -76.615541) (xy 313.283582 -76.621641)
			(xy 313.227848 -76.619604) (xy 313.173005 -76.609474) (xy 313.120221 -76.591467) (xy 313.070621 -76.565966)
			(xy 313.025263 -76.533515) (xy 312.985114 -76.494806) (xy 312.951028 -76.450663) (xy 312.923732 -76.402028)
			(xy 312.903809 -76.349937) (xy 312.891683 -76.2955) (xy 312.887612 -76.239878) (xy 298.308705 -76.239878)
			(xy 298.286109 -76.322104) (xy 298.222432 -76.523317) (xy 298.151094 -76.721944) (xy 298.0722 -76.917692)
			(xy 297.985867 -77.110274) (xy 297.89222 -77.299409) (xy 297.791398 -77.484818) (xy 297.748589 -77.556825)
			(xy 309.90387 -77.556825) (xy 309.90387 -77.492903) (xy 309.911881 -77.429485) (xy 309.927778 -77.367571)
			(xy 309.95131 -77.308138) (xy 309.982104 -77.252123) (xy 310.019677 -77.200408) (xy 310.063434 -77.153811)
			(xy 310.112687 -77.113066) (xy 310.166658 -77.078815) (xy 310.224497 -77.051598) (xy 310.28529 -77.031845)
			(xy 310.34808 -77.019867) (xy 310.411876 -77.015854) (xy 310.475672 -77.019867) (xy 310.538462 -77.031845)
			(xy 310.565705 -77.040697) (xy 330.21752 -77.040697) (xy 330.21752 -76.976775) (xy 330.225531 -76.913357)
			(xy 330.241428 -76.851443) (xy 330.26496 -76.79201) (xy 330.295754 -76.735995) (xy 330.333327 -76.68428)
			(xy 330.377084 -76.637683) (xy 330.426337 -76.596938) (xy 330.480308 -76.562687) (xy 330.538147 -76.53547)
			(xy 330.59894 -76.515717) (xy 330.66173 -76.503739) (xy 330.725526 -76.499726) (xy 330.789322 -76.503739)
			(xy 330.852112 -76.515717) (xy 330.912905 -76.53547) (xy 330.970744 -76.562687) (xy 331.024715 -76.596938)
			(xy 331.073968 -76.637683) (xy 331.117725 -76.68428) (xy 331.155298 -76.735995) (xy 331.186092 -76.79201)
			(xy 331.209624 -76.851443) (xy 331.217011 -76.880212) (xy 395.471902 -76.880212) (xy 395.475973 -76.82459)
			(xy 395.488099 -76.770153) (xy 395.508022 -76.718062) (xy 395.535318 -76.669427) (xy 395.569404 -76.625284)
			(xy 395.609553 -76.586575) (xy 395.654911 -76.554124) (xy 395.704511 -76.528623) (xy 395.757295 -76.510616)
			(xy 395.812138 -76.500486) (xy 395.867872 -76.498449) (xy 395.923309 -76.504549) (xy 395.977266 -76.518655)
			(xy 396.028595 -76.540467) (xy 396.076201 -76.569521) (xy 396.119069 -76.605196) (xy 396.156286 -76.646733)
			(xy 396.1659 -76.661264) (xy 398.977864 -76.661264) (xy 398.981935 -76.605642) (xy 398.994061 -76.551205)
			(xy 399.013984 -76.499114) (xy 399.04128 -76.450479) (xy 399.075366 -76.406336) (xy 399.115515 -76.367627)
			(xy 399.160873 -76.335176) (xy 399.210473 -76.309675) (xy 399.263257 -76.291668) (xy 399.3181 -76.281538)
			(xy 399.373834 -76.279501) (xy 399.429271 -76.285601) (xy 399.483228 -76.299707) (xy 399.534557 -76.321519)
			(xy 399.582163 -76.350573) (xy 399.625031 -76.386248) (xy 399.662248 -76.427785) (xy 399.693021 -76.474298)
			(xy 399.716693 -76.524795) (xy 399.732761 -76.578202) (xy 399.740881 -76.633378) (xy 399.74139 -76.661264)
			(xy 399.740881 -76.68915) (xy 399.732761 -76.744326) (xy 399.716693 -76.797733) (xy 399.693021 -76.84823)
			(xy 399.662248 -76.894743) (xy 399.625031 -76.93628) (xy 399.582163 -76.971955) (xy 399.534557 -77.001009)
			(xy 399.483228 -77.022821) (xy 399.429271 -77.036927) (xy 399.373834 -77.043027) (xy 399.3181 -77.04099)
			(xy 399.263257 -77.03086) (xy 399.210473 -77.012853) (xy 399.160873 -76.987352) (xy 399.115515 -76.954901)
			(xy 399.075366 -76.916192) (xy 399.04128 -76.872049) (xy 399.013984 -76.823414) (xy 398.994061 -76.771323)
			(xy 398.981935 -76.716886) (xy 398.977864 -76.661264) (xy 396.1659 -76.661264) (xy 396.187059 -76.693246)
			(xy 396.210731 -76.743743) (xy 396.226799 -76.79715) (xy 396.234919 -76.852326) (xy 396.235428 -76.880212)
			(xy 396.234919 -76.908098) (xy 396.226799 -76.963274) (xy 396.210731 -77.016681) (xy 396.187059 -77.067178)
			(xy 396.156489 -77.113384) (xy 410.948378 -77.113384) (xy 410.94888 -77.081423) (xy 410.956891 -77.018005)
			(xy 410.972788 -76.956091) (xy 410.99632 -76.896658) (xy 411.027114 -76.840643) (xy 411.064687 -76.788928)
			(xy 411.108444 -76.742331) (xy 411.157697 -76.701586) (xy 411.211668 -76.667335) (xy 411.269507 -76.640118)
			(xy 411.3303 -76.620365) (xy 411.39309 -76.608387) (xy 411.456886 -76.604374) (xy 411.520682 -76.608387)
			(xy 411.583472 -76.620365) (xy 411.644265 -76.640118) (xy 411.702104 -76.667335) (xy 411.756075 -76.701586)
			(xy 411.805328 -76.742331) (xy 411.849085 -76.788928) (xy 411.886658 -76.840643) (xy 411.917348 -76.896468)
			(xy 412.980378 -76.896468) (xy 412.980875 -76.865181) (xy 412.988549 -76.80308) (xy 413.00379 -76.742391)
			(xy 413.026367 -76.684032) (xy 413.055938 -76.628887) (xy 413.092056 -76.577789) (xy 413.134175 -76.531513)
			(xy 413.181657 -76.490758) (xy 413.207454 -76.47305) (xy 413.217608 -76.46553) (xy 413.229468 -76.443255)
			(xy 413.23006 -76.430632) (xy 413.23006 -76.346304) (xy 413.229424 -76.333697) (xy 413.21756 -76.31145)
			(xy 413.207454 -76.303886) (xy 413.181637 -76.286212) (xy 413.134174 -76.245442) (xy 413.092073 -76.199156)
			(xy 413.05597 -76.148053) (xy 413.02641 -76.092906) (xy 413.003841 -76.034549) (xy 412.988604 -75.973864)
			(xy 412.980928 -75.911767) (xy 412.98093 -75.849198) (xy 412.98861 -75.787102) (xy 413.003852 -75.726417)
			(xy 413.026425 -75.668062) (xy 413.055988 -75.612917) (xy 413.092095 -75.561817) (xy 413.134199 -75.515533)
			(xy 413.181665 -75.474767) (xy 413.207454 -75.45705) (xy 413.217608 -75.44953) (xy 413.229468 -75.427255)
			(xy 413.23006 -75.414632) (xy 413.23006 -75.330304) (xy 413.229424 -75.317697) (xy 413.21756 -75.29545)
			(xy 413.207454 -75.287886) (xy 413.181637 -75.270212) (xy 413.134174 -75.229442) (xy 413.092073 -75.183156)
			(xy 413.05597 -75.132053) (xy 413.02641 -75.076906) (xy 413.003841 -75.018549) (xy 412.988604 -74.957864)
			(xy 412.980928 -74.895767) (xy 412.98093 -74.833198) (xy 412.98861 -74.771102) (xy 413.003852 -74.710417)
			(xy 413.026425 -74.652062) (xy 413.055988 -74.596917) (xy 413.092095 -74.545817) (xy 413.134199 -74.499533)
			(xy 413.181665 -74.458767) (xy 413.207454 -74.44105) (xy 413.217608 -74.43353) (xy 413.229468 -74.411255)
			(xy 413.23006 -74.398632) (xy 413.23006 -74.314304) (xy 413.229424 -74.301697) (xy 413.21756 -74.27945)
			(xy 413.207454 -74.271886) (xy 413.181637 -74.254212) (xy 413.134174 -74.213442) (xy 413.092073 -74.167156)
			(xy 413.05597 -74.116053) (xy 413.02641 -74.060906) (xy 413.003841 -74.002549) (xy 412.988604 -73.941864)
			(xy 412.980928 -73.879767) (xy 412.98093 -73.817198) (xy 412.98861 -73.755102) (xy 413.003852 -73.694417)
			(xy 413.026425 -73.636062) (xy 413.055988 -73.580917) (xy 413.092095 -73.529817) (xy 413.134199 -73.483533)
			(xy 413.181665 -73.442767) (xy 413.207454 -73.42505) (xy 413.217608 -73.41753) (xy 413.229468 -73.395255)
			(xy 413.23006 -73.382632) (xy 413.23006 -73.298304) (xy 413.229424 -73.285697) (xy 413.21756 -73.26345)
			(xy 413.207454 -73.255886) (xy 413.181684 -73.238139) (xy 413.134204 -73.197387) (xy 413.092085 -73.151115)
			(xy 413.055964 -73.100024) (xy 413.026388 -73.044885) (xy 413.003802 -72.986533) (xy 412.98855 -72.92585)
			(xy 412.980862 -72.863753) (xy 412.980378 -72.832468) (xy 412.980918 -72.800399) (xy 412.988975 -72.73677)
			(xy 413.00497 -72.674659) (xy 413.02865 -72.615053) (xy 413.059637 -72.558898) (xy 413.09744 -72.507086)
			(xy 413.141459 -72.460439) (xy 413.190995 -72.419699) (xy 413.217868 -72.402192) (xy 413.22879 -72.395334)
			(xy 413.241236 -72.373236) (xy 413.243522 -72.262492) (xy 413.231838 -72.239886) (xy 413.22117 -72.23252)
			(xy 413.19597 -72.214713) (xy 413.149647 -72.173945) (xy 413.108598 -72.127872) (xy 413.073425 -72.07717)
			(xy 413.044646 -72.022585) (xy 413.022682 -71.964919) (xy 413.007858 -71.905019) (xy 413.00039 -71.843766)
			(xy 412.999936 -71.812912) (xy 413.000438 -71.780951) (xy 413.008449 -71.717533) (xy 413.024346 -71.655619)
			(xy 413.047878 -71.596186) (xy 413.078672 -71.540171) (xy 413.116245 -71.488456) (xy 413.160002 -71.441859)
			(xy 413.209255 -71.401114) (xy 413.263226 -71.366863) (xy 413.321065 -71.339646) (xy 413.381858 -71.319893)
			(xy 413.444648 -71.307915) (xy 413.508444 -71.303902) (xy 413.57224 -71.307915) (xy 413.63503 -71.319893)
			(xy 413.695823 -71.339646) (xy 413.753662 -71.366863) (xy 413.807633 -71.401114) (xy 413.856886 -71.441859)
			(xy 413.900643 -71.488456) (xy 413.938216 -71.540171) (xy 413.96901 -71.596186) (xy 413.992542 -71.655619)
			(xy 414.008439 -71.717533) (xy 414.01645 -71.780951) (xy 414.016952 -71.812912) (xy 414.016507 -71.844984)
			(xy 414.008439 -71.908618) (xy 413.992431 -71.970733) (xy 413.968739 -72.030341) (xy 413.937739 -72.086496)
			(xy 413.899922 -72.138307) (xy 413.85589 -72.18495) (xy 413.806341 -72.225685) (xy 413.779462 -72.243188)
			(xy 413.76854 -72.250046) (xy 413.756094 -72.272144) (xy 413.753808 -72.382888) (xy 413.765492 -72.405494)
			(xy 413.77616 -72.41286) (xy 413.801358 -72.43067) (xy 413.847679 -72.471439) (xy 413.888727 -72.517512)
			(xy 413.9239 -72.568213) (xy 413.95268 -72.622797) (xy 413.974644 -72.680463) (xy 413.98947 -72.740362)
			(xy 413.996939 -72.801615) (xy 413.997394 -72.832468) (xy 413.996937 -72.863756) (xy 413.989258 -72.92586)
			(xy 413.974012 -72.98655) (xy 413.95143 -73.04491) (xy 413.921853 -73.100055) (xy 413.885729 -73.151152)
			(xy 413.843605 -73.197426) (xy 413.796118 -73.238179) (xy 413.770318 -73.255886) (xy 413.760188 -73.263432)
			(xy 413.748318 -73.285688) (xy 413.747712 -73.298304) (xy 413.747712 -73.382632) (xy 413.748398 -73.395231)
			(xy 413.760227 -73.417479) (xy 413.770318 -73.42505) (xy 413.796076 -73.442808) (xy 413.843539 -73.48357)
			(xy 413.885641 -73.529847) (xy 413.921746 -73.580942) (xy 413.951308 -73.636081) (xy 413.97388 -73.694431)
			(xy 413.989121 -73.75511) (xy 413.996801 -73.8172) (xy 413.996803 -73.879764) (xy 413.989128 -73.941855)
			(xy 413.973891 -74.002535) (xy 413.951323 -74.060887) (xy 413.921765 -74.116028) (xy 413.885663 -74.167125)
			(xy 413.843565 -74.213406) (xy 413.796105 -74.25417) (xy 413.770318 -74.271886) (xy 413.760188 -74.279432)
			(xy 413.748318 -74.301688) (xy 413.747712 -74.314304) (xy 413.747712 -74.398632) (xy 413.748398 -74.411231)
			(xy 413.760227 -74.433479) (xy 413.770318 -74.44105) (xy 413.796076 -74.458808) (xy 413.843539 -74.49957)
			(xy 413.885641 -74.545847) (xy 413.921746 -74.596942) (xy 413.951308 -74.652081) (xy 413.97388 -74.710431)
			(xy 413.988327 -74.767948) (xy 421.29456 -74.767948) (xy 421.29456 -66.06794) (xy 421.295065 -65.962416)
			(xy 421.303149 -65.751522) (xy 421.319305 -65.541093) (xy 421.343508 -65.331436) (xy 421.375725 -65.122861)
			(xy 421.415907 -64.915673) (xy 421.463995 -64.710176) (xy 421.519919 -64.506672) (xy 421.583596 -64.305459)
			(xy 421.654934 -64.106832) (xy 421.733828 -63.911084) (xy 421.820161 -63.718502) (xy 421.913808 -63.529367)
			(xy 422.01463 -63.343958) (xy 422.12248 -63.162547) (xy 422.237199 -62.9854) (xy 422.358619 -62.812778)
			(xy 422.486562 -62.644932) (xy 422.62084 -62.48211) (xy 422.761256 -62.324551) (xy 422.907604 -62.172486)
			(xy 423.059669 -62.026138) (xy 423.217228 -61.885722) (xy 423.38005 -61.751444) (xy 423.547896 -61.623501)
			(xy 423.720518 -61.502081) (xy 423.897665 -61.387362) (xy 424.079076 -61.279512) (xy 424.264485 -61.17869)
			(xy 424.45362 -61.085043) (xy 424.646202 -60.99871) (xy 424.84195 -60.919816) (xy 425.040577 -60.848478)
			(xy 425.24179 -60.784801) (xy 425.445294 -60.728877) (xy 425.650791 -60.680789) (xy 425.857979 -60.640607)
			(xy 426.066554 -60.60839) (xy 426.276211 -60.584187) (xy 426.48664 -60.568031) (xy 426.697534 -60.559947)
			(xy 426.908582 -60.559947) (xy 427.119476 -60.568031) (xy 427.329905 -60.584187) (xy 427.539562 -60.60839)
			(xy 427.748137 -60.640607) (xy 427.955325 -60.680789) (xy 428.160822 -60.728877) (xy 428.364326 -60.784801)
			(xy 428.565539 -60.848478) (xy 428.764166 -60.919816) (xy 428.959914 -60.99871) (xy 429.152496 -61.085043)
			(xy 429.341631 -61.17869) (xy 429.52704 -61.279512) (xy 429.708451 -61.387362) (xy 429.885598 -61.502081)
			(xy 430.05822 -61.623501) (xy 430.226066 -61.751444) (xy 430.388888 -61.885722) (xy 430.546447 -62.026138)
			(xy 430.698512 -62.172486) (xy 430.84486 -62.324551) (xy 430.985276 -62.48211) (xy 431.119554 -62.644932)
			(xy 431.247497 -62.812778) (xy 431.368917 -62.9854) (xy 431.483636 -63.162547) (xy 431.591486 -63.343958)
			(xy 431.692308 -63.529367) (xy 431.785955 -63.718502) (xy 431.872288 -63.911084) (xy 431.951182 -64.106832)
			(xy 432.02252 -64.305459) (xy 432.086197 -64.506672) (xy 432.142121 -64.710176) (xy 432.174962 -64.850518)
			(xy 444.009526 -64.850518) (xy 444.010047 -64.821601) (xy 444.018774 -64.76443) (xy 444.036031 -64.70923)
			(xy 444.061422 -64.657269) (xy 444.094366 -64.609735) (xy 444.134106 -64.567718) (xy 444.156592 -64.549528)
			(xy 444.165375 -64.541898) (xy 444.175572 -64.521015) (xy 444.17615 -64.509396) (xy 444.17615 -64.42964)
			(xy 444.175649 -64.418003) (xy 444.165435 -64.397093) (xy 444.156592 -64.389508) (xy 444.134111 -64.371314)
			(xy 444.094376 -64.329295) (xy 444.061437 -64.281761) (xy 444.036048 -64.2298) (xy 444.018791 -64.174603)
			(xy 444.010061 -64.117434) (xy 444.009526 -64.088518) (xy 444.009972 -64.061264) (xy 444.017728 -64.007311)
			(xy 444.033083 -63.95501) (xy 444.055726 -63.905428) (xy 444.085195 -63.859573) (xy 444.120891 -63.81838)
			(xy 444.162086 -63.782686) (xy 444.207942 -63.753218) (xy 444.257525 -63.730577) (xy 444.309826 -63.715224)
			(xy 444.36378 -63.707471) (xy 444.391034 -63.70701) (xy 444.4187 -63.707506) (xy 444.47345 -63.715498)
			(xy 444.526474 -63.73131) (xy 444.57666 -63.75461) (xy 444.622957 -63.784911) (xy 444.664395 -63.821577)
			(xy 444.682626 -63.842392) (xy 444.689738 -63.851028) (xy 444.709804 -63.860426) (xy 444.79845 -63.860934)
			(xy 444.80932 -63.860502) (xy 444.829186 -63.851682) (xy 444.836804 -63.843916) (xy 444.837312 -63.843408)
			(xy 444.855523 -63.82321) (xy 444.896657 -63.787636) (xy 444.942425 -63.758262) (xy 444.991899 -63.735683)
			(xy 445.044077 -63.720357) (xy 445.097903 -63.712593) (xy 445.125094 -63.71209) (xy 445.152347 -63.712561)
			(xy 445.206297 -63.720317) (xy 445.258595 -63.735672) (xy 445.308175 -63.758314) (xy 445.354028 -63.787781)
			(xy 445.39522 -63.823474) (xy 445.430914 -63.864666) (xy 445.445329 -63.887096) (xy 445.634618 -63.887096)
			(xy 445.635127 -63.858179) (xy 445.643857 -63.801007) (xy 445.661116 -63.745807) (xy 445.68651 -63.693846)
			(xy 445.719455 -63.646312) (xy 445.759198 -63.604296) (xy 445.781684 -63.586106) (xy 445.790493 -63.578501)
			(xy 445.800672 -63.557598) (xy 445.801242 -63.545974) (xy 445.801242 -63.466218) (xy 445.800698 -63.454586)
			(xy 445.790515 -63.433675) (xy 445.781684 -63.426086) (xy 445.75919 -63.407907) (xy 445.719457 -63.365884)
			(xy 445.686519 -63.318347) (xy 445.661133 -63.266383) (xy 445.643879 -63.211184) (xy 445.635152 -63.154013)
			(xy 445.634618 -63.125096) (xy 445.635052 -63.097842) (xy 445.64281 -63.043889) (xy 445.658168 -62.991589)
			(xy 445.680813 -62.942007) (xy 445.710283 -62.896152) (xy 445.74598 -62.854959) (xy 445.787176 -62.819265)
			(xy 445.833033 -62.789798) (xy 445.882617 -62.767157) (xy 445.934918 -62.751804) (xy 445.988872 -62.74405)
			(xy 446.016126 -62.743588) (xy 446.043791 -62.744097) (xy 446.098541 -62.752087) (xy 446.151564 -62.767897)
			(xy 446.20175 -62.791195) (xy 446.248047 -62.821493) (xy 446.289486 -62.858157) (xy 446.307718 -62.87897)
			(xy 446.31483 -62.887606) (xy 446.334896 -62.897004) (xy 446.423542 -62.897512) (xy 446.434413 -62.897083)
			(xy 446.454279 -62.888262) (xy 446.461896 -62.880494) (xy 446.462404 -62.879986) (xy 446.480615 -62.859787)
			(xy 446.521749 -62.824214) (xy 446.567517 -62.794841) (xy 446.616991 -62.772263) (xy 446.669169 -62.756936)
			(xy 446.722995 -62.749172) (xy 446.750186 -62.748668) (xy 446.777436 -62.749191) (xy 446.831381 -62.756945)
			(xy 446.883673 -62.772297) (xy 446.933249 -62.794935) (xy 446.979098 -62.824398) (xy 447.020288 -62.860085)
			(xy 447.05598 -62.901271) (xy 447.085447 -62.947118) (xy 447.108089 -62.996691) (xy 447.123447 -63.048982)
			(xy 447.131206 -63.102926) (xy 447.131694 -63.130176) (xy 447.131161 -63.159092) (xy 447.122435 -63.216263)
			(xy 447.10518 -63.271462) (xy 447.079791 -63.323423) (xy 447.04685 -63.370958) (xy 447.007112 -63.412975)
			(xy 446.984628 -63.431166) (xy 446.975834 -63.438785) (xy 446.965646 -63.459677) (xy 446.96507 -63.471298)
			(xy 446.96507 -63.551054) (xy 446.965568 -63.562692) (xy 446.975783 -63.583602) (xy 446.984628 -63.591186)
			(xy 447.007111 -63.609378) (xy 447.046845 -63.651398) (xy 447.079783 -63.698933) (xy 447.105171 -63.750894)
			(xy 447.122428 -63.806091) (xy 447.1277 -63.840614) (xy 447.549778 -63.840614) (xy 447.550277 -63.811696)
			(xy 447.559006 -63.754523) (xy 447.576265 -63.699322) (xy 447.601661 -63.64736) (xy 447.634609 -63.599827)
			(xy 447.674356 -63.557812) (xy 447.696844 -63.539624) (xy 447.705638 -63.532004) (xy 447.715827 -63.511113)
			(xy 447.716402 -63.499492) (xy 447.716402 -63.419736) (xy 447.715885 -63.408101) (xy 447.70568 -63.387192)
			(xy 447.696844 -63.379604) (xy 447.674372 -63.3614) (xy 447.634634 -63.319384) (xy 447.601692 -63.271852)
			(xy 447.576301 -63.219893) (xy 447.559043 -63.164698) (xy 447.550313 -63.107529) (xy 447.549778 -63.078614)
			(xy 447.550291 -63.051364) (xy 447.558045 -62.997418) (xy 447.573398 -62.945124) (xy 447.596037 -62.895548)
			(xy 447.6255 -62.849699) (xy 447.661189 -62.808509) (xy 447.702376 -62.772817) (xy 447.748224 -62.74335)
			(xy 447.797798 -62.720708) (xy 447.85009 -62.705351) (xy 447.904036 -62.697593) (xy 447.931286 -62.697106)
			(xy 447.958953 -62.697567) (xy 448.013705 -62.705566) (xy 448.06673 -62.721385) (xy 448.116915 -62.744692)
			(xy 448.163211 -62.774999) (xy 448.204648 -62.811671) (xy 448.222878 -62.832488) (xy 448.22999 -62.841124)
			(xy 448.250056 -62.850522) (xy 448.338702 -62.85103) (xy 448.349569 -62.850573) (xy 448.369435 -62.841771)
			(xy 448.377056 -62.834012) (xy 448.377564 -62.833504) (xy 448.395748 -62.81328) (xy 448.436887 -62.777708)
			(xy 448.482661 -62.748338) (xy 448.53214 -62.725763) (xy 448.584324 -62.710443) (xy 448.638153 -62.702685)
			(xy 448.665346 -62.702186) (xy 448.692598 -62.702635) (xy 448.746547 -62.710398) (xy 448.798842 -62.725758)
			(xy 448.848419 -62.748404) (xy 448.894269 -62.777875) (xy 448.935458 -62.81357) (xy 448.971149 -62.854763)
			(xy 449.000615 -62.900616) (xy 449.023256 -62.950196) (xy 449.038611 -63.002492) (xy 449.046368 -63.056442)
			(xy 449.046854 -63.083694) (xy 449.046349 -63.112612) (xy 449.037619 -63.169784) (xy 449.02036 -63.224984)
			(xy 448.994966 -63.276946) (xy 448.962019 -63.324479) (xy 448.922275 -63.366495) (xy 448.899788 -63.384684)
			(xy 448.890996 -63.392306) (xy 448.880805 -63.413195) (xy 448.88023 -63.424816) (xy 448.88023 -63.504572)
			(xy 448.880789 -63.516202) (xy 448.890963 -63.537112) (xy 448.899788 -63.544704) (xy 448.922271 -63.562896)
			(xy 448.962007 -63.604915) (xy 448.994946 -63.65245) (xy 449.020335 -63.704411) (xy 449.037591 -63.759608)
			(xy 449.046319 -63.816778) (xy 449.046854 -63.845694) (xy 449.046317 -63.872943) (xy 449.038562 -63.926887)
			(xy 449.02321 -63.979177) (xy 449.000573 -64.028752) (xy 448.971112 -64.0746) (xy 448.935426 -64.115789)
			(xy 448.894242 -64.151481) (xy 448.848397 -64.180948) (xy 448.798826 -64.203592) (xy 448.746537 -64.218951)
			(xy 448.692595 -64.226713) (xy 448.665346 -64.227202) (xy 448.63768 -64.226716) (xy 448.582929 -64.218721)
			(xy 448.529905 -64.202907) (xy 448.479719 -64.179605) (xy 448.433423 -64.149303) (xy 448.391985 -64.112635)
			(xy 448.373754 -64.09182) (xy 448.366642 -64.083184) (xy 448.346576 -64.073786) (xy 448.25793 -64.073278)
			(xy 448.247058 -64.073695) (xy 448.227192 -64.082525) (xy 448.219576 -64.090296) (xy 448.219068 -64.090804)
			(xy 448.20087 -64.111014) (xy 448.159733 -64.146587) (xy 448.113962 -64.175959) (xy 448.064486 -64.198535)
			(xy 448.012305 -64.213859) (xy 447.958478 -64.22162) (xy 447.931286 -64.222122) (xy 447.904035 -64.221635)
			(xy 447.850088 -64.213877) (xy 447.797794 -64.198521) (xy 447.748218 -64.175879) (xy 447.702368 -64.146413)
			(xy 447.661178 -64.110722) (xy 447.625487 -64.069532) (xy 447.596021 -64.023682) (xy 447.573379 -63.974106)
			(xy 447.558023 -63.921812) (xy 447.550265 -63.867865) (xy 447.549778 -63.840614) (xy 447.1277 -63.840614)
			(xy 447.131158 -63.86326) (xy 447.131694 -63.892176) (xy 447.131222 -63.919429) (xy 447.123468 -63.97338)
			(xy 447.108115 -64.025679) (xy 447.085474 -64.07526) (xy 447.056007 -64.121114) (xy 447.020314 -64.162307)
			(xy 446.979122 -64.198001) (xy 446.933269 -64.227469) (xy 446.883688 -64.250111) (xy 446.83139 -64.265466)
			(xy 446.777439 -64.273222) (xy 446.750186 -64.273684) (xy 446.722523 -64.273142) (xy 446.667775 -64.265154)
			(xy 446.614754 -64.24935) (xy 446.564568 -64.226058) (xy 446.51827 -64.195767) (xy 446.476828 -64.159111)
			(xy 446.458594 -64.138302) (xy 446.451482 -64.129666) (xy 446.431416 -64.120268) (xy 446.34277 -64.11976)
			(xy 446.331901 -64.120204) (xy 446.312036 -64.129016) (xy 446.304416 -64.136778) (xy 446.303908 -64.137286)
			(xy 446.285737 -64.157522) (xy 446.244594 -64.193093) (xy 446.198819 -64.222462) (xy 446.149337 -64.245034)
			(xy 446.097151 -64.260353) (xy 446.043319 -64.268106) (xy 446.016126 -64.268604) (xy 445.988874 -64.26812)
			(xy 445.934923 -64.260367) (xy 445.882625 -64.245014) (xy 445.833045 -64.222374) (xy 445.787192 -64.192909)
			(xy 445.745999 -64.157217) (xy 445.710305 -64.116026) (xy 445.680836 -64.070174) (xy 445.658194 -64.020595)
			(xy 445.642838 -63.968298) (xy 445.635081 -63.914348) (xy 445.634618 -63.887096) (xy 445.445329 -63.887096)
			(xy 445.460382 -63.910518) (xy 445.483025 -63.960098) (xy 445.498381 -64.012395) (xy 445.506139 -64.066345)
			(xy 445.506602 -64.093598) (xy 445.506081 -64.122515) (xy 445.497353 -64.179686) (xy 445.480095 -64.234885)
			(xy 445.454704 -64.286846) (xy 445.421761 -64.33438) (xy 445.382021 -64.376397) (xy 445.359536 -64.394588)
			(xy 445.350734 -64.402199) (xy 445.34055 -64.423097) (xy 445.339978 -64.43472) (xy 445.339978 -64.514476)
			(xy 445.340553 -64.526103) (xy 445.350717 -64.547013) (xy 445.359536 -64.554608) (xy 445.382031 -64.572785)
			(xy 445.421764 -64.614809) (xy 445.4547 -64.662347) (xy 445.480086 -64.714311) (xy 445.497341 -64.76951)
			(xy 445.506068 -64.826681) (xy 445.506602 -64.855598) (xy 445.506143 -64.882851) (xy 445.498386 -64.936802)
			(xy 445.48303 -64.989101) (xy 445.460387 -65.038681) (xy 445.430919 -65.084535) (xy 445.395225 -65.125728)
			(xy 445.354031 -65.161421) (xy 445.308178 -65.190889) (xy 445.258597 -65.213531) (xy 445.23021 -65.221866)
			(xy 450.718428 -65.221866) (xy 450.718983 -65.19295) (xy 450.727703 -65.13578) (xy 450.744953 -65.080582)
			(xy 450.770337 -65.02862) (xy 450.803275 -64.981085) (xy 450.843011 -64.939067) (xy 450.865494 -64.920876)
			(xy 450.874301 -64.913269) (xy 450.884485 -64.892368) (xy 450.885052 -64.880744) (xy 450.885052 -64.800988)
			(xy 450.884522 -64.789355) (xy 450.874328 -64.768444) (xy 450.865494 -64.760856) (xy 450.842988 -64.742691)
			(xy 450.803255 -64.700666) (xy 450.770318 -64.653126) (xy 450.744934 -64.601159) (xy 450.727683 -64.545957)
			(xy 450.71896 -64.488784) (xy 450.718428 -64.459866) (xy 450.718823 -64.432611) (xy 450.726586 -64.378655)
			(xy 450.741948 -64.326354) (xy 450.764597 -64.276771) (xy 450.794072 -64.230917) (xy 450.829773 -64.189723)
			(xy 450.870973 -64.15403) (xy 450.916833 -64.124564) (xy 450.96642 -64.101924) (xy 451.018724 -64.086571)
			(xy 451.072681 -64.078818) (xy 451.099936 -64.078358) (xy 451.127601 -64.07887) (xy 451.18235 -64.086862)
			(xy 451.235373 -64.102671) (xy 451.285558 -64.125969) (xy 451.331856 -64.156266) (xy 451.373295 -64.192928)
			(xy 451.391528 -64.21374) (xy 451.39864 -64.222376) (xy 451.418706 -64.231774) (xy 451.507352 -64.232282)
			(xy 451.51822 -64.231837) (xy 451.538085 -64.223025) (xy 451.545706 -64.215264) (xy 451.546214 -64.214756)
			(xy 451.564434 -64.194566) (xy 451.605565 -64.15899) (xy 451.65133 -64.129614) (xy 451.700803 -64.107033)
			(xy 451.75298 -64.091705) (xy 451.806805 -64.083941) (xy 451.833996 -64.083438) (xy 451.861251 -64.083859)
			(xy 451.915206 -64.091617) (xy 451.967507 -64.106975) (xy 452.01709 -64.12962) (xy 452.062946 -64.159092)
			(xy 452.10414 -64.19479) (xy 452.139833 -64.235988) (xy 452.1693 -64.281847) (xy 452.19194 -64.331432)
			(xy 452.207292 -64.383735) (xy 452.215044 -64.437691) (xy 452.215504 -64.464946) (xy 452.214983 -64.493863)
			(xy 452.20626 -64.551036) (xy 452.189005 -64.606236) (xy 452.163614 -64.658199) (xy 452.130669 -64.705732)
			(xy 452.090925 -64.747747) (xy 452.068438 -64.765936) (xy 452.059614 -64.773527) (xy 452.049442 -64.79444)
			(xy 452.04888 -64.806068) (xy 452.04888 -64.885824) (xy 452.049426 -64.897455) (xy 452.059611 -64.918364)
			(xy 452.068438 -64.925956) (xy 452.090908 -64.944162) (xy 452.130643 -64.98618) (xy 452.163582 -65.033712)
			(xy 452.188972 -65.08567) (xy 452.206232 -65.140864) (xy 452.214966 -65.198031) (xy 452.215362 -65.219326)
			(xy 453.652128 -65.219326) (xy 453.652654 -65.190409) (xy 453.66138 -65.133238) (xy 453.678636 -65.078039)
			(xy 453.704026 -65.026077) (xy 453.736969 -64.978543) (xy 453.776709 -64.936526) (xy 453.799194 -64.918336)
			(xy 453.807974 -64.910702) (xy 453.818173 -64.889822) (xy 453.818752 -64.878204) (xy 453.818752 -64.798448)
			(xy 453.818245 -64.786812) (xy 453.808035 -64.765901) (xy 453.799194 -64.758316) (xy 453.776717 -64.740117)
			(xy 453.736982 -64.698099) (xy 453.704042 -64.650566) (xy 453.678653 -64.598606) (xy 453.661395 -64.54341)
			(xy 453.652664 -64.486242) (xy 453.652128 -64.457326) (xy 453.652614 -64.430075) (xy 453.66037 -64.376127)
			(xy 453.675725 -64.323832) (xy 453.698367 -64.274255) (xy 453.727833 -64.228405) (xy 453.763524 -64.187214)
			(xy 453.804715 -64.151523) (xy 453.850565 -64.122057) (xy 453.900142 -64.099415) (xy 453.952437 -64.08406)
			(xy 454.006385 -64.076304) (xy 454.060887 -64.076304) (xy 454.114835 -64.08406) (xy 454.16713 -64.099415)
			(xy 454.216707 -64.122057) (xy 454.262557 -64.151523) (xy 454.303748 -64.187214) (xy 454.339439 -64.228405)
			(xy 454.368905 -64.274255) (xy 454.391547 -64.323832) (xy 454.406902 -64.376127) (xy 454.414658 -64.430075)
			(xy 454.415144 -64.457326) (xy 454.414594 -64.486242) (xy 454.405874 -64.543413) (xy 454.388624 -64.598612)
			(xy 454.363238 -64.650574) (xy 454.330299 -64.698108) (xy 454.290562 -64.740126) (xy 454.268078 -64.758316)
			(xy 454.25927 -64.765922) (xy 454.249087 -64.786824) (xy 454.24852 -64.798448) (xy 454.24852 -64.878204)
			(xy 454.249064 -64.889835) (xy 454.259249 -64.910745) (xy 454.268078 -64.918336) (xy 454.290574 -64.936512)
			(xy 454.33031 -64.978534) (xy 454.363248 -65.026072) (xy 454.388634 -65.078036) (xy 454.405887 -65.133237)
			(xy 454.414612 -65.190409) (xy 454.41491 -65.206626) (xy 455.750168 -65.206626) (xy 455.750679 -65.177709)
			(xy 455.759406 -65.120536) (xy 455.776664 -65.065336) (xy 455.802056 -65.013373) (xy 455.835003 -64.96584)
			(xy 455.874747 -64.923825) (xy 455.897234 -64.905636) (xy 455.906021 -64.898009) (xy 455.916214 -64.877123)
			(xy 455.916792 -64.865504) (xy 455.916792 -64.785748) (xy 455.916271 -64.774114) (xy 455.90607 -64.753204)
			(xy 455.897234 -64.745616) (xy 455.874765 -64.727407) (xy 455.835028 -64.685392) (xy 455.802086 -64.637861)
			(xy 455.776695 -64.585903) (xy 455.759436 -64.530709) (xy 455.750704 -64.473541) (xy 455.750168 -64.444626)
			(xy 455.750654 -64.417375) (xy 455.75841 -64.363427) (xy 455.773765 -64.311132) (xy 455.796407 -64.261555)
			(xy 455.825873 -64.215705) (xy 455.861564 -64.174514) (xy 455.902755 -64.138823) (xy 455.948605 -64.109357)
			(xy 455.998182 -64.086715) (xy 456.050477 -64.07136) (xy 456.104425 -64.063604) (xy 456.158927 -64.063604)
			(xy 456.212875 -64.07136) (xy 456.26517 -64.086715) (xy 456.314747 -64.109357) (xy 456.360597 -64.138823)
			(xy 456.401788 -64.174514) (xy 456.437479 -64.215705) (xy 456.466945 -64.261555) (xy 456.489587 -64.311132)
			(xy 456.504942 -64.363427) (xy 456.512698 -64.417375) (xy 456.513184 -64.444626) (xy 456.512619 -64.473541)
			(xy 456.5039 -64.530711) (xy 456.486652 -64.585909) (xy 456.461269 -64.637871) (xy 456.428334 -64.685406)
			(xy 456.3886 -64.727425) (xy 456.366118 -64.745616) (xy 456.3573 -64.753212) (xy 456.347125 -64.774122)
			(xy 456.34656 -64.785748) (xy 456.34656 -64.865504) (xy 456.34709 -64.877138) (xy 456.357283 -64.898048)
			(xy 456.366118 -64.905636) (xy 456.388622 -64.923802) (xy 456.428356 -64.965828) (xy 456.461292 -65.013368)
			(xy 456.486676 -65.065334) (xy 456.503928 -65.120536) (xy 456.512652 -65.177709) (xy 456.513184 -65.206626)
			(xy 456.513093 -65.211706) (xy 457.878688 -65.211706) (xy 457.879177 -65.182788) (xy 457.887908 -65.125614)
			(xy 457.905169 -65.070413) (xy 457.930566 -65.01845) (xy 457.963516 -64.970917) (xy 458.003265 -64.928904)
			(xy 458.025754 -64.910716) (xy 458.034553 -64.903101) (xy 458.044739 -64.882206) (xy 458.045312 -64.870584)
			(xy 458.045312 -64.790828) (xy 458.044738 -64.779201) (xy 458.034573 -64.758291) (xy 458.025754 -64.750696)
			(xy 458.003259 -64.732519) (xy 457.963527 -64.690495) (xy 457.93059 -64.642957) (xy 457.905204 -64.590993)
			(xy 457.88795 -64.535793) (xy 457.879222 -64.478623) (xy 457.878688 -64.449706) (xy 457.879161 -64.422453)
			(xy 457.886917 -64.368503) (xy 457.902272 -64.316206) (xy 457.924914 -64.266626) (xy 457.954381 -64.220773)
			(xy 457.990073 -64.17958) (xy 458.031265 -64.143887) (xy 458.077117 -64.114418) (xy 458.126696 -64.091776)
			(xy 458.178993 -64.076419) (xy 458.232943 -64.068662) (xy 458.260196 -64.068198) (xy 458.288579 -64.068643)
			(xy 458.34472 -64.07704) (xy 458.398996 -64.093663) (xy 458.45021 -64.118146) (xy 458.497231 -64.149948)
			(xy 458.53902 -64.188366) (xy 458.574654 -64.232553) (xy 458.603347 -64.281533) (xy 458.624465 -64.334224)
			(xy 458.637542 -64.389462) (xy 458.640434 -64.417702) (xy 458.641704 -64.431926) (xy 458.658214 -64.454786)
			(xy 458.767942 -64.500506) (xy 458.796136 -64.495934) (xy 458.807058 -64.48679) (xy 458.827811 -64.469891)
			(xy 458.873142 -64.441443) (xy 458.922001 -64.419603) (xy 458.973431 -64.404801) (xy 459.026425 -64.397325)
			(xy 459.053184 -64.396874) (xy 459.080436 -64.397372) (xy 459.134386 -64.405127) (xy 459.186684 -64.420481)
			(xy 459.236264 -64.443121) (xy 459.282116 -64.472588) (xy 459.323309 -64.50828) (xy 459.359003 -64.549471)
			(xy 459.388471 -64.595322) (xy 459.411114 -64.644901) (xy 459.42647 -64.697198) (xy 459.434227 -64.751148)
			(xy 459.434227 -64.805652) (xy 459.42647 -64.859602) (xy 459.411114 -64.911899) (xy 459.388471 -64.961478)
			(xy 459.359003 -65.007329) (xy 459.323309 -65.04852) (xy 459.282116 -65.084212) (xy 459.236264 -65.113679)
			(xy 459.186684 -65.136319) (xy 459.134386 -65.151673) (xy 459.080436 -65.159428) (xy 459.053184 -65.15989)
			(xy 459.024807 -65.15929) (xy 458.968677 -65.150907) (xy 458.914408 -65.134299) (xy 458.8632 -65.109833)
			(xy 458.816182 -65.078049) (xy 458.774394 -65.039648) (xy 458.738757 -64.995479) (xy 458.710058 -64.946517)
			(xy 458.688932 -64.893842) (xy 458.675845 -64.838619) (xy 458.672946 -64.810386) (xy 458.671676 -64.796162)
			(xy 458.655166 -64.773302) (xy 458.545438 -64.727582) (xy 458.517244 -64.732154) (xy 458.506322 -64.741298)
			(xy 458.494638 -64.750696) (xy 458.485832 -64.758304) (xy 458.47565 -64.779204) (xy 458.47508 -64.790828)
			(xy 458.47508 -64.870584) (xy 458.47565 -64.882212) (xy 458.485817 -64.903121) (xy 458.494638 -64.910716)
			(xy 458.517137 -64.928888) (xy 458.55687 -64.970913) (xy 458.589806 -65.018452) (xy 458.615191 -65.070417)
			(xy 458.632444 -65.125617) (xy 458.64117 -65.182789) (xy 458.641704 -65.211706) (xy 458.641218 -65.238957)
			(xy 458.633462 -65.292905) (xy 458.618107 -65.3452) (xy 458.595465 -65.394777) (xy 458.565999 -65.440627)
			(xy 458.530308 -65.481818) (xy 458.489117 -65.517509) (xy 458.443267 -65.546975) (xy 458.39369 -65.569617)
			(xy 458.341395 -65.584972) (xy 458.287447 -65.592728) (xy 458.232945 -65.592728) (xy 458.178997 -65.584972)
			(xy 458.126702 -65.569617) (xy 458.077125 -65.546975) (xy 458.031275 -65.517509) (xy 457.990084 -65.481818)
			(xy 457.954393 -65.440627) (xy 457.924927 -65.394777) (xy 457.902285 -65.3452) (xy 457.88693 -65.292905)
			(xy 457.879174 -65.238957) (xy 457.878688 -65.211706) (xy 456.513093 -65.211706) (xy 456.512698 -65.233877)
			(xy 456.504942 -65.287825) (xy 456.489587 -65.34012) (xy 456.466945 -65.389697) (xy 456.437479 -65.435547)
			(xy 456.401788 -65.476738) (xy 456.360597 -65.512429) (xy 456.314747 -65.541895) (xy 456.26517 -65.564537)
			(xy 456.212875 -65.579892) (xy 456.158927 -65.587648) (xy 456.104425 -65.587648) (xy 456.050477 -65.579892)
			(xy 455.998182 -65.564537) (xy 455.948605 -65.541895) (xy 455.902755 -65.512429) (xy 455.861564 -65.476738)
			(xy 455.825873 -65.435547) (xy 455.796407 -65.389697) (xy 455.773765 -65.34012) (xy 455.75841 -65.287825)
			(xy 455.750654 -65.233877) (xy 455.750168 -65.206626) (xy 454.41491 -65.206626) (xy 454.415144 -65.219326)
			(xy 454.414658 -65.246577) (xy 454.406902 -65.300525) (xy 454.391547 -65.35282) (xy 454.368905 -65.402397)
			(xy 454.339439 -65.448247) (xy 454.303748 -65.489438) (xy 454.262557 -65.525129) (xy 454.216707 -65.554595)
			(xy 454.16713 -65.577237) (xy 454.114835 -65.592592) (xy 454.060887 -65.600348) (xy 454.006385 -65.600348)
			(xy 453.952437 -65.592592) (xy 453.900142 -65.577237) (xy 453.850565 -65.554595) (xy 453.804715 -65.525129)
			(xy 453.763524 -65.489438) (xy 453.727833 -65.448247) (xy 453.698367 -65.402397) (xy 453.675725 -65.35282)
			(xy 453.66037 -65.300525) (xy 453.652614 -65.246577) (xy 453.652128 -65.219326) (xy 452.215362 -65.219326)
			(xy 452.215504 -65.226946) (xy 452.215065 -65.254199) (xy 452.207302 -65.308148) (xy 452.191941 -65.360444)
			(xy 452.169294 -65.410022) (xy 452.139823 -65.455872) (xy 452.104126 -65.497062) (xy 452.062932 -65.532753)
			(xy 452.017078 -65.562218) (xy 451.967497 -65.584858) (xy 451.915199 -65.600213) (xy 451.861249 -65.607969)
			(xy 451.833996 -65.608454) (xy 451.80633 -65.607984) (xy 451.751579 -65.599984) (xy 451.698555 -65.584165)
			(xy 451.64837 -65.56086) (xy 451.602074 -65.530556) (xy 451.560636 -65.493887) (xy 451.542404 -65.473072)
			(xy 451.535292 -65.464436) (xy 451.515226 -65.455038) (xy 451.42658 -65.45453) (xy 451.415713 -65.454989)
			(xy 451.395848 -65.463791) (xy 451.388226 -65.471548) (xy 451.387718 -65.472056) (xy 451.369535 -65.492281)
			(xy 451.328396 -65.527854) (xy 451.282623 -65.557226) (xy 451.233143 -65.5798) (xy 451.180959 -65.59512)
			(xy 451.127129 -65.602876) (xy 451.099936 -65.603374) (xy 451.072682 -65.602911) (xy 451.01873 -65.595158)
			(xy 450.96643 -65.579805) (xy 450.916848 -65.557164) (xy 450.870993 -65.527697) (xy 450.829799 -65.492003)
			(xy 450.794104 -65.450809) (xy 450.764637 -65.404954) (xy 450.741996 -65.355372) (xy 450.726642 -65.303072)
			(xy 450.718889 -65.24912) (xy 450.718428 -65.221866) (xy 445.23021 -65.221866) (xy 445.206299 -65.228887)
			(xy 445.152347 -65.236643) (xy 445.125094 -65.237106) (xy 445.097427 -65.236655) (xy 445.042674 -65.228653)
			(xy 444.98965 -65.212832) (xy 444.939464 -65.189523) (xy 444.893169 -65.159215) (xy 444.851732 -65.122542)
			(xy 444.833502 -65.101724) (xy 444.82639 -65.093088) (xy 444.806324 -65.08369) (xy 444.717678 -65.083182)
			(xy 444.706809 -65.083624) (xy 444.686943 -65.092436) (xy 444.679324 -65.1002) (xy 444.678816 -65.100708)
			(xy 444.660645 -65.120944) (xy 444.619502 -65.156514) (xy 444.573726 -65.185883) (xy 444.524244 -65.208455)
			(xy 444.472059 -65.223774) (xy 444.418227 -65.231528) (xy 444.391034 -65.232026) (xy 444.363783 -65.231513)
			(xy 444.309835 -65.223761) (xy 444.257539 -65.20841) (xy 444.20796 -65.185773) (xy 444.162108 -65.15631)
			(xy 444.120915 -65.120622) (xy 444.085221 -65.079434) (xy 444.055752 -65.033586) (xy 444.033108 -64.98401)
			(xy 444.01775 -64.931716) (xy 444.009991 -64.877769) (xy 444.009526 -64.850518) (xy 432.174962 -64.850518)
			(xy 432.190209 -64.915673) (xy 432.230391 -65.122861) (xy 432.262608 -65.331436) (xy 432.286811 -65.541093)
			(xy 432.302967 -65.751522) (xy 432.311051 -65.962416) (xy 432.311556 -66.06794) (xy 432.311556 -72.415584)
			(xy 448.803264 -72.415584) (xy 448.803264 -72.330888) (xy 448.811315 -72.246574) (xy 448.827344 -72.163408)
			(xy 448.851205 -72.082141) (xy 448.882684 -72.003511) (xy 448.921495 -71.92823) (xy 448.967285 -71.856978)
			(xy 449.019641 -71.790402) (xy 449.078089 -71.729104) (xy 449.142099 -71.673639) (xy 449.211091 -71.62451)
			(xy 449.284441 -71.582161) (xy 449.361484 -71.546977) (xy 449.441523 -71.519275) (xy 449.523832 -71.499307)
			(xy 449.607667 -71.487254) (xy 449.692268 -71.483224) (xy 449.776869 -71.487254) (xy 449.860704 -71.499307)
			(xy 449.943013 -71.519275) (xy 450.023052 -71.546977) (xy 450.100095 -71.582161) (xy 450.173445 -71.62451)
			(xy 450.242437 -71.673639) (xy 450.306447 -71.729104) (xy 450.364895 -71.790402) (xy 450.417251 -71.856978)
			(xy 450.463041 -71.92823) (xy 450.501852 -72.003511) (xy 450.533331 -72.082141) (xy 450.557192 -72.163408)
			(xy 450.573221 -72.246574) (xy 450.581272 -72.330888) (xy 450.581776 -72.373236) (xy 450.581272 -72.415584)
			(xy 456.311504 -72.415584) (xy 456.311504 -72.330888) (xy 456.319555 -72.246574) (xy 456.335584 -72.163408)
			(xy 456.359445 -72.082141) (xy 456.390924 -72.003511) (xy 456.429735 -71.92823) (xy 456.475525 -71.856978)
			(xy 456.527881 -71.790402) (xy 456.586329 -71.729104) (xy 456.650339 -71.673639) (xy 456.719331 -71.62451)
			(xy 456.792681 -71.582161) (xy 456.869724 -71.546977) (xy 456.949763 -71.519275) (xy 457.032072 -71.499307)
			(xy 457.115907 -71.487254) (xy 457.200508 -71.483224) (xy 457.285109 -71.487254) (xy 457.368944 -71.499307)
			(xy 457.451253 -71.519275) (xy 457.531292 -71.546977) (xy 457.608335 -71.582161) (xy 457.681685 -71.62451)
			(xy 457.750677 -71.673639) (xy 457.814687 -71.729104) (xy 457.873135 -71.790402) (xy 457.925491 -71.856978)
			(xy 457.971281 -71.92823) (xy 458.010092 -72.003511) (xy 458.041571 -72.082141) (xy 458.065432 -72.163408)
			(xy 458.081461 -72.246574) (xy 458.089512 -72.330888) (xy 458.090016 -72.373236) (xy 458.089512 -72.415584)
			(xy 458.081461 -72.499898) (xy 458.065432 -72.583064) (xy 458.041571 -72.664331) (xy 458.010092 -72.742961)
			(xy 457.971281 -72.818242) (xy 457.925491 -72.889494) (xy 457.873135 -72.95607) (xy 457.814687 -73.017368)
			(xy 457.750677 -73.072833) (xy 457.681685 -73.121962) (xy 457.608335 -73.164311) (xy 457.531292 -73.199495)
			(xy 457.451253 -73.227197) (xy 457.368944 -73.247165) (xy 457.285109 -73.259218) (xy 457.200508 -73.263249)
			(xy 457.115907 -73.259218) (xy 457.032072 -73.247165) (xy 456.949763 -73.227197) (xy 456.869724 -73.199495)
			(xy 456.792681 -73.164311) (xy 456.719331 -73.121962) (xy 456.650339 -73.072833) (xy 456.586329 -73.017368)
			(xy 456.527881 -72.95607) (xy 456.475525 -72.889494) (xy 456.429735 -72.818242) (xy 456.390924 -72.742961)
			(xy 456.359445 -72.664331) (xy 456.335584 -72.583064) (xy 456.319555 -72.499898) (xy 456.311504 -72.415584)
			(xy 450.581272 -72.415584) (xy 450.573221 -72.499898) (xy 450.557192 -72.583064) (xy 450.533331 -72.664331)
			(xy 450.501852 -72.742961) (xy 450.463041 -72.818242) (xy 450.417251 -72.889494) (xy 450.364895 -72.95607)
			(xy 450.306447 -73.017368) (xy 450.242437 -73.072833) (xy 450.173445 -73.121962) (xy 450.100095 -73.164311)
			(xy 450.023052 -73.199495) (xy 449.943013 -73.227197) (xy 449.860704 -73.247165) (xy 449.776869 -73.259218)
			(xy 449.692268 -73.263249) (xy 449.607667 -73.259218) (xy 449.523832 -73.247165) (xy 449.441523 -73.227197)
			(xy 449.361484 -73.199495) (xy 449.284441 -73.164311) (xy 449.211091 -73.121962) (xy 449.142099 -73.072833)
			(xy 449.078089 -73.017368) (xy 449.019641 -72.95607) (xy 448.967285 -72.889494) (xy 448.921495 -72.818242)
			(xy 448.882684 -72.742961) (xy 448.851205 -72.664331) (xy 448.827344 -72.583064) (xy 448.811315 -72.499898)
			(xy 448.803264 -72.415584) (xy 432.311556 -72.415584) (xy 432.311556 -74.471233) (xy 437.258962 -74.471233)
			(xy 437.258962 -74.407311) (xy 437.266973 -74.343893) (xy 437.28287 -74.281979) (xy 437.306402 -74.222546)
			(xy 437.337196 -74.166531) (xy 437.374769 -74.114816) (xy 437.418526 -74.068219) (xy 437.467779 -74.027474)
			(xy 437.52175 -73.993223) (xy 437.579589 -73.966006) (xy 437.640382 -73.946253) (xy 437.703172 -73.934275)
			(xy 437.766968 -73.930262) (xy 437.830764 -73.934275) (xy 437.893554 -73.946253) (xy 437.954347 -73.966006)
			(xy 438.012186 -73.993223) (xy 438.066157 -74.027474) (xy 438.11541 -74.068219) (xy 438.159167 -74.114816)
			(xy 438.19674 -74.166531) (xy 438.227534 -74.222546) (xy 438.251066 -74.281979) (xy 438.266963 -74.343893)
			(xy 438.274974 -74.407311) (xy 438.275476 -74.439272) (xy 438.274974 -74.471233) (xy 438.266963 -74.534651)
			(xy 438.251066 -74.596565) (xy 438.227534 -74.655998) (xy 438.19674 -74.712013) (xy 438.159167 -74.763728)
			(xy 438.11541 -74.810325) (xy 438.066157 -74.85107) (xy 438.012186 -74.885321) (xy 437.954347 -74.912538)
			(xy 437.893554 -74.932291) (xy 437.830764 -74.944269) (xy 437.766968 -74.948283) (xy 437.703172 -74.944269)
			(xy 437.640382 -74.932291) (xy 437.579589 -74.912538) (xy 437.52175 -74.885321) (xy 437.467779 -74.85107)
			(xy 437.418526 -74.810325) (xy 437.374769 -74.763728) (xy 437.337196 -74.712013) (xy 437.306402 -74.655998)
			(xy 437.28287 -74.596565) (xy 437.266973 -74.534651) (xy 437.258962 -74.471233) (xy 432.311556 -74.471233)
			(xy 432.311556 -74.767948) (xy 432.311051 -74.873472) (xy 432.302967 -75.084366) (xy 432.286811 -75.294795)
			(xy 432.262608 -75.504452) (xy 432.230391 -75.713027) (xy 432.190209 -75.920215) (xy 432.142121 -76.125712)
			(xy 432.086197 -76.329216) (xy 432.02252 -76.530429) (xy 431.951182 -76.729056) (xy 431.872288 -76.924804)
			(xy 431.785955 -77.117386) (xy 431.692308 -77.306521) (xy 431.591486 -77.49193) (xy 431.493988 -77.655928)
			(xy 438.975246 -77.655928) (xy 438.975246 -77.655674) (xy 438.975652 -77.625465) (xy 438.982796 -77.565472)
			(xy 438.997002 -77.506748) (xy 439.018072 -77.450124) (xy 439.045707 -77.396397) (xy 439.079517 -77.346326)
			(xy 439.098944 -77.323188) (xy 439.104624 -77.316141) (xy 439.11099 -77.299211) (xy 439.11139 -77.290168)
			(xy 439.11139 -77.259688) (xy 439.110942 -77.250654) (xy 439.104583 -77.233738) (xy 439.098944 -77.226668)
			(xy 439.07954 -77.203514) (xy 439.04575 -77.153436) (xy 439.018127 -77.099709) (xy 438.99706 -77.04309)
			(xy 438.982845 -76.984374) (xy 438.975682 -76.924388) (xy 438.975246 -76.894182) (xy 438.975246 -76.893928)
			(xy 438.975704 -76.862445) (xy 438.983482 -76.799962) (xy 438.998909 -76.738915) (xy 439.02175 -76.680238)
			(xy 439.051655 -76.624828) (xy 439.088169 -76.573531) (xy 439.109104 -76.550012) (xy 439.115016 -76.543036)
			(xy 439.121911 -76.526113) (xy 439.122566 -76.516992) (xy 439.123328 -76.486766) (xy 439.123202 -76.477595)
			(xy 439.11721 -76.460274) (xy 439.111644 -76.452984) (xy 439.08978 -76.425538) (xy 439.053018 -76.365768)
			(xy 439.024828 -76.301509) (xy 439.005746 -76.233983) (xy 438.996135 -76.164474) (xy 438.995566 -76.129388)
			(xy 438.995954 -76.099158) (xy 439.003081 -76.03912) (xy 439.01728 -75.980351) (xy 439.038351 -75.923682)
			(xy 439.065996 -75.869913) (xy 439.099825 -75.819803) (xy 439.119264 -75.796648) (xy 439.124921 -75.789586)
			(xy 439.131301 -75.772667) (xy 439.13171 -75.763628) (xy 439.13171 -75.733148) (xy 439.131277 -75.724113)
			(xy 439.124907 -75.707197) (xy 439.119264 -75.700128) (xy 439.099832 -75.67697) (xy 439.066023 -75.626851)
			(xy 439.038392 -75.57308) (xy 439.017327 -75.516413) (xy 439.003125 -75.457649) (xy 438.995986 -75.397616)
			(xy 438.995566 -75.367388) (xy 438.995954 -75.337158) (xy 439.003081 -75.27712) (xy 439.01728 -75.218351)
			(xy 439.038351 -75.161682) (xy 439.065996 -75.107913) (xy 439.099825 -75.057803) (xy 439.119264 -75.034648)
			(xy 439.124921 -75.027586) (xy 439.131301 -75.010667) (xy 439.13171 -75.001628) (xy 439.13171 -74.971148)
			(xy 439.131277 -74.962113) (xy 439.124907 -74.945197) (xy 439.119264 -74.938128) (xy 439.099844 -74.914987)
			(xy 439.066056 -74.864906) (xy 439.038435 -74.811177) (xy 439.01737 -74.754554) (xy 439.003159 -74.695836)
			(xy 438.996 -74.635849) (xy 438.995566 -74.605642) (xy 438.995566 -74.605388) (xy 438.996045 -74.574658)
			(xy 439.003454 -74.513645) (xy 439.018163 -74.453971) (xy 439.039958 -74.396505) (xy 439.06852 -74.342084)
			(xy 439.103433 -74.291503) (xy 439.144189 -74.245499) (xy 439.190192 -74.204742) (xy 439.240772 -74.169827)
			(xy 439.295192 -74.141264) (xy 439.352658 -74.119467) (xy 439.412332 -74.104757) (xy 439.473344 -74.097346)
			(xy 439.504074 -74.09688) (xy 439.534794 -74.097368) (xy 439.595787 -74.104764) (xy 439.655445 -74.119451)
			(xy 439.712901 -74.141216) (xy 439.767317 -74.169741) (xy 439.792872 -74.186796) (xy 439.801557 -74.192189)
			(xy 439.821574 -74.19625) (xy 439.841591 -74.192189) (xy 439.850276 -74.186796) (xy 439.875839 -74.169752)
			(xy 439.930251 -74.141217) (xy 439.987704 -74.119443) (xy 440.047361 -74.104747) (xy 440.108354 -74.097344)
			(xy 440.139074 -74.09688) (xy 440.139582 -74.09688) (xy 440.157038 -74.09704) (xy 440.191867 -74.099455)
			(xy 440.209178 -74.101706) (xy 440.222132 -74.103484) (xy 440.245754 -74.094594) (xy 440.318906 -74.01052)
			(xy 440.32424 -73.985628) (xy 440.320684 -73.973182) (xy 440.311574 -73.939041) (xy 440.301754 -73.869066)
			(xy 440.301126 -73.833736) (xy 440.301126 -73.833228) (xy 440.301564 -73.802495) (xy 440.30897 -73.741477)
			(xy 440.323678 -73.681797) (xy 440.345472 -73.624325) (xy 440.374036 -73.5699) (xy 440.408952 -73.519314)
			(xy 440.449711 -73.473307) (xy 440.495719 -73.432548) (xy 440.546305 -73.397633) (xy 440.600731 -73.36907)
			(xy 440.658203 -73.347276) (xy 440.717883 -73.332569) (xy 440.778901 -73.325164) (xy 440.809634 -73.32472)
			(xy 440.840355 -73.325171) (xy 440.90135 -73.332574) (xy 440.961009 -73.34727) (xy 441.018464 -73.369043)
			(xy 441.072878 -73.397577) (xy 441.098432 -73.414636) (xy 441.107117 -73.420029) (xy 441.127134 -73.42409)
			(xy 441.147151 -73.420029) (xy 441.155836 -73.414636) (xy 441.18139 -73.397578) (xy 441.235805 -73.369047)
			(xy 441.29326 -73.347276) (xy 441.352919 -73.332584) (xy 441.413913 -73.325184) (xy 441.475355 -73.325184)
			(xy 441.536349 -73.332584) (xy 441.596008 -73.347276) (xy 441.653463 -73.369047) (xy 441.707878 -73.397578)
			(xy 441.733432 -73.414636) (xy 441.742117 -73.420029) (xy 441.762134 -73.42409) (xy 441.782151 -73.420029)
			(xy 441.790836 -73.414636) (xy 441.81639 -73.397578) (xy 441.870805 -73.369047) (xy 441.92826 -73.347276)
			(xy 441.987919 -73.332584) (xy 442.048913 -73.325184) (xy 442.110355 -73.325184) (xy 442.171349 -73.332584)
			(xy 442.231008 -73.347276) (xy 442.288463 -73.369047) (xy 442.342878 -73.397578) (xy 442.368432 -73.414636)
			(xy 442.377117 -73.420029) (xy 442.397134 -73.42409) (xy 442.417151 -73.420029) (xy 442.425836 -73.414636)
			(xy 442.451378 -73.397559) (xy 442.505796 -73.369031) (xy 442.563255 -73.347264) (xy 442.622916 -73.332576)
			(xy 442.683912 -73.32518) (xy 442.714634 -73.32472) (xy 442.748202 -73.325282) (xy 442.814752 -73.334142)
			(xy 442.879556 -73.35169) (xy 442.941483 -73.37762) (xy 442.999456 -73.41148) (xy 443.026292 -73.431654)
			(xy 443.035547 -73.438107) (xy 443.057534 -73.443035) (xy 443.079521 -73.438107) (xy 443.088776 -73.431654)
			(xy 443.115607 -73.411474) (xy 443.173585 -73.377623) (xy 443.235515 -73.351697) (xy 443.300317 -73.334147)
			(xy 443.366866 -73.325277) (xy 443.400434 -73.32472) (xy 443.431167 -73.325124) (xy 443.492184 -73.332537)
			(xy 443.551863 -73.34725) (xy 443.609333 -73.36905) (xy 443.663756 -73.397618) (xy 443.714339 -73.432538)
			(xy 443.760344 -73.4733) (xy 443.801101 -73.51931) (xy 443.836014 -73.569897) (xy 443.864576 -73.624324)
			(xy 443.886368 -73.681797) (xy 443.901075 -73.741477) (xy 443.90848 -73.802495) (xy 443.908942 -73.833228)
			(xy 443.908942 -73.833482) (xy 443.908488 -73.863689) (xy 443.901352 -73.92368) (xy 443.887153 -73.982402)
			(xy 443.866092 -74.039026) (xy 443.838466 -74.092754) (xy 443.804666 -74.142828) (xy 443.785244 -74.165968)
			(xy 443.779581 -74.173026) (xy 443.773205 -74.189948) (xy 443.772798 -74.198988) (xy 443.772798 -74.229468)
			(xy 443.773222 -74.238504) (xy 443.779598 -74.25542) (xy 443.785244 -74.262488) (xy 443.804672 -74.285622)
			(xy 443.83846 -74.335704) (xy 443.866079 -74.389436) (xy 443.887142 -74.446059) (xy 443.901352 -74.504778)
			(xy 443.906986 -74.552005) (xy 444.335402 -74.552005) (xy 444.335402 -74.488083) (xy 444.343413 -74.424665)
			(xy 444.35931 -74.362751) (xy 444.382842 -74.303318) (xy 444.413636 -74.247303) (xy 444.451209 -74.195588)
			(xy 444.494966 -74.148991) (xy 444.544219 -74.108246) (xy 444.59819 -74.073995) (xy 444.656029 -74.046778)
			(xy 444.716822 -74.027025) (xy 444.779612 -74.015047) (xy 444.843408 -74.011034) (xy 444.907204 -74.015047)
			(xy 444.969994 -74.027025) (xy 445.030787 -74.046778) (xy 445.088626 -74.073995) (xy 445.142597 -74.108246)
			(xy 445.19185 -74.148991) (xy 445.235607 -74.195588) (xy 445.27318 -74.247303) (xy 445.303974 -74.303318)
			(xy 445.327506 -74.362751) (xy 445.343403 -74.424665) (xy 445.351414 -74.488083) (xy 445.351916 -74.520044)
			(xy 445.351414 -74.552005) (xy 445.343403 -74.615423) (xy 445.327506 -74.677337) (xy 445.303974 -74.73677)
			(xy 445.27318 -74.792785) (xy 445.235607 -74.8445) (xy 445.19185 -74.891097) (xy 445.162102 -74.915706)
			(xy 448.803264 -74.915706) (xy 448.803264 -74.83101) (xy 448.811315 -74.746696) (xy 448.827344 -74.66353)
			(xy 448.851205 -74.582263) (xy 448.882684 -74.503633) (xy 448.921495 -74.428352) (xy 448.967285 -74.3571)
			(xy 449.019641 -74.290524) (xy 449.078089 -74.229226) (xy 449.142099 -74.173761) (xy 449.211091 -74.124632)
			(xy 449.284441 -74.082283) (xy 449.361484 -74.047099) (xy 449.441523 -74.019397) (xy 449.523832 -73.999429)
			(xy 449.607667 -73.987376) (xy 449.692268 -73.983346) (xy 449.776869 -73.987376) (xy 449.860704 -73.999429)
			(xy 449.943013 -74.019397) (xy 450.023052 -74.047099) (xy 450.100095 -74.082283) (xy 450.173445 -74.124632)
			(xy 450.242437 -74.173761) (xy 450.306447 -74.229226) (xy 450.364895 -74.290524) (xy 450.417251 -74.3571)
			(xy 450.463041 -74.428352) (xy 450.501852 -74.503633) (xy 450.533331 -74.582263) (xy 450.557192 -74.66353)
			(xy 450.573221 -74.746696) (xy 450.581272 -74.83101) (xy 450.581776 -74.873358) (xy 450.581272 -74.915706)
			(xy 456.311504 -74.915706) (xy 456.311504 -74.83101) (xy 456.319555 -74.746696) (xy 456.335584 -74.66353)
			(xy 456.359445 -74.582263) (xy 456.390924 -74.503633) (xy 456.429735 -74.428352) (xy 456.475525 -74.3571)
			(xy 456.527881 -74.290524) (xy 456.586329 -74.229226) (xy 456.650339 -74.173761) (xy 456.719331 -74.124632)
			(xy 456.792681 -74.082283) (xy 456.869724 -74.047099) (xy 456.949763 -74.019397) (xy 457.032072 -73.999429)
			(xy 457.115907 -73.987376) (xy 457.200508 -73.983346) (xy 457.285109 -73.987376) (xy 457.368944 -73.999429)
			(xy 457.451253 -74.019397) (xy 457.531292 -74.047099) (xy 457.608335 -74.082283) (xy 457.681685 -74.124632)
			(xy 457.750677 -74.173761) (xy 457.814687 -74.229226) (xy 457.873135 -74.290524) (xy 457.925491 -74.3571)
			(xy 457.971281 -74.428352) (xy 458.010092 -74.503633) (xy 458.041571 -74.582263) (xy 458.065432 -74.66353)
			(xy 458.081461 -74.746696) (xy 458.089512 -74.83101) (xy 458.090016 -74.873358) (xy 458.089512 -74.915706)
			(xy 458.081461 -75.00002) (xy 458.065432 -75.083186) (xy 458.041571 -75.164453) (xy 458.010092 -75.243083)
			(xy 457.971281 -75.318364) (xy 457.925491 -75.389616) (xy 457.873135 -75.456192) (xy 457.814687 -75.51749)
			(xy 457.750677 -75.572955) (xy 457.681685 -75.622084) (xy 457.608335 -75.664433) (xy 457.531292 -75.699617)
			(xy 457.451253 -75.727319) (xy 457.368944 -75.747287) (xy 457.285109 -75.75934) (xy 457.200508 -75.763371)
			(xy 457.115907 -75.75934) (xy 457.032072 -75.747287) (xy 456.949763 -75.727319) (xy 456.869724 -75.699617)
			(xy 456.792681 -75.664433) (xy 456.719331 -75.622084) (xy 456.650339 -75.572955) (xy 456.586329 -75.51749)
			(xy 456.527881 -75.456192) (xy 456.475525 -75.389616) (xy 456.429735 -75.318364) (xy 456.390924 -75.243083)
			(xy 456.359445 -75.164453) (xy 456.335584 -75.083186) (xy 456.319555 -75.00002) (xy 456.311504 -74.915706)
			(xy 450.581272 -74.915706) (xy 450.573221 -75.00002) (xy 450.557192 -75.083186) (xy 450.533331 -75.164453)
			(xy 450.501852 -75.243083) (xy 450.463041 -75.318364) (xy 450.417251 -75.389616) (xy 450.364895 -75.456192)
			(xy 450.306447 -75.51749) (xy 450.242437 -75.572955) (xy 450.173445 -75.622084) (xy 450.100095 -75.664433)
			(xy 450.023052 -75.699617) (xy 449.943013 -75.727319) (xy 449.860704 -75.747287) (xy 449.776869 -75.75934)
			(xy 449.692268 -75.763371) (xy 449.607667 -75.75934) (xy 449.523832 -75.747287) (xy 449.441523 -75.727319)
			(xy 449.361484 -75.699617) (xy 449.284441 -75.664433) (xy 449.211091 -75.622084) (xy 449.142099 -75.572955)
			(xy 449.078089 -75.51749) (xy 449.019641 -75.456192) (xy 448.967285 -75.389616) (xy 448.921495 -75.318364)
			(xy 448.882684 -75.243083) (xy 448.851205 -75.164453) (xy 448.827344 -75.083186) (xy 448.811315 -75.00002)
			(xy 448.803264 -74.915706) (xy 445.162102 -74.915706) (xy 445.142597 -74.931842) (xy 445.088626 -74.966093)
			(xy 445.030787 -74.99331) (xy 444.969994 -75.013063) (xy 444.907204 -75.025041) (xy 444.843408 -75.029055)
			(xy 444.779612 -75.025041) (xy 444.716822 -75.013063) (xy 444.656029 -74.99331) (xy 444.59819 -74.966093)
			(xy 444.544219 -74.931842) (xy 444.494966 -74.891097) (xy 444.451209 -74.8445) (xy 444.413636 -74.792785)
			(xy 444.382842 -74.73677) (xy 444.35931 -74.677337) (xy 444.343413 -74.615423) (xy 444.335402 -74.552005)
			(xy 443.906986 -74.552005) (xy 443.908509 -74.564767) (xy 443.908942 -74.594974) (xy 443.908942 -74.595228)
			(xy 443.90847 -74.625958) (xy 443.901059 -74.68697) (xy 443.886349 -74.746645) (xy 443.864553 -74.804111)
			(xy 443.83599 -74.858531) (xy 443.801076 -74.909112) (xy 443.76032 -74.955116) (xy 443.714316 -74.995872)
			(xy 443.663736 -75.030787) (xy 443.609316 -75.05935) (xy 443.55185 -75.081147) (xy 443.492176 -75.095858)
			(xy 443.431164 -75.10327) (xy 443.400434 -75.103736) (xy 443.366865 -75.103201) (xy 443.300313 -75.094336)
			(xy 443.235509 -75.076782) (xy 443.173582 -75.050846) (xy 443.115611 -75.016979) (xy 443.088776 -74.996802)
			(xy 443.079521 -74.990349) (xy 443.057534 -74.985421) (xy 443.035547 -74.990349) (xy 443.026292 -74.996802)
			(xy 442.999434 -75.016945) (xy 442.941464 -75.050803) (xy 442.879541 -75.076737) (xy 442.814745 -75.094296)
			(xy 442.748201 -75.103175) (xy 442.714634 -75.103736) (xy 442.67755 -75.102466) (xy 442.665104 -75.10145)
			(xy 442.642498 -75.111102) (xy 442.574172 -75.193398) (xy 442.568838 -75.217274) (xy 442.571886 -75.229212)
			(xy 442.579514 -75.260664) (xy 442.587668 -75.324868) (xy 442.588142 -75.357228) (xy 442.587702 -75.387457)
			(xy 442.580585 -75.447493) (xy 442.566396 -75.50626) (xy 442.545335 -75.562929) (xy 442.517699 -75.6167)
			(xy 442.483879 -75.666811) (xy 442.464444 -75.689968) (xy 442.458781 -75.697026) (xy 442.452405 -75.713948)
			(xy 442.451998 -75.722988) (xy 442.451998 -75.753468) (xy 442.452422 -75.762504) (xy 442.458798 -75.77942)
			(xy 442.464444 -75.786488) (xy 442.483872 -75.809622) (xy 442.51766 -75.859704) (xy 442.545279 -75.913436)
			(xy 442.566342 -75.970059) (xy 442.580552 -76.028778) (xy 442.587709 -76.088767) (xy 442.588142 -76.118974)
			(xy 442.588142 -76.119228) (xy 442.58766 -76.15071) (xy 442.579888 -76.213193) (xy 442.564465 -76.274239)
			(xy 442.541629 -76.332916) (xy 442.511727 -76.388327) (xy 442.475217 -76.439625) (xy 442.454284 -76.463144)
			(xy 442.448389 -76.470132) (xy 442.441484 -76.487046) (xy 442.440822 -76.496164) (xy 442.44006 -76.52639)
			(xy 442.44016 -76.535563) (xy 442.44617 -76.552884) (xy 442.451744 -76.560172) (xy 442.473586 -76.587635)
			(xy 442.510352 -76.6474) (xy 442.538547 -76.711655) (xy 442.557634 -76.779177) (xy 442.56725 -76.848683)
			(xy 442.567822 -76.883768) (xy 442.567411 -76.913997) (xy 442.560289 -76.974035) (xy 442.546094 -77.032803)
			(xy 442.525028 -77.089472) (xy 442.497386 -77.143242) (xy 442.463561 -77.193352) (xy 442.453657 -77.205151)
			(xy 444.690478 -77.205151) (xy 444.690478 -77.150649) (xy 444.698234 -77.096701) (xy 444.713589 -77.044406)
			(xy 444.736231 -76.994829) (xy 444.765697 -76.948979) (xy 444.801388 -76.907788) (xy 444.842579 -76.872097)
			(xy 444.888429 -76.842631) (xy 444.938006 -76.819989) (xy 444.990301 -76.804634) (xy 445.044249 -76.796878)
			(xy 445.0715 -76.796392) (xy 445.101406 -76.796966) (xy 445.160484 -76.806313) (xy 445.217381 -76.824762)
			(xy 445.270702 -76.851862) (xy 445.319143 -76.886949) (xy 445.34074 -76.907644) (xy 445.347598 -76.914502)
			(xy 445.365378 -76.922122) (xy 445.454532 -76.924916) (xy 445.472312 -76.918566) (xy 445.479678 -76.911962)
			(xy 445.500683 -76.8941) (xy 445.546872 -76.863989) (xy 445.596915 -76.840839) (xy 445.649768 -76.825133)
			(xy 445.704331 -76.817197) (xy 445.7319 -76.816712) (xy 445.759153 -76.817158) (xy 445.813103 -76.824915)
			(xy 445.865401 -76.840271) (xy 445.914981 -76.862913) (xy 445.960833 -76.892381) (xy 446.002026 -76.928074)
			(xy 446.037719 -76.969267) (xy 446.067187 -77.015119) (xy 446.089829 -77.064699) (xy 446.105185 -77.116997)
			(xy 446.112942 -77.170947) (xy 446.112942 -77.225453) (xy 446.105185 -77.279403) (xy 446.089829 -77.331701)
			(xy 446.067187 -77.381281) (xy 446.037719 -77.427133) (xy 446.002026 -77.468326) (xy 445.960833 -77.504019)
			(xy 445.914981 -77.533487) (xy 445.865401 -77.556129) (xy 445.813103 -77.571485) (xy 445.759153 -77.579242)
			(xy 445.7319 -77.579728) (xy 445.701994 -77.579148) (xy 445.642917 -77.569802) (xy 445.586021 -77.551353)
			(xy 445.532699 -77.524255) (xy 445.484258 -77.48917) (xy 445.46266 -77.468476) (xy 445.455802 -77.461618)
			(xy 445.438022 -77.453998) (xy 445.348868 -77.451204) (xy 445.331088 -77.457554) (xy 445.323722 -77.464158)
			(xy 445.30272 -77.482024) (xy 445.256529 -77.512133) (xy 445.206486 -77.535282) (xy 445.153633 -77.550987)
			(xy 445.099069 -77.558923) (xy 445.0715 -77.559408) (xy 445.044249 -77.558922) (xy 444.990301 -77.551166)
			(xy 444.938006 -77.535811) (xy 444.888429 -77.513169) (xy 444.842579 -77.483703) (xy 444.801388 -77.448012)
			(xy 444.765697 -77.406821) (xy 444.736231 -77.360971) (xy 444.713589 -77.311394) (xy 444.698234 -77.259099)
			(xy 444.690478 -77.205151) (xy 442.453657 -77.205151) (xy 442.444124 -77.216508) (xy 442.438442 -77.223553)
			(xy 442.432078 -77.240485) (xy 442.431678 -77.249528) (xy 442.431678 -77.280008) (xy 442.432113 -77.289043)
			(xy 442.438479 -77.305961) (xy 442.444124 -77.313028) (xy 442.463521 -77.336187) (xy 442.497313 -77.386264)
			(xy 442.524937 -77.439989) (xy 442.546006 -77.496608) (xy 442.560222 -77.555323) (xy 442.567385 -77.615308)
			(xy 442.567822 -77.645514) (xy 442.567822 -77.645768) (xy 442.567332 -77.676499) (xy 442.559928 -77.737513)
			(xy 442.545222 -77.79719) (xy 442.523431 -77.854659) (xy 442.494871 -77.909082) (xy 442.459959 -77.959665)
			(xy 442.419205 -78.005672) (xy 442.373202 -78.046431) (xy 442.322621 -78.081347) (xy 442.2682 -78.109912)
			(xy 442.210734 -78.131709) (xy 442.151058 -78.146419) (xy 442.090045 -78.15383) (xy 442.059314 -78.154276)
			(xy 442.028594 -78.153801) (xy 441.9676 -78.146404) (xy 441.907941 -78.131714) (xy 441.850486 -78.109946)
			(xy 441.79607 -78.081417) (xy 441.770516 -78.06436) (xy 441.761831 -78.058967) (xy 441.741814 -78.054906)
			(xy 441.721797 -78.058967) (xy 441.713112 -78.06436) (xy 441.687558 -78.081418) (xy 441.633143 -78.109949)
			(xy 441.575688 -78.13172) (xy 441.516029 -78.146412) (xy 441.455035 -78.153812) (xy 441.393593 -78.153812)
			(xy 441.332599 -78.146412) (xy 441.27294 -78.13172) (xy 441.215485 -78.109949) (xy 441.16107 -78.081418)
			(xy 441.135516 -78.06436) (xy 441.126831 -78.058967) (xy 441.106814 -78.054906) (xy 441.086797 -78.058967)
			(xy 441.078112 -78.06436) (xy 441.052557 -78.081416) (xy 440.998142 -78.109947) (xy 440.940687 -78.131718)
			(xy 440.881028 -78.146411) (xy 440.820035 -78.153813) (xy 440.789314 -78.154276) (xy 440.757374 -78.153791)
			(xy 440.693996 -78.145786) (xy 440.632122 -78.129902) (xy 440.572726 -78.106388) (xy 440.516746 -78.075615)
			(xy 440.49061 -78.057248) (xy 440.48144 -78.051335) (xy 440.460071 -78.047063) (xy 440.43885 -78.052022)
			(xy 440.429904 -78.058264) (xy 440.403091 -78.078338) (xy 440.345165 -78.111971) (xy 440.283328 -78.137715)
			(xy 440.218649 -78.155128) (xy 440.152245 -78.163907) (xy 440.118754 -78.164436) (xy 440.088033 -78.163981)
			(xy 440.027039 -78.156577) (xy 439.96738 -78.141882) (xy 439.909925 -78.12011) (xy 439.85551 -78.091578)
			(xy 439.829956 -78.07452) (xy 439.821271 -78.069127) (xy 439.801254 -78.065066) (xy 439.781237 -78.069127)
			(xy 439.772552 -78.07452) (xy 439.74701 -78.091597) (xy 439.692592 -78.120126) (xy 439.635134 -78.141893)
			(xy 439.575472 -78.156581) (xy 439.514476 -78.163976) (xy 439.483754 -78.164436) (xy 439.453023 -78.163988)
			(xy 439.39201 -78.156574) (xy 439.332335 -78.141862) (xy 439.274868 -78.120064) (xy 439.220448 -78.091498)
			(xy 439.169867 -78.056582) (xy 439.123863 -78.015824) (xy 439.083107 -77.969819) (xy 439.048192 -77.919237)
			(xy 439.019629 -77.864815) (xy 438.997833 -77.807348) (xy 438.983122 -77.747672) (xy 438.975711 -77.686659)
			(xy 438.975246 -77.655928) (xy 431.493988 -77.655928) (xy 431.483636 -77.673341) (xy 431.368917 -77.850488)
			(xy 431.247497 -78.02311) (xy 431.119554 -78.190956) (xy 430.985276 -78.353778) (xy 430.84486 -78.511337)
			(xy 430.698512 -78.663402) (xy 430.546447 -78.80975) (xy 430.388888 -78.950166) (xy 430.226066 -79.084444)
			(xy 430.05822 -79.212387) (xy 429.885598 -79.333807) (xy 429.708451 -79.448526) (xy 429.52704 -79.556376)
			(xy 429.341631 -79.657198) (xy 429.152496 -79.750845) (xy 428.959914 -79.837178) (xy 428.764166 -79.916072)
			(xy 428.565539 -79.98741) (xy 428.364326 -80.051087) (xy 428.160822 -80.107011) (xy 427.955325 -80.155099)
			(xy 427.748137 -80.195281) (xy 427.539562 -80.227498) (xy 427.329905 -80.251701) (xy 427.119476 -80.267857)
			(xy 426.908582 -80.275941) (xy 426.697534 -80.275941) (xy 426.48664 -80.267857) (xy 426.276211 -80.251701)
			(xy 426.066554 -80.227498) (xy 425.857979 -80.195281) (xy 425.650791 -80.155099) (xy 425.445294 -80.107011)
			(xy 425.24179 -80.051087) (xy 425.040577 -79.98741) (xy 424.84195 -79.916072) (xy 424.646202 -79.837178)
			(xy 424.45362 -79.750845) (xy 424.264485 -79.657198) (xy 424.079076 -79.556376) (xy 423.897665 -79.448526)
			(xy 423.720518 -79.333807) (xy 423.547896 -79.212387) (xy 423.38005 -79.084444) (xy 423.217228 -78.950166)
			(xy 423.059669 -78.80975) (xy 422.907604 -78.663402) (xy 422.761256 -78.511337) (xy 422.62084 -78.353778)
			(xy 422.486562 -78.190956) (xy 422.358619 -78.02311) (xy 422.237199 -77.850488) (xy 422.12248 -77.673341)
			(xy 422.01463 -77.49193) (xy 421.913808 -77.306521) (xy 421.820161 -77.117386) (xy 421.733828 -76.924804)
			(xy 421.654934 -76.729056) (xy 421.583596 -76.530429) (xy 421.519919 -76.329216) (xy 421.463995 -76.125712)
			(xy 421.415907 -75.920215) (xy 421.375725 -75.713027) (xy 421.343508 -75.504452) (xy 421.319305 -75.294795)
			(xy 421.303149 -75.084366) (xy 421.295065 -74.873472) (xy 421.29456 -74.767948) (xy 413.988327 -74.767948)
			(xy 413.989121 -74.77111) (xy 413.996801 -74.8332) (xy 413.996803 -74.895764) (xy 413.989128 -74.957855)
			(xy 413.973891 -75.018535) (xy 413.951323 -75.076887) (xy 413.921765 -75.132028) (xy 413.885663 -75.183125)
			(xy 413.843565 -75.229406) (xy 413.796105 -75.27017) (xy 413.770318 -75.287886) (xy 413.760188 -75.295432)
			(xy 413.748318 -75.317688) (xy 413.747712 -75.330304) (xy 413.747712 -75.414632) (xy 413.748398 -75.427231)
			(xy 413.760227 -75.449479) (xy 413.770318 -75.45705) (xy 413.796076 -75.474808) (xy 413.843539 -75.51557)
			(xy 413.885641 -75.561847) (xy 413.921746 -75.612942) (xy 413.951308 -75.668081) (xy 413.97388 -75.726431)
			(xy 413.989121 -75.78711) (xy 413.996801 -75.8492) (xy 413.996803 -75.911764) (xy 413.989128 -75.973855)
			(xy 413.973891 -76.034535) (xy 413.951323 -76.092887) (xy 413.921765 -76.148028) (xy 413.885663 -76.199125)
			(xy 413.843565 -76.245406) (xy 413.796105 -76.28617) (xy 413.770318 -76.303886) (xy 413.760188 -76.311432)
			(xy 413.748318 -76.333688) (xy 413.747712 -76.346304) (xy 413.747712 -76.430632) (xy 413.748398 -76.443231)
			(xy 413.760227 -76.465479) (xy 413.770318 -76.47305) (xy 413.796121 -76.490751) (xy 413.843597 -76.531512)
			(xy 413.885712 -76.577791) (xy 413.921829 -76.62889) (xy 413.951401 -76.684035) (xy 413.973981 -76.742393)
			(xy 413.989229 -76.803081) (xy 413.996912 -76.865181) (xy 413.997394 -76.896468) (xy 413.996892 -76.928429)
			(xy 413.988881 -76.991847) (xy 413.972984 -77.053761) (xy 413.949452 -77.113194) (xy 413.918658 -77.169209)
			(xy 413.881085 -77.220924) (xy 413.837328 -77.267521) (xy 413.788075 -77.308266) (xy 413.734104 -77.342517)
			(xy 413.676265 -77.369734) (xy 413.615472 -77.389487) (xy 413.552682 -77.401465) (xy 413.488886 -77.405479)
			(xy 413.42509 -77.401465) (xy 413.3623 -77.389487) (xy 413.301507 -77.369734) (xy 413.243668 -77.342517)
			(xy 413.189697 -77.308266) (xy 413.140444 -77.267521) (xy 413.096687 -77.220924) (xy 413.059114 -77.169209)
			(xy 413.02832 -77.113194) (xy 413.004788 -77.053761) (xy 412.988891 -76.991847) (xy 412.98088 -76.928429)
			(xy 412.980378 -76.896468) (xy 411.917348 -76.896468) (xy 411.917452 -76.896658) (xy 411.940984 -76.956091)
			(xy 411.956881 -77.018005) (xy 411.964892 -77.081423) (xy 411.965394 -77.113384) (xy 411.96487 -77.146942)
			(xy 411.95602 -77.213473) (xy 411.938499 -77.278262) (xy 411.91261 -77.340184) (xy 411.878802 -77.398165)
			(xy 411.837665 -77.451196) (xy 411.789911 -77.498357) (xy 411.763464 -77.519022) (xy 411.755485 -77.525705)
			(xy 411.745239 -77.54379) (xy 411.743652 -77.554074) (xy 411.73527 -77.62748) (xy 411.734644 -77.637904)
			(xy 411.740811 -77.657834) (xy 411.747208 -77.666088) (xy 411.764312 -77.6869) (xy 411.793161 -77.73239)
			(xy 411.815318 -77.78149) (xy 411.83034 -77.83322) (xy 411.837928 -77.88655) (xy 411.838394 -77.913484)
			(xy 411.837908 -77.940735) (xy 411.830152 -77.994683) (xy 411.814797 -78.046978) (xy 411.792155 -78.096555)
			(xy 411.762689 -78.142405) (xy 411.726998 -78.183596) (xy 411.685807 -78.219287) (xy 411.639957 -78.248753)
			(xy 411.59038 -78.271395) (xy 411.538085 -78.28675) (xy 411.484137 -78.294506) (xy 411.429635 -78.294506)
			(xy 411.375687 -78.28675) (xy 411.323392 -78.271395) (xy 411.273815 -78.248753) (xy 411.227965 -78.219287)
			(xy 411.186774 -78.183596) (xy 411.151083 -78.142405) (xy 411.121617 -78.096555) (xy 411.098975 -78.046978)
			(xy 411.08362 -77.994683) (xy 411.075864 -77.940735) (xy 411.075378 -77.913484) (xy 411.075863 -77.88655)
			(xy 411.083446 -77.83322) (xy 411.09846 -77.781487) (xy 411.120605 -77.732382) (xy 411.149441 -77.686883)
			(xy 411.166564 -77.666088) (xy 411.172986 -77.657846) (xy 411.179153 -77.637908) (xy 411.178502 -77.62748)
			(xy 411.17012 -77.554074) (xy 411.168481 -77.543804) (xy 411.158267 -77.525714) (xy 411.150308 -77.519022)
			(xy 411.123863 -77.498354) (xy 411.076097 -77.451203) (xy 411.034951 -77.398177) (xy 411.001142 -77.340196)
			(xy 410.975257 -77.278271) (xy 410.957747 -77.213477) (xy 410.948916 -77.146943) (xy 410.948378 -77.113384)
			(xy 396.156489 -77.113384) (xy 396.156286 -77.113691) (xy 396.119069 -77.155228) (xy 396.076201 -77.190903)
			(xy 396.028595 -77.219957) (xy 395.977266 -77.241769) (xy 395.923309 -77.255875) (xy 395.867872 -77.261975)
			(xy 395.812138 -77.259938) (xy 395.757295 -77.249808) (xy 395.704511 -77.231801) (xy 395.654911 -77.2063)
			(xy 395.609553 -77.173849) (xy 395.569404 -77.13514) (xy 395.535318 -77.090997) (xy 395.508022 -77.042362)
			(xy 395.488099 -76.990271) (xy 395.475973 -76.935834) (xy 395.471902 -76.880212) (xy 331.217011 -76.880212)
			(xy 331.225521 -76.913357) (xy 331.233532 -76.976775) (xy 331.234034 -77.008736) (xy 331.233532 -77.040697)
			(xy 331.225521 -77.104115) (xy 331.209624 -77.166029) (xy 331.186092 -77.225462) (xy 331.155298 -77.281477)
			(xy 331.117725 -77.333192) (xy 331.073968 -77.379789) (xy 331.024715 -77.420534) (xy 331.019212 -77.424026)
			(xy 389.89965 -77.424026) (xy 389.903721 -77.368404) (xy 389.915847 -77.313967) (xy 389.93577 -77.261876)
			(xy 389.963066 -77.213241) (xy 389.997152 -77.169098) (xy 390.037301 -77.130389) (xy 390.082659 -77.097938)
			(xy 390.132259 -77.072437) (xy 390.185043 -77.05443) (xy 390.239886 -77.0443) (xy 390.29562 -77.042263)
			(xy 390.351057 -77.048363) (xy 390.405014 -77.062469) (xy 390.456343 -77.084281) (xy 390.503949 -77.113335)
			(xy 390.546817 -77.14901) (xy 390.584034 -77.190547) (xy 390.614807 -77.23706) (xy 390.638479 -77.287557)
			(xy 390.654547 -77.340964) (xy 390.662667 -77.39614) (xy 390.663176 -77.424026) (xy 390.662667 -77.451912)
			(xy 390.654547 -77.507088) (xy 390.638479 -77.560495) (xy 390.614807 -77.610992) (xy 390.584034 -77.657505)
			(xy 390.546817 -77.699042) (xy 390.503949 -77.734717) (xy 390.456343 -77.763771) (xy 390.405014 -77.785583)
			(xy 390.351057 -77.799689) (xy 390.29562 -77.805789) (xy 390.239886 -77.803752) (xy 390.185043 -77.793622)
			(xy 390.132259 -77.775615) (xy 390.082659 -77.750114) (xy 390.037301 -77.717663) (xy 389.997152 -77.678954)
			(xy 389.963066 -77.634811) (xy 389.93577 -77.586176) (xy 389.915847 -77.534085) (xy 389.903721 -77.479648)
			(xy 389.89965 -77.424026) (xy 331.019212 -77.424026) (xy 330.970744 -77.454785) (xy 330.912905 -77.482002)
			(xy 330.852112 -77.501755) (xy 330.789322 -77.513733) (xy 330.725526 -77.517747) (xy 330.66173 -77.513733)
			(xy 330.59894 -77.501755) (xy 330.538147 -77.482002) (xy 330.480308 -77.454785) (xy 330.426337 -77.420534)
			(xy 330.377084 -77.379789) (xy 330.333327 -77.333192) (xy 330.295754 -77.281477) (xy 330.26496 -77.225462)
			(xy 330.241428 -77.166029) (xy 330.225531 -77.104115) (xy 330.21752 -77.040697) (xy 310.565705 -77.040697)
			(xy 310.599255 -77.051598) (xy 310.657094 -77.078815) (xy 310.711065 -77.113066) (xy 310.760318 -77.153811)
			(xy 310.804075 -77.200408) (xy 310.841648 -77.252123) (xy 310.872442 -77.308138) (xy 310.895974 -77.367571)
			(xy 310.911871 -77.429485) (xy 310.919882 -77.492903) (xy 310.920384 -77.524864) (xy 311.045858 -77.524864)
			(xy 311.049929 -77.469242) (xy 311.062055 -77.414805) (xy 311.081978 -77.362714) (xy 311.109274 -77.314079)
			(xy 311.14336 -77.269936) (xy 311.183509 -77.231227) (xy 311.228867 -77.198776) (xy 311.278467 -77.173275)
			(xy 311.331251 -77.155268) (xy 311.386094 -77.145138) (xy 311.441828 -77.143101) (xy 311.497265 -77.149201)
			(xy 311.551222 -77.163307) (xy 311.602551 -77.185119) (xy 311.650157 -77.214173) (xy 311.693025 -77.249848)
			(xy 311.730242 -77.291385) (xy 311.761015 -77.337898) (xy 311.784687 -77.388395) (xy 311.800755 -77.441802)
			(xy 311.808875 -77.496978) (xy 311.809384 -77.524864) (xy 311.80911 -77.53985) (xy 316.057532 -77.53985)
			(xy 316.061603 -77.484228) (xy 316.073729 -77.429791) (xy 316.093652 -77.3777) (xy 316.120948 -77.329065)
			(xy 316.155034 -77.284922) (xy 316.195183 -77.246213) (xy 316.240541 -77.213762) (xy 316.290141 -77.188261)
			(xy 316.342925 -77.170254) (xy 316.397768 -77.160124) (xy 316.453502 -77.158087) (xy 316.508939 -77.164187)
			(xy 316.562896 -77.178293) (xy 316.614225 -77.200105) (xy 316.661831 -77.229159) (xy 316.704699 -77.264834)
			(xy 316.741916 -77.306371) (xy 316.772689 -77.352884) (xy 316.796361 -77.403381) (xy 316.812429 -77.456788)
			(xy 316.820549 -77.511964) (xy 316.821058 -77.53985) (xy 316.820549 -77.567736) (xy 316.812429 -77.622912)
			(xy 316.796361 -77.676319) (xy 316.772689 -77.726816) (xy 316.741916 -77.773329) (xy 316.704699 -77.814866)
			(xy 316.661831 -77.850541) (xy 316.614225 -77.879595) (xy 316.562896 -77.901407) (xy 316.5167 -77.913484)
			(xy 402.535896 -77.913484) (xy 402.539967 -77.857862) (xy 402.552093 -77.803425) (xy 402.572016 -77.751334)
			(xy 402.599312 -77.702699) (xy 402.633398 -77.658556) (xy 402.673547 -77.619847) (xy 402.718905 -77.587396)
			(xy 402.768505 -77.561895) (xy 402.821289 -77.543888) (xy 402.876132 -77.533758) (xy 402.931866 -77.531721)
			(xy 402.987303 -77.537821) (xy 403.04126 -77.551927) (xy 403.092589 -77.573739) (xy 403.140195 -77.602793)
			(xy 403.183063 -77.638468) (xy 403.22028 -77.680005) (xy 403.251053 -77.726518) (xy 403.274725 -77.777015)
			(xy 403.290793 -77.830422) (xy 403.298913 -77.885598) (xy 403.299422 -77.913484) (xy 403.298913 -77.94137)
			(xy 403.290793 -77.996546) (xy 403.274725 -78.049953) (xy 403.251053 -78.10045) (xy 403.22028 -78.146963)
			(xy 403.183063 -78.1885) (xy 403.140195 -78.224175) (xy 403.092589 -78.253229) (xy 403.04126 -78.275041)
			(xy 402.987303 -78.289147) (xy 402.931866 -78.295247) (xy 402.876132 -78.29321) (xy 402.821289 -78.28308)
			(xy 402.768505 -78.265073) (xy 402.718905 -78.239572) (xy 402.673547 -78.207121) (xy 402.633398 -78.168412)
			(xy 402.599312 -78.124269) (xy 402.572016 -78.075634) (xy 402.552093 -78.023543) (xy 402.539967 -77.969106)
			(xy 402.535896 -77.913484) (xy 316.5167 -77.913484) (xy 316.508939 -77.915513) (xy 316.453502 -77.921613)
			(xy 316.397768 -77.919576) (xy 316.342925 -77.909446) (xy 316.290141 -77.891439) (xy 316.240541 -77.865938)
			(xy 316.195183 -77.833487) (xy 316.155034 -77.794778) (xy 316.120948 -77.750635) (xy 316.093652 -77.702)
			(xy 316.073729 -77.649909) (xy 316.061603 -77.595472) (xy 316.057532 -77.53985) (xy 311.80911 -77.53985)
			(xy 311.808875 -77.55275) (xy 311.800755 -77.607926) (xy 311.784687 -77.661333) (xy 311.761015 -77.71183)
			(xy 311.730242 -77.758343) (xy 311.693025 -77.79988) (xy 311.650157 -77.835555) (xy 311.602551 -77.864609)
			(xy 311.551222 -77.886421) (xy 311.497265 -77.900527) (xy 311.441828 -77.906627) (xy 311.386094 -77.90459)
			(xy 311.331251 -77.89446) (xy 311.278467 -77.876453) (xy 311.228867 -77.850952) (xy 311.183509 -77.818501)
			(xy 311.14336 -77.779792) (xy 311.109274 -77.735649) (xy 311.081978 -77.687014) (xy 311.062055 -77.634923)
			(xy 311.049929 -77.580486) (xy 311.045858 -77.524864) (xy 310.920384 -77.524864) (xy 310.919882 -77.556825)
			(xy 310.911871 -77.620243) (xy 310.895974 -77.682157) (xy 310.872442 -77.74159) (xy 310.841648 -77.797605)
			(xy 310.804075 -77.84932) (xy 310.760318 -77.895917) (xy 310.711065 -77.936662) (xy 310.657094 -77.970913)
			(xy 310.599255 -77.99813) (xy 310.538462 -78.017883) (xy 310.475672 -78.029861) (xy 310.411876 -78.033875)
			(xy 310.34808 -78.029861) (xy 310.28529 -78.017883) (xy 310.224497 -77.99813) (xy 310.166658 -77.970913)
			(xy 310.112687 -77.936662) (xy 310.063434 -77.895917) (xy 310.019677 -77.84932) (xy 309.982104 -77.797605)
			(xy 309.95131 -77.74159) (xy 309.927778 -77.682157) (xy 309.911881 -77.620243) (xy 309.90387 -77.556825)
			(xy 297.748589 -77.556825) (xy 297.683548 -77.666229) (xy 297.568829 -77.843376) (xy 297.447409 -78.015998)
			(xy 297.319466 -78.183844) (xy 297.185188 -78.346666) (xy 297.044772 -78.504225) (xy 296.898424 -78.65629)
			(xy 296.746359 -78.802638) (xy 296.5888 -78.943054) (xy 296.425978 -79.077332) (xy 296.258132 -79.205275)
			(xy 296.08551 -79.326695) (xy 295.908363 -79.441414) (xy 295.726952 -79.549264) (xy 295.541543 -79.650086)
			(xy 295.387227 -79.726493) (xy 305.720744 -79.726493) (xy 305.720744 -79.662571) (xy 305.728755 -79.599153)
			(xy 305.744652 -79.537239) (xy 305.768184 -79.477806) (xy 305.798978 -79.421791) (xy 305.836551 -79.370076)
			(xy 305.880308 -79.323479) (xy 305.929561 -79.282734) (xy 305.983532 -79.248483) (xy 306.041371 -79.221266)
			(xy 306.102164 -79.201513) (xy 306.164954 -79.189535) (xy 306.22875 -79.185522) (xy 306.292546 -79.189535)
			(xy 306.355336 -79.201513) (xy 306.416129 -79.221266) (xy 306.473968 -79.248483) (xy 306.527939 -79.282734)
			(xy 306.577192 -79.323479) (xy 306.620949 -79.370076) (xy 306.658522 -79.421791) (xy 306.689316 -79.477806)
			(xy 306.712848 -79.537239) (xy 306.728745 -79.599153) (xy 306.736756 -79.662571) (xy 306.737258 -79.694532)
			(xy 306.737103 -79.704395) (xy 307.009286 -79.704395) (xy 307.009286 -79.640473) (xy 307.017297 -79.577055)
			(xy 307.033194 -79.515141) (xy 307.056726 -79.455708) (xy 307.08752 -79.399693) (xy 307.125093 -79.347978)
			(xy 307.16885 -79.301381) (xy 307.218103 -79.260636) (xy 307.272074 -79.226385) (xy 307.329913 -79.199168)
			(xy 307.390706 -79.179415) (xy 307.453496 -79.167437) (xy 307.517292 -79.163424) (xy 307.581088 -79.167437)
			(xy 307.643878 -79.179415) (xy 307.704671 -79.199168) (xy 307.76251 -79.226385) (xy 307.816481 -79.260636)
			(xy 307.865734 -79.301381) (xy 307.909491 -79.347978) (xy 307.947064 -79.399693) (xy 307.977858 -79.455708)
			(xy 308.00139 -79.515141) (xy 308.017287 -79.577055) (xy 308.025298 -79.640473) (xy 308.0258 -79.672434)
			(xy 308.025298 -79.704395) (xy 308.017287 -79.767813) (xy 308.00139 -79.829727) (xy 307.996204 -79.842825)
			(xy 310.91987 -79.842825) (xy 310.91987 -79.778903) (xy 310.927881 -79.715485) (xy 310.943778 -79.653571)
			(xy 310.96731 -79.594138) (xy 310.998104 -79.538123) (xy 311.035677 -79.486408) (xy 311.079434 -79.439811)
			(xy 311.128687 -79.399066) (xy 311.182658 -79.364815) (xy 311.240497 -79.337598) (xy 311.30129 -79.317845)
			(xy 311.36408 -79.305867) (xy 311.427876 -79.301854) (xy 311.491672 -79.305867) (xy 311.554462 -79.317845)
			(xy 311.615255 -79.337598) (xy 311.673094 -79.364815) (xy 311.727065 -79.399066) (xy 311.776318 -79.439811)
			(xy 311.820075 -79.486408) (xy 311.857648 -79.538123) (xy 311.888442 -79.594138) (xy 311.911974 -79.653571)
			(xy 311.927871 -79.715485) (xy 311.935882 -79.778903) (xy 311.936384 -79.810864) (xy 312.061858 -79.810864)
			(xy 312.065929 -79.755242) (xy 312.078055 -79.700805) (xy 312.097978 -79.648714) (xy 312.125274 -79.600079)
			(xy 312.15936 -79.555936) (xy 312.199509 -79.517227) (xy 312.244867 -79.484776) (xy 312.294467 -79.459275)
			(xy 312.347251 -79.441268) (xy 312.402094 -79.431138) (xy 312.457828 -79.429101) (xy 312.513265 -79.435201)
			(xy 312.567222 -79.449307) (xy 312.618551 -79.471119) (xy 312.666157 -79.500173) (xy 312.709025 -79.535848)
			(xy 312.746242 -79.577385) (xy 312.777015 -79.623898) (xy 312.800687 -79.674395) (xy 312.804911 -79.688436)
			(xy 396.876016 -79.688436) (xy 396.87655 -79.655096) (xy 396.885254 -79.588988) (xy 396.902532 -79.524587)
			(xy 396.928086 -79.462998) (xy 396.961476 -79.405282) (xy 397.00213 -79.35243) (xy 397.025368 -79.328518)
			(xy 397.025622 -79.328264) (xy 397.032203 -79.320884) (xy 397.039642 -79.302582) (xy 397.0401 -79.292704)
			(xy 397.0401 -79.210408) (xy 397.032734 -79.19212) (xy 397.025622 -79.185008) (xy 397.025114 -79.1845)
			(xy 397.00191 -79.160597) (xy 396.961336 -79.107761) (xy 396.928008 -79.050078) (xy 396.902499 -78.988537)
			(xy 396.885244 -78.924192) (xy 396.87654 -78.858145) (xy 396.876016 -78.824836) (xy 396.876518 -78.792875)
			(xy 396.884529 -78.729457) (xy 396.900426 -78.667543) (xy 396.923958 -78.60811) (xy 396.954752 -78.552095)
			(xy 396.992325 -78.50038) (xy 397.036082 -78.453783) (xy 397.085335 -78.413038) (xy 397.139306 -78.378787)
			(xy 397.197145 -78.35157) (xy 397.257938 -78.331817) (xy 397.320728 -78.319839) (xy 397.384524 -78.315826)
			(xy 397.44832 -78.319839) (xy 397.51111 -78.331817) (xy 397.571903 -78.35157) (xy 397.629742 -78.378787)
			(xy 397.683713 -78.413038) (xy 397.732966 -78.453783) (xy 397.776723 -78.50038) (xy 397.814296 -78.552095)
			(xy 397.84509 -78.60811) (xy 397.868622 -78.667543) (xy 397.884519 -78.729457) (xy 397.89253 -78.792875)
			(xy 397.893032 -78.824836) (xy 397.892531 -78.858176) (xy 397.883817 -78.924286) (xy 397.866532 -78.988687)
			(xy 397.840973 -79.050275) (xy 397.807577 -79.10799) (xy 397.76692 -79.160842) (xy 397.74368 -79.184754)
			(xy 397.743426 -79.185008) (xy 397.73685 -79.192391) (xy 397.729409 -79.210691) (xy 397.728948 -79.220568)
			(xy 397.728948 -79.302864) (xy 397.736314 -79.321152) (xy 397.743426 -79.328264) (xy 397.743934 -79.328772)
			(xy 397.767115 -79.352696) (xy 397.807694 -79.405527) (xy 397.841025 -79.463205) (xy 397.866539 -79.524742)
			(xy 397.883798 -79.589083) (xy 397.892506 -79.655128) (xy 397.893032 -79.688436) (xy 397.89253 -79.720397)
			(xy 397.884519 -79.783815) (xy 397.868622 -79.845729) (xy 397.84509 -79.905162) (xy 397.814296 -79.961177)
			(xy 397.776723 -80.012892) (xy 397.732966 -80.059489) (xy 397.683713 -80.100234) (xy 397.629742 -80.134485)
			(xy 397.571903 -80.161702) (xy 397.51111 -80.181455) (xy 397.44832 -80.193433) (xy 397.384524 -80.197447)
			(xy 397.320728 -80.193433) (xy 397.257938 -80.181455) (xy 397.197145 -80.161702) (xy 397.139306 -80.134485)
			(xy 397.085335 -80.100234) (xy 397.036082 -80.059489) (xy 396.992325 -80.012892) (xy 396.954752 -79.961177)
			(xy 396.923958 -79.905162) (xy 396.900426 -79.845729) (xy 396.884529 -79.783815) (xy 396.876518 -79.720397)
			(xy 396.876016 -79.688436) (xy 312.804911 -79.688436) (xy 312.816755 -79.727802) (xy 312.824875 -79.782978)
			(xy 312.825384 -79.810864) (xy 312.824875 -79.83875) (xy 312.816755 -79.893926) (xy 312.800687 -79.947333)
			(xy 312.777015 -79.99783) (xy 312.746242 -80.044343) (xy 312.709025 -80.08588) (xy 312.666157 -80.121555)
			(xy 312.618551 -80.150609) (xy 312.567222 -80.172421) (xy 312.513265 -80.186527) (xy 312.457828 -80.192627)
			(xy 312.402094 -80.19059) (xy 312.347251 -80.18046) (xy 312.294467 -80.162453) (xy 312.244867 -80.136952)
			(xy 312.199509 -80.104501) (xy 312.15936 -80.065792) (xy 312.125274 -80.021649) (xy 312.097978 -79.973014)
			(xy 312.078055 -79.920923) (xy 312.065929 -79.866486) (xy 312.061858 -79.810864) (xy 311.936384 -79.810864)
			(xy 311.935882 -79.842825) (xy 311.927871 -79.906243) (xy 311.911974 -79.968157) (xy 311.888442 -80.02759)
			(xy 311.857648 -80.083605) (xy 311.820075 -80.13532) (xy 311.776318 -80.181917) (xy 311.727065 -80.222662)
			(xy 311.673094 -80.256913) (xy 311.615255 -80.28413) (xy 311.554462 -80.303883) (xy 311.491672 -80.315861)
			(xy 311.427876 -80.319875) (xy 311.36408 -80.315861) (xy 311.30129 -80.303883) (xy 311.240497 -80.28413)
			(xy 311.182658 -80.256913) (xy 311.128687 -80.222662) (xy 311.079434 -80.181917) (xy 311.035677 -80.13532)
			(xy 310.998104 -80.083605) (xy 310.96731 -80.02759) (xy 310.943778 -79.968157) (xy 310.927881 -79.906243)
			(xy 310.91987 -79.842825) (xy 307.996204 -79.842825) (xy 307.977858 -79.88916) (xy 307.947064 -79.945175)
			(xy 307.909491 -79.99689) (xy 307.865734 -80.043487) (xy 307.816481 -80.084232) (xy 307.76251 -80.118483)
			(xy 307.704671 -80.1457) (xy 307.643878 -80.165453) (xy 307.581088 -80.177431) (xy 307.517292 -80.181445)
			(xy 307.453496 -80.177431) (xy 307.390706 -80.165453) (xy 307.329913 -80.1457) (xy 307.272074 -80.118483)
			(xy 307.218103 -80.084232) (xy 307.16885 -80.043487) (xy 307.125093 -79.99689) (xy 307.08752 -79.945175)
			(xy 307.056726 -79.88916) (xy 307.033194 -79.829727) (xy 307.017297 -79.767813) (xy 307.009286 -79.704395)
			(xy 306.737103 -79.704395) (xy 306.736756 -79.726493) (xy 306.728745 -79.789911) (xy 306.712848 -79.851825)
			(xy 306.689316 -79.911258) (xy 306.658522 -79.967273) (xy 306.620949 -80.018988) (xy 306.577192 -80.065585)
			(xy 306.527939 -80.10633) (xy 306.473968 -80.140581) (xy 306.416129 -80.167798) (xy 306.355336 -80.187551)
			(xy 306.292546 -80.199529) (xy 306.22875 -80.203543) (xy 306.164954 -80.199529) (xy 306.102164 -80.187551)
			(xy 306.041371 -80.167798) (xy 305.983532 -80.140581) (xy 305.929561 -80.10633) (xy 305.880308 -80.065585)
			(xy 305.836551 -80.018988) (xy 305.798978 -79.967273) (xy 305.768184 -79.911258) (xy 305.744652 -79.851825)
			(xy 305.728755 -79.789911) (xy 305.720744 -79.726493) (xy 295.387227 -79.726493) (xy 295.352408 -79.743733)
			(xy 295.159826 -79.830066) (xy 294.964078 -79.90896) (xy 294.765451 -79.980298) (xy 294.564238 -80.043975)
			(xy 294.360734 -80.099899) (xy 294.155237 -80.147987) (xy 293.948049 -80.188169) (xy 293.739474 -80.220386)
			(xy 293.529817 -80.244589) (xy 293.319388 -80.260745) (xy 293.108494 -80.268829) (xy 292.897446 -80.268829)
			(xy 292.686552 -80.260745) (xy 292.476123 -80.244589) (xy 292.266466 -80.220386) (xy 292.057891 -80.188169)
			(xy 291.850703 -80.147987) (xy 291.645206 -80.099899) (xy 291.441702 -80.043975) (xy 291.240489 -79.980298)
			(xy 291.041862 -79.90896) (xy 290.846114 -79.830066) (xy 290.653532 -79.743733) (xy 290.464397 -79.650086)
			(xy 290.278988 -79.549264) (xy 290.097577 -79.441414) (xy 289.92043 -79.326695) (xy 289.747808 -79.205275)
			(xy 289.579962 -79.077332) (xy 289.41714 -78.943054) (xy 289.259581 -78.802638) (xy 289.107516 -78.65629)
			(xy 288.961168 -78.504225) (xy 288.820752 -78.346666) (xy 288.686474 -78.183844) (xy 288.558531 -78.015998)
			(xy 288.437111 -77.843376) (xy 288.322392 -77.666229) (xy 288.214542 -77.484818) (xy 288.11372 -77.299409)
			(xy 288.020073 -77.110274) (xy 287.93374 -76.917692) (xy 287.854846 -76.721944) (xy 287.783508 -76.523317)
			(xy 287.719831 -76.322104) (xy 287.663907 -76.1186) (xy 287.615819 -75.913103) (xy 287.575637 -75.705915)
			(xy 287.54342 -75.49734) (xy 287.519217 -75.287683) (xy 287.503061 -75.077254) (xy 287.494977 -74.86636)
			(xy 287.494472 -74.760836) (xy 270.45651 -74.760836) (xy 270.46654 -74.786169) (xy 270.482437 -74.848083)
			(xy 270.490448 -74.911501) (xy 270.49095 -74.943462) (xy 270.490448 -74.975423) (xy 270.482437 -75.038841)
			(xy 270.46654 -75.100755) (xy 270.443008 -75.160188) (xy 270.412214 -75.216203) (xy 270.374641 -75.267918)
			(xy 270.330884 -75.314515) (xy 270.281631 -75.35526) (xy 270.22766 -75.389511) (xy 270.169821 -75.416728)
			(xy 270.109028 -75.436481) (xy 270.046238 -75.448459) (xy 269.982442 -75.452473) (xy 269.918646 -75.448459)
			(xy 269.855856 -75.436481) (xy 269.795063 -75.416728) (xy 269.737224 -75.389511) (xy 269.683253 -75.35526)
			(xy 269.634 -75.314515) (xy 269.590243 -75.267918) (xy 269.55267 -75.216203) (xy 269.521876 -75.160188)
			(xy 269.498344 -75.100755) (xy 269.482447 -75.038841) (xy 269.474436 -74.975423) (xy 258.862583 -74.975423)
			(xy 258.841346 -75.007523) (xy 258.804129 -75.04906) (xy 258.761261 -75.084735) (xy 258.713655 -75.113789)
			(xy 258.662326 -75.135601) (xy 258.608369 -75.149707) (xy 258.552932 -75.155807) (xy 258.497198 -75.15377)
			(xy 258.442355 -75.14364) (xy 258.389571 -75.125633) (xy 258.339971 -75.100132) (xy 258.294613 -75.067681)
			(xy 258.254464 -75.028972) (xy 258.220378 -74.984829) (xy 258.193082 -74.936194) (xy 258.173159 -74.884103)
			(xy 258.161033 -74.829666) (xy 258.156962 -74.774044) (xy 231.39272 -74.774044) (xy 231.399848 -74.830475)
			(xy 231.40035 -74.862436) (xy 231.399848 -74.894397) (xy 231.391837 -74.957815) (xy 231.37594 -75.019729)
			(xy 231.352408 -75.079162) (xy 231.321614 -75.135177) (xy 231.284041 -75.186892) (xy 231.240284 -75.233489)
			(xy 231.191031 -75.274234) (xy 231.13706 -75.308485) (xy 231.079221 -75.335702) (xy 231.018428 -75.355455)
			(xy 230.955638 -75.367433) (xy 230.891842 -75.371447) (xy 230.828046 -75.367433) (xy 230.765256 -75.355455)
			(xy 230.704463 -75.335702) (xy 230.646624 -75.308485) (xy 230.592653 -75.274234) (xy 230.5434 -75.233489)
			(xy 230.499643 -75.186892) (xy 230.46207 -75.135177) (xy 230.431276 -75.079162) (xy 230.407744 -75.019729)
			(xy 230.391847 -74.957815) (xy 230.383836 -74.894397) (xy 225.741226 -74.894397) (xy 225.739379 -74.895266)
			(xy 225.678586 -74.915019) (xy 225.615796 -74.926997) (xy 225.552 -74.931011) (xy 225.488204 -74.926997)
			(xy 225.425414 -74.915019) (xy 225.364621 -74.895266) (xy 225.306782 -74.868049) (xy 225.252811 -74.833798)
			(xy 225.203558 -74.793053) (xy 225.159801 -74.746456) (xy 225.122228 -74.694741) (xy 225.091434 -74.638726)
			(xy 225.067902 -74.579293) (xy 225.052005 -74.517379) (xy 225.043994 -74.453961) (xy 184.371488 -74.453961)
			(xy 184.371488 -74.767948) (xy 184.370983 -74.873472) (xy 184.363081 -75.079606) (xy 191.473072 -75.079606)
			(xy 191.477143 -75.023984) (xy 191.489269 -74.969547) (xy 191.509192 -74.917456) (xy 191.536488 -74.868821)
			(xy 191.570574 -74.824678) (xy 191.610723 -74.785969) (xy 191.656081 -74.753518) (xy 191.705681 -74.728017)
			(xy 191.758465 -74.71001) (xy 191.813308 -74.69988) (xy 191.869042 -74.697843) (xy 191.924479 -74.703943)
			(xy 191.978436 -74.718049) (xy 192.029765 -74.739861) (xy 192.077371 -74.768915) (xy 192.120239 -74.80459)
			(xy 192.157456 -74.846127) (xy 192.188229 -74.89264) (xy 192.211901 -74.943137) (xy 192.227969 -74.996544)
			(xy 192.236089 -75.05172) (xy 192.236598 -75.079606) (xy 192.236089 -75.107492) (xy 192.227969 -75.162668)
			(xy 192.211901 -75.216075) (xy 192.188229 -75.266572) (xy 192.157456 -75.313085) (xy 192.120239 -75.354622)
			(xy 192.077371 -75.390297) (xy 192.029765 -75.419351) (xy 191.978436 -75.441163) (xy 191.924479 -75.455269)
			(xy 191.869042 -75.461369) (xy 191.813308 -75.459332) (xy 191.758465 -75.449202) (xy 191.705681 -75.431195)
			(xy 191.656081 -75.405694) (xy 191.610723 -75.373243) (xy 191.570574 -75.334534) (xy 191.536488 -75.290391)
			(xy 191.509192 -75.241756) (xy 191.489269 -75.189665) (xy 191.477143 -75.135228) (xy 191.473072 -75.079606)
			(xy 184.363081 -75.079606) (xy 184.362899 -75.084366) (xy 184.346743 -75.294795) (xy 184.32254 -75.504452)
			(xy 184.290323 -75.713027) (xy 184.263859 -75.84948) (xy 192.153032 -75.84948) (xy 192.153584 -75.816815)
			(xy 192.161953 -75.752023) (xy 192.178551 -75.688836) (xy 192.203105 -75.628295) (xy 192.23521 -75.571398)
			(xy 192.274338 -75.51908) (xy 192.319844 -75.472205) (xy 192.370978 -75.431543) (xy 192.426899 -75.397765)
			(xy 192.486685 -75.371427) (xy 192.549352 -75.352963) (xy 192.58153 -75.347322) (xy 192.591865 -75.345172)
			(xy 192.609587 -75.333745) (xy 192.61582 -75.325224) (xy 192.657222 -75.26274) (xy 192.66276 -75.253603)
			(xy 192.666307 -75.232551) (xy 192.66408 -75.2221) (xy 192.656959 -75.191801) (xy 192.649321 -75.130031)
			(xy 192.64884 -75.09891) (xy 192.64884 -75.098148) (xy 192.649342 -75.066187) (xy 192.657353 -75.002769)
			(xy 192.67325 -74.940855) (xy 192.696782 -74.881422) (xy 192.727576 -74.825407) (xy 192.765149 -74.773692)
			(xy 192.808906 -74.727095) (xy 192.858159 -74.68635) (xy 192.91213 -74.652099) (xy 192.969969 -74.624882)
			(xy 193.030762 -74.605129) (xy 193.093552 -74.593151) (xy 193.157348 -74.589138) (xy 193.221144 -74.593151)
			(xy 193.283934 -74.605129) (xy 193.344727 -74.624882) (xy 193.402566 -74.652099) (xy 193.456537 -74.68635)
			(xy 193.50579 -74.727095) (xy 193.549547 -74.773692) (xy 193.58712 -74.825407) (xy 193.617914 -74.881422)
			(xy 193.641446 -74.940855) (xy 193.657343 -75.002769) (xy 193.665354 -75.066187) (xy 193.665856 -75.098148)
			(xy 193.66534 -75.130814) (xy 193.656967 -75.195608) (xy 193.644594 -75.2427) (xy 195.017663 -75.2427)
			(xy 195.021677 -75.178904) (xy 195.033654 -75.116114) (xy 195.053406 -75.05532) (xy 195.080622 -74.997481)
			(xy 195.114871 -74.943509) (xy 195.155615 -74.894255) (xy 195.202211 -74.850495) (xy 195.253923 -74.81292)
			(xy 195.309937 -74.782122) (xy 195.369369 -74.758587) (xy 195.431281 -74.742687) (xy 195.494699 -74.73467)
			(xy 195.52666 -74.734166) (xy 195.558937 -74.734708) (xy 195.622974 -74.742863) (xy 195.685464 -74.759058)
			(xy 195.7454 -74.783034) (xy 195.801819 -74.814405) (xy 195.853813 -74.852665) (xy 195.900545 -74.8972)
			(xy 195.941264 -74.947292) (xy 195.958714 -74.97445) (xy 195.965064 -74.98461) (xy 195.98513 -74.997056)
			(xy 196.089016 -75.007216) (xy 196.111114 -74.998834) (xy 196.119242 -74.990198) (xy 196.137375 -74.971459)
			(xy 196.177822 -74.938549) (xy 196.222372 -74.911452) (xy 196.270197 -74.890672) (xy 196.320405 -74.876597)
			(xy 196.372062 -74.869489) (xy 196.398134 -74.86904) (xy 196.425387 -74.869432) (xy 196.479338 -74.877194)
			(xy 196.531635 -74.892554) (xy 196.581214 -74.9152) (xy 196.627066 -74.94467) (xy 196.668258 -74.980366)
			(xy 196.70395 -75.021561) (xy 196.733417 -75.067416) (xy 196.756058 -75.116997) (xy 196.771414 -75.169295)
			(xy 196.77917 -75.223247) (xy 196.77917 -75.264) (xy 196.967899 -75.264) (xy 196.971913 -75.200208)
			(xy 196.98389 -75.137421) (xy 197.003641 -75.076631) (xy 197.030855 -75.018795) (xy 197.065103 -74.964826)
			(xy 197.105845 -74.915575) (xy 197.152439 -74.871818) (xy 197.204149 -74.834246) (xy 197.26016 -74.803451)
			(xy 197.319589 -74.779919) (xy 197.381499 -74.76402) (xy 197.444913 -74.756006) (xy 197.476872 -74.755502)
			(xy 197.510793 -74.756054) (xy 197.578029 -74.765094) (xy 197.643468 -74.78299) (xy 197.705947 -74.809425)
			(xy 197.764359 -74.84393) (xy 197.817666 -74.885893) (xy 197.864923 -74.934568) (xy 197.885558 -74.961496)
			(xy 197.891654 -74.969878) (xy 197.909942 -74.980292) (xy 198.004176 -74.991722) (xy 198.024242 -74.985626)
			(xy 198.03237 -74.978768) (xy 198.053068 -74.962118) (xy 198.098174 -74.934066) (xy 198.146734 -74.912538)
			(xy 198.197809 -74.897949) (xy 198.250413 -74.890582) (xy 198.276972 -74.890122) (xy 198.304228 -74.890523)
			(xy 198.358187 -74.898277) (xy 198.410492 -74.913632) (xy 198.46008 -74.936275) (xy 198.50594 -74.965744)
			(xy 198.547139 -75.001441) (xy 198.582839 -75.042638) (xy 198.612312 -75.088496) (xy 198.634958 -75.138082)
			(xy 198.650317 -75.190386) (xy 198.65317 -75.210227) (xy 200.969164 -75.210227) (xy 200.971771 -75.147193)
			(xy 200.982154 -75.084965) (xy 201.000156 -75.024499) (xy 201.025498 -74.966724) (xy 201.057792 -74.912528)
			(xy 201.096542 -74.862743) (xy 201.141153 -74.818133) (xy 201.19094 -74.779384) (xy 201.245137 -74.747092)
			(xy 201.302912 -74.721751) (xy 201.363378 -74.703751) (xy 201.425607 -74.693369) (xy 201.488641 -74.690765)
			(xy 201.551514 -74.695977) (xy 201.613259 -74.708927) (xy 201.672928 -74.729415) (xy 201.729605 -74.757126)
			(xy 201.782418 -74.791635) (xy 201.830557 -74.832413) (xy 201.873283 -74.878831) (xy 201.909938 -74.930178)
			(xy 201.939961 -74.985665) (xy 201.962889 -75.04444) (xy 201.978371 -75.105599) (xy 201.986169 -75.168204)
			(xy 201.986642 -75.199748) (xy 201.986168 -75.230304) (xy 201.978814 -75.290973) (xy 201.964242 -75.350324)
			(xy 201.953876 -75.379072) (xy 201.953876 -75.379326) (xy 201.951188 -75.387511) (xy 201.950853 -75.404724)
			(xy 201.95625 -75.421073) (xy 201.961242 -75.428094) (xy 202.022202 -75.507088) (xy 202.046332 -75.517502)
			(xy 202.05954 -75.515978) (xy 202.069544 -75.515006) (xy 202.089621 -75.513991) (xy 202.099672 -75.513946)
			(xy 202.128878 -75.514499) (xy 202.186601 -75.523444) (xy 202.242291 -75.541068) (xy 202.294651 -75.566961)
			(xy 202.318874 -75.583288) (xy 202.319128 -75.583542) (xy 202.329873 -75.590158) (xy 202.354903 -75.593098)
			(xy 202.36688 -75.58913) (xy 202.445874 -75.557888) (xy 202.45741 -75.552576) (xy 202.473663 -75.533097)
			(xy 202.476862 -75.520804) (xy 202.483762 -75.489979) (xy 202.504159 -75.430193) (xy 202.531806 -75.373395)
			(xy 202.566275 -75.32046) (xy 202.607037 -75.272202) (xy 202.653463 -75.229366) (xy 202.704838 -75.192611)
			(xy 202.76037 -75.162504) (xy 202.819205 -75.139508) (xy 202.880435 -75.123978) (xy 202.943118 -75.116152)
			(xy 202.974702 -75.115674) (xy 203.005432 -75.116154) (xy 203.066445 -75.123562) (xy 203.12612 -75.138271)
			(xy 203.183587 -75.160065) (xy 203.238008 -75.188627) (xy 203.288589 -75.22354) (xy 203.334594 -75.264295)
			(xy 203.37535 -75.310298) (xy 203.377763 -75.313794) (xy 210.32927 -75.313794) (xy 210.333341 -75.258172)
			(xy 210.345467 -75.203735) (xy 210.36539 -75.151644) (xy 210.392686 -75.103009) (xy 210.426772 -75.058866)
			(xy 210.466921 -75.020157) (xy 210.512279 -74.987706) (xy 210.561879 -74.962205) (xy 210.614663 -74.944198)
			(xy 210.669506 -74.934068) (xy 210.72524 -74.932031) (xy 210.780677 -74.938131) (xy 210.834634 -74.952237)
			(xy 210.885963 -74.974049) (xy 210.933569 -75.003103) (xy 210.976437 -75.038778) (xy 211.013654 -75.080315)
			(xy 211.044427 -75.126828) (xy 211.068099 -75.177325) (xy 211.084167 -75.230732) (xy 211.092287 -75.285908)
			(xy 211.092796 -75.313794) (xy 211.092287 -75.34168) (xy 211.084167 -75.396856) (xy 211.068099 -75.450263)
			(xy 211.044427 -75.50076) (xy 211.013654 -75.547273) (xy 211.006419 -75.555348) (xy 216.331546 -75.555348)
			(xy 216.3321 -75.528098) (xy 216.339849 -75.474153) (xy 216.355197 -75.42186) (xy 216.37783 -75.372283)
			(xy 216.407289 -75.326432) (xy 216.442973 -75.28524) (xy 216.484156 -75.249545) (xy 216.53 -75.220075)
			(xy 216.579572 -75.19743) (xy 216.631861 -75.182069) (xy 216.685805 -75.174307) (xy 216.713054 -75.17384)
			(xy 216.741614 -75.174299) (xy 216.798096 -75.182808) (xy 216.852678 -75.199642) (xy 216.904141 -75.224425)
			(xy 216.951333 -75.256604) (xy 216.993201 -75.295458) (xy 217.028809 -75.34012) (xy 217.057361 -75.389592)
			(xy 217.078218 -75.442767) (xy 217.090914 -75.498457) (xy 217.093546 -75.5269) (xy 217.095053 -75.540902)
			(xy 217.104665 -75.567359) (xy 217.121137 -75.590184) (xy 217.143216 -75.607645) (xy 217.169223 -75.618412)
			(xy 217.197183 -75.621668) (xy 217.211148 -75.619864) (xy 217.231264 -75.616794) (xy 217.271826 -75.613491)
			(xy 217.292174 -75.61326) (xy 217.323717 -75.61374) (xy 217.38632 -75.621541) (xy 217.447477 -75.637025)
			(xy 217.506249 -75.659955) (xy 217.561734 -75.689979) (xy 217.613078 -75.726635) (xy 217.659494 -75.769361)
			(xy 217.687948 -75.802955) (xy 259.333994 -75.802955) (xy 259.333994 -75.739033) (xy 259.342005 -75.675615)
			(xy 259.357902 -75.613701) (xy 259.381434 -75.554268) (xy 259.412228 -75.498253) (xy 259.449801 -75.446538)
			(xy 259.493558 -75.399941) (xy 259.542811 -75.359196) (xy 259.596782 -75.324945) (xy 259.654621 -75.297728)
			(xy 259.715414 -75.277975) (xy 259.778204 -75.265997) (xy 259.842 -75.261984) (xy 259.905796 -75.265997)
			(xy 259.968586 -75.277975) (xy 260.029379 -75.297728) (xy 260.087218 -75.324945) (xy 260.141189 -75.359196)
			(xy 260.190442 -75.399941) (xy 260.234199 -75.446538) (xy 260.271772 -75.498253) (xy 260.302566 -75.554268)
			(xy 260.326098 -75.613701) (xy 260.341995 -75.675615) (xy 260.350006 -75.739033) (xy 260.350508 -75.770994)
			(xy 260.350006 -75.802955) (xy 260.341995 -75.866373) (xy 260.326098 -75.928287) (xy 260.302566 -75.98772)
			(xy 260.271772 -76.043735) (xy 260.234199 -76.09545) (xy 260.190442 -76.142047) (xy 260.141189 -76.182792)
			(xy 260.087218 -76.217043) (xy 260.029379 -76.24426) (xy 259.968586 -76.264013) (xy 259.905796 -76.275991)
			(xy 259.842 -76.280005) (xy 259.778204 -76.275991) (xy 259.715414 -76.264013) (xy 259.654621 -76.24426)
			(xy 259.596782 -76.217043) (xy 259.542811 -76.182792) (xy 259.493558 -76.142047) (xy 259.449801 -76.09545)
			(xy 259.412228 -76.043735) (xy 259.381434 -75.98772) (xy 259.357902 -75.928287) (xy 259.342005 -75.866373)
			(xy 259.333994 -75.802955) (xy 217.687948 -75.802955) (xy 217.700268 -75.8175) (xy 217.734775 -75.870314)
			(xy 217.762484 -75.92699) (xy 217.78297 -75.986658) (xy 217.795917 -76.048402) (xy 217.801128 -76.111273)
			(xy 217.798521 -76.174306) (xy 217.788138 -76.236532) (xy 217.770138 -76.296997) (xy 217.744796 -76.35477)
			(xy 217.712503 -76.408965) (xy 217.673754 -76.458749) (xy 217.629145 -76.503358) (xy 217.57936 -76.542106)
			(xy 217.525165 -76.574399) (xy 217.510116 -76.581) (xy 221.98152 -76.581) (xy 221.985591 -76.525378)
			(xy 221.997717 -76.470941) (xy 222.01764 -76.41885) (xy 222.044936 -76.370215) (xy 222.079022 -76.326072)
			(xy 222.119171 -76.287363) (xy 222.164529 -76.254912) (xy 222.214129 -76.229411) (xy 222.266913 -76.211404)
			(xy 222.321756 -76.201274) (xy 222.37749 -76.199237) (xy 222.432927 -76.205337) (xy 222.486884 -76.219443)
			(xy 222.538213 -76.241255) (xy 222.585819 -76.270309) (xy 222.628687 -76.305984) (xy 222.665904 -76.347521)
			(xy 222.696677 -76.394034) (xy 222.720349 -76.444531) (xy 222.736417 -76.497938) (xy 222.744537 -76.553114)
			(xy 222.745046 -76.581) (xy 222.744537 -76.608886) (xy 222.736417 -76.664062) (xy 222.720349 -76.717469)
			(xy 222.696677 -76.767966) (xy 222.665904 -76.814479) (xy 222.628687 -76.856016) (xy 222.585819 -76.891691)
			(xy 222.538213 -76.920745) (xy 222.486884 -76.942557) (xy 222.432927 -76.956663) (xy 222.37749 -76.962763)
			(xy 222.321756 -76.960726) (xy 222.266913 -76.950596) (xy 222.214129 -76.932589) (xy 222.164529 -76.907088)
			(xy 222.119171 -76.874637) (xy 222.079022 -76.835928) (xy 222.044936 -76.791785) (xy 222.01764 -76.74315)
			(xy 221.997717 -76.691059) (xy 221.985591 -76.636622) (xy 221.98152 -76.581) (xy 217.510116 -76.581)
			(xy 217.467391 -76.59974) (xy 217.406926 -76.61774) (xy 217.3447 -76.628122) (xy 217.281667 -76.630728)
			(xy 217.218796 -76.625516) (xy 217.157052 -76.612568) (xy 217.097384 -76.592082) (xy 217.040708 -76.564372)
			(xy 216.987896 -76.529865) (xy 216.939757 -76.48909) (xy 216.897031 -76.442673) (xy 216.860375 -76.391329)
			(xy 216.830352 -76.335844) (xy 216.807423 -76.277072) (xy 216.791939 -76.215914) (xy 216.78414 -76.153311)
			(xy 216.783666 -76.121768) (xy 216.783666 -76.12126) (xy 216.78383 -76.103804) (xy 216.786242 -76.068975)
			(xy 216.788492 -76.051664) (xy 216.790015 -76.037701) (xy 216.786127 -76.009892) (xy 216.774812 -75.984192)
			(xy 216.756925 -75.962547) (xy 216.733818 -75.946591) (xy 216.707239 -75.937533) (xy 216.693242 -75.936348)
			(xy 216.664324 -75.93429) (xy 216.607553 -75.922549) (xy 216.553211 -75.902356) (xy 216.502549 -75.874174)
			(xy 216.456734 -75.838653) (xy 216.41682 -75.796609) (xy 216.383725 -75.749012) (xy 216.358211 -75.696955)
			(xy 216.340866 -75.641638) (xy 216.332089 -75.584334) (xy 216.331546 -75.555348) (xy 211.006419 -75.555348)
			(xy 210.976437 -75.58881) (xy 210.933569 -75.624485) (xy 210.885963 -75.653539) (xy 210.834634 -75.675351)
			(xy 210.780677 -75.689457) (xy 210.72524 -75.695557) (xy 210.669506 -75.69352) (xy 210.614663 -75.68339)
			(xy 210.561879 -75.665383) (xy 210.512279 -75.639882) (xy 210.466921 -75.607431) (xy 210.426772 -75.568722)
			(xy 210.392686 -75.524579) (xy 210.36539 -75.475944) (xy 210.345467 -75.423853) (xy 210.333341 -75.369416)
			(xy 210.32927 -75.313794) (xy 203.377763 -75.313794) (xy 203.410265 -75.360879) (xy 203.438829 -75.415299)
			(xy 203.460624 -75.472765) (xy 203.475335 -75.532439) (xy 203.482745 -75.593452) (xy 203.48321 -75.624182)
			(xy 203.482637 -75.657453) (xy 203.473948 -75.723424) (xy 203.45673 -75.787699) (xy 203.431276 -75.84918)
			(xy 203.398021 -75.906816) (xy 203.357534 -75.959623) (xy 203.310506 -76.006698) (xy 203.25774 -76.047238)
			(xy 203.22921 -76.064364) (xy 203.219304 -76.069952) (xy 203.206604 -76.088494) (xy 203.189586 -76.188316)
			(xy 203.195682 -76.209906) (xy 203.203048 -76.218542) (xy 203.222325 -76.241624) (xy 203.255843 -76.291559)
			(xy 203.283235 -76.3451) (xy 203.304119 -76.401498) (xy 203.318203 -76.459966) (xy 203.325292 -76.519688)
			(xy 203.32573 -76.549758) (xy 203.325228 -76.581719) (xy 203.317217 -76.645137) (xy 203.303098 -76.700126)
			(xy 203.680314 -76.700126) (xy 203.680816 -76.668165) (xy 203.688827 -76.604747) (xy 203.704724 -76.542833)
			(xy 203.728256 -76.4834) (xy 203.75905 -76.427385) (xy 203.796623 -76.37567) (xy 203.84038 -76.329073)
			(xy 203.889633 -76.288328) (xy 203.943604 -76.254077) (xy 204.001443 -76.22686) (xy 204.062236 -76.207107)
			(xy 204.125026 -76.195129) (xy 204.188822 -76.191116) (xy 204.252618 -76.195129) (xy 204.315408 -76.207107)
			(xy 204.376201 -76.22686) (xy 204.43404 -76.254077) (xy 204.488011 -76.288328) (xy 204.537264 -76.329073)
			(xy 204.581021 -76.37567) (xy 204.618594 -76.427385) (xy 204.649388 -76.4834) (xy 204.67292 -76.542833)
			(xy 204.688817 -76.604747) (xy 204.696828 -76.668165) (xy 204.69733 -76.700126) (xy 204.697008 -76.725186)
			(xy 204.692047 -76.775062) (xy 204.687424 -76.799694) (xy 204.685905 -76.809895) (xy 204.690079 -76.830071)
			(xy 204.695552 -76.83881) (xy 204.737462 -76.899008) (xy 204.743629 -76.907093) (xy 204.760791 -76.917969)
			(xy 204.770736 -76.92009) (xy 204.771244 -76.92009) (xy 204.803428 -76.925717) (xy 204.866104 -76.944171)
			(xy 204.925901 -76.970502) (xy 204.948765 -76.984309) (xy 209.707728 -76.984309) (xy 209.707728 -76.920387)
			(xy 209.715739 -76.856969) (xy 209.731636 -76.795055) (xy 209.755168 -76.735622) (xy 209.785962 -76.679607)
			(xy 209.823535 -76.627892) (xy 209.867292 -76.581295) (xy 209.916545 -76.54055) (xy 209.970516 -76.506299)
			(xy 210.028355 -76.479082) (xy 210.089148 -76.459329) (xy 210.151938 -76.447351) (xy 210.215734 -76.443338)
			(xy 210.27953 -76.447351) (xy 210.34232 -76.459329) (xy 210.403113 -76.479082) (xy 210.460952 -76.506299)
			(xy 210.514923 -76.54055) (xy 210.564176 -76.581295) (xy 210.607933 -76.627892) (xy 210.645506 -76.679607)
			(xy 210.6763 -76.735622) (xy 210.699832 -76.795055) (xy 210.715729 -76.856969) (xy 210.72374 -76.920387)
			(xy 210.724242 -76.952348) (xy 210.72374 -76.984309) (xy 210.715729 -77.047727) (xy 210.699832 -77.109641)
			(xy 210.6763 -77.169074) (xy 210.645506 -77.225089) (xy 210.607933 -77.276804) (xy 210.564176 -77.323401)
			(xy 210.514923 -77.364146) (xy 210.460952 -77.398397) (xy 210.403113 -77.425614) (xy 210.34232 -77.445367)
			(xy 210.27953 -77.457345) (xy 210.215734 -77.461359) (xy 210.151938 -77.457345) (xy 210.089148 -77.445367)
			(xy 210.028355 -77.425614) (xy 209.970516 -77.398397) (xy 209.916545 -77.364146) (xy 209.867292 -77.323401)
			(xy 209.823535 -77.276804) (xy 209.785962 -77.225089) (xy 209.755168 -77.169074) (xy 209.731636 -77.109641)
			(xy 209.715739 -77.047727) (xy 209.707728 -76.984309) (xy 204.948765 -76.984309) (xy 204.981831 -77.004276)
			(xy 205.032974 -77.044937) (xy 205.078487 -77.091814) (xy 205.11762 -77.144136) (xy 205.149728 -77.201039)
			(xy 205.174282 -77.261586) (xy 205.190877 -77.32478) (xy 205.199241 -77.38958) (xy 205.199742 -77.422248)
			(xy 205.19924 -77.454209) (xy 205.191229 -77.517627) (xy 205.185599 -77.539553) (xy 208.455 -77.539553)
			(xy 208.455 -77.475631) (xy 208.463011 -77.412213) (xy 208.478908 -77.350299) (xy 208.50244 -77.290866)
			(xy 208.533234 -77.234851) (xy 208.570807 -77.183136) (xy 208.614564 -77.136539) (xy 208.663817 -77.095794)
			(xy 208.717788 -77.061543) (xy 208.775627 -77.034326) (xy 208.83642 -77.014573) (xy 208.89921 -77.002595)
			(xy 208.963006 -76.998582) (xy 209.026802 -77.002595) (xy 209.089592 -77.014573) (xy 209.150385 -77.034326)
			(xy 209.208224 -77.061543) (xy 209.262195 -77.095794) (xy 209.311448 -77.136539) (xy 209.355205 -77.183136)
			(xy 209.392778 -77.234851) (xy 209.423572 -77.290866) (xy 209.447104 -77.350299) (xy 209.463001 -77.412213)
			(xy 209.469309 -77.462146) (xy 217.221126 -77.462146) (xy 217.221126 -77.407654) (xy 217.22888 -77.353717)
			(xy 217.244231 -77.301433) (xy 217.266866 -77.251865) (xy 217.296324 -77.206023) (xy 217.332006 -77.164839)
			(xy 217.373186 -77.129152) (xy 217.419025 -77.099688) (xy 217.46859 -77.077047) (xy 217.520872 -77.06169)
			(xy 217.574808 -77.053929) (xy 217.602054 -77.05344) (xy 217.627422 -77.05387) (xy 217.677712 -77.06059)
			(xy 217.726666 -77.073918) (xy 217.773422 -77.093617) (xy 217.817154 -77.119342) (xy 217.857089 -77.150637)
			(xy 217.875104 -77.168502) (xy 217.883526 -77.176157) (xy 217.90488 -77.183941) (xy 217.916252 -77.183488)
			(xy 217.995246 -77.175868) (xy 218.006527 -77.174169) (xy 218.026052 -77.162432) (xy 218.032838 -77.153262)
			(xy 218.050484 -77.127172) (xy 218.091226 -77.079134) (xy 218.137593 -77.036501) (xy 218.188875 -76.999926)
			(xy 218.244283 -76.96997) (xy 218.30297 -76.947093) (xy 218.364034 -76.931645) (xy 218.42654 -76.923863)
			(xy 218.458034 -76.923392) (xy 218.489994 -76.923896) (xy 218.553408 -76.931911) (xy 218.615319 -76.947811)
			(xy 218.674748 -76.971344) (xy 218.73076 -77.00214) (xy 218.78247 -77.039713) (xy 218.829064 -77.08347)
			(xy 218.869806 -77.132722) (xy 218.904055 -77.186692) (xy 218.931269 -77.244528) (xy 218.95102 -77.30532)
			(xy 218.962997 -77.368107) (xy 218.967011 -77.4319) (xy 218.962997 -77.495693) (xy 218.95102 -77.55848)
			(xy 218.931269 -77.619272) (xy 218.904055 -77.677108) (xy 218.869806 -77.731078) (xy 218.829064 -77.78033)
			(xy 218.78247 -77.824087) (xy 218.73076 -77.86166) (xy 218.674748 -77.892456) (xy 218.615319 -77.915989)
			(xy 218.553408 -77.931889) (xy 218.489994 -77.939904) (xy 218.458034 -77.940408) (xy 218.426755 -77.939963)
			(xy 218.364667 -77.932303) (xy 218.303989 -77.917081) (xy 218.245637 -77.894528) (xy 218.190494 -77.864985)
			(xy 218.139394 -77.828898) (xy 218.093108 -77.786813) (xy 218.052336 -77.739366) (xy 218.034616 -77.713586)
			(xy 218.028266 -77.703934) (xy 218.008454 -77.69225) (xy 217.918284 -77.684122) (xy 217.906771 -77.683553)
			(xy 217.885206 -77.691639) (xy 217.876882 -77.699616) (xy 217.858843 -77.717758) (xy 217.818743 -77.749529)
			(xy 217.774756 -77.775657) (xy 217.727673 -77.795673) (xy 217.678338 -77.809217) (xy 217.627635 -77.816048)
			(xy 217.602054 -77.816456) (xy 217.574808 -77.815871) (xy 217.520872 -77.80811) (xy 217.46859 -77.792753)
			(xy 217.419025 -77.770112) (xy 217.373186 -77.740648) (xy 217.332006 -77.704961) (xy 217.296324 -77.663777)
			(xy 217.266866 -77.617935) (xy 217.244231 -77.568367) (xy 217.22888 -77.516083) (xy 217.221126 -77.462146)
			(xy 209.469309 -77.462146) (xy 209.471012 -77.475631) (xy 209.471514 -77.507592) (xy 209.471012 -77.539553)
			(xy 209.463001 -77.602971) (xy 209.447104 -77.664885) (xy 209.423572 -77.724318) (xy 209.392778 -77.780333)
			(xy 209.355205 -77.832048) (xy 209.311448 -77.878645) (xy 209.262195 -77.91939) (xy 209.208224 -77.953641)
			(xy 209.150385 -77.980858) (xy 209.089592 -78.000611) (xy 209.026802 -78.012589) (xy 208.963006 -78.016603)
			(xy 208.89921 -78.012589) (xy 208.83642 -78.000611) (xy 208.775627 -77.980858) (xy 208.717788 -77.953641)
			(xy 208.663817 -77.91939) (xy 208.614564 -77.878645) (xy 208.570807 -77.832048) (xy 208.533234 -77.780333)
			(xy 208.50244 -77.724318) (xy 208.478908 -77.664885) (xy 208.463011 -77.602971) (xy 208.455 -77.539553)
			(xy 205.185599 -77.539553) (xy 205.175332 -77.579541) (xy 205.1518 -77.638974) (xy 205.121006 -77.694989)
			(xy 205.083433 -77.746704) (xy 205.039676 -77.793301) (xy 204.990423 -77.834046) (xy 204.936452 -77.868297)
			(xy 204.878613 -77.895514) (xy 204.81782 -77.915267) (xy 204.75503 -77.927245) (xy 204.691234 -77.931259)
			(xy 204.627438 -77.927245) (xy 204.564648 -77.915267) (xy 204.503855 -77.895514) (xy 204.446016 -77.868297)
			(xy 204.392045 -77.834046) (xy 204.342792 -77.793301) (xy 204.299035 -77.746704) (xy 204.261462 -77.694989)
			(xy 204.230668 -77.638974) (xy 204.207136 -77.579541) (xy 204.191239 -77.517627) (xy 204.183228 -77.454209)
			(xy 204.182726 -77.422248) (xy 204.183045 -77.397188) (xy 204.188008 -77.347312) (xy 204.192632 -77.32268)
			(xy 204.194174 -77.31248) (xy 204.189986 -77.292301) (xy 204.184504 -77.283564) (xy 204.142594 -77.223366)
			(xy 204.13641 -77.215296) (xy 204.11926 -77.204413) (xy 204.10932 -77.202284) (xy 204.108812 -77.202284)
			(xy 204.076636 -77.19662) (xy 204.013964 -77.178164) (xy 203.954172 -77.151833) (xy 203.898246 -77.118061)
			(xy 203.847105 -77.077403) (xy 203.801593 -77.03053) (xy 203.76246 -76.978214) (xy 203.73035 -76.921317)
			(xy 203.705792 -76.860775) (xy 203.689191 -76.797587) (xy 203.680819 -76.732792) (xy 203.680314 -76.700126)
			(xy 203.303098 -76.700126) (xy 203.30132 -76.707051) (xy 203.277788 -76.766484) (xy 203.246994 -76.822499)
			(xy 203.209421 -76.874214) (xy 203.165664 -76.920811) (xy 203.116411 -76.961556) (xy 203.06244 -76.995807)
			(xy 203.004601 -77.023024) (xy 202.943808 -77.042777) (xy 202.881018 -77.054755) (xy 202.817222 -77.058769)
			(xy 202.753426 -77.054755) (xy 202.690636 -77.042777) (xy 202.629843 -77.023024) (xy 202.572004 -76.995807)
			(xy 202.518033 -76.961556) (xy 202.46878 -76.920811) (xy 202.425023 -76.874214) (xy 202.38745 -76.822499)
			(xy 202.356656 -76.766484) (xy 202.333124 -76.707051) (xy 202.317227 -76.645137) (xy 202.309216 -76.581719)
			(xy 202.308714 -76.549758) (xy 202.309318 -76.514127) (xy 202.319265 -76.443563) (xy 202.338961 -76.375077)
			(xy 202.368018 -76.310008) (xy 202.386438 -76.279502) (xy 202.391311 -76.270804) (xy 202.394755 -76.251193)
			(xy 202.390468 -76.231749) (xy 202.379096 -76.215405) (xy 202.362354 -76.204626) (xy 202.342769 -76.201038)
			(xy 202.323294 -76.205183) (xy 202.31481 -76.210414) (xy 202.292251 -76.22525) (xy 202.243807 -76.249088)
			(xy 202.21829 -76.257912) (xy 202.218036 -76.257912) (xy 202.20821 -76.261768) (xy 202.192595 -76.275936)
			(xy 202.18781 -76.285344) (xy 202.157076 -76.354178) (xy 202.153223 -76.363958) (xy 202.152951 -76.38495)
			(xy 202.156568 -76.394818) (xy 202.156822 -76.395072) (xy 202.156822 -76.39558) (xy 202.170219 -76.42772)
			(xy 202.189107 -76.494739) (xy 202.198653 -76.563711) (xy 202.19924 -76.598526) (xy 202.198813 -76.628742)
			(xy 202.191658 -76.688748) (xy 202.177441 -76.747484) (xy 202.156362 -76.80412) (xy 202.128717 -76.857858)
			(xy 202.094898 -76.90794) (xy 202.05538 -76.95366) (xy 202.010721 -76.994373) (xy 201.986388 -77.012292)
			(xy 201.977274 -77.019402) (xy 201.966167 -77.039648) (xy 201.965052 -77.051154) (xy 201.960734 -77.130148)
			(xy 201.960683 -77.141627) (xy 201.969525 -77.162784) (xy 201.977752 -77.170788) (xy 202.00029 -77.191498)
			(xy 202.040733 -77.237445) (xy 202.075368 -77.287913) (xy 202.103696 -77.342173) (xy 202.125307 -77.399442)
			(xy 202.139887 -77.45889) (xy 202.147226 -77.519659) (xy 202.147678 -77.550264) (xy 202.14718 -77.581924)
			(xy 202.139332 -77.644756) (xy 202.123742 -77.706127) (xy 202.100651 -77.765087) (xy 202.070416 -77.820723)
			(xy 202.033506 -77.872172) (xy 201.990491 -77.918639) (xy 201.966576 -77.939392) (xy 201.958382 -77.947099)
			(xy 201.949022 -77.967524) (xy 201.948542 -77.978762) (xy 201.949558 -78.068678) (xy 201.95921 -78.088998)
			(xy 201.968354 -78.09611) (xy 201.993339 -78.116879) (xy 202.038386 -78.163698) (xy 202.077105 -78.215871)
			(xy 202.108864 -78.27255) (xy 202.133148 -78.332813) (xy 202.149559 -78.395677) (xy 202.157832 -78.460119)
			(xy 202.158346 -78.492604) (xy 202.157777 -78.526933) (xy 202.1485 -78.594962) (xy 202.130169 -78.661128)
			(xy 202.103116 -78.724232) (xy 202.085956 -78.75397) (xy 202.078844 -78.765908) (xy 202.07859 -78.792578)
			(xy 202.134724 -78.89367) (xy 202.157838 -78.907386) (xy 202.171554 -78.90764) (xy 202.203519 -78.908653)
			(xy 202.266836 -78.917655) (xy 202.328526 -78.934518) (xy 202.387618 -78.958976) (xy 202.44318 -78.990644)
			(xy 202.494338 -79.029023) (xy 202.540285 -79.073508) (xy 202.560682 -79.09814) (xy 202.566699 -79.105068)
			(xy 202.582456 -79.114445) (xy 202.591416 -79.116428) (xy 202.621642 -79.121762) (xy 202.630567 -79.122954)
			(xy 202.648266 -79.119696) (xy 202.656186 -79.115412) (xy 202.678222 -79.102946) (xy 202.724883 -79.083299)
			(xy 202.773733 -79.069994) (xy 202.823912 -79.063265) (xy 202.849226 -79.062834) (xy 202.849734 -79.062834)
			(xy 202.876987 -79.063238) (xy 202.930937 -79.071) (xy 202.983233 -79.086359) (xy 203.032811 -79.109005)
			(xy 203.078663 -79.138475) (xy 203.119853 -79.174171) (xy 203.146408 -79.20482) (xy 208.001362 -79.20482)
			(xy 208.001881 -79.176833) (xy 208.010057 -79.121458) (xy 208.026237 -79.067873) (xy 208.050073 -79.017227)
			(xy 208.081053 -78.970608) (xy 208.118513 -78.929015) (xy 208.161649 -78.893343) (xy 208.209534 -78.864357)
			(xy 208.26114 -78.842679) (xy 208.288128 -78.83525) (xy 208.296464 -78.832742) (xy 208.310873 -78.82299)
			(xy 208.316322 -78.8162) (xy 208.334102 -78.792324) (xy 208.339203 -78.785008) (xy 208.344414 -78.767966)
			(xy 208.344262 -78.75905) (xy 208.3435 -78.733142) (xy 208.343923 -78.701598) (xy 208.351722 -78.638994)
			(xy 208.367204 -78.577835) (xy 208.390133 -78.51906) (xy 208.420155 -78.463574) (xy 208.45681 -78.412227)
			(xy 208.499535 -78.365808) (xy 208.547674 -78.325031) (xy 208.600487 -78.290522) (xy 208.657163 -78.26281)
			(xy 208.716832 -78.242321) (xy 208.778576 -78.229371) (xy 208.841449 -78.224157) (xy 208.904483 -78.22676)
			(xy 208.966711 -78.237141) (xy 209.027178 -78.255139) (xy 209.084954 -78.280478) (xy 209.139152 -78.312769)
			(xy 209.188939 -78.351516) (xy 209.233551 -78.396124) (xy 209.272303 -78.445907) (xy 209.304599 -78.500102)
			(xy 209.329944 -78.557875) (xy 209.347948 -78.61834) (xy 209.358335 -78.680567) (xy 209.360944 -78.743601)
			(xy 209.355737 -78.806474) (xy 209.342792 -78.86822) (xy 209.32231 -78.927891) (xy 209.294603 -78.984569)
			(xy 209.260099 -79.037386) (xy 209.219326 -79.085528) (xy 209.172912 -79.128258) (xy 209.121569 -79.164918)
			(xy 209.066085 -79.194946) (xy 209.03289 -79.2079) (xy 209.527336 -79.2079) (xy 209.531351 -79.144097)
			(xy 209.54333 -79.0813) (xy 209.563086 -79.020499) (xy 209.590306 -78.962654) (xy 209.624561 -78.908677)
			(xy 209.665312 -78.859419) (xy 209.711915 -78.815656) (xy 209.763636 -78.77808) (xy 209.819658 -78.747283)
			(xy 209.879098 -78.723749) (xy 209.94102 -78.707852) (xy 210.004445 -78.69984) (xy 210.03641 -78.69936)
			(xy 210.066344 -78.699789) (xy 210.125796 -78.70683) (xy 210.184011 -78.720802) (xy 210.240184 -78.741511)
			(xy 210.293536 -78.768671) (xy 210.343332 -78.801906) (xy 210.388881 -78.840757) (xy 210.409536 -78.862428)
			(xy 210.416993 -78.869674) (xy 210.435988 -78.878075) (xy 210.446366 -78.878684) (xy 210.520534 -78.878938)
			(xy 210.530944 -78.878551) (xy 210.550094 -78.870397) (xy 210.557618 -78.86319) (xy 210.581675 -78.838674)
			(xy 210.635282 -78.795728) (xy 210.694185 -78.760396) (xy 210.757312 -78.733322) (xy 210.82351 -78.714999)
			(xy 210.891574 -78.705761) (xy 210.925918 -78.705202) (xy 210.926172 -78.705202) (xy 210.958136 -78.705661)
			(xy 211.021561 -78.71367) (xy 211.083481 -78.729566) (xy 211.142921 -78.753097) (xy 211.198943 -78.783892)
			(xy 211.250663 -78.821467) (xy 211.297266 -78.865227) (xy 211.338017 -78.914484) (xy 211.372272 -78.96846)
			(xy 211.399492 -79.026303) (xy 211.419248 -79.087102) (xy 211.431227 -79.149898) (xy 211.435242 -79.2137)
			(xy 211.431227 -79.277502) (xy 211.419248 -79.340298) (xy 211.399492 -79.401097) (xy 211.372272 -79.45894)
			(xy 211.338017 -79.512916) (xy 211.297266 -79.562173) (xy 211.250663 -79.605933) (xy 211.198943 -79.643508)
			(xy 211.142921 -79.674303) (xy 211.083481 -79.697834) (xy 211.021561 -79.71373) (xy 210.958136 -79.721739)
			(xy 210.926172 -79.722218) (xy 210.896237 -79.721808) (xy 210.836784 -79.714764) (xy 210.778568 -79.70079)
			(xy 210.722396 -79.680078) (xy 210.669043 -79.652915) (xy 210.619249 -79.619677) (xy 210.5737 -79.580822)
			(xy 210.553046 -79.55915) (xy 210.545599 -79.551893) (xy 210.526596 -79.543499) (xy 210.516216 -79.542894)
			(xy 210.442048 -79.54264) (xy 210.431644 -79.543077) (xy 210.412494 -79.551197) (xy 210.404964 -79.558388)
			(xy 210.380912 -79.582909) (xy 210.327304 -79.625855) (xy 210.2684 -79.661187) (xy 210.205272 -79.68826)
			(xy 210.139073 -79.706582) (xy 210.071008 -79.715818) (xy 210.036664 -79.716376) (xy 210.03641 -79.716376)
			(xy 210.004445 -79.71596) (xy 209.94102 -79.707948) (xy 209.879098 -79.692051) (xy 209.819658 -79.668517)
			(xy 209.763636 -79.63772) (xy 209.711915 -79.600144) (xy 209.665312 -79.556381) (xy 209.624561 -79.507123)
			(xy 209.590306 -79.453146) (xy 209.563086 -79.395301) (xy 209.54333 -79.3345) (xy 209.531351 -79.271703)
			(xy 209.527336 -79.2079) (xy 209.03289 -79.2079) (xy 209.007313 -79.217881) (xy 208.946156 -79.233369)
			(xy 208.883552 -79.241174) (xy 208.852008 -79.24165) (xy 208.82864 -79.241142) (xy 208.8198 -79.241128)
			(xy 208.802915 -79.246311) (xy 208.79562 -79.251302) (xy 208.77149 -79.269336) (xy 208.76484 -79.274838)
			(xy 208.755354 -79.289242) (xy 208.752948 -79.29753) (xy 208.745668 -79.324681) (xy 208.724152 -79.376612)
			(xy 208.695249 -79.424824) (xy 208.659584 -79.468273) (xy 208.617931 -79.506019) (xy 208.57119 -79.537244)
			(xy 208.520373 -79.561274) (xy 208.46658 -79.577587) (xy 208.410976 -79.58583) (xy 208.38287 -79.586328)
			(xy 208.355619 -79.58585) (xy 208.301672 -79.57809) (xy 208.249378 -79.562732) (xy 208.199802 -79.540089)
			(xy 208.153953 -79.510621) (xy 208.112764 -79.474929) (xy 208.077073 -79.433739) (xy 208.047606 -79.387889)
			(xy 208.024964 -79.338312) (xy 208.009608 -79.286018) (xy 208.001849 -79.232071) (xy 208.001362 -79.20482)
			(xy 203.146408 -79.20482) (xy 203.155545 -79.215365) (xy 203.185011 -79.261218) (xy 203.207653 -79.310799)
			(xy 203.223008 -79.363097) (xy 203.230764 -79.417047) (xy 203.230764 -79.471553) (xy 203.223008 -79.525503)
			(xy 203.207653 -79.577801) (xy 203.185011 -79.627382) (xy 203.155545 -79.673235) (xy 203.119853 -79.714429)
			(xy 203.078663 -79.750125) (xy 203.032811 -79.779595) (xy 202.983233 -79.802241) (xy 202.930937 -79.8176)
			(xy 202.876987 -79.825362) (xy 202.849734 -79.82585) (xy 202.82045 -79.825345) (xy 202.762571 -79.816396)
			(xy 202.70674 -79.798704) (xy 202.65427 -79.772685) (xy 202.630024 -79.756254) (xy 202.62244 -79.75135)
			(xy 202.605009 -79.746664) (xy 202.595988 -79.74711) (xy 202.565508 -79.750158) (xy 202.556392 -79.751295)
			(xy 202.53985 -79.759259) (xy 202.53325 -79.765652) (xy 202.509132 -79.790271) (xy 202.455421 -79.833456)
			(xy 202.396375 -79.869) (xy 202.333074 -79.896254) (xy 202.266676 -79.914721) (xy 202.198393 -79.924062)
			(xy 202.163934 -79.924656) (xy 202.133206 -79.924112) (xy 202.072196 -79.916708) (xy 202.012524 -79.902005)
			(xy 201.95506 -79.880216) (xy 201.90064 -79.85166) (xy 201.850059 -79.816753) (xy 201.804055 -79.776003)
			(xy 201.763298 -79.730005) (xy 201.728382 -79.67943) (xy 201.699817 -79.625015) (xy 201.678019 -79.567554)
			(xy 201.663306 -79.507884) (xy 201.655893 -79.446876) (xy 201.655426 -79.416148) (xy 201.656022 -79.38182)
			(xy 201.665291 -79.313792) (xy 201.683615 -79.247626) (xy 201.71066 -79.184521) (xy 201.727816 -79.154782)
			(xy 201.734928 -79.142844) (xy 201.735182 -79.116174) (xy 201.679048 -79.015082) (xy 201.655934 -79.001366)
			(xy 201.642218 -79.001112) (xy 201.609252 -79.00009) (xy 201.543986 -78.990577) (xy 201.480498 -78.972706)
			(xy 201.419852 -78.946777) (xy 201.363068 -78.913226) (xy 201.311098 -78.872615) (xy 201.264813 -78.825627)
			(xy 201.224992 -78.773049) (xy 201.192302 -78.715765) (xy 201.167292 -78.654735) (xy 201.150381 -78.590984)
			(xy 201.141854 -78.525582) (xy 201.14133 -78.492604) (xy 201.141803 -78.460943) (xy 201.149654 -78.39811)
			(xy 201.165248 -78.336738) (xy 201.188344 -78.277778) (xy 201.218583 -78.222143) (xy 201.255497 -78.170694)
			(xy 201.298515 -78.124228) (xy 201.322432 -78.103476) (xy 201.330642 -78.095783) (xy 201.339993 -78.075348)
			(xy 201.340466 -78.064106) (xy 201.33945 -77.97419) (xy 201.329798 -77.95387) (xy 201.320654 -77.946758)
			(xy 201.295656 -77.926005) (xy 201.250609 -77.879184) (xy 201.211891 -77.827007) (xy 201.180133 -77.770325)
			(xy 201.155852 -77.710061) (xy 201.139443 -77.647194) (xy 201.131174 -77.58275) (xy 201.130662 -77.550264)
			(xy 201.13108 -77.520048) (xy 201.138236 -77.460041) (xy 201.152455 -77.401305) (xy 201.173536 -77.344669)
			(xy 201.201181 -77.290931) (xy 201.235002 -77.240849) (xy 201.274521 -77.19513) (xy 201.31918 -77.154417)
			(xy 201.343514 -77.136498) (xy 201.352632 -77.129393) (xy 201.363738 -77.109143) (xy 201.36485 -77.097636)
			(xy 201.369168 -77.018642) (xy 201.369224 -77.007162) (xy 201.360378 -76.986005) (xy 201.35215 -76.978002)
			(xy 201.329608 -76.957296) (xy 201.289165 -76.911349) (xy 201.25453 -76.86088) (xy 201.226202 -76.806619)
			(xy 201.204593 -76.74935) (xy 201.190014 -76.689901) (xy 201.182675 -76.629131) (xy 201.182224 -76.598526)
			(xy 201.182647 -76.567468) (xy 201.19021 -76.505815) (xy 201.205226 -76.445542) (xy 201.227473 -76.387547)
			(xy 201.256618 -76.332693) (xy 201.292227 -76.281798) (xy 201.33377 -76.23562) (xy 201.38063 -76.194845)
			(xy 201.432106 -76.160082) (xy 201.487434 -76.131848) (xy 201.545789 -76.110564) (xy 201.606302 -76.096546)
			(xy 201.637138 -76.092812) (xy 201.647552 -76.091796) (xy 201.666094 -76.081128) (xy 201.723498 -76.002896)
			(xy 201.72807 -75.982068) (xy 201.725784 -75.971654) (xy 201.722211 -75.952807) (xy 201.718391 -75.914635)
			(xy 201.718164 -75.895454) (xy 201.718433 -75.874715) (xy 201.722886 -75.833476) (xy 201.727054 -75.813158)
			(xy 201.730102 -75.800204) (xy 201.722482 -75.774804) (xy 201.641456 -75.696318) (xy 201.615802 -75.68946)
			(xy 201.603102 -75.692762) (xy 201.572564 -75.700014) (xy 201.510279 -75.707779) (xy 201.478896 -75.708256)
			(xy 201.478134 -75.708256) (xy 201.44659 -75.707768) (xy 201.383985 -75.699969) (xy 201.322826 -75.684485)
			(xy 201.264053 -75.661555) (xy 201.208566 -75.631531) (xy 201.15722 -75.594874) (xy 201.110803 -75.552147)
			(xy 201.070027 -75.504007) (xy 201.035519 -75.451193) (xy 201.007809 -75.394515) (xy 200.987323 -75.334846)
			(xy 200.974375 -75.2731) (xy 200.969164 -75.210227) (xy 198.65317 -75.210227) (xy 198.658075 -75.244344)
			(xy 198.658075 -75.298856) (xy 198.650317 -75.352814) (xy 198.634958 -75.405118) (xy 198.612312 -75.454704)
			(xy 198.582839 -75.500562) (xy 198.547139 -75.541759) (xy 198.50594 -75.577456) (xy 198.46008 -75.606925)
			(xy 198.410492 -75.629568) (xy 198.358187 -75.644923) (xy 198.304228 -75.652677) (xy 198.276972 -75.653138)
			(xy 198.249673 -75.652661) (xy 198.195632 -75.644887) (xy 198.143251 -75.629486) (xy 198.093602 -75.606774)
			(xy 198.047698 -75.577215) (xy 198.026782 -75.559666) (xy 198.018908 -75.552808) (xy 197.998842 -75.546204)
			(xy 197.915022 -75.554586) (xy 197.904682 -75.556177) (xy 197.886454 -75.566397) (xy 197.879716 -75.574398)
			(xy 197.858992 -75.600369) (xy 197.811921 -75.647262) (xy 197.759146 -75.687628) (xy 197.701565 -75.72078)
			(xy 197.640157 -75.746153) (xy 197.575969 -75.763315) (xy 197.510093 -75.771975) (xy 197.476872 -75.772518)
			(xy 197.444913 -75.771994) (xy 197.381499 -75.76398) (xy 197.319589 -75.748081) (xy 197.26016 -75.724549)
			(xy 197.204149 -75.693754) (xy 197.152439 -75.656182) (xy 197.105845 -75.612425) (xy 197.065103 -75.563174)
			(xy 197.030855 -75.509205) (xy 197.003641 -75.451369) (xy 196.98389 -75.390579) (xy 196.971913 -75.327792)
			(xy 196.967899 -75.264) (xy 196.77917 -75.264) (xy 196.77917 -75.277753) (xy 196.771414 -75.331705)
			(xy 196.756058 -75.384003) (xy 196.733417 -75.433584) (xy 196.70395 -75.479439) (xy 196.668258 -75.520634)
			(xy 196.627066 -75.55633) (xy 196.581214 -75.5858) (xy 196.531635 -75.608446) (xy 196.479338 -75.623806)
			(xy 196.425387 -75.631568) (xy 196.398134 -75.632056) (xy 196.371489 -75.631626) (xy 196.318717 -75.62422)
			(xy 196.267491 -75.609534) (xy 196.218811 -75.587854) (xy 196.173626 -75.559602) (xy 196.132818 -75.525332)
			(xy 196.11467 -75.505818) (xy 196.106542 -75.496928) (xy 196.084952 -75.488292) (xy 195.980558 -75.496674)
			(xy 195.960238 -75.508866) (xy 195.953888 -75.518518) (xy 195.93627 -75.544891) (xy 195.895499 -75.593475)
			(xy 195.849004 -75.636613) (xy 195.797507 -75.673637) (xy 195.741806 -75.703971) (xy 195.682767 -75.727146)
			(xy 195.621304 -75.7428) (xy 195.558372 -75.750693) (xy 195.52666 -75.751182) (xy 195.494699 -75.75073)
			(xy 195.431281 -75.742713) (xy 195.369369 -75.726813) (xy 195.309937 -75.703278) (xy 195.253923 -75.67248)
			(xy 195.202211 -75.634905) (xy 195.155615 -75.591145) (xy 195.114871 -75.541891) (xy 195.080622 -75.487919)
			(xy 195.053406 -75.43008) (xy 195.033654 -75.369286) (xy 195.021677 -75.306496) (xy 195.017663 -75.2427)
			(xy 193.644594 -75.2427) (xy 193.640365 -75.258796) (xy 193.615807 -75.319338) (xy 193.583698 -75.376236)
			(xy 193.544567 -75.428553) (xy 193.499058 -75.475428) (xy 193.44792 -75.516089) (xy 193.391996 -75.549866)
			(xy 193.332207 -75.576203) (xy 193.269538 -75.594666) (xy 193.237358 -75.600306) (xy 193.227018 -75.60244)
			(xy 193.209298 -75.613878) (xy 193.203068 -75.622404) (xy 193.161666 -75.684888) (xy 193.156167 -75.694045)
			(xy 193.152597 -75.71508) (xy 193.154808 -75.725528) (xy 193.161916 -75.755829) (xy 193.169563 -75.817598)
			(xy 193.170048 -75.848718) (xy 193.170048 -75.84948) (xy 193.169546 -75.881441) (xy 193.161535 -75.944859)
			(xy 193.145638 -76.006773) (xy 193.122106 -76.066206) (xy 193.091312 -76.122221) (xy 193.053739 -76.173936)
			(xy 193.009982 -76.220533) (xy 192.960729 -76.261278) (xy 192.906758 -76.295529) (xy 192.848919 -76.322746)
			(xy 192.788126 -76.342499) (xy 192.725336 -76.354477) (xy 192.66154 -76.358491) (xy 192.597744 -76.354477)
			(xy 192.534954 -76.342499) (xy 192.474161 -76.322746) (xy 192.416322 -76.295529) (xy 192.362351 -76.261278)
			(xy 192.313098 -76.220533) (xy 192.269341 -76.173936) (xy 192.231768 -76.122221) (xy 192.200974 -76.066206)
			(xy 192.177442 -76.006773) (xy 192.161545 -75.944859) (xy 192.153534 -75.881441) (xy 192.153032 -75.84948)
			(xy 184.263859 -75.84948) (xy 184.250141 -75.920215) (xy 184.202053 -76.125712) (xy 184.146129 -76.329216)
			(xy 184.082452 -76.530429) (xy 184.011114 -76.729056) (xy 183.93222 -76.924804) (xy 183.845887 -77.117386)
			(xy 183.792805 -77.224593) (xy 192.007992 -77.224593) (xy 192.007992 -77.160671) (xy 192.016003 -77.097253)
			(xy 192.0319 -77.035339) (xy 192.055432 -76.975906) (xy 192.086226 -76.919891) (xy 192.123799 -76.868176)
			(xy 192.167556 -76.821579) (xy 192.216809 -76.780834) (xy 192.27078 -76.746583) (xy 192.328619 -76.719366)
			(xy 192.389412 -76.699613) (xy 192.452202 -76.687635) (xy 192.515998 -76.683622) (xy 192.579794 -76.687635)
			(xy 192.642584 -76.699613) (xy 192.703377 -76.719366) (xy 192.761216 -76.746583) (xy 192.815187 -76.780834)
			(xy 192.86444 -76.821579) (xy 192.897992 -76.857309) (xy 195.036688 -76.857309) (xy 195.036688 -76.793387)
			(xy 195.044699 -76.729969) (xy 195.060596 -76.668055) (xy 195.084128 -76.608622) (xy 195.114922 -76.552607)
			(xy 195.152495 -76.500892) (xy 195.196252 -76.454295) (xy 195.245505 -76.41355) (xy 195.299476 -76.379299)
			(xy 195.357315 -76.352082) (xy 195.418108 -76.332329) (xy 195.480898 -76.320351) (xy 195.544694 -76.316338)
			(xy 195.60849 -76.320351) (xy 195.67128 -76.332329) (xy 195.732073 -76.352082) (xy 195.789912 -76.379299)
			(xy 195.843883 -76.41355) (xy 195.893136 -76.454295) (xy 195.936893 -76.500892) (xy 195.974466 -76.552607)
			(xy 196.00526 -76.608622) (xy 196.028792 -76.668055) (xy 196.044689 -76.729969) (xy 196.0527 -76.793387)
			(xy 196.053202 -76.825348) (xy 196.0527 -76.857309) (xy 196.044689 -76.920727) (xy 196.028792 -76.982641)
			(xy 196.00526 -77.042074) (xy 195.974466 -77.098089) (xy 195.936893 -77.149804) (xy 195.893136 -77.196401)
			(xy 195.843883 -77.237146) (xy 195.789912 -77.271397) (xy 195.732073 -77.298614) (xy 195.67128 -77.318367)
			(xy 195.60849 -77.330345) (xy 195.544694 -77.334359) (xy 195.480898 -77.330345) (xy 195.418108 -77.318367)
			(xy 195.357315 -77.298614) (xy 195.299476 -77.271397) (xy 195.245505 -77.237146) (xy 195.196252 -77.196401)
			(xy 195.152495 -77.149804) (xy 195.114922 -77.098089) (xy 195.084128 -77.042074) (xy 195.060596 -76.982641)
			(xy 195.044699 -76.920727) (xy 195.036688 -76.857309) (xy 192.897992 -76.857309) (xy 192.908197 -76.868176)
			(xy 192.94577 -76.919891) (xy 192.976564 -76.975906) (xy 193.000096 -77.035339) (xy 193.015993 -77.097253)
			(xy 193.024004 -77.160671) (xy 193.024506 -77.192632) (xy 193.024004 -77.224593) (xy 193.015993 -77.288011)
			(xy 193.000096 -77.349925) (xy 192.976564 -77.409358) (xy 192.94577 -77.465373) (xy 192.908197 -77.517088)
			(xy 192.86444 -77.563685) (xy 192.815187 -77.60443) (xy 192.761216 -77.638681) (xy 192.703377 -77.665898)
			(xy 192.642584 -77.685651) (xy 192.579794 -77.697629) (xy 192.515998 -77.701643) (xy 192.452202 -77.697629)
			(xy 192.389412 -77.685651) (xy 192.328619 -77.665898) (xy 192.27078 -77.638681) (xy 192.216809 -77.60443)
			(xy 192.167556 -77.563685) (xy 192.123799 -77.517088) (xy 192.086226 -77.465373) (xy 192.055432 -77.409358)
			(xy 192.0319 -77.349925) (xy 192.016003 -77.288011) (xy 192.007992 -77.224593) (xy 183.792805 -77.224593)
			(xy 183.75224 -77.306521) (xy 183.651418 -77.49193) (xy 183.543568 -77.673341) (xy 183.428849 -77.850488)
			(xy 183.307429 -78.02311) (xy 183.179486 -78.190956) (xy 183.045208 -78.353778) (xy 182.943256 -78.468177)
			(xy 189.108582 -78.468177) (xy 189.108582 -78.404255) (xy 189.116593 -78.340837) (xy 189.13249 -78.278923)
			(xy 189.156022 -78.21949) (xy 189.186816 -78.163475) (xy 189.224389 -78.11176) (xy 189.268146 -78.065163)
			(xy 189.317399 -78.024418) (xy 189.37137 -77.990167) (xy 189.429209 -77.96295) (xy 189.490002 -77.943197)
			(xy 189.552792 -77.931219) (xy 189.616588 -77.927206) (xy 189.680384 -77.931219) (xy 189.743174 -77.943197)
			(xy 189.803967 -77.96295) (xy 189.861806 -77.990167) (xy 189.915777 -78.024418) (xy 189.96503 -78.065163)
			(xy 190.008787 -78.11176) (xy 190.04636 -78.163475) (xy 190.077154 -78.21949) (xy 190.100686 -78.278923)
			(xy 190.116583 -78.340837) (xy 190.124594 -78.404255) (xy 190.124901 -78.42377) (xy 197.388226 -78.42377)
			(xy 197.38864 -78.393617) (xy 197.39578 -78.333735) (xy 197.409955 -78.275118) (xy 197.430966 -78.218591)
			(xy 197.458519 -78.164946) (xy 197.492226 -78.114939) (xy 197.531613 -78.069272) (xy 197.55358 -78.048612)
			(xy 197.559792 -78.042449) (xy 197.567962 -78.026986) (xy 197.569582 -78.018386) (xy 197.5739 -77.988922)
			(xy 197.574766 -77.980353) (xy 197.571394 -77.963476) (xy 197.567296 -77.955902) (xy 197.55495 -77.933893)
			(xy 197.535479 -77.887337) (xy 197.5223 -77.838624) (xy 197.515641 -77.788602) (xy 197.515226 -77.76337)
			(xy 197.515767 -77.735169) (xy 197.524083 -77.679382) (xy 197.540515 -77.625426) (xy 197.564705 -77.574474)
			(xy 197.579996 -77.550772) (xy 197.584912 -77.542931) (xy 197.589195 -77.52494) (xy 197.588378 -77.51572)
			(xy 197.58406 -77.484986) (xy 197.582513 -77.475768) (xy 197.573651 -77.459327) (xy 197.566788 -77.452982)
			(xy 197.543192 -77.432239) (xy 197.500767 -77.3859) (xy 197.464377 -77.334686) (xy 197.434574 -77.279377)
			(xy 197.411814 -77.220818) (xy 197.396443 -77.159901) (xy 197.388696 -77.097553) (xy 197.388226 -77.06614)
			(xy 197.388728 -77.034179) (xy 197.396739 -76.970761) (xy 197.412636 -76.908847) (xy 197.436168 -76.849414)
			(xy 197.466962 -76.793399) (xy 197.504535 -76.741684) (xy 197.548292 -76.695087) (xy 197.597545 -76.654342)
			(xy 197.651516 -76.620091) (xy 197.709355 -76.592874) (xy 197.770148 -76.573121) (xy 197.832938 -76.561143)
			(xy 197.896734 -76.55713) (xy 197.96053 -76.561143) (xy 198.02332 -76.573121) (xy 198.084113 -76.592874)
			(xy 198.141952 -76.620091) (xy 198.195923 -76.654342) (xy 198.245176 -76.695087) (xy 198.288933 -76.741684)
			(xy 198.326506 -76.793399) (xy 198.3573 -76.849414) (xy 198.380832 -76.908847) (xy 198.396729 -76.970761)
			(xy 198.40474 -77.034179) (xy 198.405242 -77.06614) (xy 198.404792 -77.097555) (xy 198.397053 -77.159907)
			(xy 198.381687 -77.220829) (xy 198.358926 -77.279392) (xy 198.32912 -77.334702) (xy 198.292722 -77.385915)
			(xy 198.250288 -77.43225) (xy 198.22668 -77.452982) (xy 198.219901 -77.459394) (xy 198.211043 -77.4758)
			(xy 198.209408 -77.484986) (xy 198.20509 -77.51572) (xy 198.204327 -77.524934) (xy 198.208623 -77.542901)
			(xy 198.213472 -77.550772) (xy 198.228788 -77.574461) (xy 198.252998 -77.62541) (xy 198.269434 -77.679371)
			(xy 198.277738 -77.735165) (xy 198.278242 -77.76337) (xy 198.27787 -77.788606) (xy 198.271244 -77.838641)
			(xy 198.258063 -77.887361) (xy 198.23856 -77.933912) (xy 198.226172 -77.955902) (xy 198.222065 -77.963473)
			(xy 198.218695 -77.980353) (xy 198.219568 -77.988922) (xy 198.223886 -78.018386) (xy 198.225476 -78.026995)
			(xy 198.233664 -78.042455) (xy 198.239888 -78.048612) (xy 198.261836 -78.069291) (xy 198.301224 -78.114955)
			(xy 198.334931 -78.164958) (xy 198.362484 -78.2186) (xy 198.383496 -78.275124) (xy 198.397671 -78.333738)
			(xy 198.40481 -78.393618) (xy 198.405242 -78.42377) (xy 198.405242 -78.425294) (xy 198.405566 -78.433999)
			(xy 198.41138 -78.450408) (xy 198.422368 -78.46391) (xy 198.429626 -78.468728) (xy 198.515732 -78.521052)
			(xy 198.542148 -78.521814) (xy 198.554086 -78.515464) (xy 198.581541 -78.501523) (xy 198.639111 -78.479668)
			(xy 198.698896 -78.464919) (xy 198.760025 -78.457491) (xy 198.790814 -78.457044) (xy 198.822771 -78.457643)
			(xy 198.886182 -78.465655) (xy 198.948089 -78.481551) (xy 199.007515 -78.505081) (xy 199.063523 -78.535874)
			(xy 199.115231 -78.573443) (xy 199.161822 -78.617196) (xy 199.202563 -78.666444) (xy 199.236809 -78.720409)
			(xy 199.264023 -78.778242) (xy 199.283773 -78.839028) (xy 199.295749 -78.901811) (xy 199.299763 -78.9656)
			(xy 199.295749 -79.029389) (xy 199.283773 -79.092172) (xy 199.264023 -79.152958) (xy 199.236809 -79.210791)
			(xy 199.202563 -79.264756) (xy 199.161822 -79.314004) (xy 199.115231 -79.357757) (xy 199.063523 -79.395326)
			(xy 199.007515 -79.426119) (xy 198.948089 -79.449649) (xy 198.886182 -79.465545) (xy 198.822771 -79.473557)
			(xy 198.790814 -79.47406) (xy 198.760679 -79.473616) (xy 198.700831 -79.46648) (xy 198.671434 -79.459836)
			(xy 198.660512 -79.457042) (xy 198.638668 -79.46136) (xy 198.566786 -79.514192) (xy 198.558244 -79.521132)
			(xy 198.547576 -79.540355) (xy 198.546212 -79.551276) (xy 198.546212 -79.55153) (xy 198.543536 -79.583211)
			(xy 198.531148 -79.645574) (xy 198.511083 -79.705906) (xy 198.483654 -79.763267) (xy 198.449289 -79.816761)
			(xy 198.408523 -79.865554) (xy 198.361993 -79.908885) (xy 198.310425 -79.946078) (xy 198.254623 -79.976553)
			(xy 198.195457 -79.999834) (xy 198.133851 -80.015559) (xy 198.070765 -80.023481) (xy 198.038974 -80.02397)
			(xy 198.00824 -80.023587) (xy 197.94722 -80.016174) (xy 197.887539 -80.001461) (xy 197.830066 -79.979661)
			(xy 197.77564 -79.951092) (xy 197.725055 -79.916171) (xy 197.679048 -79.875407) (xy 197.63829 -79.829394)
			(xy 197.603375 -79.778805) (xy 197.574813 -79.724375) (xy 197.55302 -79.6669) (xy 197.538314 -79.607217)
			(xy 197.530909 -79.546196) (xy 197.530466 -79.515462) (xy 197.530943 -79.483806) (xy 197.538797 -79.420982)
			(xy 197.554389 -79.359619) (xy 197.57748 -79.300667) (xy 197.607712 -79.245039) (xy 197.644617 -79.193594)
			(xy 197.687623 -79.14713) (xy 197.736066 -79.106365) (xy 197.762368 -79.088742) (xy 197.77456 -79.080868)
			(xy 197.786752 -79.054452) (xy 197.771258 -78.934056) (xy 197.752462 -78.911704) (xy 197.738492 -78.907132)
			(xy 197.708333 -78.896705) (xy 197.650651 -78.869412) (xy 197.596836 -78.835116) (xy 197.547735 -78.794358)
			(xy 197.504119 -78.747777) (xy 197.466673 -78.696106) (xy 197.435986 -78.640156) (xy 197.412539 -78.580806)
			(xy 197.396702 -78.518989) (xy 197.388722 -78.455677) (xy 197.388226 -78.42377) (xy 190.124901 -78.42377)
			(xy 190.125096 -78.436216) (xy 190.124594 -78.468177) (xy 190.116583 -78.531595) (xy 190.100686 -78.593509)
			(xy 190.077154 -78.652942) (xy 190.04636 -78.708957) (xy 190.008787 -78.760672) (xy 189.96503 -78.807269)
			(xy 189.915777 -78.848014) (xy 189.861806 -78.882265) (xy 189.803967 -78.909482) (xy 189.743174 -78.929235)
			(xy 189.680384 -78.941213) (xy 189.616588 -78.945227) (xy 189.552792 -78.941213) (xy 189.490002 -78.929235)
			(xy 189.429209 -78.909482) (xy 189.37137 -78.882265) (xy 189.317399 -78.848014) (xy 189.268146 -78.807269)
			(xy 189.224389 -78.760672) (xy 189.186816 -78.708957) (xy 189.156022 -78.652942) (xy 189.13249 -78.593509)
			(xy 189.116593 -78.531595) (xy 189.108582 -78.468177) (xy 182.943256 -78.468177) (xy 182.904792 -78.511337)
			(xy 182.758444 -78.663402) (xy 182.606379 -78.80975) (xy 182.44882 -78.950166) (xy 182.285998 -79.084444)
			(xy 182.118152 -79.212387) (xy 181.94553 -79.333807) (xy 181.857214 -79.391) (xy 195.119291 -79.391)
			(xy 195.123305 -79.327207) (xy 195.135281 -79.264421) (xy 195.155032 -79.20363) (xy 195.182246 -79.145795)
			(xy 195.216494 -79.091825) (xy 195.257236 -79.042574) (xy 195.303828 -78.998817) (xy 195.355538 -78.961244)
			(xy 195.411549 -78.930448) (xy 195.470977 -78.906914) (xy 195.532887 -78.891014) (xy 195.596301 -78.882998)
			(xy 195.62826 -78.882494) (xy 195.660143 -78.883037) (xy 195.723406 -78.891027) (xy 195.785174 -78.906861)
			(xy 195.844479 -78.930292) (xy 195.90039 -78.960951) (xy 195.952031 -78.998358) (xy 195.998591 -79.041926)
			(xy 196.039341 -79.090972) (xy 196.073641 -79.144726) (xy 196.087746 -79.173324) (xy 196.093874 -79.185296)
			(xy 196.111344 -79.205733) (xy 196.133541 -79.220905) (xy 196.158926 -79.229762) (xy 196.185744 -79.231691)
			(xy 196.212135 -79.226557) (xy 196.236274 -79.214717) (xy 196.256489 -79.19699) (xy 196.264276 -79.186024)
			(xy 196.279518 -79.163962) (xy 196.315166 -79.123907) (xy 196.356075 -79.089243) (xy 196.401438 -79.060652)
			(xy 196.450359 -79.038699) (xy 196.501874 -79.023818) (xy 196.554966 -79.016301) (xy 196.581776 -79.015844)
			(xy 196.609027 -79.016402) (xy 196.662973 -79.024155) (xy 196.715267 -79.039507) (xy 196.764844 -79.062145)
			(xy 196.810695 -79.091609) (xy 196.851885 -79.127298) (xy 196.887577 -79.168486) (xy 196.917043 -79.214335)
			(xy 196.939685 -79.26391) (xy 196.95504 -79.316203) (xy 196.962797 -79.370149) (xy 196.962797 -79.424651)
			(xy 196.95504 -79.478597) (xy 196.939685 -79.53089) (xy 196.917043 -79.580465) (xy 196.887577 -79.626314)
			(xy 196.851885 -79.667502) (xy 196.810695 -79.703191) (xy 196.764844 -79.732655) (xy 196.715267 -79.755293)
			(xy 196.662973 -79.770645) (xy 196.609027 -79.778398) (xy 196.581776 -79.77886) (xy 196.554601 -79.778325)
			(xy 196.500803 -79.770604) (xy 196.448646 -79.755323) (xy 196.399187 -79.73279) (xy 196.353429 -79.703463)
			(xy 196.312298 -79.667936) (xy 196.276629 -79.626929) (xy 196.261482 -79.604362) (xy 196.253896 -79.593265)
			(xy 196.233922 -79.575286) (xy 196.209948 -79.563142) (xy 196.183635 -79.557675) (xy 196.156808 -79.559262)
			(xy 196.131324 -79.567795) (xy 196.108949 -79.582682) (xy 196.091235 -79.602891) (xy 196.084952 -79.614776)
			(xy 196.07065 -79.642864) (xy 196.036118 -79.695596) (xy 195.995337 -79.743658) (xy 195.94893 -79.786313)
			(xy 195.897608 -79.822908) (xy 195.842159 -79.852882) (xy 195.783431 -79.875776) (xy 195.722325 -79.891238)
			(xy 195.659776 -79.899033) (xy 195.62826 -79.89951) (xy 195.596301 -79.899002) (xy 195.532887 -79.890986)
			(xy 195.470977 -79.875086) (xy 195.411549 -79.851552) (xy 195.355538 -79.820756) (xy 195.303828 -79.783183)
			(xy 195.257236 -79.739426) (xy 195.216494 -79.690175) (xy 195.182246 -79.636205) (xy 195.155032 -79.57837)
			(xy 195.135281 -79.517579) (xy 195.123305 -79.454793) (xy 195.119291 -79.391) (xy 181.857214 -79.391)
			(xy 181.768383 -79.448526) (xy 181.586972 -79.556376) (xy 181.401563 -79.657198) (xy 181.212428 -79.750845)
			(xy 181.019846 -79.837178) (xy 180.824098 -79.916072) (xy 180.625471 -79.98741) (xy 180.424258 -80.051087)
			(xy 180.220754 -80.107011) (xy 180.015257 -80.155099) (xy 179.916056 -80.174338) (xy 189.281562 -80.174338)
			(xy 189.282048 -80.147087) (xy 189.289804 -80.093139) (xy 189.305159 -80.040844) (xy 189.327801 -79.991267)
			(xy 189.357267 -79.945417) (xy 189.392958 -79.904226) (xy 189.434149 -79.868535) (xy 189.479999 -79.839069)
			(xy 189.529576 -79.816427) (xy 189.581871 -79.801072) (xy 189.635819 -79.793316) (xy 189.690321 -79.793316)
			(xy 189.744269 -79.801072) (xy 189.796564 -79.816427) (xy 189.846141 -79.839069) (xy 189.891991 -79.868535)
			(xy 189.933182 -79.904226) (xy 189.968873 -79.945417) (xy 189.998339 -79.991267) (xy 190.020981 -80.040844)
			(xy 190.036336 -80.093139) (xy 190.044092 -80.147087) (xy 190.044578 -80.174338) (xy 190.043986 -80.205075)
			(xy 190.037924 -80.242367) (xy 222.412554 -80.242367) (xy 222.412554 -80.178445) (xy 222.420565 -80.115027)
			(xy 222.436462 -80.053113) (xy 222.459994 -79.99368) (xy 222.490788 -79.937665) (xy 222.528361 -79.88595)
			(xy 222.572118 -79.839353) (xy 222.621371 -79.798608) (xy 222.675342 -79.764357) (xy 222.733181 -79.73714)
			(xy 222.793974 -79.717387) (xy 222.856764 -79.705409) (xy 222.92056 -79.701396) (xy 222.984356 -79.705409)
			(xy 223.047146 -79.717387) (xy 223.107939 -79.73714) (xy 223.165778 -79.764357) (xy 223.219749 -79.798608)
			(xy 223.269002 -79.839353) (xy 223.312759 -79.88595) (xy 223.350332 -79.937665) (xy 223.381126 -79.99368)
			(xy 223.404658 -80.053113) (xy 223.420555 -80.115027) (xy 223.428566 -80.178445) (xy 223.429068 -80.210406)
			(xy 223.428566 -80.242367) (xy 223.425833 -80.264) (xy 224.341942 -80.264) (xy 224.346013 -80.208378)
			(xy 224.358139 -80.153941) (xy 224.378062 -80.10185) (xy 224.405358 -80.053215) (xy 224.439444 -80.009072)
			(xy 224.479593 -79.970363) (xy 224.524951 -79.937912) (xy 224.574551 -79.912411) (xy 224.627335 -79.894404)
			(xy 224.682178 -79.884274) (xy 224.737912 -79.882237) (xy 224.793349 -79.888337) (xy 224.847306 -79.902443)
			(xy 224.898635 -79.924255) (xy 224.946241 -79.953309) (xy 224.989109 -79.988984) (xy 225.026326 -80.030521)
			(xy 225.057099 -80.077034) (xy 225.080771 -80.127531) (xy 225.096839 -80.180938) (xy 225.104959 -80.236114)
			(xy 225.105468 -80.264) (xy 225.104959 -80.291886) (xy 225.096839 -80.347062) (xy 225.080771 -80.400469)
			(xy 225.057099 -80.450966) (xy 225.026326 -80.497479) (xy 224.989109 -80.539016) (xy 224.946241 -80.574691)
			(xy 224.898635 -80.603745) (xy 224.847306 -80.625557) (xy 224.793349 -80.639663) (xy 224.737912 -80.645763)
			(xy 224.682178 -80.643726) (xy 224.627335 -80.633596) (xy 224.574551 -80.615589) (xy 224.524951 -80.590088)
			(xy 224.479593 -80.557637) (xy 224.439444 -80.518928) (xy 224.405358 -80.474785) (xy 224.378062 -80.42615)
			(xy 224.358139 -80.374059) (xy 224.346013 -80.319622) (xy 224.341942 -80.264) (xy 223.425833 -80.264)
			(xy 223.420555 -80.305785) (xy 223.404658 -80.367699) (xy 223.381126 -80.427132) (xy 223.350332 -80.483147)
			(xy 223.312759 -80.534862) (xy 223.269002 -80.581459) (xy 223.219749 -80.622204) (xy 223.165778 -80.656455)
			(xy 223.107939 -80.683672) (xy 223.047146 -80.703425) (xy 222.984356 -80.715403) (xy 222.92056 -80.719417)
			(xy 222.856764 -80.715403) (xy 222.793974 -80.703425) (xy 222.733181 -80.683672) (xy 222.675342 -80.656455)
			(xy 222.621371 -80.622204) (xy 222.572118 -80.581459) (xy 222.528361 -80.534862) (xy 222.490788 -80.483147)
			(xy 222.459994 -80.427132) (xy 222.436462 -80.367699) (xy 222.420565 -80.305785) (xy 222.412554 -80.242367)
			(xy 190.037924 -80.242367) (xy 190.034122 -80.265753) (xy 190.014656 -80.324065) (xy 189.986092 -80.3785)
			(xy 189.968124 -80.403446) (xy 189.95998 -80.415051) (xy 189.949861 -80.441524) (xy 189.947407 -80.469759)
			(xy 189.952806 -80.497582) (xy 189.965644 -80.522849) (xy 189.984931 -80.543615) (xy 190.009182 -80.558282)
			(xy 190.022734 -80.56245) (xy 190.054597 -80.571694) (xy 190.115789 -80.597333) (xy 190.173126 -80.630713)
			(xy 190.225635 -80.671267) (xy 190.272424 -80.718305) (xy 190.312697 -80.771029) (xy 190.34577 -80.828544)
			(xy 190.371083 -80.889871) (xy 190.388204 -80.95397) (xy 190.396842 -81.019751) (xy 190.397384 -81.052924)
			(xy 190.396882 -81.084885) (xy 190.388871 -81.148303) (xy 190.381404 -81.177384) (xy 192.393568 -81.177384)
			(xy 192.397639 -81.121762) (xy 192.409765 -81.067325) (xy 192.429688 -81.015234) (xy 192.456984 -80.966599)
			(xy 192.49107 -80.922456) (xy 192.531219 -80.883747) (xy 192.576577 -80.851296) (xy 192.626177 -80.825795)
			(xy 192.678961 -80.807788) (xy 192.733804 -80.797658) (xy 192.789538 -80.795621) (xy 192.844975 -80.801721)
			(xy 192.898932 -80.815827) (xy 192.950261 -80.837639) (xy 192.997867 -80.866693) (xy 193.040735 -80.902368)
			(xy 193.077952 -80.943905) (xy 193.108725 -80.990418) (xy 193.132397 -81.040915) (xy 193.148465 -81.094322)
			(xy 193.156585 -81.149498) (xy 193.157094 -81.177384) (xy 193.156585 -81.20527) (xy 193.148465 -81.260446)
			(xy 193.132397 -81.313853) (xy 193.108725 -81.36435) (xy 193.077952 -81.410863) (xy 193.040735 -81.4524)
			(xy 192.997867 -81.488075) (xy 192.950261 -81.517129) (xy 192.898932 -81.538941) (xy 192.844975 -81.553047)
			(xy 192.789538 -81.559147) (xy 192.733804 -81.55711) (xy 192.678961 -81.54698) (xy 192.626177 -81.528973)
			(xy 192.576577 -81.503472) (xy 192.531219 -81.471021) (xy 192.49107 -81.432312) (xy 192.456984 -81.388169)
			(xy 192.429688 -81.339534) (xy 192.409765 -81.287443) (xy 192.397639 -81.233006) (xy 192.393568 -81.177384)
			(xy 190.381404 -81.177384) (xy 190.372974 -81.210217) (xy 190.349442 -81.26965) (xy 190.318648 -81.325665)
			(xy 190.281075 -81.37738) (xy 190.237318 -81.423977) (xy 190.188065 -81.464722) (xy 190.134094 -81.498973)
			(xy 190.076255 -81.52619) (xy 190.015462 -81.545943) (xy 189.952672 -81.557921) (xy 189.888876 -81.561935)
			(xy 189.82508 -81.557921) (xy 189.76229 -81.545943) (xy 189.701497 -81.52619) (xy 189.643658 -81.498973)
			(xy 189.589687 -81.464722) (xy 189.540434 -81.423977) (xy 189.496677 -81.37738) (xy 189.459104 -81.325665)
			(xy 189.42831 -81.26965) (xy 189.404778 -81.210217) (xy 189.388881 -81.148303) (xy 189.38087 -81.084885)
			(xy 189.380368 -81.052924) (xy 189.380908 -81.018954) (xy 189.389952 -80.95162) (xy 189.407883 -80.886089)
			(xy 189.434382 -80.82353) (xy 189.468975 -80.765057) (xy 189.511047 -80.711712) (xy 189.535054 -80.687672)
			(xy 189.544983 -80.677535) (xy 189.559177 -80.652974) (xy 189.56606 -80.625454) (xy 189.565099 -80.597103)
			(xy 189.55637 -80.570112) (xy 189.540546 -80.546568) (xy 189.518851 -80.52829) (xy 189.506098 -80.522064)
			(xy 189.481369 -80.510358) (xy 189.43523 -80.480954) (xy 189.393765 -80.445261) (xy 189.357823 -80.404011)
			(xy 189.328142 -80.35805) (xy 189.30533 -80.308321) (xy 189.289855 -80.255844) (xy 189.282035 -80.201694)
			(xy 189.281562 -80.174338) (xy 179.916056 -80.174338) (xy 179.808069 -80.195281) (xy 179.599494 -80.227498)
			(xy 179.389837 -80.251701) (xy 179.179408 -80.267857) (xy 178.968514 -80.275941) (xy 178.757466 -80.275941)
			(xy 178.546572 -80.267857) (xy 178.336143 -80.251701) (xy 178.126486 -80.227498) (xy 177.917911 -80.195281)
			(xy 177.710723 -80.155099) (xy 177.505226 -80.107011) (xy 177.301722 -80.051087) (xy 177.100509 -79.98741)
			(xy 176.901882 -79.916072) (xy 176.706134 -79.837178) (xy 176.513552 -79.750845) (xy 176.324417 -79.657198)
			(xy 176.139008 -79.556376) (xy 175.957597 -79.448526) (xy 175.78045 -79.333807) (xy 175.607828 -79.212387)
			(xy 175.439982 -79.084444) (xy 175.27716 -78.950166) (xy 175.119601 -78.80975) (xy 174.967536 -78.663402)
			(xy 174.821188 -78.511337) (xy 174.680772 -78.353778) (xy 174.546494 -78.190956) (xy 174.418551 -78.02311)
			(xy 174.297131 -77.850488) (xy 174.182412 -77.673341) (xy 174.074562 -77.49193) (xy 173.97374 -77.306521)
			(xy 173.880093 -77.117386) (xy 173.79376 -76.924804) (xy 173.714866 -76.729056) (xy 173.643528 -76.530429)
			(xy 173.579851 -76.329216) (xy 173.523927 -76.125712) (xy 173.475839 -75.920215) (xy 173.435657 -75.713027)
			(xy 173.40344 -75.504452) (xy 173.379237 -75.294795) (xy 173.363081 -75.084366) (xy 173.354997 -74.873472)
			(xy 173.354492 -74.767948) (xy 169.47134 -74.767948) (xy 169.47134 -76.81341) (xy 169.471594 -76.818744)
			(xy 169.471594 -76.819506) (xy 169.472032 -76.823098) (xy 169.473816 -76.830112) (xy 169.47515 -76.833476)
			(xy 169.476747 -76.836968) (xy 169.480833 -76.843469) (xy 169.483278 -76.84643) (xy 169.486326 -76.849986)
			(xy 174.710301 -82.073961) (xy 220.75114 -82.073961) (xy 220.75114 -82.010039) (xy 220.759151 -81.946621)
			(xy 220.775048 -81.884707) (xy 220.79858 -81.825274) (xy 220.829374 -81.769259) (xy 220.866947 -81.717544)
			(xy 220.910704 -81.670947) (xy 220.959957 -81.630202) (xy 221.013928 -81.595951) (xy 221.071767 -81.568734)
			(xy 221.13256 -81.548981) (xy 221.19535 -81.537003) (xy 221.259146 -81.53299) (xy 221.322942 -81.537003)
			(xy 221.385732 -81.548981) (xy 221.446525 -81.568734) (xy 221.504364 -81.595951) (xy 221.558335 -81.630202)
			(xy 221.607588 -81.670947) (xy 221.635218 -81.70037) (xy 230.62845 -81.70037) (xy 230.632464 -81.494686)
			(xy 230.6445 -81.289316) (xy 230.664539 -81.084572) (xy 230.692552 -80.880765) (xy 230.728495 -80.678206)
			(xy 230.772314 -80.477204) (xy 230.823941 -80.278065) (xy 230.883299 -80.081092) (xy 230.950297 -79.886584)
			(xy 231.024833 -79.694839) (xy 231.106793 -79.506148) (xy 231.196053 -79.320798) (xy 231.292476 -79.139072)
			(xy 231.395917 -78.961246) (xy 231.506216 -78.787592) (xy 231.623207 -78.618373) (xy 231.746711 -78.453847)
			(xy 231.87654 -78.294266) (xy 232.012497 -78.139871) (xy 232.154374 -77.990899) (xy 232.301955 -77.847575)
			(xy 232.455016 -77.710119) (xy 232.613323 -77.578739) (xy 232.776636 -77.453636) (xy 232.944705 -77.334999)
			(xy 233.117275 -77.223011) (xy 233.294083 -77.11784) (xy 233.47486 -77.019649) (xy 233.65933 -76.928585)
			(xy 233.847212 -76.844788) (xy 234.038222 -76.768385) (xy 234.232066 -76.699492) (xy 234.428451 -76.638215)
			(xy 234.627077 -76.584647) (xy 234.827642 -76.53887) (xy 235.02984 -76.500952) (xy 235.233364 -76.470953)
			(xy 235.437903 -76.448916) (xy 235.643146 -76.434877) (xy 235.848781 -76.428857) (xy 236.054494 -76.430864)
			(xy 236.259972 -76.440896) (xy 236.464902 -76.458937) (xy 236.668972 -76.48496) (xy 236.871872 -76.518925)
			(xy 237.073292 -76.56078) (xy 237.272925 -76.610462) (xy 237.470468 -76.667896) (xy 237.66562 -76.732993)
			(xy 237.858084 -76.805654) (xy 238.047566 -76.88577) (xy 238.233777 -76.973217) (xy 238.416436 -77.067863)
			(xy 238.470499 -77.098609) (xy 248.114052 -77.098609) (xy 248.114052 -77.034687) (xy 248.122063 -76.971269)
			(xy 248.13796 -76.909355) (xy 248.161492 -76.849922) (xy 248.192286 -76.793907) (xy 248.229859 -76.742192)
			(xy 248.273616 -76.695595) (xy 248.322869 -76.65485) (xy 248.37684 -76.620599) (xy 248.434679 -76.593382)
			(xy 248.495472 -76.573629) (xy 248.558262 -76.561651) (xy 248.622058 -76.557638) (xy 248.685854 -76.561651)
			(xy 248.748644 -76.573629) (xy 248.809437 -76.593382) (xy 248.867276 -76.620599) (xy 248.921247 -76.65485)
			(xy 248.9705 -76.695595) (xy 249.014257 -76.742192) (xy 249.05183 -76.793907) (xy 249.082624 -76.849922)
			(xy 249.106156 -76.909355) (xy 249.122053 -76.971269) (xy 249.130064 -77.034687) (xy 249.130566 -77.066648)
			(xy 249.130064 -77.098609) (xy 249.123294 -77.152203) (xy 249.55728 -77.152203) (xy 249.55728 -77.088281)
			(xy 249.565291 -77.024863) (xy 249.581188 -76.962949) (xy 249.60472 -76.903516) (xy 249.635514 -76.847501)
			(xy 249.673087 -76.795786) (xy 249.716844 -76.749189) (xy 249.766097 -76.708444) (xy 249.820068 -76.674193)
			(xy 249.877907 -76.646976) (xy 249.9387 -76.627223) (xy 250.00149 -76.615245) (xy 250.065286 -76.611232)
			(xy 250.129082 -76.615245) (xy 250.191872 -76.627223) (xy 250.252665 -76.646976) (xy 250.310504 -76.674193)
			(xy 250.364475 -76.708444) (xy 250.413728 -76.749189) (xy 250.457485 -76.795786) (xy 250.495058 -76.847501)
			(xy 250.525852 -76.903516) (xy 250.549384 -76.962949) (xy 250.565281 -77.024863) (xy 250.573292 -77.088281)
			(xy 250.573794 -77.120242) (xy 250.573531 -77.136963) (xy 250.845822 -77.136963) (xy 250.845822 -77.073041)
			(xy 250.853833 -77.009623) (xy 250.86973 -76.947709) (xy 250.893262 -76.888276) (xy 250.924056 -76.832261)
			(xy 250.961629 -76.780546) (xy 251.005386 -76.733949) (xy 251.054639 -76.693204) (xy 251.10861 -76.658953)
			(xy 251.166449 -76.631736) (xy 251.227242 -76.611983) (xy 251.290032 -76.600005) (xy 251.353828 -76.595992)
			(xy 251.417624 -76.600005) (xy 251.480414 -76.611983) (xy 251.541207 -76.631736) (xy 251.599046 -76.658953)
			(xy 251.653017 -76.693204) (xy 251.665631 -76.703639) (xy 255.134866 -76.703639) (xy 255.134866 -76.639717)
			(xy 255.142877 -76.576299) (xy 255.158774 -76.514385) (xy 255.182306 -76.454952) (xy 255.2131 -76.398937)
			(xy 255.250673 -76.347222) (xy 255.29443 -76.300625) (xy 255.343683 -76.25988) (xy 255.397654 -76.225629)
			(xy 255.455493 -76.198412) (xy 255.516286 -76.178659) (xy 255.579076 -76.166681) (xy 255.642872 -76.162668)
			(xy 255.706668 -76.166681) (xy 255.769458 -76.178659) (xy 255.830251 -76.198412) (xy 255.88809 -76.225629)
			(xy 255.942061 -76.25988) (xy 255.991314 -76.300625) (xy 256.035071 -76.347222) (xy 256.072644 -76.398937)
			(xy 256.103438 -76.454952) (xy 256.12697 -76.514385) (xy 256.142867 -76.576299) (xy 256.150878 -76.639717)
			(xy 256.15138 -76.671678) (xy 256.150878 -76.703639) (xy 256.142867 -76.767057) (xy 256.12697 -76.828971)
			(xy 256.103438 -76.888404) (xy 256.072644 -76.944419) (xy 256.035071 -76.996134) (xy 255.991314 -77.042731)
			(xy 255.942061 -77.083476) (xy 255.88809 -77.117727) (xy 255.830251 -77.144944) (xy 255.769458 -77.164697)
			(xy 255.706668 -77.176675) (xy 255.642872 -77.180689) (xy 255.579076 -77.176675) (xy 255.516286 -77.164697)
			(xy 255.455493 -77.144944) (xy 255.397654 -77.117727) (xy 255.343683 -77.083476) (xy 255.29443 -77.042731)
			(xy 255.250673 -76.996134) (xy 255.2131 -76.944419) (xy 255.182306 -76.888404) (xy 255.158774 -76.828971)
			(xy 255.142877 -76.767057) (xy 255.134866 -76.703639) (xy 251.665631 -76.703639) (xy 251.70227 -76.733949)
			(xy 251.746027 -76.780546) (xy 251.7836 -76.832261) (xy 251.814394 -76.888276) (xy 251.837926 -76.947709)
			(xy 251.853823 -77.009623) (xy 251.861834 -77.073041) (xy 251.862336 -77.105002) (xy 251.861834 -77.136963)
			(xy 251.853823 -77.200381) (xy 251.837926 -77.262295) (xy 251.814394 -77.321728) (xy 251.7836 -77.377743)
			(xy 251.746027 -77.429458) (xy 251.70227 -77.476055) (xy 251.653017 -77.5168) (xy 251.599046 -77.551051)
			(xy 251.541207 -77.578268) (xy 251.480414 -77.598021) (xy 251.417624 -77.609999) (xy 251.353828 -77.614013)
			(xy 251.290032 -77.609999) (xy 251.227242 -77.598021) (xy 251.166449 -77.578268) (xy 251.10861 -77.551051)
			(xy 251.054639 -77.5168) (xy 251.005386 -77.476055) (xy 250.961629 -77.429458) (xy 250.924056 -77.377743)
			(xy 250.893262 -77.321728) (xy 250.86973 -77.262295) (xy 250.853833 -77.200381) (xy 250.845822 -77.136963)
			(xy 250.573531 -77.136963) (xy 250.573292 -77.152203) (xy 250.565281 -77.215621) (xy 250.549384 -77.277535)
			(xy 250.525852 -77.336968) (xy 250.495058 -77.392983) (xy 250.457485 -77.444698) (xy 250.413728 -77.491295)
			(xy 250.364475 -77.53204) (xy 250.310504 -77.566291) (xy 250.252665 -77.593508) (xy 250.191872 -77.613261)
			(xy 250.133538 -77.624389) (xy 266.667736 -77.624389) (xy 266.667736 -77.560467) (xy 266.675747 -77.497049)
			(xy 266.691644 -77.435135) (xy 266.715176 -77.375702) (xy 266.74597 -77.319687) (xy 266.783543 -77.267972)
			(xy 266.8273 -77.221375) (xy 266.876553 -77.18063) (xy 266.930524 -77.146379) (xy 266.988363 -77.119162)
			(xy 267.049156 -77.099409) (xy 267.111946 -77.087431) (xy 267.175742 -77.083418) (xy 267.239538 -77.087431)
			(xy 267.302328 -77.099409) (xy 267.363121 -77.119162) (xy 267.42096 -77.146379) (xy 267.474931 -77.18063)
			(xy 267.524184 -77.221375) (xy 267.567941 -77.267972) (xy 267.605514 -77.319687) (xy 267.636308 -77.375702)
			(xy 267.65984 -77.435135) (xy 267.675737 -77.497049) (xy 267.683748 -77.560467) (xy 267.68425 -77.592428)
			(xy 267.683748 -77.624389) (xy 267.675737 -77.687807) (xy 267.65984 -77.749721) (xy 267.636308 -77.809154)
			(xy 267.605514 -77.865169) (xy 267.567941 -77.916884) (xy 267.524184 -77.963481) (xy 267.474931 -78.004226)
			(xy 267.42096 -78.038477) (xy 267.363121 -78.065694) (xy 267.302328 -78.085447) (xy 267.239538 -78.097425)
			(xy 267.175742 -78.101439) (xy 267.111946 -78.097425) (xy 267.049156 -78.085447) (xy 266.988363 -78.065694)
			(xy 266.930524 -78.038477) (xy 266.876553 -78.004226) (xy 266.8273 -77.963481) (xy 266.783543 -77.916884)
			(xy 266.74597 -77.865169) (xy 266.715176 -77.809154) (xy 266.691644 -77.749721) (xy 266.675747 -77.687807)
			(xy 266.667736 -77.624389) (xy 250.133538 -77.624389) (xy 250.129082 -77.625239) (xy 250.065286 -77.629253)
			(xy 250.00149 -77.625239) (xy 249.9387 -77.613261) (xy 249.877907 -77.593508) (xy 249.820068 -77.566291)
			(xy 249.766097 -77.53204) (xy 249.716844 -77.491295) (xy 249.673087 -77.444698) (xy 249.635514 -77.392983)
			(xy 249.60472 -77.336968) (xy 249.581188 -77.277535) (xy 249.565291 -77.215621) (xy 249.55728 -77.152203)
			(xy 249.123294 -77.152203) (xy 249.122053 -77.162027) (xy 249.106156 -77.223941) (xy 249.082624 -77.283374)
			(xy 249.05183 -77.339389) (xy 249.014257 -77.391104) (xy 248.9705 -77.437701) (xy 248.921247 -77.478446)
			(xy 248.867276 -77.512697) (xy 248.809437 -77.539914) (xy 248.748644 -77.559667) (xy 248.685854 -77.571645)
			(xy 248.622058 -77.575659) (xy 248.558262 -77.571645) (xy 248.495472 -77.559667) (xy 248.434679 -77.539914)
			(xy 248.37684 -77.512697) (xy 248.322869 -77.478446) (xy 248.273616 -77.437701) (xy 248.229859 -77.391104)
			(xy 248.192286 -77.339389) (xy 248.161492 -77.283374) (xy 248.13796 -77.223941) (xy 248.122063 -77.162027)
			(xy 248.114052 -77.098609) (xy 238.470499 -77.098609) (xy 238.595262 -77.169563) (xy 238.769984 -77.278163)
			(xy 238.940337 -77.393498) (xy 239.106059 -77.515391) (xy 239.2669 -77.643657) (xy 239.422613 -77.7781)
			(xy 239.572963 -77.918517) (xy 239.71772 -78.064693) (xy 239.856663 -78.216405) (xy 239.989581 -78.373423)
			(xy 240.116272 -78.535508) (xy 240.236542 -78.702411) (xy 240.350209 -78.873881) (xy 240.457099 -79.049654)
			(xy 240.55705 -79.229464) (xy 240.649909 -79.413037) (xy 240.735536 -79.600093) (xy 240.7635 -79.668073)
			(xy 263.667234 -79.668073) (xy 263.667234 -79.604151) (xy 263.675245 -79.540733) (xy 263.691142 -79.478819)
			(xy 263.714674 -79.419386) (xy 263.745468 -79.363371) (xy 263.783041 -79.311656) (xy 263.826798 -79.265059)
			(xy 263.876051 -79.224314) (xy 263.930022 -79.190063) (xy 263.987861 -79.162846) (xy 264.048654 -79.143093)
			(xy 264.111444 -79.131115) (xy 264.17524 -79.127102) (xy 264.239036 -79.131115) (xy 264.301826 -79.143093)
			(xy 264.362619 -79.162846) (xy 264.420458 -79.190063) (xy 264.474429 -79.224314) (xy 264.523682 -79.265059)
			(xy 264.567439 -79.311656) (xy 264.605012 -79.363371) (xy 264.635806 -79.419386) (xy 264.659338 -79.478819)
			(xy 264.675235 -79.540733) (xy 264.683246 -79.604151) (xy 264.683748 -79.636112) (xy 264.683246 -79.668073)
			(xy 264.675235 -79.731491) (xy 264.659338 -79.793405) (xy 264.635806 -79.852838) (xy 264.605012 -79.908853)
			(xy 264.567439 -79.960568) (xy 264.523682 -80.007165) (xy 264.474429 -80.04791) (xy 264.420458 -80.082161)
			(xy 264.362619 -80.109378) (xy 264.301826 -80.129131) (xy 264.239036 -80.141109) (xy 264.17524 -80.145123)
			(xy 264.111444 -80.141109) (xy 264.048654 -80.129131) (xy 263.987861 -80.109378) (xy 263.930022 -80.082161)
			(xy 263.876051 -80.04791) (xy 263.826798 -80.007165) (xy 263.783041 -79.960568) (xy 263.745468 -79.908853)
			(xy 263.714674 -79.852838) (xy 263.691142 -79.793405) (xy 263.675245 -79.731491) (xy 263.667234 -79.668073)
			(xy 240.7635 -79.668073) (xy 240.813798 -79.790348) (xy 240.884579 -79.983511) (xy 240.947769 -80.179289)
			(xy 241.003272 -80.377383) (xy 241.051004 -80.577492) (xy 241.090893 -80.77931) (xy 241.122877 -80.982532)
			(xy 241.146907 -81.186846) (xy 241.162948 -81.391942) (xy 241.166987 -81.495392) (xy 246.88673 -81.495392)
			(xy 246.887149 -81.465405) (xy 246.894205 -81.405848) (xy 246.908218 -81.347534) (xy 246.928994 -81.291274)
			(xy 246.956244 -81.237848) (xy 246.989589 -81.187999) (xy 247.028568 -81.142418) (xy 247.050306 -81.121758)
			(xy 247.057827 -81.114085) (xy 247.066357 -81.094393) (xy 247.066816 -81.083658) (xy 247.065546 -81.007966)
			(xy 247.064869 -80.997241) (xy 247.055809 -80.977777) (xy 247.04802 -80.970374) (xy 247.027833 -80.952164)
			(xy 246.9923 -80.911016) (xy 246.96297 -80.865241) (xy 246.940436 -80.815765) (xy 246.925155 -80.76359)
			(xy 246.917437 -80.709775) (xy 246.916956 -80.682592) (xy 246.917442 -80.655341) (xy 246.925198 -80.601393)
			(xy 246.940553 -80.549098) (xy 246.963195 -80.499521) (xy 246.992661 -80.453671) (xy 247.028352 -80.41248)
			(xy 247.069543 -80.376789) (xy 247.115393 -80.347323) (xy 247.16497 -80.324681) (xy 247.217265 -80.309326)
			(xy 247.271213 -80.30157) (xy 247.325715 -80.30157) (xy 247.379663 -80.309326) (xy 247.431958 -80.324681)
			(xy 247.481535 -80.347323) (xy 247.527385 -80.376789) (xy 247.568576 -80.41248) (xy 247.604267 -80.453671)
			(xy 247.633733 -80.499521) (xy 247.656375 -80.549098) (xy 247.67173 -80.601393) (xy 247.679486 -80.655341)
			(xy 247.679972 -80.682592) (xy 247.679403 -80.712071) (xy 247.670291 -80.770322) (xy 247.652344 -80.826483)
			(xy 247.625986 -80.879222) (xy 247.625865 -80.879399) (xy 269.584418 -80.879399) (xy 269.584418 -80.815477)
			(xy 269.592429 -80.752059) (xy 269.608326 -80.690145) (xy 269.631858 -80.630712) (xy 269.662652 -80.574697)
			(xy 269.700225 -80.522982) (xy 269.743982 -80.476385) (xy 269.793235 -80.43564) (xy 269.847206 -80.401389)
			(xy 269.905045 -80.374172) (xy 269.965838 -80.354419) (xy 270.028628 -80.342441) (xy 270.092424 -80.338428)
			(xy 270.15622 -80.342441) (xy 270.21901 -80.354419) (xy 270.279803 -80.374172) (xy 270.337642 -80.401389)
			(xy 270.391613 -80.43564) (xy 270.440866 -80.476385) (xy 270.484623 -80.522982) (xy 270.522196 -80.574697)
			(xy 270.55299 -80.630712) (xy 270.576522 -80.690145) (xy 270.592419 -80.752059) (xy 270.598975 -80.803961)
			(xy 278.764994 -80.803961) (xy 278.764994 -80.740039) (xy 278.773005 -80.676621) (xy 278.788902 -80.614707)
			(xy 278.812434 -80.555274) (xy 278.843228 -80.499259) (xy 278.880801 -80.447544) (xy 278.924558 -80.400947)
			(xy 278.973811 -80.360202) (xy 279.027782 -80.325951) (xy 279.085621 -80.298734) (xy 279.146414 -80.278981)
			(xy 279.209204 -80.267003) (xy 279.273 -80.26299) (xy 279.336796 -80.267003) (xy 279.399586 -80.278981)
			(xy 279.460379 -80.298734) (xy 279.518218 -80.325951) (xy 279.572189 -80.360202) (xy 279.621442 -80.400947)
			(xy 279.665199 -80.447544) (xy 279.702772 -80.499259) (xy 279.733566 -80.555274) (xy 279.757098 -80.614707)
			(xy 279.772995 -80.676621) (xy 279.781006 -80.740039) (xy 279.781508 -80.772) (xy 279.781006 -80.803961)
			(xy 279.772995 -80.867379) (xy 279.757098 -80.929293) (xy 279.733566 -80.988726) (xy 279.702772 -81.044741)
			(xy 279.667351 -81.093494) (xy 398.27606 -81.093494) (xy 398.27606 -81.008798) (xy 398.284111 -80.924484)
			(xy 398.30014 -80.841318) (xy 398.324001 -80.760051) (xy 398.35548 -80.681421) (xy 398.394291 -80.60614)
			(xy 398.440081 -80.534888) (xy 398.492437 -80.468312) (xy 398.550885 -80.407014) (xy 398.614895 -80.351549)
			(xy 398.683887 -80.30242) (xy 398.757237 -80.260071) (xy 398.83428 -80.224887) (xy 398.914319 -80.197185)
			(xy 398.996628 -80.177217) (xy 399.080463 -80.165164) (xy 399.165064 -80.161134) (xy 399.249665 -80.165164)
			(xy 399.3335 -80.177217) (xy 399.415809 -80.197185) (xy 399.495848 -80.224887) (xy 399.572891 -80.260071)
			(xy 399.646241 -80.30242) (xy 399.715233 -80.351549) (xy 399.779243 -80.407014) (xy 399.837691 -80.468312)
			(xy 399.890047 -80.534888) (xy 399.935837 -80.60614) (xy 399.974648 -80.681421) (xy 400.006127 -80.760051)
			(xy 400.029988 -80.841318) (xy 400.046017 -80.924484) (xy 400.054068 -81.008798) (xy 400.054572 -81.051146)
			(xy 400.054068 -81.093494) (xy 400.046017 -81.177808) (xy 400.029988 -81.260974) (xy 400.006127 -81.342241)
			(xy 399.998403 -81.361534) (xy 461.778348 -81.361534) (xy 461.782419 -81.305912) (xy 461.794545 -81.251475)
			(xy 461.814468 -81.199384) (xy 461.841764 -81.150749) (xy 461.87585 -81.106606) (xy 461.915999 -81.067897)
			(xy 461.961357 -81.035446) (xy 462.010957 -81.009945) (xy 462.063741 -80.991938) (xy 462.118584 -80.981808)
			(xy 462.174318 -80.979771) (xy 462.229755 -80.985871) (xy 462.283712 -80.999977) (xy 462.335041 -81.021789)
			(xy 462.382647 -81.050843) (xy 462.425515 -81.086518) (xy 462.462732 -81.128055) (xy 462.493505 -81.174568)
			(xy 462.517177 -81.225065) (xy 462.533245 -81.278472) (xy 462.541365 -81.333648) (xy 462.541874 -81.361534)
			(xy 462.541365 -81.38942) (xy 462.533245 -81.444596) (xy 462.517177 -81.498003) (xy 462.493505 -81.5485)
			(xy 462.462732 -81.595013) (xy 462.425515 -81.63655) (xy 462.382647 -81.672225) (xy 462.335041 -81.701279)
			(xy 462.283712 -81.723091) (xy 462.229755 -81.737197) (xy 462.174318 -81.743297) (xy 462.118584 -81.74126)
			(xy 462.063741 -81.73113) (xy 462.010957 -81.713123) (xy 461.961357 -81.687622) (xy 461.915999 -81.655171)
			(xy 461.87585 -81.616462) (xy 461.841764 -81.572319) (xy 461.814468 -81.523684) (xy 461.794545 -81.471593)
			(xy 461.782419 -81.417156) (xy 461.778348 -81.361534) (xy 399.998403 -81.361534) (xy 399.974648 -81.420871)
			(xy 399.935837 -81.496152) (xy 399.890047 -81.567404) (xy 399.837691 -81.63398) (xy 399.779243 -81.695278)
			(xy 399.715233 -81.750743) (xy 399.646241 -81.799872) (xy 399.572891 -81.842221) (xy 399.495848 -81.877405)
			(xy 399.415809 -81.905107) (xy 399.3335 -81.925075) (xy 399.249665 -81.937128) (xy 399.165064 -81.941159)
			(xy 399.080463 -81.937128) (xy 398.996628 -81.925075) (xy 398.914319 -81.905107) (xy 398.83428 -81.877405)
			(xy 398.757237 -81.842221) (xy 398.683887 -81.799872) (xy 398.614895 -81.750743) (xy 398.550885 -81.695278)
			(xy 398.492437 -81.63398) (xy 398.440081 -81.567404) (xy 398.394291 -81.496152) (xy 398.35548 -81.420871)
			(xy 398.324001 -81.342241) (xy 398.30014 -81.260974) (xy 398.284111 -81.177808) (xy 398.27606 -81.093494)
			(xy 279.667351 -81.093494) (xy 279.665199 -81.096456) (xy 279.621442 -81.143053) (xy 279.572189 -81.183798)
			(xy 279.518218 -81.218049) (xy 279.460379 -81.245266) (xy 279.399586 -81.265019) (xy 279.336796 -81.276997)
			(xy 279.273 -81.281011) (xy 279.209204 -81.276997) (xy 279.146414 -81.265019) (xy 279.085621 -81.245266)
			(xy 279.027782 -81.218049) (xy 278.973811 -81.183798) (xy 278.924558 -81.143053) (xy 278.880801 -81.096456)
			(xy 278.843228 -81.044741) (xy 278.812434 -80.988726) (xy 278.788902 -80.929293) (xy 278.773005 -80.867379)
			(xy 278.764994 -80.803961) (xy 270.598975 -80.803961) (xy 270.60043 -80.815477) (xy 270.600932 -80.847438)
			(xy 270.60043 -80.879399) (xy 270.592419 -80.942817) (xy 270.576522 -81.004731) (xy 270.55299 -81.064164)
			(xy 270.522196 -81.120179) (xy 270.484623 -81.171894) (xy 270.440866 -81.218491) (xy 270.391613 -81.259236)
			(xy 270.337642 -81.293487) (xy 270.279803 -81.320704) (xy 270.21901 -81.340457) (xy 270.15622 -81.352435)
			(xy 270.092424 -81.356449) (xy 270.028628 -81.352435) (xy 269.965838 -81.340457) (xy 269.905045 -81.320704)
			(xy 269.847206 -81.293487) (xy 269.793235 -81.259236) (xy 269.743982 -81.218491) (xy 269.700225 -81.171894)
			(xy 269.662652 -81.120179) (xy 269.631858 -81.064164) (xy 269.608326 -81.004731) (xy 269.592429 -80.942817)
			(xy 269.584418 -80.879399) (xy 247.625865 -80.879399) (xy 247.60936 -80.903572) (xy 247.60936 -80.903826)
			(xy 247.603652 -80.912754) (xy 247.599467 -80.933507) (xy 247.601232 -80.943958) (xy 247.620536 -81.02854)
			(xy 247.63349 -81.046066) (xy 247.642888 -81.051146) (xy 247.672096 -81.068114) (xy 247.726215 -81.108537)
			(xy 247.774507 -81.155767) (xy 247.816122 -81.208974) (xy 247.85033 -81.26722) (xy 247.876526 -81.329482)
			(xy 247.894251 -81.394664) (xy 247.903193 -81.461618) (xy 247.903746 -81.495392) (xy 247.903244 -81.527353)
			(xy 247.895233 -81.590771) (xy 247.879336 -81.652685) (xy 247.855804 -81.712118) (xy 247.82501 -81.768133)
			(xy 247.787437 -81.819848) (xy 247.74368 -81.866445) (xy 247.694427 -81.90719) (xy 247.640456 -81.941441)
			(xy 247.582617 -81.968658) (xy 247.521824 -81.988411) (xy 247.459034 -82.000389) (xy 247.395238 -82.004403)
			(xy 247.331442 -82.000389) (xy 247.268652 -81.988411) (xy 247.207859 -81.968658) (xy 247.15002 -81.941441)
			(xy 247.096049 -81.90719) (xy 247.046796 -81.866445) (xy 247.003039 -81.819848) (xy 246.965466 -81.768133)
			(xy 246.934672 -81.712118) (xy 246.91114 -81.652685) (xy 246.895243 -81.590771) (xy 246.887232 -81.527353)
			(xy 246.88673 -81.495392) (xy 241.166987 -81.495392) (xy 241.170974 -81.597509) (xy 241.171476 -81.70037)
			(xy 241.170974 -81.803231) (xy 241.162948 -82.008798) (xy 241.146907 -82.213894) (xy 241.122877 -82.418208)
			(xy 241.090893 -82.62143) (xy 241.051004 -82.823248) (xy 241.003272 -83.023357) (xy 240.947769 -83.221451)
			(xy 240.884579 -83.417229) (xy 240.813798 -83.610392) (xy 240.735536 -83.800647) (xy 240.649909 -83.987703)
			(xy 240.55705 -84.171276) (xy 240.457099 -84.351086) (xy 240.350209 -84.526859) (xy 240.236542 -84.698329)
			(xy 240.116272 -84.865232) (xy 239.989581 -85.027317) (xy 239.856663 -85.184335) (xy 239.71772 -85.336047)
			(xy 239.572963 -85.482223) (xy 239.422613 -85.62264) (xy 239.2669 -85.757083) (xy 239.106059 -85.885349)
			(xy 238.940337 -86.007242) (xy 238.769984 -86.122577) (xy 238.595262 -86.231177) (xy 238.416436 -86.332877)
			(xy 238.233777 -86.427523) (xy 238.047566 -86.51497) (xy 237.858084 -86.595086) (xy 237.66562 -86.667747)
			(xy 237.470468 -86.732844) (xy 237.398882 -86.753657) (xy 304.929026 -86.753657) (xy 304.929026 -86.689735)
			(xy 304.937037 -86.626317) (xy 304.952934 -86.564403) (xy 304.976466 -86.50497) (xy 305.00726 -86.448955)
			(xy 305.044833 -86.39724) (xy 305.08859 -86.350643) (xy 305.137843 -86.309898) (xy 305.191814 -86.275647)
			(xy 305.249653 -86.24843) (xy 305.310446 -86.228677) (xy 305.373236 -86.216699) (xy 305.437032 -86.212686)
			(xy 305.500828 -86.216699) (xy 305.563618 -86.228677) (xy 305.624411 -86.24843) (xy 305.68225 -86.275647)
			(xy 305.736221 -86.309898) (xy 305.785474 -86.350643) (xy 305.829231 -86.39724) (xy 305.866804 -86.448955)
			(xy 305.897598 -86.50497) (xy 305.92113 -86.564403) (xy 305.937027 -86.626317) (xy 305.945038 -86.689735)
			(xy 305.94554 -86.721696) (xy 305.94521 -86.742735) (xy 306.183532 -86.742735) (xy 306.183532 -86.678813)
			(xy 306.191543 -86.615395) (xy 306.20744 -86.553481) (xy 306.230972 -86.494048) (xy 306.261766 -86.438033)
			(xy 306.299339 -86.386318) (xy 306.343096 -86.339721) (xy 306.392349 -86.298976) (xy 306.44632 -86.264725)
			(xy 306.504159 -86.237508) (xy 306.564952 -86.217755) (xy 306.627742 -86.205777) (xy 306.691538 -86.201764)
			(xy 306.755334 -86.205777) (xy 306.818124 -86.217755) (xy 306.878917 -86.237508) (xy 306.936756 -86.264725)
			(xy 306.990727 -86.298976) (xy 307.03998 -86.339721) (xy 307.083737 -86.386318) (xy 307.12131 -86.438033)
			(xy 307.152104 -86.494048) (xy 307.175636 -86.553481) (xy 307.191533 -86.615395) (xy 307.199544 -86.678813)
			(xy 307.200046 -86.710774) (xy 307.199544 -86.742735) (xy 307.191533 -86.806153) (xy 307.175636 -86.868067)
			(xy 307.152104 -86.9275) (xy 307.12131 -86.983515) (xy 307.083737 -87.03523) (xy 307.03998 -87.081827)
			(xy 306.990727 -87.122572) (xy 306.936756 -87.156823) (xy 306.878917 -87.18404) (xy 306.818124 -87.203793)
			(xy 306.755334 -87.215771) (xy 306.691538 -87.219785) (xy 306.627742 -87.215771) (xy 306.564952 -87.203793)
			(xy 306.504159 -87.18404) (xy 306.44632 -87.156823) (xy 306.392349 -87.122572) (xy 306.343096 -87.081827)
			(xy 306.299339 -87.03523) (xy 306.261766 -86.983515) (xy 306.230972 -86.9275) (xy 306.20744 -86.868067)
			(xy 306.191543 -86.806153) (xy 306.183532 -86.742735) (xy 305.94521 -86.742735) (xy 305.945038 -86.753657)
			(xy 305.937027 -86.817075) (xy 305.92113 -86.878989) (xy 305.897598 -86.938422) (xy 305.866804 -86.994437)
			(xy 305.829231 -87.046152) (xy 305.785474 -87.092749) (xy 305.736221 -87.133494) (xy 305.68225 -87.167745)
			(xy 305.624411 -87.194962) (xy 305.563618 -87.214715) (xy 305.500828 -87.226693) (xy 305.437032 -87.230707)
			(xy 305.373236 -87.226693) (xy 305.310446 -87.214715) (xy 305.249653 -87.194962) (xy 305.191814 -87.167745)
			(xy 305.137843 -87.133494) (xy 305.08859 -87.092749) (xy 305.044833 -87.046152) (xy 305.00726 -86.994437)
			(xy 304.976466 -86.938422) (xy 304.952934 -86.878989) (xy 304.937037 -86.817075) (xy 304.929026 -86.753657)
			(xy 237.398882 -86.753657) (xy 237.272925 -86.790278) (xy 237.073292 -86.83996) (xy 236.871872 -86.881815)
			(xy 236.668972 -86.91578) (xy 236.464902 -86.941803) (xy 236.259972 -86.959844) (xy 236.054494 -86.969876)
			(xy 235.848781 -86.971883) (xy 235.643146 -86.965863) (xy 235.437903 -86.951824) (xy 235.233364 -86.929787)
			(xy 235.02984 -86.899788) (xy 234.827642 -86.86187) (xy 234.627077 -86.816093) (xy 234.428451 -86.762525)
			(xy 234.232066 -86.701248) (xy 234.038222 -86.632355) (xy 233.847212 -86.555952) (xy 233.65933 -86.472155)
			(xy 233.47486 -86.381091) (xy 233.294083 -86.2829) (xy 233.117275 -86.177729) (xy 232.944705 -86.065741)
			(xy 232.776636 -85.947104) (xy 232.613323 -85.822001) (xy 232.455016 -85.690621) (xy 232.301955 -85.553165)
			(xy 232.154374 -85.409841) (xy 232.012497 -85.260869) (xy 231.87654 -85.106474) (xy 231.746711 -84.946893)
			(xy 231.623207 -84.782367) (xy 231.506216 -84.613148) (xy 231.395917 -84.439494) (xy 231.292476 -84.261668)
			(xy 231.196053 -84.079942) (xy 231.106793 -83.894592) (xy 231.024833 -83.705901) (xy 230.950297 -83.514156)
			(xy 230.883299 -83.319648) (xy 230.823941 -83.122675) (xy 230.772314 -82.923536) (xy 230.728495 -82.722534)
			(xy 230.692552 -82.519975) (xy 230.664539 -82.316168) (xy 230.6445 -82.111424) (xy 230.632464 -81.906054)
			(xy 230.62845 -81.70037) (xy 221.635218 -81.70037) (xy 221.651345 -81.717544) (xy 221.688918 -81.769259)
			(xy 221.719712 -81.825274) (xy 221.743244 -81.884707) (xy 221.759141 -81.946621) (xy 221.767152 -82.010039)
			(xy 221.767654 -82.042) (xy 221.767152 -82.073961) (xy 221.759141 -82.137379) (xy 221.743244 -82.199293)
			(xy 221.719712 -82.258726) (xy 221.688918 -82.314741) (xy 221.651345 -82.366456) (xy 221.607588 -82.413053)
			(xy 221.558335 -82.453798) (xy 221.504364 -82.488049) (xy 221.446525 -82.515266) (xy 221.385732 -82.535019)
			(xy 221.322942 -82.546997) (xy 221.259146 -82.551011) (xy 221.19535 -82.546997) (xy 221.13256 -82.535019)
			(xy 221.071767 -82.515266) (xy 221.013928 -82.488049) (xy 220.959957 -82.453798) (xy 220.910704 -82.413053)
			(xy 220.866947 -82.366456) (xy 220.829374 -82.314741) (xy 220.79858 -82.258726) (xy 220.775048 -82.199293)
			(xy 220.759151 -82.137379) (xy 220.75114 -82.073961) (xy 174.710301 -82.073961) (xy 175.834802 -83.198462)
			(xy 175.841247 -83.204425) (xy 175.857098 -83.211944) (xy 175.86579 -83.213194) (xy 175.871378 -83.213448)
			(xy 179.233068 -83.213448) (xy 179.2381 -83.21359) (xy 179.247953 -83.21564) (xy 179.252626 -83.217512)
			(xy 179.25288 -83.217512) (xy 179.29352 -83.23453) (xy 179.294028 -83.234784) (xy 179.313256 -83.242772)
			(xy 179.349533 -83.263206) (xy 179.382701 -83.288374) (xy 179.39766 -83.302856) (xy 179.474904 -83.3801)
			(xy 197.622661 -83.3801) (xy 197.626675 -83.316302) (xy 197.638653 -83.25351) (xy 197.658407 -83.192714)
			(xy 197.685624 -83.134873) (xy 197.719875 -83.0809) (xy 197.760622 -83.031645) (xy 197.80722 -82.987885)
			(xy 197.858935 -82.95031) (xy 197.914952 -82.919513) (xy 197.974386 -82.89598) (xy 198.036302 -82.880081)
			(xy 198.099722 -82.872067) (xy 198.131684 -82.871564) (xy 198.165422 -82.87212) (xy 198.232304 -82.881064)
			(xy 198.297417 -82.898772) (xy 198.359617 -82.924931) (xy 198.417813 -82.959084) (xy 198.470983 -83.00063)
			(xy 198.518194 -83.048841) (xy 198.538846 -83.075526) (xy 198.545993 -83.084056) (xy 198.565621 -83.094478)
			(xy 198.576692 -83.095592) (xy 198.6661 -83.100418) (xy 198.686674 -83.09229) (xy 198.694548 -83.083908)
			(xy 198.715179 -83.062393) (xy 198.760634 -83.023829) (xy 198.810288 -82.990848) (xy 198.863461 -82.963902)
			(xy 198.91942 -82.943362) (xy 198.977398 -82.92951) (xy 199.036599 -82.922537) (xy 199.066404 -82.92211)
			(xy 199.098241 -82.922625) (xy 199.161417 -82.930579) (xy 199.223104 -82.946361) (xy 199.282336 -82.969725)
			(xy 199.338187 -83.000305) (xy 199.38978 -83.037622) (xy 199.436309 -83.08109) (xy 199.457056 -83.105244)
			(xy 199.45731 -83.105498) (xy 199.465189 -83.113759) (xy 199.48603 -83.122996) (xy 199.497442 -83.123278)
			(xy 199.577452 -83.121246) (xy 199.589004 -83.120391) (xy 199.609508 -83.109657) (xy 199.616822 -83.100672)
			(xy 199.637452 -83.07382) (xy 199.684698 -83.025309) (xy 199.737963 -82.983498) (xy 199.796306 -82.949125)
			(xy 199.858695 -82.922798) (xy 199.924025 -82.904984) (xy 199.991142 -82.895998) (xy 200.025 -82.89544)
			(xy 200.056109 -82.895856) (xy 200.117863 -82.903436) (xy 200.17823 -82.918496) (xy 200.236309 -82.94081)
			(xy 200.29123 -82.970045) (xy 200.342173 -83.005763) (xy 200.388377 -83.047431) (xy 200.429151 -83.094426)
			(xy 200.463885 -83.146046) (xy 200.47839 -83.17357) (xy 200.48474 -83.186016) (xy 200.508362 -83.201002)
			(xy 200.62571 -83.203796) (xy 200.650094 -83.19008) (xy 200.656952 -83.178142) (xy 200.67397 -83.149367)
			(xy 200.714493 -83.096195) (xy 200.761632 -83.048788) (xy 200.814576 -83.007966) (xy 200.87241 -82.97443)
			(xy 200.934139 -82.948759) (xy 200.998699 -82.931395) (xy 201.064977 -82.922638) (xy 201.098404 -82.92211)
			(xy 201.130366 -82.922576) (xy 201.193786 -82.930588) (xy 201.255702 -82.946486) (xy 201.315136 -82.970018)
			(xy 201.371153 -83.000814) (xy 201.422869 -83.038388) (xy 201.469467 -83.082147) (xy 201.510214 -83.131402)
			(xy 201.544466 -83.185375) (xy 201.571683 -83.243215) (xy 201.591437 -83.30401) (xy 201.603415 -83.366802)
			(xy 201.607429 -83.4306) (xy 201.605417 -83.462579) (xy 202.495398 -83.462579) (xy 202.495398 -83.398657)
			(xy 202.503409 -83.335239) (xy 202.519306 -83.273325) (xy 202.542838 -83.213892) (xy 202.573632 -83.157877)
			(xy 202.611205 -83.106162) (xy 202.654962 -83.059565) (xy 202.704215 -83.01882) (xy 202.758186 -82.984569)
			(xy 202.816025 -82.957352) (xy 202.876818 -82.937599) (xy 202.939608 -82.925621) (xy 203.003404 -82.921608)
			(xy 203.0672 -82.925621) (xy 203.12999 -82.937599) (xy 203.190783 -82.957352) (xy 203.248622 -82.984569)
			(xy 203.302593 -83.01882) (xy 203.351846 -83.059565) (xy 203.395603 -83.106162) (xy 203.433176 -83.157877)
			(xy 203.46397 -83.213892) (xy 203.487502 -83.273325) (xy 203.503399 -83.335239) (xy 203.51141 -83.398657)
			(xy 203.511912 -83.430618) (xy 203.51141 -83.462579) (xy 203.503399 -83.525997) (xy 203.487502 -83.587911)
			(xy 203.46397 -83.647344) (xy 203.433176 -83.703359) (xy 203.395603 -83.755074) (xy 203.351846 -83.801671)
			(xy 203.302593 -83.842416) (xy 203.254165 -83.873149) (xy 203.648086 -83.873149) (xy 203.648086 -83.818651)
			(xy 203.655841 -83.764709) (xy 203.671193 -83.712418) (xy 203.693831 -83.662845) (xy 203.723292 -83.616998)
			(xy 203.758978 -83.57581) (xy 203.800163 -83.540119) (xy 203.846007 -83.510652) (xy 203.895577 -83.488009)
			(xy 203.947866 -83.47265) (xy 204.001807 -83.464889) (xy 204.029056 -83.4644) (xy 204.02931 -83.4644)
			(xy 204.057168 -83.464904) (xy 204.112289 -83.47303) (xy 204.165643 -83.48908) (xy 204.2161 -83.512711)
			(xy 204.239622 -83.527646) (xy 204.247242 -83.532726) (xy 204.265276 -83.537044) (xy 204.340714 -83.526884)
			(xy 204.349574 -83.525304) (xy 204.365446 -83.516844) (xy 204.371702 -83.510374) (xy 204.371956 -83.509866)
			(xy 204.392666 -83.486993) (xy 204.438738 -83.445945) (xy 204.489442 -83.410778) (xy 204.544032 -83.382011)
			(xy 204.601704 -83.360067) (xy 204.661609 -83.345269) (xy 204.722865 -83.337834) (xy 204.753718 -83.3374)
			(xy 204.784439 -83.337862) (xy 204.845433 -83.345264) (xy 204.905091 -83.359957) (xy 204.962547 -83.381727)
			(xy 205.016962 -83.410258) (xy 205.042516 -83.427316) (xy 205.051201 -83.432709) (xy 205.071218 -83.43677)
			(xy 205.091235 -83.432709) (xy 205.09992 -83.427316) (xy 205.125473 -83.410256) (xy 205.179887 -83.381723)
			(xy 205.237343 -83.359952) (xy 205.297002 -83.34526) (xy 205.357997 -83.337862) (xy 205.388718 -83.3374)
			(xy 205.420679 -83.337887) (xy 205.484096 -83.345901) (xy 205.546009 -83.361799) (xy 205.605441 -83.385332)
			(xy 205.661455 -83.416128) (xy 205.713168 -83.453701) (xy 205.759764 -83.497459) (xy 205.800509 -83.546712)
			(xy 205.834759 -83.600684) (xy 205.861975 -83.658522) (xy 205.881727 -83.719315) (xy 205.893705 -83.782104)
			(xy 205.897719 -83.8459) (xy 205.893705 -83.909696) (xy 205.881727 -83.972485) (xy 205.861975 -84.033278)
			(xy 205.84126 -84.0773) (xy 210.260192 -84.0773) (xy 210.264205 -84.013504) (xy 210.276183 -83.950715)
			(xy 210.295936 -83.889921) (xy 210.323152 -83.832083) (xy 210.357403 -83.778112) (xy 210.398149 -83.72886)
			(xy 210.444746 -83.685102) (xy 210.49646 -83.64753) (xy 210.552475 -83.616735) (xy 210.611908 -83.593204)
			(xy 210.673821 -83.577307) (xy 210.737239 -83.569296) (xy 210.7692 -83.568794) (xy 210.800526 -83.569227)
			(xy 210.862703 -83.576925) (xy 210.923463 -83.592205) (xy 210.981886 -83.614834) (xy 211.037085 -83.64447)
			(xy 211.088225 -83.680664) (xy 211.13453 -83.722867) (xy 211.15528 -83.74634) (xy 211.15528 -83.746594)
			(xy 211.161662 -83.753276) (xy 211.177931 -83.762004) (xy 211.18703 -83.763612) (xy 211.26323 -83.774026)
			(xy 211.281264 -83.769708) (xy 211.289138 -83.764628) (xy 211.312874 -83.749252) (xy 211.36394 -83.724951)
			(xy 211.418032 -83.708451) (xy 211.473967 -83.700113) (xy 211.502244 -83.699604) (xy 211.529494 -83.700069)
			(xy 211.583439 -83.707831) (xy 211.63573 -83.72319) (xy 211.685303 -83.745834) (xy 211.731149 -83.775303)
			(xy 211.772336 -83.810995) (xy 211.808024 -83.852186) (xy 211.837487 -83.898036) (xy 211.860125 -83.947611)
			(xy 211.875479 -83.999904) (xy 211.883234 -84.05385) (xy 211.883234 -84.10835) (xy 211.875479 -84.162296)
			(xy 211.860125 -84.214589) (xy 211.837487 -84.264164) (xy 211.808024 -84.310014) (xy 211.772336 -84.351205)
			(xy 211.731149 -84.386897) (xy 211.685303 -84.416366) (xy 211.63573 -84.43901) (xy 211.583439 -84.454369)
			(xy 211.529494 -84.462131) (xy 211.502244 -84.46262) (xy 211.473466 -84.462095) (xy 211.416561 -84.453454)
			(xy 211.361601 -84.43636) (xy 211.309834 -84.411203) (xy 211.285836 -84.39531) (xy 211.278216 -84.389976)
			(xy 211.260182 -84.385658) (xy 211.174584 -84.396326) (xy 211.158074 -84.404962) (xy 211.151978 -84.412074)
			(xy 211.131262 -84.435092) (xy 211.085127 -84.476406) (xy 211.034318 -84.511813) (xy 210.979585 -84.540788)
			(xy 210.921739 -84.562903) (xy 210.861636 -84.577831) (xy 210.800165 -84.58535) (xy 210.7692 -84.58581)
			(xy 210.737239 -84.585304) (xy 210.673821 -84.577293) (xy 210.611908 -84.561396) (xy 210.552475 -84.537865)
			(xy 210.49646 -84.50707) (xy 210.444746 -84.469498) (xy 210.398149 -84.42574) (xy 210.357403 -84.376488)
			(xy 210.323152 -84.322517) (xy 210.295936 -84.264679) (xy 210.276183 -84.203885) (xy 210.264205 -84.141096)
			(xy 210.260192 -84.0773) (xy 205.84126 -84.0773) (xy 205.834759 -84.091116) (xy 205.800509 -84.145088)
			(xy 205.759764 -84.194341) (xy 205.713168 -84.238099) (xy 205.661455 -84.275672) (xy 205.605441 -84.306468)
			(xy 205.546009 -84.330001) (xy 205.484096 -84.345899) (xy 205.420679 -84.353913) (xy 205.388718 -84.354416)
			(xy 205.357998 -84.353932) (xy 205.297005 -84.346536) (xy 205.237346 -84.331847) (xy 205.179891 -84.310082)
			(xy 205.125475 -84.281555) (xy 205.09992 -84.2645) (xy 205.091235 -84.259107) (xy 205.071218 -84.255046)
			(xy 205.051201 -84.259107) (xy 205.042516 -84.2645) (xy 205.016955 -84.281547) (xy 204.962542 -84.310082)
			(xy 204.905089 -84.331855) (xy 204.845431 -84.34655) (xy 204.784438 -84.353952) (xy 204.753718 -84.354416)
			(xy 204.722858 -84.353966) (xy 204.661592 -84.346493) (xy 204.601681 -84.331656) (xy 204.544009 -84.309673)
			(xy 204.489423 -84.280866) (xy 204.438728 -84.245662) (xy 204.392669 -84.204577) (xy 204.371956 -84.181696)
			(xy 204.371702 -84.181442) (xy 204.365447 -84.174969) (xy 204.349576 -84.166504) (xy 204.340714 -84.164932)
			(xy 204.265276 -84.154772) (xy 204.247242 -84.15909) (xy 204.239622 -84.16417) (xy 204.216127 -84.179152)
			(xy 204.165667 -84.202794) (xy 204.112303 -84.218837) (xy 204.057172 -84.226939) (xy 204.02931 -84.227416)
			(xy 204.029056 -84.227416) (xy 204.001807 -84.226911) (xy 203.947866 -84.21915) (xy 203.895577 -84.203791)
			(xy 203.846007 -84.181148) (xy 203.800163 -84.151681) (xy 203.758978 -84.11599) (xy 203.723292 -84.074802)
			(xy 203.693831 -84.028955) (xy 203.671193 -83.979382) (xy 203.655841 -83.927091) (xy 203.648086 -83.873149)
			(xy 203.254165 -83.873149) (xy 203.248622 -83.876667) (xy 203.190783 -83.903884) (xy 203.12999 -83.923637)
			(xy 203.0672 -83.935615) (xy 203.003404 -83.939629) (xy 202.939608 -83.935615) (xy 202.876818 -83.923637)
			(xy 202.816025 -83.903884) (xy 202.758186 -83.876667) (xy 202.704215 -83.842416) (xy 202.654962 -83.801671)
			(xy 202.611205 -83.755074) (xy 202.573632 -83.703359) (xy 202.542838 -83.647344) (xy 202.519306 -83.587911)
			(xy 202.503409 -83.525997) (xy 202.495398 -83.462579) (xy 201.605417 -83.462579) (xy 201.603415 -83.494398)
			(xy 201.591437 -83.55719) (xy 201.571683 -83.617985) (xy 201.544466 -83.675825) (xy 201.510214 -83.729798)
			(xy 201.469467 -83.779053) (xy 201.422869 -83.822812) (xy 201.371153 -83.860386) (xy 201.315136 -83.891182)
			(xy 201.255702 -83.914714) (xy 201.193786 -83.930612) (xy 201.130366 -83.938624) (xy 201.098404 -83.939126)
			(xy 201.067297 -83.938671) (xy 201.005546 -83.931092) (xy 200.945181 -83.916035) (xy 200.887104 -83.893725)
			(xy 200.832184 -83.864495) (xy 200.78124 -83.828782) (xy 200.735035 -83.787119) (xy 200.69426 -83.74013)
			(xy 200.659522 -83.688517) (xy 200.645014 -83.660996) (xy 200.638664 -83.64855) (xy 200.615042 -83.633564)
			(xy 200.497694 -83.63077) (xy 200.47331 -83.644486) (xy 200.466452 -83.656424) (xy 200.449418 -83.685189)
			(xy 200.408898 -83.738363) (xy 200.361762 -83.785771) (xy 200.308821 -83.826595) (xy 200.250989 -83.860132)
			(xy 200.189262 -83.885804) (xy 200.124703 -83.903169) (xy 200.058426 -83.911927) (xy 200.025 -83.912456)
			(xy 199.993162 -83.911951) (xy 199.929986 -83.903997) (xy 199.868298 -83.888213) (xy 199.809065 -83.864848)
			(xy 199.753215 -83.834266) (xy 199.701622 -83.796948) (xy 199.655095 -83.753477) (xy 199.634348 -83.729322)
			(xy 199.634094 -83.729068) (xy 199.626218 -83.720804) (xy 199.605375 -83.71157) (xy 199.593962 -83.711288)
			(xy 199.513952 -83.71332) (xy 199.502402 -83.714189) (xy 199.481899 -83.724914) (xy 199.474582 -83.733894)
			(xy 199.45394 -83.760737) (xy 199.406698 -83.809249) (xy 199.353435 -83.851063) (xy 199.295094 -83.885437)
			(xy 199.232706 -83.911765) (xy 199.167377 -83.92958) (xy 199.100261 -83.938568) (xy 199.066404 -83.939126)
			(xy 199.032665 -83.938583) (xy 198.965783 -83.929637) (xy 198.90067 -83.911927) (xy 198.83847 -83.885766)
			(xy 198.780274 -83.851611) (xy 198.727104 -83.810063) (xy 198.679893 -83.76185) (xy 198.659242 -83.735164)
			(xy 198.652102 -83.726627) (xy 198.632469 -83.716209) (xy 198.621396 -83.715098) (xy 198.531988 -83.710272)
			(xy 198.511414 -83.7184) (xy 198.50354 -83.726782) (xy 198.482913 -83.748301) (xy 198.437458 -83.786865)
			(xy 198.387802 -83.819846) (xy 198.33463 -83.846792) (xy 198.278669 -83.867331) (xy 198.22069 -83.881182)
			(xy 198.161489 -83.888154) (xy 198.131684 -83.88858) (xy 198.099722 -83.888133) (xy 198.036302 -83.880119)
			(xy 197.974386 -83.86422) (xy 197.914952 -83.840687) (xy 197.858935 -83.80989) (xy 197.80722 -83.772315)
			(xy 197.760622 -83.728555) (xy 197.719875 -83.6793) (xy 197.685624 -83.625327) (xy 197.658407 -83.567486)
			(xy 197.638653 -83.50669) (xy 197.626675 -83.443898) (xy 197.622661 -83.3801) (xy 179.474904 -83.3801)
			(xy 180.650853 -84.556049) (xy 189.406778 -84.556049) (xy 189.406778 -84.492127) (xy 189.414789 -84.428709)
			(xy 189.430686 -84.366795) (xy 189.454218 -84.307362) (xy 189.485012 -84.251347) (xy 189.522585 -84.199632)
			(xy 189.566342 -84.153035) (xy 189.615595 -84.11229) (xy 189.669566 -84.078039) (xy 189.727405 -84.050822)
			(xy 189.788198 -84.031069) (xy 189.850988 -84.019091) (xy 189.914784 -84.015078) (xy 189.97858 -84.019091)
			(xy 190.04137 -84.031069) (xy 190.102163 -84.050822) (xy 190.160002 -84.078039) (xy 190.213973 -84.11229)
			(xy 190.263226 -84.153035) (xy 190.306983 -84.199632) (xy 190.344556 -84.251347) (xy 190.37535 -84.307362)
			(xy 190.398882 -84.366795) (xy 190.414779 -84.428709) (xy 190.42279 -84.492127) (xy 190.423292 -84.524088)
			(xy 190.42279 -84.556049) (xy 190.414779 -84.619467) (xy 190.398882 -84.681381) (xy 190.37535 -84.740814)
			(xy 190.344556 -84.796829) (xy 190.306983 -84.848544) (xy 190.263226 -84.895141) (xy 190.213973 -84.935886)
			(xy 190.160002 -84.970137) (xy 190.102163 -84.997354) (xy 190.04137 -85.017107) (xy 189.97858 -85.029085)
			(xy 189.914784 -85.033099) (xy 189.850988 -85.029085) (xy 189.788198 -85.017107) (xy 189.727405 -84.997354)
			(xy 189.669566 -84.970137) (xy 189.615595 -84.935886) (xy 189.566342 -84.895141) (xy 189.522585 -84.848544)
			(xy 189.485012 -84.796829) (xy 189.454218 -84.740814) (xy 189.430686 -84.681381) (xy 189.414789 -84.619467)
			(xy 189.406778 -84.556049) (xy 180.650853 -84.556049) (xy 181.26647 -85.171666) (xy 194.596101 -85.171666)
			(xy 194.601312 -85.1088) (xy 194.614259 -85.04706) (xy 194.634743 -84.987397) (xy 194.662451 -84.930725)
			(xy 194.696955 -84.877916) (xy 194.737727 -84.82978) (xy 194.784139 -84.787057) (xy 194.83548 -84.750403)
			(xy 194.89096 -84.720381) (xy 194.949728 -84.697452) (xy 195.010881 -84.681969) (xy 195.073479 -84.674168)
			(xy 195.10502 -84.673694) (xy 195.135619 -84.674137) (xy 195.196374 -84.681471) (xy 195.255811 -84.696042)
			(xy 195.31307 -84.71764) (xy 195.367324 -84.745952) (xy 195.417788 -84.78057) (xy 195.441062 -84.80044)
			(xy 195.452364 -84.809776) (xy 195.478942 -84.822115) (xy 195.507931 -84.826397) (xy 195.536942 -84.822268)
			(xy 195.563585 -84.810069) (xy 195.585665 -84.790805) (xy 195.601365 -84.766063) (xy 195.60939 -84.73788)
			(xy 195.609718 -84.723224) (xy 195.609718 -84.718398) (xy 195.61017 -84.686857) (xy 195.617973 -84.624261)
			(xy 195.633458 -84.56311) (xy 195.656389 -84.504344) (xy 195.686412 -84.448866) (xy 195.723067 -84.397527)
			(xy 195.76579 -84.351117) (xy 195.813926 -84.310347) (xy 195.866735 -84.275845) (xy 195.923406 -84.248139)
			(xy 195.983069 -84.227656) (xy 196.044808 -84.21471) (xy 196.107673 -84.2095) (xy 196.1707 -84.212106)
			(xy 196.232921 -84.222488) (xy 196.29338 -84.240486) (xy 196.351149 -84.265825) (xy 196.405339 -84.298114)
			(xy 196.45512 -84.336858) (xy 196.499726 -84.381462) (xy 196.538473 -84.431241) (xy 196.570764 -84.48543)
			(xy 196.596105 -84.543197) (xy 196.614107 -84.603655) (xy 196.624491 -84.665876) (xy 196.6271 -84.728903)
			(xy 196.621893 -84.791769) (xy 196.60895 -84.853508) (xy 196.58847 -84.913172) (xy 196.560767 -84.969844)
			(xy 196.526267 -85.022655) (xy 196.4855 -85.070793) (xy 196.439091 -85.113518) (xy 196.387754 -85.150176)
			(xy 196.337084 -85.1776) (xy 212.280498 -85.1776) (xy 212.284512 -85.113804) (xy 212.29649 -85.051014)
			(xy 212.316244 -84.99022) (xy 212.343461 -84.932382) (xy 212.377713 -84.878411) (xy 212.418459 -84.829159)
			(xy 212.465057 -84.785402) (xy 212.516772 -84.74783) (xy 212.572788 -84.717037) (xy 212.632222 -84.693507)
			(xy 212.694136 -84.677612) (xy 212.757555 -84.669602) (xy 212.789516 -84.669122) (xy 212.823564 -84.669657)
			(xy 212.891051 -84.678741) (xy 212.95672 -84.696758) (xy 213.019394 -84.723385) (xy 213.07795 -84.758144)
			(xy 213.104984 -84.77885) (xy 213.114206 -84.785356) (xy 213.136143 -84.7905) (xy 213.158169 -84.785748)
			(xy 213.167468 -84.779358) (xy 213.194156 -84.759643) (xy 213.251676 -84.726567) (xy 213.313009 -84.701255)
			(xy 213.377115 -84.684136) (xy 213.442902 -84.675502) (xy 213.476078 -84.674964) (xy 213.507245 -84.675417)
			(xy 213.569112 -84.683041) (xy 213.629584 -84.698165) (xy 213.687756 -84.720563) (xy 213.742756 -84.749898)
			(xy 213.793761 -84.785733) (xy 213.8172 -84.806282) (xy 213.823724 -84.811816) (xy 213.839429 -84.818571)
			(xy 213.847934 -84.81949) (xy 213.877398 -84.821268) (xy 213.886015 -84.821551) (xy 213.902633 -84.817002)
			(xy 213.90991 -84.812378) (xy 213.935547 -84.795098) (xy 213.9902 -84.766191) (xy 214.047952 -84.744118)
			(xy 214.107953 -84.729204) (xy 214.169319 -84.72167) (xy 214.200232 -84.721192) (xy 214.200486 -84.721192)
			(xy 214.232634 -84.721675) (xy 214.296415 -84.7298) (xy 214.358664 -84.745897) (xy 214.418388 -84.769709)
			(xy 214.474636 -84.800857) (xy 214.526511 -84.838844) (xy 214.573186 -84.883065) (xy 214.593932 -84.907628)
			(xy 214.600028 -84.915248) (xy 214.617046 -84.924646) (xy 214.705184 -84.93633) (xy 214.723472 -84.931758)
			(xy 214.7316 -84.925916) (xy 214.75604 -84.909084) (xy 214.809052 -84.882418) (xy 214.865552 -84.864278)
			(xy 214.924179 -84.855101) (xy 214.95385 -84.854542) (xy 214.981104 -84.855002) (xy 215.035058 -84.862753)
			(xy 215.087359 -84.878106) (xy 215.136942 -84.900746) (xy 215.182798 -84.930213) (xy 215.223992 -84.965908)
			(xy 215.259687 -85.007102) (xy 215.289154 -85.052958) (xy 215.311794 -85.102541) (xy 215.327147 -85.154842)
			(xy 215.334898 -85.208796) (xy 215.335358 -85.23605) (xy 215.335358 -85.236304) (xy 215.334674 -85.269708)
			(xy 215.323049 -85.335498) (xy 215.312244 -85.367114) (xy 215.308733 -85.379018) (xy 215.312033 -85.403571)
			(xy 215.318594 -85.414104) (xy 215.336882 -85.439758) (xy 215.344836 -85.449648) (xy 215.367627 -85.460726)
			(xy 215.380316 -85.46084) (xy 215.388952 -85.460586) (xy 215.401906 -85.460332) (xy 215.424004 -85.447886)
			(xy 215.482678 -85.353144) (xy 215.484202 -85.327744) (xy 215.478868 -85.316314) (xy 215.478868 -85.315806)
			(xy 215.463758 -85.281971) (xy 215.442397 -85.211019) (xy 215.431567 -85.137716) (xy 215.430862 -85.100668)
			(xy 215.431326 -85.069937) (xy 215.438738 -85.008925) (xy 215.453449 -84.94925) (xy 215.475245 -84.891784)
			(xy 215.503809 -84.837364) (xy 215.538724 -84.786783) (xy 215.57948 -84.740779) (xy 215.625484 -84.700022)
			(xy 215.676065 -84.665108) (xy 215.730486 -84.636544) (xy 215.787952 -84.614748) (xy 215.847627 -84.600037)
			(xy 215.908639 -84.592626) (xy 215.93937 -84.59216) (xy 215.970089 -84.592684) (xy 216.031081 -84.600083)
			(xy 216.090736 -84.614778) (xy 216.148186 -84.636555) (xy 216.197681 -84.662518) (xy 218.0971 -84.662518)
			(xy 218.097528 -84.636037) (xy 218.104841 -84.583583) (xy 218.119342 -84.532646) (xy 218.140753 -84.484206)
			(xy 218.168662 -84.439194) (xy 218.202531 -84.398478) (xy 218.221814 -84.380324) (xy 218.227912 -84.374379)
			(xy 218.236093 -84.359454) (xy 218.237816 -84.351114) (xy 218.242642 -84.321904) (xy 218.243735 -84.313268)
			(xy 218.240755 -84.29613) (xy 218.2368 -84.288376) (xy 218.22114 -84.259613) (xy 218.196464 -84.19895)
			(xy 218.179782 -84.13562) (xy 218.17137 -84.070673) (xy 218.171366 -84.005183) (xy 218.179771 -83.940234)
			(xy 218.196447 -83.876903) (xy 218.221116 -83.816237) (xy 218.2368 -83.787488) (xy 218.24079 -83.779744)
			(xy 218.243778 -83.762596) (xy 218.242642 -83.75396) (xy 218.237816 -83.72475) (xy 218.236091 -83.716411)
			(xy 218.227907 -83.701489) (xy 218.221814 -83.69554) (xy 218.202546 -83.677373) (xy 218.168694 -83.63665)
			(xy 218.140796 -83.591638) (xy 218.119389 -83.543201) (xy 218.104882 -83.492271) (xy 218.097556 -83.439824)
			(xy 218.0971 -83.413346) (xy 218.097586 -83.386095) (xy 218.105342 -83.332147) (xy 218.120697 -83.279852)
			(xy 218.143339 -83.230275) (xy 218.172805 -83.184425) (xy 218.208496 -83.143234) (xy 218.249687 -83.107543)
			(xy 218.295537 -83.078077) (xy 218.345114 -83.055435) (xy 218.397409 -83.04008) (xy 218.451357 -83.032324)
			(xy 218.505859 -83.032324) (xy 218.559807 -83.04008) (xy 218.612102 -83.055435) (xy 218.661679 -83.078077)
			(xy 218.707529 -83.107543) (xy 218.74872 -83.143234) (xy 218.784411 -83.184425) (xy 218.813877 -83.230275)
			(xy 218.836519 -83.279852) (xy 218.851874 -83.332147) (xy 218.85963 -83.386095) (xy 218.860116 -83.413346)
			(xy 218.859868 -83.433437) (xy 218.855668 -83.473398) (xy 218.851734 -83.493102) (xy 218.85026 -83.501543)
			(xy 218.852327 -83.518542) (xy 218.855798 -83.526376) (xy 218.869006 -83.553046) (xy 218.873111 -83.560647)
			(xy 218.88545 -83.572723) (xy 218.893136 -83.576668) (xy 218.922136 -83.590666) (xy 218.976656 -83.624936)
			(xy 219.001848 -83.644994) (xy 219.008862 -83.650242) (xy 219.025353 -83.656103) (xy 219.034106 -83.656424)
			(xy 219.18803 -83.656424) (xy 219.196778 -83.656069) (xy 219.213269 -83.650226) (xy 219.220288 -83.644994)
			(xy 219.245481 -83.624937) (xy 219.300004 -83.590674) (xy 219.329 -83.576668) (xy 219.336684 -83.572722)
			(xy 219.349015 -83.560641) (xy 219.35313 -83.553046) (xy 219.366338 -83.526376) (xy 219.369848 -83.518552)
			(xy 219.371926 -83.501541) (xy 219.370402 -83.493102) (xy 219.366469 -83.473398) (xy 219.362266 -83.433437)
			(xy 219.36202 -83.413346) (xy 219.362506 -83.386095) (xy 219.370262 -83.332147) (xy 219.385617 -83.279852)
			(xy 219.408259 -83.230275) (xy 219.437725 -83.184425) (xy 219.473416 -83.143234) (xy 219.514607 -83.107543)
			(xy 219.560457 -83.078077) (xy 219.610034 -83.055435) (xy 219.662329 -83.04008) (xy 219.716277 -83.032324)
			(xy 219.770779 -83.032324) (xy 219.824727 -83.04008) (xy 219.877022 -83.055435) (xy 219.926599 -83.078077)
			(xy 219.972449 -83.107543) (xy 220.01364 -83.143234) (xy 220.049331 -83.184425) (xy 220.078797 -83.230275)
			(xy 220.101439 -83.279852) (xy 220.110878 -83.312) (xy 221.740982 -83.312) (xy 221.745053 -83.256378)
			(xy 221.757179 -83.201941) (xy 221.777102 -83.14985) (xy 221.804398 -83.101215) (xy 221.838484 -83.057072)
			(xy 221.878633 -83.018363) (xy 221.923991 -82.985912) (xy 221.973591 -82.960411) (xy 222.026375 -82.942404)
			(xy 222.081218 -82.932274) (xy 222.136952 -82.930237) (xy 222.192389 -82.936337) (xy 222.246346 -82.950443)
			(xy 222.297675 -82.972255) (xy 222.345281 -83.001309) (xy 222.388149 -83.036984) (xy 222.425366 -83.078521)
			(xy 222.456139 -83.125034) (xy 222.479811 -83.175531) (xy 222.495879 -83.228938) (xy 222.503999 -83.284114)
			(xy 222.504508 -83.312) (xy 222.503999 -83.339886) (xy 222.495879 -83.395062) (xy 222.479811 -83.448469)
			(xy 222.456139 -83.498966) (xy 222.425366 -83.545479) (xy 222.388149 -83.587016) (xy 222.345281 -83.622691)
			(xy 222.297675 -83.651745) (xy 222.246346 -83.673557) (xy 222.192389 -83.687663) (xy 222.136952 -83.693763)
			(xy 222.081218 -83.691726) (xy 222.026375 -83.681596) (xy 221.973591 -83.663589) (xy 221.923991 -83.638088)
			(xy 221.878633 -83.605637) (xy 221.838484 -83.566928) (xy 221.804398 -83.522785) (xy 221.777102 -83.47415)
			(xy 221.757179 -83.422059) (xy 221.745053 -83.367622) (xy 221.740982 -83.312) (xy 220.110878 -83.312)
			(xy 220.116794 -83.332147) (xy 220.12455 -83.386095) (xy 220.125036 -83.413346) (xy 220.124572 -83.439825)
			(xy 220.117265 -83.492277) (xy 220.10277 -83.543213) (xy 220.081365 -83.591654) (xy 220.053464 -83.636666)
			(xy 220.019602 -83.677384) (xy 220.000322 -83.69554) (xy 219.994226 -83.701487) (xy 219.986046 -83.716411)
			(xy 219.98432 -83.72475) (xy 219.979494 -83.75396) (xy 219.978378 -83.762594) (xy 219.981375 -83.779734)
			(xy 219.985336 -83.787488) (xy 220.001051 -83.816223) (xy 220.025724 -83.876892) (xy 220.042403 -83.940227)
			(xy 220.05081 -84.00518) (xy 220.050806 -84.070675) (xy 220.042392 -84.135627) (xy 220.025707 -84.198961)
			(xy 220.001026 -84.259628) (xy 219.985336 -84.288376) (xy 219.98136 -84.296125) (xy 219.978365 -84.313269)
			(xy 219.979494 -84.321904) (xy 219.98432 -84.351114) (xy 219.98605 -84.359451) (xy 219.99423 -84.374375)
			(xy 220.000322 -84.380324) (xy 220.01958 -84.398502) (xy 220.053431 -84.439224) (xy 220.081329 -84.484234)
			(xy 220.102738 -84.532668) (xy 220.117247 -84.583596) (xy 220.124578 -84.636041) (xy 220.125036 -84.662518)
			(xy 220.12455 -84.689769) (xy 220.116794 -84.743717) (xy 220.101439 -84.796012) (xy 220.078797 -84.845589)
			(xy 220.049331 -84.891439) (xy 220.01364 -84.93263) (xy 219.972449 -84.968321) (xy 219.926599 -84.997787)
			(xy 219.877022 -85.020429) (xy 219.824727 -85.035784) (xy 219.770779 -85.04354) (xy 219.716277 -85.04354)
			(xy 219.662329 -85.035784) (xy 219.610034 -85.020429) (xy 219.560457 -84.997787) (xy 219.514607 -84.968321)
			(xy 219.473416 -84.93263) (xy 219.437725 -84.891439) (xy 219.408259 -84.845589) (xy 219.385617 -84.796012)
			(xy 219.370262 -84.743717) (xy 219.362506 -84.689769) (xy 219.36202 -84.662518) (xy 219.362261 -84.642427)
			(xy 219.366466 -84.602465) (xy 219.370402 -84.582762) (xy 219.3719 -84.574323) (xy 219.369818 -84.557321)
			(xy 219.366338 -84.549488) (xy 219.35313 -84.522818) (xy 219.349028 -84.515214) (xy 219.336688 -84.503138)
			(xy 219.329 -84.499196) (xy 219.300001 -84.485196) (xy 219.24548 -84.450928) (xy 219.220288 -84.43087)
			(xy 219.213294 -84.425591) (xy 219.196787 -84.41975) (xy 219.18803 -84.41944) (xy 219.034106 -84.41944)
			(xy 219.025359 -84.419799) (xy 219.008867 -84.425638) (xy 219.001848 -84.43087) (xy 218.97665 -84.450919)
			(xy 218.922131 -84.485188) (xy 218.893136 -84.499196) (xy 218.885465 -84.503164) (xy 218.873127 -84.515229)
			(xy 218.869006 -84.522818) (xy 218.855798 -84.549488) (xy 218.852303 -84.557318) (xy 218.850217 -84.574324)
			(xy 218.851734 -84.582762) (xy 218.855677 -84.602464) (xy 218.859873 -84.642427) (xy 218.860116 -84.662518)
			(xy 218.85963 -84.689769) (xy 218.851874 -84.743717) (xy 218.836519 -84.796012) (xy 218.813877 -84.845589)
			(xy 218.784411 -84.891439) (xy 218.74872 -84.93263) (xy 218.707529 -84.968321) (xy 218.661679 -84.997787)
			(xy 218.612102 -85.020429) (xy 218.559807 -85.035784) (xy 218.505859 -85.04354) (xy 218.451357 -85.04354)
			(xy 218.397409 -85.035784) (xy 218.345114 -85.020429) (xy 218.295537 -84.997787) (xy 218.249687 -84.968321)
			(xy 218.208496 -84.93263) (xy 218.172805 -84.891439) (xy 218.143339 -84.845589) (xy 218.120697 -84.796012)
			(xy 218.105342 -84.743717) (xy 218.097586 -84.689769) (xy 218.0971 -84.662518) (xy 216.197681 -84.662518)
			(xy 216.202594 -84.665095) (xy 216.253166 -84.699983) (xy 216.299165 -84.740711) (xy 216.339921 -84.786686)
			(xy 216.374841 -84.837236) (xy 216.403415 -84.891625) (xy 216.425228 -84.949062) (xy 216.43996 -85.008708)
			(xy 216.447397 -85.069695) (xy 216.447878 -85.100414) (xy 216.447878 -85.100922) (xy 216.447624 -85.11286)
			(xy 216.447624 -85.113114) (xy 216.44789 -85.122473) (xy 216.454265 -85.140059) (xy 216.46007 -85.147404)
			(xy 216.51214 -85.206586) (xy 216.528904 -85.215222) (xy 216.538556 -85.216238) (xy 216.569385 -85.220007)
			(xy 216.629889 -85.234032) (xy 216.688235 -85.255321) (xy 216.743555 -85.283556) (xy 216.795023 -85.318319)
			(xy 216.841876 -85.359091) (xy 216.883414 -85.405265) (xy 216.919021 -85.456154) (xy 216.948164 -85.511)
			(xy 216.970412 -85.568987) (xy 216.985432 -85.629252) (xy 216.993002 -85.690898) (xy 216.99347 -85.721952)
			(xy 216.992902 -85.755413) (xy 216.984118 -85.821756) (xy 216.966707 -85.886373) (xy 216.940971 -85.948148)
			(xy 216.907355 -86.006014) (xy 216.86644 -86.058971) (xy 216.818931 -86.106104) (xy 216.765651 -86.146598)
			(xy 216.70752 -86.179753) (xy 216.676732 -86.192868) (xy 216.662762 -86.198456) (xy 216.64549 -86.223348)
			(xy 216.642442 -86.331552) (xy 216.642614 -86.341367) (xy 216.649468 -86.359741) (xy 216.66273 -86.374189)
			(xy 216.671398 -86.378796) (xy 216.699914 -86.392976) (xy 216.753556 -86.427299) (xy 216.802494 -86.468052)
			(xy 216.84596 -86.514596) (xy 216.883275 -86.566202) (xy 216.913855 -86.622063) (xy 216.937221 -86.681306)
			(xy 216.953008 -86.743002) (xy 216.960968 -86.806186) (xy 216.961466 -86.838028) (xy 216.960964 -86.869989)
			(xy 216.952953 -86.933407) (xy 216.937056 -86.995321) (xy 216.913524 -87.054754) (xy 216.88273 -87.110769)
			(xy 216.845157 -87.162484) (xy 216.8014 -87.209081) (xy 216.752147 -87.249826) (xy 216.698176 -87.284077)
			(xy 216.640337 -87.311294) (xy 216.579544 -87.331047) (xy 216.516754 -87.343025) (xy 216.452958 -87.347039)
			(xy 216.389162 -87.343025) (xy 216.326372 -87.331047) (xy 216.265579 -87.311294) (xy 216.20774 -87.284077)
			(xy 216.153769 -87.249826) (xy 216.104516 -87.209081) (xy 216.060759 -87.162484) (xy 216.023186 -87.110769)
			(xy 215.992392 -87.054754) (xy 215.96886 -86.995321) (xy 215.952963 -86.933407) (xy 215.944952 -86.869989)
			(xy 215.94445 -86.838028) (xy 215.944988 -86.804566) (xy 215.953776 -86.738222) (xy 215.971189 -86.673603)
			(xy 215.996929 -86.611827) (xy 216.030548 -86.553961) (xy 216.071468 -86.501004) (xy 216.11898 -86.453872)
			(xy 216.172264 -86.413379) (xy 216.230398 -86.380226) (xy 216.261188 -86.367112) (xy 216.275158 -86.361524)
			(xy 216.29243 -86.336632) (xy 216.295478 -86.228428) (xy 216.295365 -86.218608) (xy 216.288492 -86.200225)
			(xy 216.275203 -86.185782) (xy 216.266522 -86.181184) (xy 216.239093 -86.167642) (xy 216.187395 -86.134936)
			(xy 216.139998 -86.096261) (xy 216.097587 -86.052176) (xy 216.078816 -86.028022) (xy 216.072559 -86.020534)
			(xy 216.055848 -86.010502) (xy 216.036595 -86.007461) (xy 216.027 -86.009226) (xy 215.921844 -86.033102)
			(xy 215.901016 -86.054438) (xy 215.898222 -86.06917) (xy 215.89151 -86.100196) (xy 215.871358 -86.160394)
			(xy 215.843872 -86.217617) (xy 215.809478 -86.270973) (xy 215.768711 -86.319635) (xy 215.722206 -86.362845)
			(xy 215.670684 -86.399931) (xy 215.614947 -86.430317) (xy 215.555863 -86.453531) (xy 215.494348 -86.469211)
			(xy 215.431361 -86.477113) (xy 215.39962 -86.477602) (xy 215.368888 -86.477144) (xy 215.307872 -86.469737)
			(xy 215.248194 -86.45503) (xy 215.190724 -86.433236) (xy 215.136299 -86.404674) (xy 215.085715 -86.369759)
			(xy 215.039708 -86.329002) (xy 214.99895 -86.282996) (xy 214.964034 -86.232413) (xy 214.93547 -86.177989)
			(xy 214.913674 -86.120519) (xy 214.898965 -86.060842) (xy 214.891557 -85.999826) (xy 214.891112 -85.969094)
			(xy 214.891112 -85.96884) (xy 214.891495 -85.940712) (xy 214.89771 -85.884799) (xy 214.910068 -85.829917)
			(xy 214.928418 -85.776737) (xy 214.940134 -85.751162) (xy 214.945214 -85.740748) (xy 214.945214 -85.71738)
			(xy 214.905082 -85.635592) (xy 214.899572 -85.625551) (xy 214.881595 -85.611397) (xy 214.870538 -85.608414)
			(xy 214.844672 -85.602146) (xy 214.794869 -85.583377) (xy 214.748155 -85.557875) (xy 214.72652 -85.542374)
			(xy 214.726266 -85.54212) (xy 214.71835 -85.536833) (xy 214.699946 -85.532015) (xy 214.690452 -85.532722)
			(xy 214.611712 -85.541612) (xy 214.594694 -85.550756) (xy 214.588344 -85.558376) (xy 214.567566 -85.582116)
			(xy 214.521144 -85.624836) (xy 214.469796 -85.661488) (xy 214.414309 -85.69151) (xy 214.355536 -85.71444)
			(xy 214.294379 -85.729926) (xy 214.231776 -85.737731) (xy 214.200232 -85.738208) (xy 214.169065 -85.737756)
			(xy 214.107198 -85.730133) (xy 214.046725 -85.715009) (xy 213.988553 -85.692611) (xy 213.933553 -85.663275)
			(xy 213.882548 -85.627439) (xy 213.85911 -85.60689) (xy 213.852587 -85.601356) (xy 213.836881 -85.594602)
			(xy 213.828376 -85.593682) (xy 213.798912 -85.591904) (xy 213.790296 -85.59163) (xy 213.773678 -85.596173)
			(xy 213.7664 -85.600794) (xy 213.740758 -85.618066) (xy 213.686107 -85.646975) (xy 213.628356 -85.66905)
			(xy 213.568356 -85.683965) (xy 213.506991 -85.691502) (xy 213.476078 -85.69198) (xy 213.44203 -85.691448)
			(xy 213.374543 -85.682363) (xy 213.308874 -85.664345) (xy 213.2462 -85.637718) (xy 213.187644 -85.602958)
			(xy 213.16061 -85.582252) (xy 213.151392 -85.57574) (xy 213.129452 -85.570598) (xy 213.107425 -85.575353)
			(xy 213.098126 -85.581744) (xy 213.07144 -85.601462) (xy 213.01392 -85.634537) (xy 212.952585 -85.659849)
			(xy 212.88848 -85.676967) (xy 212.822692 -85.6856) (xy 212.789516 -85.686138) (xy 212.757555 -85.685598)
			(xy 212.694136 -85.677588) (xy 212.632222 -85.661693) (xy 212.572788 -85.638163) (xy 212.516772 -85.60737)
			(xy 212.465057 -85.569798) (xy 212.418459 -85.526041) (xy 212.377713 -85.476789) (xy 212.343461 -85.422818)
			(xy 212.316244 -85.36498) (xy 212.29649 -85.304186) (xy 212.284512 -85.241396) (xy 212.280498 -85.1776)
			(xy 196.337084 -85.1776) (xy 196.332278 -85.180201) (xy 196.273513 -85.203135) (xy 196.212363 -85.218623)
			(xy 196.149767 -85.226429) (xy 196.118226 -85.226906) (xy 196.087628 -85.226435) (xy 196.026874 -85.219107)
			(xy 195.967437 -85.204541) (xy 195.910178 -85.182949) (xy 195.855924 -85.154641) (xy 195.805458 -85.120028)
			(xy 195.782184 -85.10016) (xy 195.770838 -85.090881) (xy 195.744271 -85.078537) (xy 195.715293 -85.07425)
			(xy 195.68629 -85.078371) (xy 195.659653 -85.090562) (xy 195.637577 -85.109817) (xy 195.62188 -85.134551)
			(xy 195.613856 -85.162725) (xy 195.613528 -85.177376) (xy 195.613528 -85.182202) (xy 195.61303 -85.213743)
			(xy 195.605227 -85.276341) (xy 195.589741 -85.337493) (xy 195.56681 -85.39626) (xy 195.536785 -85.451739)
			(xy 195.500129 -85.503078) (xy 195.457404 -85.549489) (xy 195.409267 -85.590258) (xy 195.356456 -85.62476)
			(xy 195.299783 -85.652465) (xy 195.240119 -85.672947) (xy 195.178379 -85.685892) (xy 195.115512 -85.6911)
			(xy 195.052483 -85.688492) (xy 194.990262 -85.678108) (xy 194.929802 -85.660107) (xy 194.872033 -85.634766)
			(xy 194.817843 -85.602474) (xy 194.768063 -85.563727) (xy 194.723458 -85.51912) (xy 194.684713 -85.469339)
			(xy 194.652424 -85.415147) (xy 194.627085 -85.357377) (xy 194.609087 -85.296917) (xy 194.598706 -85.234695)
			(xy 194.596101 -85.171666) (xy 181.26647 -85.171666) (xy 182.293768 -86.198964) (xy 182.314088 -86.220209)
			(xy 182.346967 -86.268936) (xy 182.359046 -86.295738) (xy 182.368702 -86.319825) (xy 195.57085 -86.319825)
			(xy 195.57085 -86.255903) (xy 195.578861 -86.192485) (xy 195.594758 -86.130571) (xy 195.61829 -86.071138)
			(xy 195.649084 -86.015123) (xy 195.686657 -85.963408) (xy 195.730414 -85.916811) (xy 195.779667 -85.876066)
			(xy 195.833638 -85.841815) (xy 195.891477 -85.814598) (xy 195.95227 -85.794845) (xy 196.01506 -85.782867)
			(xy 196.078856 -85.778854) (xy 196.142652 -85.782867) (xy 196.205442 -85.794845) (xy 196.266235 -85.814598)
			(xy 196.324074 -85.841815) (xy 196.378045 -85.876066) (xy 196.427298 -85.916811) (xy 196.471055 -85.963408)
			(xy 196.508628 -86.015123) (xy 196.539422 -86.071138) (xy 196.562954 -86.130571) (xy 196.578851 -86.192485)
			(xy 196.586862 -86.255903) (xy 196.587364 -86.287864) (xy 196.586862 -86.319825) (xy 196.578851 -86.383243)
			(xy 196.562954 -86.445157) (xy 196.539422 -86.50459) (xy 196.508628 -86.560605) (xy 196.471055 -86.61232)
			(xy 196.427298 -86.658917) (xy 196.378045 -86.699662) (xy 196.324074 -86.733913) (xy 196.266235 -86.76113)
			(xy 196.205442 -86.780883) (xy 196.142652 -86.792861) (xy 196.078856 -86.796875) (xy 196.01506 -86.792861)
			(xy 195.95227 -86.780883) (xy 195.891477 -86.76113) (xy 195.833638 -86.733913) (xy 195.779667 -86.699662)
			(xy 195.730414 -86.658917) (xy 195.686657 -86.61232) (xy 195.649084 -86.560605) (xy 195.61829 -86.50459)
			(xy 195.594758 -86.445157) (xy 195.578861 -86.383243) (xy 195.57085 -86.319825) (xy 182.368702 -86.319825)
			(xy 182.36931 -86.321341) (xy 182.381452 -86.375142) (xy 182.383176 -86.402672) (xy 182.383176 -87.367618)
			(xy 182.383536 -87.376067) (xy 182.389127 -87.392018) (xy 182.394098 -87.39886) (xy 182.399178 -87.405464)
			(xy 182.413402 -87.414608) (xy 182.421784 -87.41664) (xy 182.441924 -87.421959) (xy 182.481342 -87.435441)
			(xy 182.500524 -87.443564) (xy 182.501032 -87.443564) (xy 182.509695 -87.446855) (xy 182.528195 -87.447649)
			(xy 182.5371 -87.445088) (xy 182.60187 -87.423244) (xy 182.610633 -87.419841) (xy 182.625094 -87.407855)
			(xy 182.630064 -87.399876) (xy 182.630064 -87.399622) (xy 182.644635 -87.374582) (xy 182.680162 -87.328823)
			(xy 182.722198 -87.28896) (xy 182.769775 -87.255908) (xy 182.821802 -87.230428) (xy 182.877083 -87.213104)
			(xy 182.934346 -87.204334) (xy 182.963312 -87.203788) (xy 182.991114 -87.204292) (xy 183.04613 -87.212368)
			(xy 183.099389 -87.228347) (xy 183.149764 -87.25189) (xy 183.196186 -87.282498) (xy 183.237672 -87.319523)
			(xy 183.273342 -87.362179) (xy 183.30244 -87.409562) (xy 183.313832 -87.434928) (xy 183.313832 -87.435182)
			(xy 183.317885 -87.443506) (xy 183.330795 -87.456756) (xy 183.347564 -87.464568) (xy 183.356758 -87.465662)
			(xy 183.357266 -87.465662) (xy 183.447944 -87.47125) (xy 183.454995 -87.471475) (xy 183.468782 -87.468504)
			(xy 183.475122 -87.465408) (xy 183.481218 -87.462106) (xy 183.491124 -87.452708) (xy 183.494934 -87.446358)
			(xy 183.512132 -87.418127) (xy 183.552718 -87.365947) (xy 183.599722 -87.319466) (xy 183.652351 -87.279465)
			(xy 183.709719 -87.24662) (xy 183.770859 -87.221483) (xy 183.83474 -87.204479) (xy 183.900285 -87.195894)
			(xy 183.933338 -87.195406) (xy 183.967008 -87.195949) (xy 184.033758 -87.204836) (xy 184.09875 -87.222463)
			(xy 184.160844 -87.24852) (xy 184.218952 -87.282551) (xy 184.272055 -87.32396) (xy 184.319223 -87.372021)
			(xy 184.359628 -87.425891) (xy 184.376568 -87.454994) (xy 184.378854 -87.45855) (xy 184.384639 -87.46638)
			(xy 184.400735 -87.477299) (xy 184.419748 -87.4814) (xy 184.4294 -87.48014) (xy 184.450261 -87.476827)
			(xy 184.492353 -87.473264) (xy 184.513474 -87.473028) (xy 184.546942 -87.473553) (xy 184.613301 -87.482327)
			(xy 184.677933 -87.499737) (xy 184.739719 -87.525485) (xy 184.797589 -87.559122) (xy 184.82437 -87.5792)
			(xy 184.830974 -87.583518) (xy 184.841642 -87.58936) (xy 184.848754 -87.5919) (xy 184.85707 -87.594486)
			(xy 184.874474 -87.594486) (xy 184.88279 -87.5919) (xy 184.889648 -87.58936) (xy 184.900316 -87.583518)
			(xy 184.907428 -87.578946) (xy 184.9343 -87.558721) (xy 184.992358 -87.524773) (xy 185.054386 -87.498776)
			(xy 185.1193 -87.481184) (xy 185.185966 -87.472303) (xy 185.219594 -87.471758) (xy 185.251559 -87.472239)
			(xy 185.314984 -87.48025) (xy 185.376905 -87.496148) (xy 185.436346 -87.519682) (xy 185.492368 -87.55048)
			(xy 185.544088 -87.588056) (xy 185.590691 -87.631819) (xy 185.631441 -87.681077) (xy 185.665697 -87.735054)
			(xy 185.692917 -87.792899) (xy 185.712672 -87.8537) (xy 185.724651 -87.916497) (xy 185.728666 -87.9803)
			(xy 185.724651 -88.044103) (xy 185.720703 -88.0648) (xy 186.044616 -88.0648) (xy 186.04863 -88.001007)
			(xy 186.060607 -87.938221) (xy 186.080359 -87.87743) (xy 186.107575 -87.819595) (xy 186.141824 -87.765626)
			(xy 186.182568 -87.716376) (xy 186.229163 -87.672621) (xy 186.280874 -87.63505) (xy 186.336887 -87.604257)
			(xy 186.396317 -87.580727) (xy 186.458228 -87.564832) (xy 186.521643 -87.556821) (xy 186.553602 -87.55634)
			(xy 186.585091 -87.556755) (xy 186.647587 -87.564521) (xy 186.708645 -87.579947) (xy 186.767331 -87.602796)
			(xy 186.822746 -87.632719) (xy 186.87404 -87.669256) (xy 186.920429 -87.711849) (xy 186.961201 -87.759846)
			(xy 186.995734 -87.812511) (xy 187.01004 -87.840566) (xy 187.016702 -87.853093) (xy 187.035678 -87.874168)
			(xy 187.059721 -87.889208) (xy 187.086974 -87.897051) (xy 187.115334 -87.897092) (xy 187.14261 -87.889327)
			(xy 187.166696 -87.874357) (xy 187.185733 -87.853337) (xy 187.192412 -87.84082) (xy 187.206731 -87.812834)
			(xy 187.241282 -87.760314) (xy 187.282045 -87.712455) (xy 187.328399 -87.669988) (xy 187.379636 -87.633561)
			(xy 187.434973 -87.60373) (xy 187.493567 -87.58095) (xy 187.554522 -87.56557) (xy 187.616909 -87.557823)
			(xy 187.648342 -87.557356) (xy 187.680299 -87.557932) (xy 187.743709 -87.565948) (xy 187.805614 -87.581847)
			(xy 187.865038 -87.605379) (xy 187.893267 -87.6209) (xy 188.754424 -87.6209) (xy 188.758439 -87.557094)
			(xy 188.770419 -87.494294) (xy 188.790176 -87.433491) (xy 188.817398 -87.375643) (xy 188.851656 -87.321664)
			(xy 188.892409 -87.272404) (xy 188.939015 -87.228641) (xy 188.990739 -87.191064) (xy 189.046764 -87.160266)
			(xy 189.106208 -87.136733) (xy 189.168133 -87.120837) (xy 189.231562 -87.112827) (xy 189.263528 -87.112348)
			(xy 189.264036 -87.112348) (xy 189.293175 -87.112735) (xy 189.351069 -87.119417) (xy 189.407819 -87.132679)
			(xy 189.462679 -87.152345) (xy 189.514929 -87.178158) (xy 189.539626 -87.193628) (xy 189.549786 -87.200232)
			(xy 189.573916 -87.203026) (xy 189.67323 -87.164926) (xy 189.689486 -87.146892) (xy 189.692534 -87.135208)
			(xy 189.701778 -87.103375) (xy 189.727492 -87.042276) (xy 189.760927 -86.985036) (xy 189.801515 -86.932626)
			(xy 189.848568 -86.885933) (xy 189.901289 -86.845749) (xy 189.958785 -86.812756) (xy 190.020079 -86.787512)
			(xy 190.084134 -86.770446) (xy 190.149863 -86.761847) (xy 190.183008 -86.76132) (xy 190.214125 -86.761813)
			(xy 190.275891 -86.769422) (xy 190.336268 -86.784512) (xy 190.38744 -86.8042) (xy 197.387035 -86.8042)
			(xy 197.391049 -86.740412) (xy 197.403024 -86.67763) (xy 197.422774 -86.616844) (xy 197.449987 -86.559012)
			(xy 197.484232 -86.505047) (xy 197.524972 -86.4558) (xy 197.571562 -86.412046) (xy 197.623268 -86.374477)
			(xy 197.679275 -86.343684) (xy 197.7387 -86.320153) (xy 197.800605 -86.304255) (xy 197.864015 -86.296242)
			(xy 197.895972 -86.295738) (xy 197.896226 -86.295738) (xy 197.925935 -86.296147) (xy 197.984946 -86.303084)
			(xy 198.042747 -86.316849) (xy 198.09855 -86.337255) (xy 198.151597 -86.364023) (xy 198.201163 -86.396788)
			(xy 198.22414 -86.415626) (xy 198.233106 -86.422402) (xy 198.254795 -86.428182) (xy 198.276884 -86.424192)
			(xy 198.28637 -86.418166) (xy 198.312218 -86.400434) (xy 198.367448 -86.370787) (xy 198.425903 -86.348151)
			(xy 198.486696 -86.332869) (xy 198.548906 -86.325173) (xy 198.580248 -86.324694) (xy 198.613604 -86.325221)
			(xy 198.679743 -86.333946) (xy 198.744174 -86.351239) (xy 198.805793 -86.376804) (xy 198.863542 -86.410203)
			(xy 198.916432 -86.450863) (xy 198.963554 -86.498085) (xy 199.0041 -86.551061) (xy 199.021192 -86.57971)
			(xy 199.027034 -86.590124) (xy 199.047608 -86.603586) (xy 199.141334 -86.613746) (xy 199.153312 -86.614394)
			(xy 199.175713 -86.605906) (xy 199.18426 -86.59749) (xy 199.184514 -86.597236) (xy 199.205188 -86.575069)
			(xy 199.250967 -86.535335) (xy 199.301144 -86.501323) (xy 199.355008 -86.473517) (xy 199.411794 -86.452309)
			(xy 199.470699 -86.438001) (xy 199.530887 -86.430796) (xy 199.561196 -86.430358) (xy 199.592509 -86.430872)
			(xy 199.654659 -86.438572) (xy 199.715394 -86.453842) (xy 199.773795 -86.476453) (xy 199.828979 -86.506061)
			(xy 199.880111 -86.54222) (xy 199.903588 -86.562946) (xy 199.910956 -86.569048) (xy 199.928825 -86.57584)
			(xy 199.938386 -86.576154) (xy 199.969628 -86.575646) (xy 199.979222 -86.575096) (xy 199.996979 -86.567793)
			(xy 200.004172 -86.561422) (xy 200.027928 -86.53928) (xy 200.080093 -86.500595) (xy 200.136756 -86.468865)
			(xy 200.196998 -86.444605) (xy 200.259837 -86.42821) (xy 200.324253 -86.419947) (xy 200.356724 -86.419436)
			(xy 200.356978 -86.419436) (xy 200.389551 -86.41998) (xy 200.454164 -86.428305) (xy 200.517181 -86.444822)
			(xy 200.577571 -86.469259) (xy 200.634341 -86.501216) (xy 200.660762 -86.520274) (xy 200.669674 -86.5263)
			(xy 200.690649 -86.530987) (xy 200.711703 -86.526669) (xy 200.720706 -86.520782) (xy 200.74665 -86.502802)
			(xy 200.802163 -86.472756) (xy 200.860968 -86.449809) (xy 200.922161 -86.434315) (xy 200.9848 -86.426512)
			(xy 201.016362 -86.42604) (xy 201.04699 -86.426516) (xy 201.107802 -86.433876) (xy 201.167291 -86.448482)
			(xy 201.224597 -86.470124) (xy 201.278891 -86.498487) (xy 201.304398 -86.515448) (xy 201.313307 -86.520979)
			(xy 201.333864 -86.524997) (xy 201.35431 -86.520447) (xy 201.363072 -86.514686) (xy 201.389298 -86.496066)
			(xy 201.445563 -86.464899) (xy 201.505311 -86.441079) (xy 201.567586 -86.424986) (xy 201.631394 -86.416878)
			(xy 201.663554 -86.416388) (xy 201.695518 -86.416874) (xy 201.758942 -86.424881) (xy 201.820863 -86.440775)
			(xy 201.880303 -86.464304) (xy 201.936326 -86.495098) (xy 201.988046 -86.532671) (xy 202.03465 -86.576431)
			(xy 202.075401 -86.625686) (xy 202.109657 -86.679661) (xy 202.136878 -86.737504) (xy 202.154342 -86.791249)
			(xy 203.558134 -86.791249) (xy 203.558134 -86.727327) (xy 203.566145 -86.663909) (xy 203.582042 -86.601995)
			(xy 203.605574 -86.542562) (xy 203.636368 -86.486547) (xy 203.673941 -86.434832) (xy 203.717698 -86.388235)
			(xy 203.766951 -86.34749) (xy 203.820922 -86.313239) (xy 203.878761 -86.286022) (xy 203.939554 -86.266269)
			(xy 204.002344 -86.254291) (xy 204.06614 -86.250278) (xy 204.129936 -86.254291) (xy 204.192726 -86.266269)
			(xy 204.253519 -86.286022) (xy 204.311358 -86.313239) (xy 204.365329 -86.34749) (xy 204.414582 -86.388235)
			(xy 204.458339 -86.434832) (xy 204.495912 -86.486547) (xy 204.526706 -86.542562) (xy 204.550238 -86.601995)
			(xy 204.566135 -86.663909) (xy 204.574146 -86.727327) (xy 204.574648 -86.759288) (xy 204.574146 -86.791249)
			(xy 204.571594 -86.811451) (xy 204.952858 -86.811451) (xy 204.952858 -86.756949) (xy 204.960613 -86.703003)
			(xy 204.975967 -86.650709) (xy 204.998606 -86.601132) (xy 205.02807 -86.555282) (xy 205.063758 -86.514091)
			(xy 205.104945 -86.478397) (xy 205.150792 -86.448928) (xy 205.200366 -86.426283) (xy 205.252658 -86.410923)
			(xy 205.306603 -86.403161) (xy 205.333854 -86.402672) (xy 205.363223 -86.40325) (xy 205.421267 -86.412247)
			(xy 205.477247 -86.430033) (xy 205.529839 -86.456191) (xy 205.5778 -86.4901) (xy 205.619997 -86.53096)
			(xy 205.638146 -86.554056) (xy 205.646274 -86.564724) (xy 205.67015 -86.575138) (xy 205.782672 -86.564724)
			(xy 205.804262 -86.549738) (xy 205.810104 -86.538054) (xy 205.824455 -86.510132) (xy 205.859053 -86.457745)
			(xy 205.899837 -86.410015) (xy 205.946184 -86.367666) (xy 205.997391 -86.331344) (xy 206.052679 -86.3016)
			(xy 206.111207 -86.278886) (xy 206.172086 -86.263548) (xy 206.234389 -86.255819) (xy 206.26578 -86.255352)
			(xy 206.29905 -86.255946) (xy 206.36502 -86.264633) (xy 206.429294 -86.28185) (xy 206.490773 -86.307302)
			(xy 206.548409 -86.340553) (xy 206.601216 -86.381037) (xy 206.648293 -86.428062) (xy 206.688835 -86.480824)
			(xy 206.705962 -86.509352) (xy 206.710709 -86.516876) (xy 206.724313 -86.528321) (xy 206.741015 -86.534412)
			(xy 206.749904 -86.534752) (xy 206.851758 -86.534498) (xy 206.87538 -86.520782) (xy 206.881984 -86.509098)
			(xy 206.899035 -86.480411) (xy 206.939555 -86.427383) (xy 206.986663 -86.380112) (xy 207.039551 -86.33941)
			(xy 207.097308 -86.305977) (xy 207.158943 -86.280386) (xy 207.223396 -86.263079) (xy 207.28956 -86.254352)
			(xy 207.322928 -86.253828) (xy 207.35489 -86.25426) (xy 207.41831 -86.262275) (xy 207.480225 -86.278175)
			(xy 207.53966 -86.30171) (xy 207.595676 -86.332507) (xy 207.647391 -86.370083) (xy 207.693988 -86.413844)
			(xy 207.734734 -86.463099) (xy 207.768985 -86.517073) (xy 207.796202 -86.574914) (xy 207.815955 -86.63571)
			(xy 207.827933 -86.698502) (xy 207.831947 -86.7623) (xy 207.827933 -86.826098) (xy 207.815955 -86.88889)
			(xy 207.796202 -86.949686) (xy 207.768985 -87.007527) (xy 207.734734 -87.061501) (xy 207.693988 -87.110757)
			(xy 207.647391 -87.154517) (xy 207.595676 -87.192093) (xy 207.53966 -87.22289) (xy 207.480225 -87.246425)
			(xy 207.41831 -87.262325) (xy 207.35489 -87.27034) (xy 207.322928 -87.270844) (xy 207.289656 -87.270326)
			(xy 207.223682 -87.261626) (xy 207.159407 -87.244398) (xy 207.097926 -87.218936) (xy 207.040291 -87.185673)
			(xy 206.987486 -87.14518) (xy 206.940411 -87.098146) (xy 206.899872 -87.045375) (xy 206.882746 -87.016844)
			(xy 206.878058 -87.009277) (xy 206.864428 -86.997839) (xy 206.847701 -86.991769) (xy 206.838804 -86.991444)
			(xy 206.73695 -86.991698) (xy 206.713328 -87.005414) (xy 206.706724 -87.017098) (xy 206.689666 -87.045781)
			(xy 206.649147 -87.098808) (xy 206.60204 -87.14608) (xy 206.549154 -87.186782) (xy 206.491397 -87.220216)
			(xy 206.429763 -87.245807) (xy 206.365311 -87.263116) (xy 206.299148 -87.271843) (xy 206.26578 -87.272368)
			(xy 206.235635 -87.271965) (xy 206.175767 -87.264833) (xy 206.117163 -87.250672) (xy 206.060645 -87.22968)
			(xy 206.007005 -87.202152) (xy 205.956997 -87.168475) (xy 205.911322 -87.12912) (xy 205.870622 -87.08464)
			(xy 205.835467 -87.03566) (xy 205.820518 -87.009478) (xy 205.816076 -87.002051) (xy 205.803201 -86.990502)
			(xy 205.787224 -86.983877) (xy 205.778608 -86.983062) (xy 205.692248 -86.978998) (xy 205.683652 -86.978857)
			(xy 205.66716 -86.983672) (xy 205.653224 -86.993721) (xy 205.648052 -87.000588) (xy 205.647798 -87.000842)
			(xy 205.632471 -87.022284) (xy 205.596853 -87.061134) (xy 205.556225 -87.094709) (xy 205.511362 -87.122373)
			(xy 205.463117 -87.143597) (xy 205.412411 -87.157977) (xy 205.360207 -87.16524) (xy 205.333854 -87.165688)
			(xy 205.306603 -87.165239) (xy 205.252658 -87.157477) (xy 205.200366 -87.142117) (xy 205.150792 -87.119472)
			(xy 205.104945 -87.090003) (xy 205.063758 -87.054309) (xy 205.02807 -87.013118) (xy 204.998606 -86.967268)
			(xy 204.975967 -86.917691) (xy 204.960613 -86.865397) (xy 204.952858 -86.811451) (xy 204.571594 -86.811451)
			(xy 204.566135 -86.854667) (xy 204.550238 -86.916581) (xy 204.526706 -86.976014) (xy 204.495912 -87.032029)
			(xy 204.458339 -87.083744) (xy 204.414582 -87.130341) (xy 204.365329 -87.171086) (xy 204.311358 -87.205337)
			(xy 204.253519 -87.232554) (xy 204.192726 -87.252307) (xy 204.129936 -87.264285) (xy 204.06614 -87.268299)
			(xy 204.002344 -87.264285) (xy 203.939554 -87.252307) (xy 203.878761 -87.232554) (xy 203.820922 -87.205337)
			(xy 203.766951 -87.171086) (xy 203.717698 -87.130341) (xy 203.673941 -87.083744) (xy 203.636368 -87.032029)
			(xy 203.605574 -86.976014) (xy 203.582042 -86.916581) (xy 203.566145 -86.854667) (xy 203.558134 -86.791249)
			(xy 202.154342 -86.791249) (xy 202.156634 -86.798303) (xy 202.168613 -86.861098) (xy 202.172628 -86.9249)
			(xy 202.168613 -86.988702) (xy 202.156634 -87.051497) (xy 202.136878 -87.112296) (xy 202.109657 -87.170139)
			(xy 202.075401 -87.224114) (xy 202.03465 -87.273369) (xy 201.988046 -87.317129) (xy 201.936326 -87.354702)
			(xy 201.880303 -87.385496) (xy 201.820863 -87.409025) (xy 201.758942 -87.424919) (xy 201.695518 -87.432926)
			(xy 201.663554 -87.433404) (xy 201.632926 -87.43293) (xy 201.572113 -87.425571) (xy 201.512624 -87.410965)
			(xy 201.455318 -87.389323) (xy 201.401024 -87.360958) (xy 201.375518 -87.343996) (xy 201.366603 -87.338475)
			(xy 201.346049 -87.334448) (xy 201.325604 -87.338996) (xy 201.316844 -87.344758) (xy 201.290617 -87.363376)
			(xy 201.234352 -87.394543) (xy 201.174604 -87.418363) (xy 201.11233 -87.434456) (xy 201.048522 -87.442565)
			(xy 201.016362 -87.443056) (xy 201.016108 -87.443056) (xy 200.983534 -87.442521) (xy 200.918922 -87.434194)
			(xy 200.855904 -87.417675) (xy 200.795514 -87.393236) (xy 200.738745 -87.361277) (xy 200.712324 -87.342218)
			(xy 200.703419 -87.33618) (xy 200.68244 -87.331497) (xy 200.661383 -87.33582) (xy 200.65238 -87.34171)
			(xy 200.62641 -87.359651) (xy 200.570904 -87.389704) (xy 200.512106 -87.412659) (xy 200.450919 -87.428161)
			(xy 200.388284 -87.435974) (xy 200.356724 -87.436452) (xy 200.325412 -87.435923) (xy 200.263262 -87.428226)
			(xy 200.202527 -87.412958) (xy 200.144126 -87.390351) (xy 200.088942 -87.360745) (xy 200.037809 -87.324589)
			(xy 200.014332 -87.303864) (xy 200.006957 -87.297771) (xy 199.989093 -87.290973) (xy 199.979534 -87.290656)
			(xy 199.948292 -87.291164) (xy 199.938699 -87.291721) (xy 199.920941 -87.299018) (xy 199.913748 -87.305388)
			(xy 199.889968 -87.327505) (xy 199.837811 -87.366195) (xy 199.781153 -87.397931) (xy 199.720915 -87.422196)
			(xy 199.658079 -87.438595) (xy 199.593666 -87.446861) (xy 199.561196 -87.447374) (xy 199.527838 -87.446908)
			(xy 199.461696 -87.438175) (xy 199.397262 -87.420874) (xy 199.335642 -87.3953) (xy 199.277893 -87.361893)
			(xy 199.225005 -87.321225) (xy 199.177885 -87.273994) (xy 199.137342 -87.221011) (xy 199.120252 -87.192358)
			(xy 199.11441 -87.181944) (xy 199.093836 -87.168482) (xy 199.00011 -87.158322) (xy 198.988132 -87.157681)
			(xy 198.96573 -87.166161) (xy 198.957184 -87.174578) (xy 198.95693 -87.174832) (xy 198.936227 -87.196971)
			(xy 198.890454 -87.236708) (xy 198.840283 -87.270724) (xy 198.786424 -87.298534) (xy 198.729642 -87.319746)
			(xy 198.67074 -87.334059) (xy 198.610556 -87.341269) (xy 198.580248 -87.34171) (xy 198.579994 -87.34171)
			(xy 198.550286 -87.341278) (xy 198.491276 -87.334344) (xy 198.433476 -87.320582) (xy 198.377672 -87.300181)
			(xy 198.324626 -87.273418) (xy 198.275058 -87.240657) (xy 198.25208 -87.221822) (xy 198.243103 -87.21506)
			(xy 198.22142 -87.209269) (xy 198.199334 -87.213256) (xy 198.18985 -87.219282) (xy 198.163992 -87.236999)
			(xy 198.108765 -87.26665) (xy 198.050313 -87.289289) (xy 197.989522 -87.304574) (xy 197.927314 -87.312274)
			(xy 197.895972 -87.312754) (xy 197.864015 -87.312158) (xy 197.800605 -87.304145) (xy 197.7387 -87.288247)
			(xy 197.679275 -87.264716) (xy 197.623268 -87.233923) (xy 197.571562 -87.196354) (xy 197.524972 -87.1526)
			(xy 197.484232 -87.103353) (xy 197.449987 -87.049388) (xy 197.422774 -86.991556) (xy 197.403024 -86.93077)
			(xy 197.391049 -86.867988) (xy 197.387035 -86.8042) (xy 190.38744 -86.8042) (xy 190.394351 -86.806859)
			(xy 190.449272 -86.836128) (xy 190.500211 -86.871881) (xy 190.523622 -86.892384) (xy 190.531913 -86.899252)
			(xy 190.552396 -86.905836) (xy 190.573783 -86.903496) (xy 190.583312 -86.89848) (xy 190.612583 -86.881993)
			(xy 190.674557 -86.856057) (xy 190.739409 -86.838515) (xy 190.806007 -86.829673) (xy 190.839598 -86.829138)
			(xy 190.874032 -86.829681) (xy 190.942272 -86.83897) (xy 191.008631 -86.857392) (xy 191.071894 -86.884608)
			(xy 191.130901 -86.92012) (xy 191.18457 -86.963277) (xy 191.20866 -86.987888) (xy 191.214965 -86.994046)
			(xy 191.230694 -87.001969) (xy 191.239394 -87.003382) (xy 191.269366 -87.006938) (xy 191.278055 -87.00769)
			(xy 191.29507 -87.003906) (xy 191.30264 -86.999572) (xy 191.325505 -86.985723) (xy 191.374307 -86.963907)
			(xy 191.425675 -86.949109) (xy 191.478604 -86.941618) (xy 191.505332 -86.941152) (xy 191.505586 -86.941152)
			(xy 191.532837 -86.941694) (xy 191.586783 -86.949449) (xy 191.639077 -86.964802) (xy 191.688654 -86.987441)
			(xy 191.734504 -87.016906) (xy 191.775694 -87.052596) (xy 191.811386 -87.093785) (xy 191.840852 -87.139634)
			(xy 191.863493 -87.189209) (xy 191.878848 -87.241503) (xy 191.886605 -87.295449) (xy 191.886605 -87.347763)
			(xy 192.086224 -87.347763) (xy 192.086224 -87.283841) (xy 192.094235 -87.220423) (xy 192.110132 -87.158509)
			(xy 192.133664 -87.099076) (xy 192.164458 -87.043061) (xy 192.202031 -86.991346) (xy 192.245788 -86.944749)
			(xy 192.295041 -86.904004) (xy 192.349012 -86.869753) (xy 192.406851 -86.842536) (xy 192.467644 -86.822783)
			(xy 192.530434 -86.810805) (xy 192.59423 -86.806792) (xy 192.658026 -86.810805) (xy 192.720816 -86.822783)
			(xy 192.781609 -86.842536) (xy 192.839448 -86.869753) (xy 192.893419 -86.904004) (xy 192.942672 -86.944749)
			(xy 192.986429 -86.991346) (xy 193.024002 -87.043061) (xy 193.054796 -87.099076) (xy 193.078328 -87.158509)
			(xy 193.094225 -87.220423) (xy 193.102236 -87.283841) (xy 193.102738 -87.315802) (xy 193.102236 -87.347763)
			(xy 193.094225 -87.411181) (xy 193.078328 -87.473095) (xy 193.054796 -87.532528) (xy 193.047431 -87.545926)
			(xy 217.14333 -87.545926) (xy 217.143786 -87.519446) (xy 217.151096 -87.466995) (xy 217.165594 -87.416059)
			(xy 217.187 -87.367619) (xy 217.214902 -87.322607) (xy 217.248764 -87.281888) (xy 217.268044 -87.263732)
			(xy 217.274145 -87.257789) (xy 217.282323 -87.242862) (xy 217.284046 -87.234522) (xy 217.288872 -87.205312)
			(xy 217.289957 -87.196676) (xy 217.286982 -87.179539) (xy 217.28303 -87.171784) (xy 217.267376 -87.143018)
			(xy 217.242698 -87.082356) (xy 217.226014 -87.019027) (xy 217.2176 -86.95408) (xy 217.217596 -86.88859)
			(xy 217.226001 -86.823642) (xy 217.242676 -86.76031) (xy 217.267345 -86.699645) (xy 217.28303 -86.670896)
			(xy 217.287017 -86.663151) (xy 217.290006 -86.646004) (xy 217.288872 -86.637368) (xy 217.284046 -86.608158)
			(xy 217.28231 -86.599823) (xy 217.274133 -86.584899) (xy 217.268044 -86.578948) (xy 217.248766 -86.560791)
			(xy 217.214918 -86.520064) (xy 217.187023 -86.475049) (xy 217.165618 -86.426611) (xy 217.151113 -86.37568)
			(xy 217.143786 -86.323232) (xy 217.14333 -86.296754) (xy 217.143816 -86.269503) (xy 217.151572 -86.215555)
			(xy 217.166927 -86.16326) (xy 217.189569 -86.113683) (xy 217.219035 -86.067833) (xy 217.254726 -86.026642)
			(xy 217.295917 -85.990951) (xy 217.341767 -85.961485) (xy 217.391344 -85.938843) (xy 217.443639 -85.923488)
			(xy 217.497587 -85.915732) (xy 217.552089 -85.915732) (xy 217.606037 -85.923488) (xy 217.658332 -85.938843)
			(xy 217.707909 -85.961485) (xy 217.753759 -85.990951) (xy 217.79495 -86.026642) (xy 217.830641 -86.067833)
			(xy 217.860107 -86.113683) (xy 217.882749 -86.16326) (xy 217.898104 -86.215555) (xy 217.90586 -86.269503)
			(xy 217.906346 -86.296754) (xy 217.906099 -86.316845) (xy 217.901898 -86.356806) (xy 217.897964 -86.37651)
			(xy 217.896483 -86.38495) (xy 217.898555 -86.401951) (xy 217.902028 -86.409784) (xy 217.915236 -86.436454)
			(xy 217.919358 -86.444046) (xy 217.931684 -86.456128) (xy 217.939366 -86.460076) (xy 217.968361 -86.474083)
			(xy 218.022884 -86.508347) (xy 218.048078 -86.528402) (xy 218.055083 -86.533664) (xy 218.071581 -86.539516)
			(xy 218.080336 -86.539832) (xy 218.23426 -86.539832) (xy 218.243009 -86.539489) (xy 218.2595 -86.533637)
			(xy 218.266518 -86.528402) (xy 218.291708 -86.508342) (xy 218.346233 -86.474081) (xy 218.37523 -86.460076)
			(xy 218.3829 -86.456107) (xy 218.39524 -86.444043) (xy 218.39936 -86.436454) (xy 218.412568 -86.409784)
			(xy 218.416075 -86.401959) (xy 218.418155 -86.384949) (xy 218.416632 -86.37651) (xy 218.412701 -86.356806)
			(xy 218.408496 -86.316845) (xy 218.40825 -86.296754) (xy 218.408736 -86.269503) (xy 218.416492 -86.215555)
			(xy 218.431847 -86.16326) (xy 218.454489 -86.113683) (xy 218.483955 -86.067833) (xy 218.519646 -86.026642)
			(xy 218.560837 -85.990951) (xy 218.606687 -85.961485) (xy 218.656264 -85.938843) (xy 218.708559 -85.923488)
			(xy 218.762507 -85.915732) (xy 218.817009 -85.915732) (xy 218.870957 -85.923488) (xy 218.923252 -85.938843)
			(xy 218.972829 -85.961485) (xy 219.018679 -85.990951) (xy 219.05987 -86.026642) (xy 219.095561 -86.067833)
			(xy 219.125027 -86.113683) (xy 219.147669 -86.16326) (xy 219.163024 -86.215555) (xy 219.17078 -86.269503)
			(xy 219.171266 -86.296754) (xy 219.170798 -86.323233) (xy 219.16349 -86.375684) (xy 219.148995 -86.42662)
			(xy 219.127592 -86.47506) (xy 219.099691 -86.520072) (xy 219.065831 -86.560791) (xy 219.046552 -86.578948)
			(xy 219.040458 -86.584896) (xy 219.032276 -86.599819) (xy 219.03055 -86.608158) (xy 219.025724 -86.637368)
			(xy 219.0246 -86.646002) (xy 219.027601 -86.663143) (xy 219.031566 -86.670896) (xy 219.047286 -86.699627)
			(xy 219.071958 -86.760298) (xy 219.088635 -86.823634) (xy 219.09704 -86.888587) (xy 219.097036 -86.954082)
			(xy 219.088621 -87.019034) (xy 219.071936 -87.082368) (xy 219.047256 -87.143035) (xy 219.031566 -87.171784)
			(xy 219.027588 -87.179533) (xy 219.024594 -87.196676) (xy 219.025724 -87.205312) (xy 219.03055 -87.234522)
			(xy 219.032295 -87.242855) (xy 219.040465 -87.25778) (xy 219.046552 -87.263732) (xy 219.065819 -87.2819)
			(xy 219.099669 -87.322624) (xy 219.127565 -87.367637) (xy 219.148972 -87.416073) (xy 219.163479 -87.467002)
			(xy 219.170809 -87.519448) (xy 219.171266 -87.545926) (xy 219.17078 -87.573177) (xy 219.163024 -87.627125)
			(xy 219.147669 -87.67942) (xy 219.125027 -87.728997) (xy 219.095561 -87.774847) (xy 219.05987 -87.816038)
			(xy 219.018679 -87.851729) (xy 218.972829 -87.881195) (xy 218.923252 -87.903837) (xy 218.870957 -87.919192)
			(xy 218.817009 -87.926948) (xy 218.762507 -87.926948) (xy 218.708559 -87.919192) (xy 218.656264 -87.903837)
			(xy 218.606687 -87.881195) (xy 218.560837 -87.851729) (xy 218.519646 -87.816038) (xy 218.483955 -87.774847)
			(xy 218.454489 -87.728997) (xy 218.431847 -87.67942) (xy 218.416492 -87.627125) (xy 218.408736 -87.573177)
			(xy 218.40825 -87.545926) (xy 218.408494 -87.525835) (xy 218.412697 -87.485874) (xy 218.416632 -87.46617)
			(xy 218.418123 -87.457731) (xy 218.416045 -87.440729) (xy 218.412568 -87.432896) (xy 218.39936 -87.406226)
			(xy 218.395246 -87.39863) (xy 218.382914 -87.38655) (xy 218.37523 -87.382604) (xy 218.346233 -87.368599)
			(xy 218.291711 -87.334334) (xy 218.266518 -87.314278) (xy 218.259515 -87.309013) (xy 218.243015 -87.303163)
			(xy 218.23426 -87.302848) (xy 218.080336 -87.302848) (xy 218.071585 -87.303173) (xy 218.055094 -87.309035)
			(xy 218.048078 -87.314278) (xy 218.022877 -87.334324) (xy 217.96836 -87.368594) (xy 217.939366 -87.382604)
			(xy 217.931699 -87.386578) (xy 217.919358 -87.398639) (xy 217.915236 -87.406226) (xy 217.902028 -87.432896)
			(xy 217.89853 -87.440725) (xy 217.896445 -87.457732) (xy 217.897964 -87.46617) (xy 217.901907 -87.485872)
			(xy 217.906104 -87.525835) (xy 217.906346 -87.545926) (xy 217.90586 -87.573177) (xy 217.898104 -87.627125)
			(xy 217.882749 -87.67942) (xy 217.860107 -87.728997) (xy 217.830641 -87.774847) (xy 217.79495 -87.816038)
			(xy 217.753759 -87.851729) (xy 217.707909 -87.881195) (xy 217.658332 -87.903837) (xy 217.606037 -87.919192)
			(xy 217.552089 -87.926948) (xy 217.497587 -87.926948) (xy 217.443639 -87.919192) (xy 217.391344 -87.903837)
			(xy 217.341767 -87.881195) (xy 217.295917 -87.851729) (xy 217.254726 -87.816038) (xy 217.219035 -87.774847)
			(xy 217.189569 -87.728997) (xy 217.166927 -87.67942) (xy 217.151572 -87.627125) (xy 217.143816 -87.573177)
			(xy 217.14333 -87.545926) (xy 193.047431 -87.545926) (xy 193.024002 -87.588543) (xy 192.986429 -87.640258)
			(xy 192.942672 -87.686855) (xy 192.893419 -87.7276) (xy 192.839448 -87.761851) (xy 192.781609 -87.789068)
			(xy 192.720816 -87.808821) (xy 192.658026 -87.820799) (xy 192.59423 -87.824813) (xy 192.530434 -87.820799)
			(xy 192.467644 -87.808821) (xy 192.406851 -87.789068) (xy 192.349012 -87.761851) (xy 192.295041 -87.7276)
			(xy 192.245788 -87.686855) (xy 192.202031 -87.640258) (xy 192.164458 -87.588543) (xy 192.133664 -87.532528)
			(xy 192.110132 -87.473095) (xy 192.094235 -87.411181) (xy 192.086224 -87.347763) (xy 191.886605 -87.347763)
			(xy 191.886605 -87.349951) (xy 191.878848 -87.403897) (xy 191.863493 -87.456191) (xy 191.840852 -87.505766)
			(xy 191.811386 -87.551615) (xy 191.775694 -87.592804) (xy 191.734504 -87.628494) (xy 191.688654 -87.657959)
			(xy 191.639077 -87.680598) (xy 191.586783 -87.695951) (xy 191.532837 -87.703706) (xy 191.505586 -87.704168)
			(xy 191.480967 -87.7038) (xy 191.43214 -87.697448) (xy 191.38454 -87.684852) (xy 191.338961 -87.666223)
			(xy 191.317372 -87.654384) (xy 191.309687 -87.65043) (xy 191.292672 -87.64745) (xy 191.284098 -87.648542)
			(xy 191.254126 -87.653622) (xy 191.245518 -87.655412) (xy 191.230186 -87.66399) (xy 191.224154 -87.670386)
			(xy 191.203431 -87.693657) (xy 191.157196 -87.735437) (xy 191.106203 -87.771255) (xy 191.051217 -87.800576)
			(xy 190.99306 -87.82296) (xy 190.932605 -87.838071) (xy 190.870756 -87.845683) (xy 190.839598 -87.846154)
			(xy 190.808481 -87.845664) (xy 190.746714 -87.838055) (xy 190.686338 -87.822965) (xy 190.628254 -87.800618)
			(xy 190.573333 -87.771348) (xy 190.522395 -87.735594) (xy 190.498984 -87.71509) (xy 190.49069 -87.708227)
			(xy 190.470209 -87.701644) (xy 190.448823 -87.703981) (xy 190.439294 -87.708994) (xy 190.41002 -87.725477)
			(xy 190.348047 -87.751414) (xy 190.283196 -87.768957) (xy 190.216599 -87.7778) (xy 190.183008 -87.778336)
			(xy 190.1825 -87.778336) (xy 190.153361 -87.777934) (xy 190.095468 -87.771256) (xy 190.038718 -87.757998)
			(xy 189.983858 -87.738335) (xy 189.931607 -87.712525) (xy 189.90691 -87.697056) (xy 189.89675 -87.690452)
			(xy 189.87262 -87.687658) (xy 189.773306 -87.725758) (xy 189.75705 -87.743792) (xy 189.754002 -87.755476)
			(xy 189.744715 -87.787296) (xy 189.719005 -87.848393) (xy 189.685576 -87.905632) (xy 189.644992 -87.958042)
			(xy 189.597944 -88.004736) (xy 189.545228 -88.044921) (xy 189.487737 -88.077916) (xy 189.426447 -88.103162)
			(xy 189.362397 -88.120231) (xy 189.296671 -88.128834) (xy 189.263528 -88.129364) (xy 189.231562 -88.128973)
			(xy 189.168133 -88.120963) (xy 189.106208 -88.105067) (xy 189.046764 -88.081534) (xy 188.990739 -88.050736)
			(xy 188.939015 -88.013159) (xy 188.892409 -87.969396) (xy 188.851656 -87.920136) (xy 188.817398 -87.866157)
			(xy 188.790176 -87.808309) (xy 188.770419 -87.747506) (xy 188.758439 -87.684706) (xy 188.754424 -87.6209)
			(xy 187.893267 -87.6209) (xy 187.921045 -87.636173) (xy 187.972751 -87.673743) (xy 188.01934 -87.717498)
			(xy 188.060079 -87.766746) (xy 188.094324 -87.820711) (xy 188.121536 -87.878543) (xy 188.141286 -87.93933)
			(xy 188.153262 -88.002112) (xy 188.157275 -88.0659) (xy 188.153262 -88.129688) (xy 188.141286 -88.19247)
			(xy 188.121536 -88.253257) (xy 188.094324 -88.311089) (xy 188.060079 -88.365054) (xy 188.01934 -88.414302)
			(xy 187.972751 -88.458057) (xy 187.921045 -88.495627) (xy 187.865038 -88.526421) (xy 187.805614 -88.549953)
			(xy 187.743709 -88.565852) (xy 187.680299 -88.573868) (xy 187.648342 -88.574372) (xy 187.616855 -88.573913)
			(xy 187.55436 -88.566153) (xy 187.493303 -88.550733) (xy 187.434618 -88.527889) (xy 187.379204 -88.497972)
			(xy 187.327909 -88.46144) (xy 187.28152 -88.418851) (xy 187.240745 -88.37086) (xy 187.206211 -88.318199)
			(xy 187.191904 -88.290146) (xy 187.185328 -88.277569) (xy 187.166338 -88.256486) (xy 187.142279 -88.241442)
			(xy 187.115009 -88.233601) (xy 187.086634 -88.233567) (xy 187.059346 -88.241343) (xy 187.035251 -88.256328)
			(xy 187.01621 -88.277366) (xy 187.009532 -88.289892) (xy 186.995217 -88.317881) (xy 186.96067 -88.370405)
			(xy 186.919908 -88.418267) (xy 186.873555 -88.460737) (xy 186.822317 -88.497165) (xy 186.766978 -88.526996)
			(xy 186.708382 -88.549774) (xy 186.647425 -88.565151) (xy 186.585036 -88.572893) (xy 186.553602 -88.573356)
			(xy 186.521643 -88.572779) (xy 186.458228 -88.564768) (xy 186.396317 -88.548873) (xy 186.336887 -88.525343)
			(xy 186.280874 -88.49455) (xy 186.229163 -88.456979) (xy 186.182568 -88.413224) (xy 186.141824 -88.363974)
			(xy 186.107575 -88.310005) (xy 186.080359 -88.25217) (xy 186.060607 -88.191379) (xy 186.04863 -88.128593)
			(xy 186.044616 -88.0648) (xy 185.720703 -88.0648) (xy 185.712672 -88.1069) (xy 185.692917 -88.167701)
			(xy 185.665697 -88.225546) (xy 185.631441 -88.279523) (xy 185.590691 -88.328781) (xy 185.544088 -88.372544)
			(xy 185.492368 -88.41012) (xy 185.436346 -88.440918) (xy 185.376905 -88.464452) (xy 185.314984 -88.48035)
			(xy 185.251559 -88.488361) (xy 185.219594 -88.488774) (xy 185.186127 -88.488246) (xy 185.11977 -88.47947)
			(xy 185.05514 -88.462055) (xy 184.993357 -88.436306) (xy 184.935489 -88.402666) (xy 184.908698 -88.382602)
			(xy 184.902094 -88.378284) (xy 184.891426 -88.372442) (xy 184.884314 -88.369902) (xy 184.875998 -88.367316)
			(xy 184.858594 -88.367316) (xy 184.850278 -88.369902) (xy 184.84342 -88.372442) (xy 184.832752 -88.378284)
			(xy 184.82564 -88.382856) (xy 184.798768 -88.403079) (xy 184.740708 -88.437023) (xy 184.67868 -88.463016)
			(xy 184.613767 -88.480605) (xy 184.547101 -88.489481) (xy 184.513474 -88.490044) (xy 184.479803 -88.489502)
			(xy 184.41305 -88.480617) (xy 184.348056 -88.462992) (xy 184.285959 -88.436937) (xy 184.227848 -88.402909)
			(xy 184.17474 -88.361502) (xy 184.127567 -88.313444) (xy 184.087155 -88.259576) (xy 184.070244 -88.230456)
			(xy 184.067958 -88.2269) (xy 184.062173 -88.219076) (xy 184.046077 -88.208174) (xy 184.027068 -88.2041)
			(xy 184.017412 -88.20531) (xy 183.996551 -88.208624) (xy 183.954459 -88.212188) (xy 183.933338 -88.212422)
			(xy 183.901383 -88.211917) (xy 183.837978 -88.203901) (xy 183.776077 -88.188003) (xy 183.716657 -88.164474)
			(xy 183.660652 -88.133684) (xy 183.608948 -88.09612) (xy 183.562358 -88.052373) (xy 183.521616 -88.003133)
			(xy 183.487366 -87.949175) (xy 183.460148 -87.891352) (xy 183.449722 -87.86114) (xy 183.447944 -87.85606)
			(xy 183.445701 -87.851338) (xy 183.439552 -87.842886) (xy 183.435752 -87.839296) (xy 183.435244 -87.838788)
			(xy 183.416702 -87.822278) (xy 183.411323 -87.817742) (xy 183.398691 -87.811557) (xy 183.39181 -87.810086)
			(xy 183.31688 -87.79637) (xy 183.30989 -87.795364) (xy 183.295845 -87.796788) (xy 183.289194 -87.799164)
			(xy 183.28259 -87.801704) (xy 183.271668 -87.809832) (xy 183.26735 -87.815674) (xy 183.249199 -87.838727)
			(xy 183.207016 -87.879508) (xy 183.159089 -87.913353) (xy 183.106546 -87.939464) (xy 183.050627 -87.957227)
			(xy 182.992648 -87.966223) (xy 182.963312 -87.966804) (xy 182.948774 -87.966627) (xy 182.919786 -87.964336)
			(xy 182.9054 -87.962232) (xy 182.904892 -87.962232) (xy 182.895748 -87.960962) (xy 182.886858 -87.96274)
			(xy 182.882204 -87.963852) (xy 182.873386 -87.967563) (xy 182.869332 -87.970106) (xy 182.812436 -88.007698)
			(xy 182.804791 -88.013082) (xy 182.793837 -88.02822) (xy 182.7911 -88.037162) (xy 182.7911 -88.037416)
			(xy 182.783074 -88.066679) (xy 182.760997 -88.123202) (xy 182.732356 -88.176699) (xy 182.697558 -88.226411)
			(xy 182.657096 -88.271634) (xy 182.611545 -88.311725) (xy 182.561551 -88.346117) (xy 182.507822 -88.37432)
			(xy 182.451121 -88.395936) (xy 182.421784 -88.403684) (xy 182.413402 -88.405716) (xy 182.399178 -88.41486)
			(xy 182.394098 -88.421464) (xy 182.389096 -88.428289) (xy 182.383507 -88.444251) (xy 182.383176 -88.452706)
			(xy 182.383176 -89.027465) (xy 213.425272 -89.027465) (xy 213.425272 -88.963543) (xy 213.433283 -88.900125)
			(xy 213.44918 -88.838211) (xy 213.472712 -88.778778) (xy 213.503506 -88.722763) (xy 213.541079 -88.671048)
			(xy 213.584836 -88.624451) (xy 213.634089 -88.583706) (xy 213.68806 -88.549455) (xy 213.745899 -88.522238)
			(xy 213.806692 -88.502485) (xy 213.869482 -88.490507) (xy 213.933278 -88.486494) (xy 213.997074 -88.490507)
			(xy 214.059864 -88.502485) (xy 214.120657 -88.522238) (xy 214.178496 -88.549455) (xy 214.232467 -88.583706)
			(xy 214.28172 -88.624451) (xy 214.325477 -88.671048) (xy 214.36305 -88.722763) (xy 214.393844 -88.778778)
			(xy 214.417376 -88.838211) (xy 214.433273 -88.900125) (xy 214.441284 -88.963543) (xy 214.441786 -88.995504)
			(xy 214.441284 -89.027465) (xy 214.433273 -89.090883) (xy 214.417376 -89.152797) (xy 214.393844 -89.21223)
			(xy 214.36305 -89.268245) (xy 214.325477 -89.31996) (xy 214.28172 -89.366557) (xy 214.232467 -89.407302)
			(xy 214.178496 -89.441553) (xy 214.120657 -89.46877) (xy 214.059864 -89.488523) (xy 213.997074 -89.500501)
			(xy 213.933278 -89.504515) (xy 213.869482 -89.500501) (xy 213.806692 -89.488523) (xy 213.745899 -89.46877)
			(xy 213.68806 -89.441553) (xy 213.634089 -89.407302) (xy 213.584836 -89.366557) (xy 213.541079 -89.31996)
			(xy 213.503506 -89.268245) (xy 213.472712 -89.21223) (xy 213.44918 -89.152797) (xy 213.433283 -89.090883)
			(xy 213.425272 -89.027465) (xy 182.383176 -89.027465) (xy 182.383176 -89.795858) (xy 248.499376 -89.795858)
			(xy 248.499814 -89.764759) (xy 248.507394 -89.703024) (xy 248.522448 -89.642675) (xy 248.544752 -89.584613)
			(xy 248.573972 -89.529705) (xy 248.609671 -89.478771) (xy 248.651317 -89.432573) (xy 248.698288 -89.3918)
			(xy 248.749881 -89.357062) (xy 248.805327 -89.328876) (xy 248.834402 -89.31783) (xy 248.84761 -89.313004)
			(xy 248.864882 -89.292176) (xy 248.881392 -89.19083) (xy 248.882498 -89.18186) (xy 248.8791 -89.164126)
			(xy 248.869714 -89.148701) (xy 248.86285 -89.142824) (xy 248.837541 -89.122081) (xy 248.791914 -89.075173)
			(xy 248.752679 -89.022801) (xy 248.720484 -88.965831) (xy 248.695861 -88.905201) (xy 248.679216 -88.841915)
			(xy 248.670825 -88.777017) (xy 248.670318 -88.744298) (xy 248.670736 -88.713565) (xy 248.678145 -88.652547)
			(xy 248.692856 -88.592867) (xy 248.714653 -88.535395) (xy 248.743219 -88.48097) (xy 248.778137 -88.430385)
			(xy 248.818898 -88.384378) (xy 248.864907 -88.343619) (xy 248.915494 -88.308704) (xy 248.969921 -88.280141)
			(xy 249.027393 -88.258347) (xy 249.087074 -88.24364) (xy 249.148093 -88.236234) (xy 249.178826 -88.23579)
			(xy 249.209151 -88.2362) (xy 249.26937 -88.243421) (xy 249.328301 -88.257757) (xy 249.385108 -88.279006)
			(xy 249.438982 -88.306864) (xy 249.489157 -88.340936) (xy 249.512328 -88.360504) (xy 249.519726 -88.366474)
			(xy 249.537619 -88.372858) (xy 249.547126 -88.37295) (xy 249.625612 -88.370664) (xy 249.643138 -88.363298)
			(xy 249.649996 -88.35644) (xy 249.673813 -88.333926) (xy 249.726216 -88.294563) (xy 249.783242 -88.26226)
			(xy 249.843946 -88.237552) (xy 249.907322 -88.220848) (xy 249.972318 -88.212425) (xy 250.005088 -88.211914)
			(xy 250.037052 -88.21235) (xy 250.100477 -88.220361) (xy 250.162397 -88.236258) (xy 250.221837 -88.259791)
			(xy 250.277858 -88.290588) (xy 250.329578 -88.328163) (xy 250.37618 -88.371925) (xy 250.41693 -88.421182)
			(xy 250.451185 -88.475158) (xy 250.478405 -88.533002) (xy 250.49816 -88.593802) (xy 250.510139 -88.656598)
			(xy 250.514154 -88.7204) (xy 250.510139 -88.784202) (xy 250.49816 -88.846998) (xy 250.485987 -88.884463)
			(xy 252.07188 -88.884463) (xy 252.07188 -88.820541) (xy 252.079891 -88.757123) (xy 252.095788 -88.695209)
			(xy 252.11932 -88.635776) (xy 252.150114 -88.579761) (xy 252.187687 -88.528046) (xy 252.231444 -88.481449)
			(xy 252.280697 -88.440704) (xy 252.334668 -88.406453) (xy 252.392507 -88.379236) (xy 252.4533 -88.359483)
			(xy 252.51609 -88.347505) (xy 252.579886 -88.343492) (xy 252.643682 -88.347505) (xy 252.706472 -88.359483)
			(xy 252.767265 -88.379236) (xy 252.825104 -88.406453) (xy 252.879075 -88.440704) (xy 252.928328 -88.481449)
			(xy 252.972085 -88.528046) (xy 253.009658 -88.579761) (xy 253.040452 -88.635776) (xy 253.063984 -88.695209)
			(xy 253.079881 -88.757123) (xy 253.087892 -88.820541) (xy 253.088394 -88.852502) (xy 253.087892 -88.884463)
			(xy 253.079881 -88.947881) (xy 253.078621 -88.952789) (xy 257.75005 -88.952789) (xy 257.75005 -88.888867)
			(xy 257.758061 -88.825449) (xy 257.773958 -88.763535) (xy 257.79749 -88.704102) (xy 257.828284 -88.648087)
			(xy 257.865857 -88.596372) (xy 257.909614 -88.549775) (xy 257.958867 -88.50903) (xy 258.012838 -88.474779)
			(xy 258.070677 -88.447562) (xy 258.13147 -88.427809) (xy 258.19426 -88.415831) (xy 258.258056 -88.411818)
			(xy 258.321852 -88.415831) (xy 258.384642 -88.427809) (xy 258.445435 -88.447562) (xy 258.503274 -88.474779)
			(xy 258.557245 -88.50903) (xy 258.606498 -88.549775) (xy 258.650255 -88.596372) (xy 258.687828 -88.648087)
			(xy 258.718622 -88.704102) (xy 258.742154 -88.763535) (xy 258.74966 -88.792769) (xy 336.912452 -88.792769)
			(xy 336.912452 -88.728847) (xy 336.920463 -88.665429) (xy 336.93636 -88.603515) (xy 336.959892 -88.544082)
			(xy 336.990686 -88.488067) (xy 337.028259 -88.436352) (xy 337.072016 -88.389755) (xy 337.121269 -88.34901)
			(xy 337.17524 -88.314759) (xy 337.233079 -88.287542) (xy 337.293872 -88.267789) (xy 337.356662 -88.255811)
			(xy 337.420458 -88.251798) (xy 337.484254 -88.255811) (xy 337.547044 -88.267789) (xy 337.607837 -88.287542)
			(xy 337.665676 -88.314759) (xy 337.719647 -88.34901) (xy 337.7689 -88.389755) (xy 337.812657 -88.436352)
			(xy 337.85023 -88.488067) (xy 337.881024 -88.544082) (xy 337.904556 -88.603515) (xy 337.920453 -88.665429)
			(xy 337.928464 -88.728847) (xy 337.928966 -88.760808) (xy 337.928464 -88.792769) (xy 337.920453 -88.856187)
			(xy 337.904556 -88.918101) (xy 337.881024 -88.977534) (xy 337.85023 -89.033549) (xy 337.812657 -89.085264)
			(xy 337.7689 -89.131861) (xy 337.719647 -89.172606) (xy 337.665676 -89.206857) (xy 337.607837 -89.234074)
			(xy 337.547044 -89.253827) (xy 337.484254 -89.265805) (xy 337.420458 -89.269819) (xy 337.356662 -89.265805)
			(xy 337.293872 -89.253827) (xy 337.233079 -89.234074) (xy 337.17524 -89.206857) (xy 337.121269 -89.172606)
			(xy 337.072016 -89.131861) (xy 337.028259 -89.085264) (xy 336.990686 -89.033549) (xy 336.959892 -88.977534)
			(xy 336.93636 -88.918101) (xy 336.920463 -88.856187) (xy 336.912452 -88.792769) (xy 258.74966 -88.792769)
			(xy 258.758051 -88.825449) (xy 258.766062 -88.888867) (xy 258.766564 -88.920828) (xy 258.766062 -88.952789)
			(xy 258.758051 -89.016207) (xy 258.742154 -89.078121) (xy 258.718622 -89.137554) (xy 258.687828 -89.193569)
			(xy 258.650255 -89.245284) (xy 258.606498 -89.291881) (xy 258.557245 -89.332626) (xy 258.542605 -89.341917)
			(xy 260.908794 -89.341917) (xy 260.908794 -89.277995) (xy 260.916805 -89.214577) (xy 260.932702 -89.152663)
			(xy 260.956234 -89.09323) (xy 260.987028 -89.037215) (xy 261.024601 -88.9855) (xy 261.068358 -88.938903)
			(xy 261.117611 -88.898158) (xy 261.171582 -88.863907) (xy 261.229421 -88.83669) (xy 261.290214 -88.816937)
			(xy 261.353004 -88.804959) (xy 261.4168 -88.800946) (xy 261.480596 -88.804959) (xy 261.543386 -88.816937)
			(xy 261.604179 -88.83669) (xy 261.662018 -88.863907) (xy 261.715989 -88.898158) (xy 261.765242 -88.938903)
			(xy 261.808999 -88.9855) (xy 261.846572 -89.037215) (xy 261.877366 -89.09323) (xy 261.900898 -89.152663)
			(xy 261.916795 -89.214577) (xy 261.924806 -89.277995) (xy 261.925308 -89.309956) (xy 261.924858 -89.338615)
			(xy 262.18235 -89.338615) (xy 262.18235 -89.274693) (xy 262.190361 -89.211275) (xy 262.206258 -89.149361)
			(xy 262.22979 -89.089928) (xy 262.260584 -89.033913) (xy 262.298157 -88.982198) (xy 262.341914 -88.935601)
			(xy 262.391167 -88.894856) (xy 262.445138 -88.860605) (xy 262.502977 -88.833388) (xy 262.56377 -88.813635)
			(xy 262.62656 -88.801657) (xy 262.690356 -88.797644) (xy 262.754152 -88.801657) (xy 262.816942 -88.813635)
			(xy 262.877735 -88.833388) (xy 262.935574 -88.860605) (xy 262.989545 -88.894856) (xy 263.038798 -88.935601)
			(xy 263.082555 -88.982198) (xy 263.120128 -89.033913) (xy 263.150922 -89.089928) (xy 263.174454 -89.149361)
			(xy 263.190351 -89.211275) (xy 263.198362 -89.274693) (xy 263.198864 -89.306654) (xy 263.198362 -89.338615)
			(xy 263.190351 -89.402033) (xy 263.174454 -89.463947) (xy 263.150922 -89.52338) (xy 263.120128 -89.579395)
			(xy 263.082555 -89.63111) (xy 263.038798 -89.677707) (xy 262.995947 -89.713156) (xy 274.908931 -89.713156)
			(xy 274.908931 -89.658644) (xy 274.916689 -89.604688) (xy 274.932047 -89.552384) (xy 274.954693 -89.502799)
			(xy 274.984166 -89.456942) (xy 275.019864 -89.415746) (xy 275.061063 -89.38005) (xy 275.106922 -89.350581)
			(xy 275.156509 -89.327938) (xy 275.208813 -89.312584) (xy 275.26277 -89.304829) (xy 275.290026 -89.304368)
			(xy 275.318942 -89.304933) (xy 275.376112 -89.313657) (xy 275.431308 -89.330917) (xy 275.483263 -89.356317)
			(xy 275.530786 -89.389273) (xy 275.552154 -89.408762) (xy 275.552408 -89.409016) (xy 275.559482 -89.415007)
			(xy 275.576682 -89.421894) (xy 275.585936 -89.422478) (xy 275.664422 -89.424002) (xy 275.682202 -89.417652)
			(xy 275.689314 -89.411302) (xy 275.712583 -89.391416) (xy 275.763041 -89.356765) (xy 275.81729 -89.328415)
			(xy 275.874548 -89.306776) (xy 275.933988 -89.29216) (xy 275.994751 -89.284778) (xy 276.025356 -89.284302)
			(xy 276.057321 -89.28476) (xy 276.120747 -89.292768) (xy 276.182669 -89.308662) (xy 276.242111 -89.332192)
			(xy 276.298134 -89.362987) (xy 276.349856 -89.400561) (xy 276.396461 -89.444322) (xy 276.437213 -89.493579)
			(xy 276.47147 -89.547555) (xy 276.498691 -89.605399) (xy 276.518447 -89.6662) (xy 276.530427 -89.728997)
			(xy 276.534442 -89.7928) (xy 276.530427 -89.856603) (xy 276.518447 -89.9194) (xy 276.498691 -89.980201)
			(xy 276.47147 -90.038045) (xy 276.437213 -90.092021) (xy 276.396461 -90.141278) (xy 276.349856 -90.185039)
			(xy 276.298134 -90.222613) (xy 276.242111 -90.253408) (xy 276.182669 -90.276938) (xy 276.120747 -90.292832)
			(xy 276.057321 -90.30084) (xy 276.025356 -90.301318) (xy 275.993218 -90.300814) (xy 275.929453 -90.292716)
			(xy 275.867218 -90.276642) (xy 275.807507 -90.252849) (xy 275.751273 -90.221717) (xy 275.699413 -90.183742)
			(xy 275.652756 -90.139531) (xy 275.612046 -90.089789) (xy 275.594572 -90.062812) (xy 275.594318 -90.062558)
			(xy 275.588935 -90.054946) (xy 275.57397 -90.043859) (xy 275.565108 -90.040968) (xy 275.489924 -90.02014)
			(xy 275.470874 -90.021918) (xy 275.462492 -90.026236) (xy 275.435643 -90.039168) (xy 275.378936 -90.057485)
			(xy 275.320075 -90.066785) (xy 275.29028 -90.067384) (xy 275.290026 -90.067384) (xy 275.26277 -90.066971)
			(xy 275.208813 -90.059216) (xy 275.156509 -90.043862) (xy 275.106922 -90.021219) (xy 275.061063 -89.99175)
			(xy 275.019864 -89.956054) (xy 274.984166 -89.914858) (xy 274.954693 -89.869001) (xy 274.932047 -89.819416)
			(xy 274.916689 -89.767112) (xy 274.908931 -89.713156) (xy 262.995947 -89.713156) (xy 262.989545 -89.718452)
			(xy 262.935574 -89.752703) (xy 262.877735 -89.77992) (xy 262.816942 -89.799673) (xy 262.754152 -89.811651)
			(xy 262.690356 -89.815665) (xy 262.62656 -89.811651) (xy 262.56377 -89.799673) (xy 262.502977 -89.77992)
			(xy 262.445138 -89.752703) (xy 262.391167 -89.718452) (xy 262.341914 -89.677707) (xy 262.298157 -89.63111)
			(xy 262.260584 -89.579395) (xy 262.22979 -89.52338) (xy 262.206258 -89.463947) (xy 262.190361 -89.402033)
			(xy 262.18235 -89.338615) (xy 261.924858 -89.338615) (xy 261.924806 -89.341917) (xy 261.916795 -89.405335)
			(xy 261.900898 -89.467249) (xy 261.877366 -89.526682) (xy 261.846572 -89.582697) (xy 261.808999 -89.634412)
			(xy 261.765242 -89.681009) (xy 261.715989 -89.721754) (xy 261.662018 -89.756005) (xy 261.604179 -89.783222)
			(xy 261.543386 -89.802975) (xy 261.480596 -89.814953) (xy 261.4168 -89.818967) (xy 261.353004 -89.814953)
			(xy 261.290214 -89.802975) (xy 261.229421 -89.783222) (xy 261.171582 -89.756005) (xy 261.117611 -89.721754)
			(xy 261.068358 -89.681009) (xy 261.024601 -89.634412) (xy 260.987028 -89.582697) (xy 260.956234 -89.526682)
			(xy 260.932702 -89.467249) (xy 260.916805 -89.405335) (xy 260.908794 -89.341917) (xy 258.542605 -89.341917)
			(xy 258.503274 -89.366877) (xy 258.445435 -89.394094) (xy 258.384642 -89.413847) (xy 258.321852 -89.425825)
			(xy 258.258056 -89.429839) (xy 258.19426 -89.425825) (xy 258.13147 -89.413847) (xy 258.070677 -89.394094)
			(xy 258.012838 -89.366877) (xy 257.958867 -89.332626) (xy 257.909614 -89.291881) (xy 257.865857 -89.245284)
			(xy 257.828284 -89.193569) (xy 257.79749 -89.137554) (xy 257.773958 -89.078121) (xy 257.758061 -89.016207)
			(xy 257.75005 -88.952789) (xy 253.078621 -88.952789) (xy 253.063984 -89.009795) (xy 253.040452 -89.069228)
			(xy 253.009658 -89.125243) (xy 252.972085 -89.176958) (xy 252.928328 -89.223555) (xy 252.879075 -89.2643)
			(xy 252.825104 -89.298551) (xy 252.767265 -89.325768) (xy 252.706472 -89.345521) (xy 252.643682 -89.357499)
			(xy 252.579886 -89.361513) (xy 252.51609 -89.357499) (xy 252.4533 -89.345521) (xy 252.392507 -89.325768)
			(xy 252.334668 -89.298551) (xy 252.280697 -89.2643) (xy 252.231444 -89.223555) (xy 252.187687 -89.176958)
			(xy 252.150114 -89.125243) (xy 252.11932 -89.069228) (xy 252.095788 -89.009795) (xy 252.079891 -88.947881)
			(xy 252.07188 -88.884463) (xy 250.485987 -88.884463) (xy 250.478405 -88.907798) (xy 250.451185 -88.965642)
			(xy 250.41693 -89.019618) (xy 250.37618 -89.068875) (xy 250.329578 -89.112637) (xy 250.277858 -89.150212)
			(xy 250.221837 -89.181009) (xy 250.162397 -89.204542) (xy 250.100477 -89.220439) (xy 250.037052 -89.22845)
			(xy 250.005088 -89.22893) (xy 249.974763 -89.228507) (xy 249.914545 -89.221288) (xy 249.855614 -89.206953)
			(xy 249.798808 -89.185708) (xy 249.744934 -89.157852) (xy 249.694757 -89.123783) (xy 249.671586 -89.104216)
			(xy 249.664182 -89.098255) (xy 249.646294 -89.091865) (xy 249.636788 -89.09177) (xy 249.558302 -89.094056)
			(xy 249.540776 -89.101422) (xy 249.533918 -89.10828) (xy 249.507698 -89.132997) (xy 249.449545 -89.175545)
			(xy 249.385962 -89.209447) (xy 249.352308 -89.222326) (xy 249.3391 -89.227152) (xy 249.321828 -89.24798)
			(xy 249.305318 -89.349326) (xy 249.304165 -89.358292) (xy 249.307582 -89.376033) (xy 249.316987 -89.391458)
			(xy 249.32386 -89.397332) (xy 249.349198 -89.418041) (xy 249.394823 -89.464955) (xy 249.434055 -89.517333)
			(xy 249.466246 -89.57431) (xy 249.490865 -89.634944) (xy 249.507504 -89.698235) (xy 249.515889 -89.763137)
			(xy 249.516392 -89.795858) (xy 249.51589 -89.827819) (xy 249.507879 -89.891237) (xy 249.491982 -89.953151)
			(xy 249.46845 -90.012584) (xy 249.437656 -90.068599) (xy 249.400083 -90.120314) (xy 249.356326 -90.166911)
			(xy 249.307073 -90.207656) (xy 249.253102 -90.241907) (xy 249.195263 -90.269124) (xy 249.13447 -90.288877)
			(xy 249.07168 -90.300855) (xy 249.007884 -90.304869) (xy 248.944088 -90.300855) (xy 248.881298 -90.288877)
			(xy 248.820505 -90.269124) (xy 248.762666 -90.241907) (xy 248.708695 -90.207656) (xy 248.659442 -90.166911)
			(xy 248.615685 -90.120314) (xy 248.578112 -90.068599) (xy 248.547318 -90.012584) (xy 248.523786 -89.953151)
			(xy 248.507889 -89.891237) (xy 248.499878 -89.827819) (xy 248.499376 -89.795858) (xy 182.383176 -89.795858)
			(xy 182.383176 -90.8144) (xy 200.735666 -90.8144) (xy 200.73968 -90.750601) (xy 200.751659 -90.687807)
			(xy 200.771413 -90.62701) (xy 200.798632 -90.569169) (xy 200.832885 -90.515195) (xy 200.873633 -90.46594)
			(xy 200.920233 -90.42218) (xy 200.971951 -90.384606) (xy 201.027969 -90.35381) (xy 201.087406 -90.330278)
			(xy 201.149324 -90.314382) (xy 201.212745 -90.30637) (xy 201.244708 -90.30589) (xy 201.277338 -90.306397)
			(xy 201.34206 -90.314774) (xy 201.405177 -90.331364) (xy 201.465653 -90.355894) (xy 201.522492 -90.387961)
			(xy 201.574761 -90.427038) (xy 201.59853 -90.4494) (xy 201.598784 -90.449654) (xy 201.606226 -90.456083)
			(xy 201.624516 -90.463267) (xy 201.634344 -90.463624) (xy 201.705972 -90.462862) (xy 201.715999 -90.462336)
			(xy 201.734464 -90.454492) (xy 201.741786 -90.447622) (xy 201.76573 -90.42403) (xy 201.818802 -90.382775)
			(xy 201.876848 -90.348876) (xy 201.938856 -90.322922) (xy 202.003744 -90.305368) (xy 202.07038 -90.29652)
			(xy 202.10399 -90.295984) (xy 202.135952 -90.29648) (xy 202.199373 -90.304491) (xy 202.261289 -90.320387)
			(xy 202.320725 -90.343919) (xy 202.376743 -90.374714) (xy 202.428459 -90.412287) (xy 202.475059 -90.456046)
			(xy 202.515806 -90.5053) (xy 202.549778 -90.558831) (xy 207.435952 -90.558831) (xy 207.435952 -90.494909)
			(xy 207.443963 -90.431491) (xy 207.45986 -90.369577) (xy 207.483392 -90.310144) (xy 207.514186 -90.254129)
			(xy 207.551759 -90.202414) (xy 207.595516 -90.155817) (xy 207.644769 -90.115072) (xy 207.69874 -90.080821)
			(xy 207.756579 -90.053604) (xy 207.817372 -90.033851) (xy 207.880162 -90.021873) (xy 207.943958 -90.01786)
			(xy 208.007754 -90.021873) (xy 208.070544 -90.033851) (xy 208.131337 -90.053604) (xy 208.189176 -90.080821)
			(xy 208.243147 -90.115072) (xy 208.2924 -90.155817) (xy 208.336157 -90.202414) (xy 208.37373 -90.254129)
			(xy 208.404524 -90.310144) (xy 208.428056 -90.369577) (xy 208.443953 -90.431491) (xy 208.451964 -90.494909)
			(xy 208.452182 -90.5088) (xy 209.489304 -90.5088) (xy 209.493318 -90.445005) (xy 209.505296 -90.382216)
			(xy 209.525049 -90.321424) (xy 209.552265 -90.263587) (xy 209.586516 -90.209617) (xy 209.627262 -90.160365)
			(xy 209.673858 -90.116609) (xy 209.725572 -90.079037) (xy 209.781587 -90.048244) (xy 209.841019 -90.024714)
			(xy 209.902932 -90.008819) (xy 209.966349 -90.000808) (xy 209.99831 -90.000328) (xy 210.027989 -90.000731)
			(xy 210.086943 -90.007639) (xy 210.144693 -90.021361) (xy 210.200454 -90.041709) (xy 210.253468 -90.068408)
			(xy 210.278472 -90.084402) (xy 210.287635 -90.089829) (xy 210.30862 -90.09333) (xy 210.329224 -90.08803)
			(xy 210.337908 -90.081862) (xy 210.364973 -90.061214) (xy 210.423538 -90.026512) (xy 210.48621 -89.999937)
			(xy 210.551869 -89.981964) (xy 210.619339 -89.972915) (xy 210.653376 -89.972388) (xy 210.685339 -89.972876)
			(xy 210.748761 -89.980885) (xy 210.81068 -89.99678) (xy 210.870118 -90.020311) (xy 210.926138 -90.051106)
			(xy 210.977856 -90.088679) (xy 211.024457 -90.132438) (xy 211.065206 -90.181693) (xy 211.09946 -90.235667)
			(xy 211.12668 -90.293509) (xy 211.146435 -90.354306) (xy 211.158413 -90.4171) (xy 211.162428 -90.4809)
			(xy 211.158413 -90.5447) (xy 211.146435 -90.607494) (xy 211.12668 -90.668291) (xy 211.09946 -90.726133)
			(xy 211.065206 -90.780107) (xy 211.024457 -90.829362) (xy 210.977856 -90.873121) (xy 210.926138 -90.910694)
			(xy 210.870118 -90.941489) (xy 210.81068 -90.96502) (xy 210.748761 -90.980915) (xy 210.685339 -90.988924)
			(xy 210.653376 -90.989404) (xy 210.623698 -90.98897) (xy 210.564745 -90.98207) (xy 210.506995 -90.968357)
			(xy 210.451233 -90.948015) (xy 210.398218 -90.921322) (xy 210.373214 -90.90533) (xy 210.364059 -90.899886)
			(xy 210.343068 -90.896387) (xy 210.322461 -90.901696) (xy 210.313778 -90.90787) (xy 210.286721 -90.928529)
			(xy 210.228153 -90.963228) (xy 210.165479 -90.989801) (xy 210.099819 -91.007771) (xy 210.032348 -91.016818)
			(xy 209.99831 -91.017344) (xy 209.966349 -91.016792) (xy 209.902932 -91.008781) (xy 209.841019 -90.992886)
			(xy 209.781587 -90.969356) (xy 209.725572 -90.938563) (xy 209.673858 -90.900991) (xy 209.627262 -90.857235)
			(xy 209.586516 -90.807983) (xy 209.552265 -90.754013) (xy 209.525049 -90.696176) (xy 209.505296 -90.635384)
			(xy 209.493318 -90.572595) (xy 209.489304 -90.5088) (xy 208.452182 -90.5088) (xy 208.452466 -90.52687)
			(xy 208.451964 -90.558831) (xy 208.443953 -90.622249) (xy 208.428056 -90.684163) (xy 208.404524 -90.743596)
			(xy 208.37373 -90.799611) (xy 208.336157 -90.851326) (xy 208.2924 -90.897923) (xy 208.243147 -90.938668)
			(xy 208.189176 -90.972919) (xy 208.131337 -91.000136) (xy 208.070544 -91.019889) (xy 208.007754 -91.031867)
			(xy 207.960026 -91.03487) (xy 250.560332 -91.03487) (xy 250.560805 -91.004006) (xy 250.56828 -90.942733)
			(xy 250.583117 -90.882816) (xy 250.605097 -90.825134) (xy 250.633897 -90.770537) (xy 250.669094 -90.719828)
			(xy 250.710171 -90.673752) (xy 250.756522 -90.632986) (xy 250.807466 -90.598131) (xy 250.834652 -90.583512)
			(xy 250.847616 -90.576196) (xy 250.869024 -90.555539) (xy 250.883566 -90.529587) (xy 250.890007 -90.500544)
			(xy 250.887801 -90.470877) (xy 250.877134 -90.443106) (xy 250.858912 -90.41959) (xy 250.847098 -90.410538)
			(xy 250.826267 -90.395123) (xy 250.788554 -90.359583) (xy 250.756003 -90.319262) (xy 250.729213 -90.274904)
			(xy 250.708677 -90.227325) (xy 250.694776 -90.177404) (xy 250.687763 -90.12606) (xy 250.687332 -90.10015)
			(xy 250.687818 -90.072899) (xy 250.695574 -90.018951) (xy 250.710929 -89.966656) (xy 250.733571 -89.917079)
			(xy 250.763037 -89.871229) (xy 250.798728 -89.830038) (xy 250.839919 -89.794347) (xy 250.885769 -89.764881)
			(xy 250.935346 -89.742239) (xy 250.987641 -89.726884) (xy 251.041589 -89.719128) (xy 251.096091 -89.719128)
			(xy 251.150039 -89.726884) (xy 251.202334 -89.742239) (xy 251.251911 -89.764881) (xy 251.297761 -89.794347)
			(xy 251.338952 -89.830038) (xy 251.374643 -89.871229) (xy 251.404109 -89.917079) (xy 251.426751 -89.966656)
			(xy 251.442106 -90.018951) (xy 251.449862 -90.072899) (xy 251.450348 -90.10015) (xy 251.449918 -90.126059)
			(xy 251.442887 -90.177398) (xy 251.428974 -90.227313) (xy 251.408436 -90.274887) (xy 251.38165 -90.319245)
			(xy 251.349109 -90.359571) (xy 251.311411 -90.395123) (xy 251.290582 -90.410538) (xy 251.278819 -90.419625)
			(xy 251.26069 -90.443163) (xy 251.250083 -90.470916) (xy 251.247892 -90.500546) (xy 251.254301 -90.529557)
			(xy 251.268772 -90.555505) (xy 251.290083 -90.576206) (xy 251.303028 -90.583512) (xy 251.330195 -90.598167)
			(xy 251.381145 -90.633013) (xy 251.427503 -90.67377) (xy 251.468585 -90.71984) (xy 251.503788 -90.770545)
			(xy 251.532593 -90.825139) (xy 251.554577 -90.882818) (xy 251.569416 -90.942734) (xy 251.576892 -91.004007)
			(xy 251.577348 -91.03487) (xy 251.830332 -91.03487) (xy 251.830805 -91.004006) (xy 251.83828 -90.942733)
			(xy 251.853117 -90.882816) (xy 251.875097 -90.825134) (xy 251.903897 -90.770537) (xy 251.939094 -90.719828)
			(xy 251.980171 -90.673752) (xy 252.026522 -90.632986) (xy 252.077466 -90.598131) (xy 252.104652 -90.583512)
			(xy 252.117616 -90.576196) (xy 252.139024 -90.555539) (xy 252.153566 -90.529587) (xy 252.160007 -90.500544)
			(xy 252.157801 -90.470877) (xy 252.147134 -90.443106) (xy 252.128912 -90.41959) (xy 252.117098 -90.410538)
			(xy 252.096267 -90.395123) (xy 252.058554 -90.359583) (xy 252.026003 -90.319262) (xy 251.999213 -90.274904)
			(xy 251.978677 -90.227325) (xy 251.964776 -90.177404) (xy 251.957763 -90.12606) (xy 251.957332 -90.10015)
			(xy 251.957818 -90.072899) (xy 251.965574 -90.018951) (xy 251.980929 -89.966656) (xy 252.003571 -89.917079)
			(xy 252.033037 -89.871229) (xy 252.068728 -89.830038) (xy 252.109919 -89.794347) (xy 252.155769 -89.764881)
			(xy 252.205346 -89.742239) (xy 252.257641 -89.726884) (xy 252.311589 -89.719128) (xy 252.366091 -89.719128)
			(xy 252.420039 -89.726884) (xy 252.472334 -89.742239) (xy 252.521911 -89.764881) (xy 252.567761 -89.794347)
			(xy 252.608952 -89.830038) (xy 252.644643 -89.871229) (xy 252.674109 -89.917079) (xy 252.696751 -89.966656)
			(xy 252.712106 -90.018951) (xy 252.719862 -90.072899) (xy 252.720348 -90.10015) (xy 252.719918 -90.126059)
			(xy 252.712887 -90.177398) (xy 252.698974 -90.227313) (xy 252.678436 -90.274887) (xy 252.65165 -90.319245)
			(xy 252.619109 -90.359571) (xy 252.581411 -90.395123) (xy 252.560582 -90.410538) (xy 252.548819 -90.419625)
			(xy 252.53069 -90.443163) (xy 252.520083 -90.470916) (xy 252.517892 -90.500546) (xy 252.524301 -90.529557)
			(xy 252.538772 -90.555505) (xy 252.560083 -90.576206) (xy 252.573028 -90.583512) (xy 252.600195 -90.598167)
			(xy 252.651145 -90.633013) (xy 252.697503 -90.67377) (xy 252.738585 -90.71984) (xy 252.773788 -90.770545)
			(xy 252.802593 -90.825139) (xy 252.824577 -90.882818) (xy 252.839416 -90.942734) (xy 252.846892 -91.004007)
			(xy 252.847348 -91.03487) (xy 253.100332 -91.03487) (xy 253.100805 -91.004006) (xy 253.10828 -90.942733)
			(xy 253.123117 -90.882816) (xy 253.145097 -90.825134) (xy 253.173897 -90.770537) (xy 253.209094 -90.719828)
			(xy 253.250171 -90.673752) (xy 253.296522 -90.632986) (xy 253.347466 -90.598131) (xy 253.374652 -90.583512)
			(xy 253.387616 -90.576196) (xy 253.409024 -90.555539) (xy 253.423566 -90.529587) (xy 253.430007 -90.500544)
			(xy 253.427801 -90.470877) (xy 253.417134 -90.443106) (xy 253.398912 -90.41959) (xy 253.387098 -90.410538)
			(xy 253.366267 -90.395123) (xy 253.328554 -90.359583) (xy 253.296003 -90.319262) (xy 253.269213 -90.274904)
			(xy 253.248677 -90.227325) (xy 253.234776 -90.177404) (xy 253.227763 -90.12606) (xy 253.227332 -90.10015)
			(xy 253.227818 -90.072899) (xy 253.235574 -90.018951) (xy 253.250929 -89.966656) (xy 253.273571 -89.917079)
			(xy 253.303037 -89.871229) (xy 253.338728 -89.830038) (xy 253.379919 -89.794347) (xy 253.425769 -89.764881)
			(xy 253.475346 -89.742239) (xy 253.527641 -89.726884) (xy 253.581589 -89.719128) (xy 253.636091 -89.719128)
			(xy 253.690039 -89.726884) (xy 253.742334 -89.742239) (xy 253.791911 -89.764881) (xy 253.837761 -89.794347)
			(xy 253.878952 -89.830038) (xy 253.914643 -89.871229) (xy 253.944109 -89.917079) (xy 253.966751 -89.966656)
			(xy 253.982106 -90.018951) (xy 253.989862 -90.072899) (xy 253.990348 -90.10015) (xy 253.989918 -90.126059)
			(xy 253.982887 -90.177398) (xy 253.968974 -90.227313) (xy 253.948436 -90.274887) (xy 253.92165 -90.319245)
			(xy 253.889109 -90.359571) (xy 253.851411 -90.395123) (xy 253.830582 -90.410538) (xy 253.818819 -90.419625)
			(xy 253.80069 -90.443163) (xy 253.790083 -90.470916) (xy 253.787892 -90.500546) (xy 253.794301 -90.529557)
			(xy 253.808772 -90.555505) (xy 253.830083 -90.576206) (xy 253.843028 -90.583512) (xy 253.870195 -90.598167)
			(xy 253.921145 -90.633013) (xy 253.967503 -90.67377) (xy 254.008585 -90.71984) (xy 254.043788 -90.770545)
			(xy 254.072593 -90.825139) (xy 254.094577 -90.882818) (xy 254.109416 -90.942734) (xy 254.116892 -91.004007)
			(xy 254.117348 -91.03487) (xy 254.116846 -91.066831) (xy 254.370834 -91.066831) (xy 254.370834 -91.002909)
			(xy 254.378845 -90.939491) (xy 254.394742 -90.877577) (xy 254.418274 -90.818144) (xy 254.449068 -90.762129)
			(xy 254.486641 -90.710414) (xy 254.530398 -90.663817) (xy 254.579651 -90.623072) (xy 254.633622 -90.588821)
			(xy 254.691461 -90.561604) (xy 254.752254 -90.541851) (xy 254.815044 -90.529873) (xy 254.87884 -90.52586)
			(xy 254.942636 -90.529873) (xy 255.005426 -90.541851) (xy 255.066219 -90.561604) (xy 255.124058 -90.588821)
			(xy 255.178029 -90.623072) (xy 255.227282 -90.663817) (xy 255.271039 -90.710414) (xy 255.308612 -90.762129)
			(xy 255.339406 -90.818144) (xy 255.362938 -90.877577) (xy 255.375205 -90.925353) (xy 259.25119 -90.925353)
			(xy 259.25119 -90.861431) (xy 259.259201 -90.798013) (xy 259.275098 -90.736099) (xy 259.29863 -90.676666)
			(xy 259.329424 -90.620651) (xy 259.366997 -90.568936) (xy 259.410754 -90.522339) (xy 259.460007 -90.481594)
			(xy 259.513978 -90.447343) (xy 259.571817 -90.420126) (xy 259.63261 -90.400373) (xy 259.6954 -90.388395)
			(xy 259.759196 -90.384382) (xy 259.822992 -90.388395) (xy 259.885782 -90.400373) (xy 259.946575 -90.420126)
			(xy 260.001137 -90.445801) (xy 260.641078 -90.445801) (xy 260.641078 -90.381879) (xy 260.649089 -90.318461)
			(xy 260.664986 -90.256547) (xy 260.688518 -90.197114) (xy 260.719312 -90.141099) (xy 260.756885 -90.089384)
			(xy 260.800642 -90.042787) (xy 260.849895 -90.002042) (xy 260.903866 -89.967791) (xy 260.961705 -89.940574)
			(xy 261.022498 -89.920821) (xy 261.085288 -89.908843) (xy 261.149084 -89.90483) (xy 261.21288 -89.908843)
			(xy 261.27567 -89.920821) (xy 261.336463 -89.940574) (xy 261.394302 -89.967791) (xy 261.448273 -90.002042)
			(xy 261.497526 -90.042787) (xy 261.541283 -90.089384) (xy 261.578856 -90.141099) (xy 261.60965 -90.197114)
			(xy 261.633182 -90.256547) (xy 261.649079 -90.318461) (xy 261.65709 -90.381879) (xy 261.657592 -90.41384)
			(xy 261.65709 -90.445801) (xy 261.649079 -90.509219) (xy 261.633182 -90.571133) (xy 261.60965 -90.630566)
			(xy 261.578856 -90.686581) (xy 261.541283 -90.738296) (xy 261.497526 -90.784893) (xy 261.448273 -90.825638)
			(xy 261.394302 -90.859889) (xy 261.336463 -90.887106) (xy 261.27567 -90.906859) (xy 261.21288 -90.918837)
			(xy 261.149084 -90.922851) (xy 261.085288 -90.918837) (xy 261.022498 -90.906859) (xy 260.961705 -90.887106)
			(xy 260.903866 -90.859889) (xy 260.849895 -90.825638) (xy 260.800642 -90.784893) (xy 260.756885 -90.738296)
			(xy 260.719312 -90.686581) (xy 260.688518 -90.630566) (xy 260.664986 -90.571133) (xy 260.649089 -90.509219)
			(xy 260.641078 -90.445801) (xy 260.001137 -90.445801) (xy 260.004414 -90.447343) (xy 260.058385 -90.481594)
			(xy 260.107638 -90.522339) (xy 260.151395 -90.568936) (xy 260.188968 -90.620651) (xy 260.219762 -90.676666)
			(xy 260.243294 -90.736099) (xy 260.259191 -90.798013) (xy 260.267202 -90.861431) (xy 260.267704 -90.893392)
			(xy 260.267202 -90.925353) (xy 260.259191 -90.988771) (xy 260.243294 -91.050685) (xy 260.219762 -91.110118)
			(xy 260.188968 -91.166133) (xy 260.151395 -91.217848) (xy 260.107638 -91.264445) (xy 260.058385 -91.30519)
			(xy 260.004414 -91.339441) (xy 259.946575 -91.366658) (xy 259.885782 -91.386411) (xy 259.822992 -91.398389)
			(xy 259.759196 -91.402403) (xy 259.6954 -91.398389) (xy 259.63261 -91.386411) (xy 259.571817 -91.366658)
			(xy 259.513978 -91.339441) (xy 259.460007 -91.30519) (xy 259.410754 -91.264445) (xy 259.366997 -91.217848)
			(xy 259.329424 -91.166133) (xy 259.29863 -91.110118) (xy 259.275098 -91.050685) (xy 259.259201 -90.988771)
			(xy 259.25119 -90.925353) (xy 255.375205 -90.925353) (xy 255.378835 -90.939491) (xy 255.386846 -91.002909)
			(xy 255.387348 -91.03487) (xy 255.386846 -91.066831) (xy 255.378835 -91.130249) (xy 255.362938 -91.192163)
			(xy 255.339406 -91.251596) (xy 255.308612 -91.307611) (xy 255.271039 -91.359326) (xy 255.227282 -91.405923)
			(xy 255.178029 -91.446668) (xy 255.124058 -91.480919) (xy 255.066219 -91.508136) (xy 255.005426 -91.527889)
			(xy 254.942636 -91.539867) (xy 254.87884 -91.543881) (xy 254.815044 -91.539867) (xy 254.752254 -91.527889)
			(xy 254.691461 -91.508136) (xy 254.633622 -91.480919) (xy 254.579651 -91.446668) (xy 254.530398 -91.405923)
			(xy 254.486641 -91.359326) (xy 254.449068 -91.307611) (xy 254.418274 -91.251596) (xy 254.394742 -91.192163)
			(xy 254.378845 -91.130249) (xy 254.370834 -91.066831) (xy 254.116846 -91.066831) (xy 254.108835 -91.130249)
			(xy 254.092938 -91.192163) (xy 254.069406 -91.251596) (xy 254.038612 -91.307611) (xy 254.001039 -91.359326)
			(xy 253.957282 -91.405923) (xy 253.908029 -91.446668) (xy 253.854058 -91.480919) (xy 253.796219 -91.508136)
			(xy 253.735426 -91.527889) (xy 253.672636 -91.539867) (xy 253.60884 -91.543881) (xy 253.545044 -91.539867)
			(xy 253.482254 -91.527889) (xy 253.421461 -91.508136) (xy 253.363622 -91.480919) (xy 253.309651 -91.446668)
			(xy 253.260398 -91.405923) (xy 253.216641 -91.359326) (xy 253.179068 -91.307611) (xy 253.148274 -91.251596)
			(xy 253.124742 -91.192163) (xy 253.108845 -91.130249) (xy 253.100834 -91.066831) (xy 253.100332 -91.03487)
			(xy 252.847348 -91.03487) (xy 252.846846 -91.066831) (xy 252.838835 -91.130249) (xy 252.822938 -91.192163)
			(xy 252.799406 -91.251596) (xy 252.768612 -91.307611) (xy 252.731039 -91.359326) (xy 252.687282 -91.405923)
			(xy 252.638029 -91.446668) (xy 252.584058 -91.480919) (xy 252.526219 -91.508136) (xy 252.465426 -91.527889)
			(xy 252.402636 -91.539867) (xy 252.33884 -91.543881) (xy 252.275044 -91.539867) (xy 252.212254 -91.527889)
			(xy 252.151461 -91.508136) (xy 252.093622 -91.480919) (xy 252.039651 -91.446668) (xy 251.990398 -91.405923)
			(xy 251.946641 -91.359326) (xy 251.909068 -91.307611) (xy 251.878274 -91.251596) (xy 251.854742 -91.192163)
			(xy 251.838845 -91.130249) (xy 251.830834 -91.066831) (xy 251.830332 -91.03487) (xy 251.577348 -91.03487)
			(xy 251.576846 -91.066831) (xy 251.568835 -91.130249) (xy 251.552938 -91.192163) (xy 251.529406 -91.251596)
			(xy 251.498612 -91.307611) (xy 251.461039 -91.359326) (xy 251.417282 -91.405923) (xy 251.368029 -91.446668)
			(xy 251.314058 -91.480919) (xy 251.256219 -91.508136) (xy 251.195426 -91.527889) (xy 251.132636 -91.539867)
			(xy 251.06884 -91.543881) (xy 251.005044 -91.539867) (xy 250.942254 -91.527889) (xy 250.881461 -91.508136)
			(xy 250.823622 -91.480919) (xy 250.769651 -91.446668) (xy 250.720398 -91.405923) (xy 250.676641 -91.359326)
			(xy 250.639068 -91.307611) (xy 250.608274 -91.251596) (xy 250.584742 -91.192163) (xy 250.568845 -91.130249)
			(xy 250.560834 -91.066831) (xy 250.560332 -91.03487) (xy 207.960026 -91.03487) (xy 207.943958 -91.035881)
			(xy 207.880162 -91.031867) (xy 207.817372 -91.019889) (xy 207.756579 -91.000136) (xy 207.69874 -90.972919)
			(xy 207.644769 -90.938668) (xy 207.595516 -90.897923) (xy 207.551759 -90.851326) (xy 207.514186 -90.799611)
			(xy 207.483392 -90.743596) (xy 207.45986 -90.684163) (xy 207.443963 -90.622249) (xy 207.435952 -90.558831)
			(xy 202.549778 -90.558831) (xy 202.550059 -90.559273) (xy 202.577277 -90.617114) (xy 202.597031 -90.677909)
			(xy 202.60901 -90.740702) (xy 202.613024 -90.8045) (xy 202.60901 -90.868298) (xy 202.597031 -90.931091)
			(xy 202.577277 -90.991886) (xy 202.550059 -91.049727) (xy 202.515806 -91.1037) (xy 202.475059 -91.152954)
			(xy 202.428459 -91.196713) (xy 202.376743 -91.234286) (xy 202.320725 -91.265081) (xy 202.261289 -91.288613)
			(xy 202.199373 -91.304509) (xy 202.135952 -91.31252) (xy 202.10399 -91.313) (xy 202.071359 -91.312497)
			(xy 202.006638 -91.30412) (xy 201.94352 -91.287529) (xy 201.883045 -91.262998) (xy 201.826205 -91.23093)
			(xy 201.773937 -91.191852) (xy 201.750168 -91.16949) (xy 201.749914 -91.169236) (xy 201.742473 -91.162805)
			(xy 201.724183 -91.155623) (xy 201.714354 -91.155266) (xy 201.642726 -91.156028) (xy 201.632699 -91.156556)
			(xy 201.614234 -91.164399) (xy 201.606912 -91.171268) (xy 201.582921 -91.194811) (xy 201.52986 -91.236071)
			(xy 201.471823 -91.269978) (xy 201.409824 -91.295939) (xy 201.344945 -91.313504) (xy 201.278316 -91.322363)
			(xy 201.244708 -91.322906) (xy 201.212745 -91.32243) (xy 201.149324 -91.314418) (xy 201.087406 -91.298522)
			(xy 201.027969 -91.27499) (xy 200.971951 -91.244194) (xy 200.920233 -91.20662) (xy 200.873633 -91.16286)
			(xy 200.832885 -91.113605) (xy 200.798632 -91.059631) (xy 200.771413 -91.00179) (xy 200.751659 -90.940993)
			(xy 200.73968 -90.878199) (xy 200.735666 -90.8144) (xy 182.383176 -90.8144) (xy 182.383176 -91.256612)
			(xy 182.38343 -91.261946) (xy 182.383684 -91.26347) (xy 182.383684 -91.263978) (xy 182.384615 -91.269522)
			(xy 182.388582 -91.280038) (xy 182.391558 -91.284806) (xy 182.394774 -91.289417) (xy 182.402845 -91.297239)
			(xy 182.40756 -91.3003) (xy 182.451248 -91.323922) (xy 182.48884 -91.343988) (xy 182.491126 -91.345258)
			(xy 182.496885 -91.34779) (xy 182.509221 -91.350234) (xy 182.51551 -91.350084) (xy 182.529226 -91.349576)
			(xy 182.541164 -91.341702) (xy 182.564795 -91.326507) (xy 182.615578 -91.302479) (xy 182.669338 -91.286166)
			(xy 182.72491 -91.27792) (xy 182.753 -91.27744) (xy 182.780248 -91.277926) (xy 182.834189 -91.285682)
			(xy 182.886477 -91.301035) (xy 182.936048 -91.323673) (xy 182.981892 -91.353136) (xy 183.023077 -91.388823)
			(xy 183.058764 -91.430008) (xy 183.088227 -91.475852) (xy 183.110865 -91.525423) (xy 183.126218 -91.577711)
			(xy 183.133974 -91.631652) (xy 183.133974 -91.686148) (xy 183.133289 -91.690909) (xy 183.260994 -91.690909)
			(xy 183.260994 -91.626987) (xy 183.269005 -91.563569) (xy 183.284902 -91.501655) (xy 183.308434 -91.442222)
			(xy 183.339228 -91.386207) (xy 183.376801 -91.334492) (xy 183.420558 -91.287895) (xy 183.469811 -91.24715)
			(xy 183.523782 -91.212899) (xy 183.581621 -91.185682) (xy 183.642414 -91.165929) (xy 183.705204 -91.153951)
			(xy 183.769 -91.149938) (xy 183.832796 -91.153951) (xy 183.895586 -91.165929) (xy 183.956379 -91.185682)
			(xy 184.014218 -91.212899) (xy 184.068189 -91.24715) (xy 184.117442 -91.287895) (xy 184.161199 -91.334492)
			(xy 184.198772 -91.386207) (xy 184.229566 -91.442222) (xy 184.253098 -91.501655) (xy 184.268995 -91.563569)
			(xy 184.277006 -91.626987) (xy 184.277507 -91.6589) (xy 185.292038 -91.6589) (xy 185.296051 -91.59511)
			(xy 185.308027 -91.532326) (xy 185.327779 -91.471538) (xy 185.354993 -91.413705) (xy 185.389241 -91.359739)
			(xy 185.429982 -91.310491) (xy 185.476575 -91.266738) (xy 185.528284 -91.229169) (xy 185.584294 -91.198377)
			(xy 185.643722 -91.174848) (xy 185.70563 -91.158953) (xy 185.769042 -91.150942) (xy 185.801 -91.15044)
			(xy 185.832569 -91.150929) (xy 185.895215 -91.15879) (xy 185.956408 -91.174344) (xy 186.015206 -91.197349)
			(xy 186.070705 -91.227453) (xy 186.096656 -91.245436) (xy 186.105981 -91.251412) (xy 186.127745 -91.25542)
			(xy 186.149188 -91.249952) (xy 186.158124 -91.243404) (xy 186.185403 -91.222069) (xy 186.244656 -91.18622)
			(xy 186.308221 -91.158734) (xy 186.374925 -91.140116) (xy 186.443537 -91.130712) (xy 186.478164 -91.13012)
			(xy 186.51013 -91.130543) (xy 186.573557 -91.138551) (xy 186.635481 -91.154447) (xy 186.694924 -91.177978)
			(xy 186.750948 -91.208774) (xy 186.802671 -91.24635) (xy 186.849277 -91.290112) (xy 186.890029 -91.339371)
			(xy 186.924287 -91.393349) (xy 186.951508 -91.451195) (xy 186.971265 -91.511996) (xy 186.983245 -91.574795)
			(xy 186.98726 -91.6386) (xy 186.986713 -91.6473) (xy 189.835732 -91.6473) (xy 189.839747 -91.583496)
			(xy 189.851726 -91.520699) (xy 189.871482 -91.459898) (xy 189.898702 -91.402053) (xy 189.932957 -91.348076)
			(xy 189.973708 -91.298817) (xy 190.020311 -91.255055) (xy 190.072031 -91.217478) (xy 190.128054 -91.18668)
			(xy 190.187494 -91.163147) (xy 190.249415 -91.147248) (xy 190.312841 -91.139237) (xy 190.344806 -91.138756)
			(xy 190.377044 -91.139256) (xy 190.441003 -91.147411) (xy 190.503417 -91.163591) (xy 190.563283 -91.187534)
			(xy 190.619641 -91.218857) (xy 190.671584 -91.257056) (xy 190.718278 -91.301518) (xy 190.739014 -91.326208)
			(xy 190.746094 -91.334022) (xy 190.764855 -91.343598) (xy 190.775336 -91.34475) (xy 190.861188 -91.349576)
			(xy 190.880746 -91.342464) (xy 190.88862 -91.334844) (xy 190.912409 -91.312386) (xy 190.964768 -91.273162)
			(xy 191.021726 -91.240977) (xy 191.08234 -91.216361) (xy 191.145611 -91.199721) (xy 191.210493 -91.191332)
			(xy 191.243204 -91.190826) (xy 191.274747 -91.191296) (xy 191.337348 -91.19909) (xy 191.398505 -91.21457)
			(xy 191.457276 -91.237497) (xy 191.512758 -91.267521) (xy 191.5641 -91.304178) (xy 191.587628 -91.325192)
			(xy 191.595407 -91.331763) (xy 191.61453 -91.33871) (xy 191.624712 -91.338654) (xy 191.707262 -91.334336)
			(xy 191.72555 -91.3257) (xy 191.732408 -91.318334) (xy 191.732408 -91.317826) (xy 191.753138 -91.295269)
			(xy 191.799088 -91.25475) (xy 191.849577 -91.220049) (xy 191.903871 -91.19167) (xy 191.961184 -91.170025)
			(xy 192.020683 -91.155428) (xy 192.081506 -91.14809) (xy 192.112138 -91.147646) (xy 192.144095 -91.148242)
			(xy 192.207503 -91.156257) (xy 192.269408 -91.172155) (xy 192.328831 -91.195687) (xy 192.384837 -91.22648)
			(xy 192.436543 -91.26405) (xy 192.483132 -91.307803) (xy 192.52387 -91.35705) (xy 192.558115 -91.411015)
			(xy 192.585327 -91.468846) (xy 192.605076 -91.529632) (xy 192.617052 -91.592413) (xy 192.621065 -91.6562)
			(xy 192.617052 -91.719987) (xy 192.605076 -91.782768) (xy 192.585327 -91.843554) (xy 192.558115 -91.901385)
			(xy 192.52387 -91.95535) (xy 192.483132 -92.004597) (xy 192.436543 -92.04835) (xy 192.384837 -92.08592)
			(xy 192.328831 -92.116713) (xy 192.269408 -92.140245) (xy 192.207503 -92.156143) (xy 192.144095 -92.164158)
			(xy 192.112138 -92.164662) (xy 192.080596 -92.164169) (xy 192.017995 -92.15638) (xy 191.956839 -92.140905)
			(xy 191.898068 -92.117982) (xy 191.842585 -92.087962) (xy 191.791243 -92.051308) (xy 191.767714 -92.030296)
			(xy 191.759956 -92.023696) (xy 191.740817 -92.016767) (xy 191.73063 -92.016834) (xy 191.64808 -92.021152)
			(xy 191.629792 -92.029788) (xy 191.622934 -92.037154) (xy 191.622934 -92.037662) (xy 191.602231 -92.060245)
			(xy 191.556276 -92.100763) (xy 191.505783 -92.135462) (xy 191.451484 -92.163837) (xy 191.433042 -92.1708)
			(xy 233.175547 -92.1708) (xy 233.179561 -92.107001) (xy 233.191539 -92.044208) (xy 233.211292 -91.983412)
			(xy 233.23851 -91.92557) (xy 233.272761 -91.871596) (xy 233.313507 -91.822339) (xy 233.360106 -91.778578)
			(xy 233.411821 -91.741002) (xy 233.467838 -91.710204) (xy 233.527273 -91.686669) (xy 233.589189 -91.670769)
			(xy 233.652609 -91.662754) (xy 233.684572 -91.66225) (xy 233.715534 -91.662676) (xy 233.777002 -91.670184)
			(xy 233.837105 -91.685092) (xy 233.894956 -91.707181) (xy 233.9497 -91.736124) (xy 234.000529 -91.771494)
			(xy 234.023916 -91.79179) (xy 234.031114 -91.797775) (xy 234.048596 -91.804432) (xy 234.057952 -91.804744)
			(xy 234.088686 -91.804744) (xy 234.098173 -91.80429) (xy 234.115794 -91.797243) (xy 234.122976 -91.791028)
			(xy 234.14651 -91.769887) (xy 234.19793 -91.733034) (xy 234.253526 -91.702846) (xy 234.312438 -91.679789)
			(xy 234.373755 -91.664219) (xy 234.43653 -91.656378) (xy 234.468162 -91.6559) (xy 234.500126 -91.656363)
			(xy 234.563552 -91.664371) (xy 234.625473 -91.680265) (xy 234.684914 -91.703796) (xy 234.740936 -91.734591)
			(xy 234.792658 -91.772165) (xy 234.817029 -91.795049) (xy 281.686248 -91.795049) (xy 281.686248 -91.731127)
			(xy 281.694259 -91.667709) (xy 281.710156 -91.605795) (xy 281.733688 -91.546362) (xy 281.764482 -91.490347)
			(xy 281.802055 -91.438632) (xy 281.845812 -91.392035) (xy 281.895065 -91.35129) (xy 281.949036 -91.317039)
			(xy 282.006875 -91.289822) (xy 282.067668 -91.270069) (xy 282.130458 -91.258091) (xy 282.194254 -91.254078)
			(xy 282.25805 -91.258091) (xy 282.32084 -91.270069) (xy 282.381633 -91.289822) (xy 282.409206 -91.302797)
			(xy 437.72937 -91.302797) (xy 437.72937 -91.238875) (xy 437.737381 -91.175457) (xy 437.753278 -91.113543)
			(xy 437.77681 -91.05411) (xy 437.807604 -90.998095) (xy 437.845177 -90.94638) (xy 437.888934 -90.899783)
			(xy 437.938187 -90.859038) (xy 437.992158 -90.824787) (xy 438.049997 -90.79757) (xy 438.11079 -90.777817)
			(xy 438.17358 -90.765839) (xy 438.237376 -90.761826) (xy 438.301172 -90.765839) (xy 438.363962 -90.777817)
			(xy 438.424755 -90.79757) (xy 438.482594 -90.824787) (xy 438.536565 -90.859038) (xy 438.585818 -90.899783)
			(xy 438.629575 -90.94638) (xy 438.667148 -90.998095) (xy 438.697942 -91.05411) (xy 438.721474 -91.113543)
			(xy 438.737371 -91.175457) (xy 438.745382 -91.238875) (xy 438.745884 -91.270836) (xy 438.745382 -91.302797)
			(xy 438.737371 -91.366215) (xy 438.721474 -91.428129) (xy 438.697942 -91.487562) (xy 438.667148 -91.543577)
			(xy 438.629575 -91.595292) (xy 438.585818 -91.641889) (xy 438.536565 -91.682634) (xy 438.482594 -91.716885)
			(xy 438.424755 -91.744102) (xy 438.363962 -91.763855) (xy 438.301172 -91.775833) (xy 438.237376 -91.779847)
			(xy 438.17358 -91.775833) (xy 438.11079 -91.763855) (xy 438.049997 -91.744102) (xy 437.992158 -91.716885)
			(xy 437.938187 -91.682634) (xy 437.888934 -91.641889) (xy 437.845177 -91.595292) (xy 437.807604 -91.543577)
			(xy 437.77681 -91.487562) (xy 437.753278 -91.428129) (xy 437.737381 -91.366215) (xy 437.72937 -91.302797)
			(xy 282.409206 -91.302797) (xy 282.439472 -91.317039) (xy 282.493443 -91.35129) (xy 282.542696 -91.392035)
			(xy 282.586453 -91.438632) (xy 282.624026 -91.490347) (xy 282.65482 -91.546362) (xy 282.678352 -91.605795)
			(xy 282.694249 -91.667709) (xy 282.70226 -91.731127) (xy 282.702762 -91.763088) (xy 282.70226 -91.795049)
			(xy 282.694249 -91.858467) (xy 282.678352 -91.920381) (xy 282.65482 -91.979814) (xy 282.624026 -92.035829)
			(xy 282.587793 -92.0857) (xy 456.731536 -92.0857) (xy 456.735551 -92.021894) (xy 456.747531 -91.959095)
			(xy 456.767288 -91.898292) (xy 456.79451 -91.840446) (xy 456.828768 -91.786467) (xy 456.869522 -91.737208)
			(xy 456.916128 -91.693446) (xy 456.967852 -91.65587) (xy 457.023877 -91.625073) (xy 457.083321 -91.601542)
			(xy 457.145246 -91.585647) (xy 457.208674 -91.577639) (xy 457.24064 -91.57716) (xy 457.274397 -91.57774)
			(xy 457.341316 -91.586678) (xy 457.406465 -91.60439) (xy 457.468698 -91.630566) (xy 457.526921 -91.664745)
			(xy 457.58011 -91.706327) (xy 457.604114 -91.730068) (xy 457.610718 -91.736926) (xy 457.628498 -91.7448)
			(xy 457.71816 -91.748102) (xy 457.73594 -91.742006) (xy 457.74356 -91.735402) (xy 457.764499 -91.71766)
			(xy 457.810537 -91.687786) (xy 457.860384 -91.664824) (xy 457.91301 -91.649251) (xy 457.967325 -91.641388)
			(xy 457.994766 -91.640914) (xy 458.022022 -91.641331) (xy 458.07598 -91.649084) (xy 458.128285 -91.664438)
			(xy 458.177872 -91.68708) (xy 458.223732 -91.716549) (xy 458.264931 -91.752245) (xy 458.300631 -91.793441)
			(xy 458.330104 -91.839298) (xy 458.35275 -91.888883) (xy 458.368109 -91.941187) (xy 458.375867 -91.995144)
			(xy 458.375867 -92.049656) (xy 458.368109 -92.103613) (xy 458.35275 -92.155917) (xy 458.330104 -92.205502)
			(xy 458.300631 -92.251359) (xy 458.264931 -92.292555) (xy 458.223732 -92.328251) (xy 458.177872 -92.35772)
			(xy 458.128285 -92.380362) (xy 458.07598 -92.395716) (xy 458.022022 -92.403469) (xy 457.994766 -92.40393)
			(xy 457.968454 -92.403454) (xy 457.916332 -92.396191) (xy 457.8657 -92.381848) (xy 457.817513 -92.360695)
			(xy 457.794868 -92.347288) (xy 457.794614 -92.347034) (xy 457.786216 -92.342541) (xy 457.767443 -92.339427)
			(xy 457.758038 -92.340938) (xy 457.679806 -92.357194) (xy 457.663804 -92.367862) (xy 457.658216 -92.37599)
			(xy 457.640357 -92.400873) (xy 457.599596 -92.446594) (xy 457.553639 -92.487087) (xy 457.503151 -92.521768)
			(xy 457.448863 -92.550133) (xy 457.391561 -92.571772) (xy 457.332075 -92.586373) (xy 457.271266 -92.593722)
			(xy 457.24064 -92.594176) (xy 457.208674 -92.593761) (xy 457.145246 -92.585753) (xy 457.083321 -92.569858)
			(xy 457.023877 -92.546327) (xy 456.967852 -92.51553) (xy 456.916128 -92.477954) (xy 456.869522 -92.434192)
			(xy 456.828768 -92.384933) (xy 456.79451 -92.330954) (xy 456.767288 -92.273108) (xy 456.747531 -92.212305)
			(xy 456.735551 -92.149506) (xy 456.731536 -92.0857) (xy 282.587793 -92.0857) (xy 282.586453 -92.087544)
			(xy 282.542696 -92.134141) (xy 282.493443 -92.174886) (xy 282.439472 -92.209137) (xy 282.381633 -92.236354)
			(xy 282.32084 -92.256107) (xy 282.25805 -92.268085) (xy 282.194254 -92.272099) (xy 282.130458 -92.268085)
			(xy 282.067668 -92.256107) (xy 282.006875 -92.236354) (xy 281.949036 -92.209137) (xy 281.895065 -92.174886)
			(xy 281.845812 -92.134141) (xy 281.802055 -92.087544) (xy 281.764482 -92.035829) (xy 281.733688 -91.979814)
			(xy 281.710156 -91.920381) (xy 281.694259 -91.858467) (xy 281.686248 -91.795049) (xy 234.817029 -91.795049)
			(xy 234.839261 -91.815925) (xy 234.880013 -91.865182) (xy 234.914269 -91.919158) (xy 234.94149 -91.977002)
			(xy 234.961246 -92.037801) (xy 234.973225 -92.100597) (xy 234.97724 -92.1644) (xy 234.973225 -92.228203)
			(xy 234.961246 -92.290999) (xy 234.94149 -92.351798) (xy 234.914269 -92.409642) (xy 234.880013 -92.463618)
			(xy 234.839261 -92.512875) (xy 234.792658 -92.556635) (xy 234.740936 -92.594209) (xy 234.684914 -92.625004)
			(xy 234.625473 -92.648535) (xy 234.563552 -92.664429) (xy 234.500126 -92.672437) (xy 234.468162 -92.672916)
			(xy 234.437201 -92.672453) (xy 234.375736 -92.66495) (xy 234.315634 -92.650048) (xy 234.257783 -92.627966)
			(xy 234.203038 -92.59903) (xy 234.152207 -92.563668) (xy 234.128818 -92.543376) (xy 234.121613 -92.537401)
			(xy 234.104136 -92.530739) (xy 234.094782 -92.530422) (xy 234.064048 -92.530422) (xy 234.054559 -92.530851)
			(xy 234.036938 -92.537916) (xy 234.029758 -92.544138) (xy 234.006205 -92.565257) (xy 233.954789 -92.602113)
			(xy 233.899198 -92.632305) (xy 233.84029 -92.655367) (xy 233.778975 -92.67094) (xy 233.716203 -92.678786)
			(xy 233.684572 -92.679266) (xy 233.652609 -92.678846) (xy 233.589189 -92.670831) (xy 233.527273 -92.654931)
			(xy 233.467838 -92.631396) (xy 233.411821 -92.600598) (xy 233.360106 -92.563022) (xy 233.313507 -92.519261)
			(xy 233.272761 -92.470004) (xy 233.23851 -92.41603) (xy 233.211292 -92.358188) (xy 233.191539 -92.297392)
			(xy 233.179561 -92.234599) (xy 233.175547 -92.1708) (xy 191.433042 -92.1708) (xy 191.394167 -92.185478)
			(xy 191.334664 -92.20007) (xy 191.273837 -92.207401) (xy 191.243204 -92.207842) (xy 191.210966 -92.207336)
			(xy 191.147007 -92.199182) (xy 191.084593 -92.183003) (xy 191.024727 -92.159061) (xy 190.96837 -92.127739)
			(xy 190.916426 -92.089541) (xy 190.869732 -92.04508) (xy 190.848996 -92.02039) (xy 190.841912 -92.01258)
			(xy 190.823154 -92.003001) (xy 190.812674 -92.001848) (xy 190.726822 -91.997022) (xy 190.707264 -92.004134)
			(xy 190.69939 -92.011754) (xy 190.675597 -92.034207) (xy 190.623238 -92.073431) (xy 190.566282 -92.105617)
			(xy 190.505668 -92.130234) (xy 190.442398 -92.146875) (xy 190.377517 -92.155265) (xy 190.344806 -92.155772)
			(xy 190.312841 -92.155363) (xy 190.249415 -92.147352) (xy 190.187494 -92.131453) (xy 190.128054 -92.10792)
			(xy 190.072031 -92.077122) (xy 190.020311 -92.039545) (xy 189.973708 -91.995783) (xy 189.932957 -91.946524)
			(xy 189.898702 -91.892547) (xy 189.871482 -91.834702) (xy 189.851726 -91.773901) (xy 189.839747 -91.711104)
			(xy 189.835732 -91.6473) (xy 186.986713 -91.6473) (xy 186.983245 -91.702405) (xy 186.971265 -91.765204)
			(xy 186.951508 -91.826005) (xy 186.924287 -91.883851) (xy 186.890029 -91.937829) (xy 186.849277 -91.987088)
			(xy 186.802671 -92.03085) (xy 186.750948 -92.068426) (xy 186.694924 -92.099222) (xy 186.635481 -92.122753)
			(xy 186.573557 -92.138649) (xy 186.51013 -92.146657) (xy 186.478164 -92.147136) (xy 186.446596 -92.146619)
			(xy 186.38395 -92.138764) (xy 186.322758 -92.123218) (xy 186.26396 -92.100219) (xy 186.20846 -92.07012)
			(xy 186.182508 -92.05214) (xy 186.173155 -92.046212) (xy 186.151408 -92.042178) (xy 186.129973 -92.04763)
			(xy 186.12104 -92.054172) (xy 186.093736 -92.075474) (xy 186.03449 -92.111329) (xy 185.970931 -92.138822)
			(xy 185.904233 -92.157447) (xy 185.835625 -92.16686) (xy 185.801 -92.167456) (xy 185.769042 -92.166858)
			(xy 185.70563 -92.158847) (xy 185.643722 -92.142952) (xy 185.584294 -92.119423) (xy 185.528284 -92.088631)
			(xy 185.476575 -92.051062) (xy 185.429982 -92.007309) (xy 185.389241 -91.958061) (xy 185.354993 -91.904095)
			(xy 185.327779 -91.846262) (xy 185.308027 -91.785474) (xy 185.296051 -91.72269) (xy 185.292038 -91.6589)
			(xy 184.277507 -91.6589) (xy 184.277508 -91.658948) (xy 184.277006 -91.690909) (xy 184.268995 -91.754327)
			(xy 184.253098 -91.816241) (xy 184.229566 -91.875674) (xy 184.198772 -91.931689) (xy 184.161199 -91.983404)
			(xy 184.117442 -92.030001) (xy 184.068189 -92.070746) (xy 184.014218 -92.104997) (xy 183.956379 -92.132214)
			(xy 183.895586 -92.151967) (xy 183.832796 -92.163945) (xy 183.769 -92.167959) (xy 183.705204 -92.163945)
			(xy 183.642414 -92.151967) (xy 183.581621 -92.132214) (xy 183.523782 -92.104997) (xy 183.469811 -92.070746)
			(xy 183.420558 -92.030001) (xy 183.376801 -91.983404) (xy 183.339228 -91.931689) (xy 183.308434 -91.875674)
			(xy 183.284902 -91.816241) (xy 183.269005 -91.754327) (xy 183.260994 -91.690909) (xy 183.133289 -91.690909)
			(xy 183.126218 -91.740089) (xy 183.110865 -91.792377) (xy 183.088227 -91.841948) (xy 183.058764 -91.887792)
			(xy 183.023077 -91.928977) (xy 182.981892 -91.964664) (xy 182.936048 -91.994127) (xy 182.886477 -92.016765)
			(xy 182.834189 -92.032118) (xy 182.780248 -92.039874) (xy 182.753 -92.040456) (xy 182.72491 -92.039956)
			(xy 182.669339 -92.031714) (xy 182.615579 -92.015408) (xy 182.564792 -91.991392) (xy 182.541164 -91.976194)
			(xy 182.537608 -91.973908) (xy 182.53321 -91.971577) (xy 182.52374 -91.968515) (xy 182.518812 -91.967812)
			(xy 182.511954 -91.967558) (xy 182.506696 -91.967826) (xy 182.496456 -91.970267) (xy 182.491634 -91.972384)
			(xy 182.464964 -91.986608) (xy 182.40756 -92.017596) (xy 182.402832 -92.020639) (xy 182.394765 -92.02847)
			(xy 182.391558 -92.03309) (xy 182.388597 -92.037866) (xy 182.384631 -92.048378) (xy 182.383684 -92.053918)
			(xy 182.383684 -92.054426) (xy 182.38343 -92.05595) (xy 182.383176 -92.061284) (xy 182.383176 -92.631514)
			(xy 182.38343 -92.637102) (xy 182.384791 -92.646378) (xy 182.393241 -92.663096) (xy 182.407132 -92.675662)
			(xy 182.42461 -92.6824) (xy 182.433976 -92.682822) (xy 183.81218 -92.682822) (xy 183.822243 -92.68326)
			(xy 183.840825 -92.690998) (xy 183.848248 -92.697808) (xy 184.429908 -93.279468) (xy 184.436666 -93.285641)
			(xy 184.453323 -93.293198) (xy 184.46242 -93.2942) (xy 184.47131 -93.294708) (xy 184.488582 -93.289628)
			(xy 184.496202 -93.28404) (xy 184.522696 -93.26482) (xy 184.579676 -93.232612) (xy 184.640317 -93.207977)
			(xy 184.703617 -93.191322) (xy 184.768529 -93.182922) (xy 184.801256 -93.18244) (xy 184.8318 -93.182895)
			(xy 184.892448 -93.190219) (xy 184.951782 -93.204753) (xy 185.008949 -93.22629) (xy 185.063124 -93.254518)
			(xy 185.113528 -93.289031) (xy 185.159436 -93.329334) (xy 185.200187 -93.374844) (xy 185.21807 -93.39961)
			(xy 185.227468 -93.40977) (xy 185.233695 -93.414438) (xy 185.248177 -93.420118) (xy 185.255916 -93.420946)
			(xy 185.259472 -93.4212) (xy 185.34253 -93.4212) (xy 185.34761 -93.420946) (xy 185.347864 -93.420946)
			(xy 185.355194 -93.419888) (xy 185.368866 -93.414216) (xy 185.374788 -93.40977) (xy 185.384186 -93.39961)
			(xy 185.402054 -93.374831) (xy 185.442797 -93.329307) (xy 185.488702 -93.288995) (xy 185.539107 -93.254475)
			(xy 185.593287 -93.226245) (xy 185.650459 -93.204711) (xy 185.709799 -93.190185) (xy 185.770453 -93.182875)
			(xy 185.801 -93.18244) (xy 185.813722 -93.182518) (xy 185.839134 -93.183788) (xy 185.8518 -93.18498)
			(xy 185.88343 -93.188639) (xy 185.945502 -93.202835) (xy 186.005317 -93.224669) (xy 186.061937 -93.2538)
			(xy 186.114478 -93.289771) (xy 186.162117 -93.33202) (xy 186.204109 -93.379886) (xy 186.222386 -93.40596)
			(xy 186.224498 -93.409) (xy 186.229475 -93.41448) (xy 186.232292 -93.416882) (xy 186.244484 -93.426788)
			(xy 186.24975 -93.429229) (xy 186.261035 -93.431929) (xy 186.266836 -93.432122) (xy 186.351164 -93.432122)
			(xy 186.363864 -93.430598) (xy 186.372877 -93.427903) (xy 186.388149 -93.416942) (xy 186.393582 -93.409262)
			(xy 186.411303 -93.383483) (xy 186.452076 -93.336037) (xy 186.498363 -93.293954) (xy 186.549463 -93.257867)
			(xy 186.604606 -93.228324) (xy 186.662957 -93.205769) (xy 186.723634 -93.190545) (xy 186.785721 -93.182882)
			(xy 186.817 -93.18244) (xy 186.848474 -93.18291) (xy 186.910941 -93.190675) (xy 186.971973 -93.206085)
			(xy 187.030639 -93.228905) (xy 187.086041 -93.258787) (xy 187.137335 -93.295275) (xy 187.183737 -93.33781)
			(xy 187.224537 -93.385745) (xy 187.242196 -93.411802) (xy 187.247817 -93.418667) (xy 187.262619 -93.428426)
			(xy 187.271152 -93.430852) (xy 187.282836 -93.432122) (xy 187.367164 -93.432122) (xy 187.379864 -93.430598)
			(xy 187.388877 -93.427903) (xy 187.404149 -93.416942) (xy 187.409582 -93.409262) (xy 187.427303 -93.383483)
			(xy 187.468076 -93.336037) (xy 187.514363 -93.293954) (xy 187.565463 -93.257867) (xy 187.620606 -93.228324)
			(xy 187.678957 -93.205769) (xy 187.739634 -93.190545) (xy 187.801721 -93.182882) (xy 187.833 -93.18244)
			(xy 187.864474 -93.18291) (xy 187.926941 -93.190675) (xy 187.987973 -93.206085) (xy 188.046639 -93.228905)
			(xy 188.102041 -93.258787) (xy 188.153335 -93.295275) (xy 188.199737 -93.33781) (xy 188.240537 -93.385745)
			(xy 188.258196 -93.411802) (xy 188.263817 -93.418667) (xy 188.278619 -93.428426) (xy 188.287152 -93.430852)
			(xy 188.298836 -93.432122) (xy 188.383164 -93.432122) (xy 188.395864 -93.430598) (xy 188.404877 -93.427903)
			(xy 188.420149 -93.416942) (xy 188.425582 -93.409262) (xy 188.443303 -93.383483) (xy 188.484076 -93.336037)
			(xy 188.530363 -93.293954) (xy 188.581463 -93.257867) (xy 188.636606 -93.228324) (xy 188.694957 -93.205769)
			(xy 188.755634 -93.190545) (xy 188.817721 -93.182882) (xy 188.849 -93.18244) (xy 188.880474 -93.18291)
			(xy 188.942941 -93.190675) (xy 189.003973 -93.206085) (xy 189.062639 -93.228905) (xy 189.118041 -93.258787)
			(xy 189.169335 -93.295275) (xy 189.215737 -93.33781) (xy 189.256537 -93.385745) (xy 189.274196 -93.411802)
			(xy 189.279817 -93.418667) (xy 189.294619 -93.428426) (xy 189.303152 -93.430852) (xy 189.314836 -93.432122)
			(xy 189.399164 -93.432122) (xy 189.411864 -93.430598) (xy 189.420877 -93.427903) (xy 189.436149 -93.416942)
			(xy 189.441582 -93.409262) (xy 189.459303 -93.383483) (xy 189.500076 -93.336037) (xy 189.546363 -93.293954)
			(xy 189.597463 -93.257867) (xy 189.652606 -93.228324) (xy 189.710957 -93.205769) (xy 189.771634 -93.190545)
			(xy 189.833721 -93.182882) (xy 189.865 -93.18244) (xy 189.896474 -93.18291) (xy 189.958941 -93.190675)
			(xy 190.019973 -93.206085) (xy 190.078639 -93.228905) (xy 190.134041 -93.258787) (xy 190.185335 -93.295275)
			(xy 190.231737 -93.33781) (xy 190.272537 -93.385745) (xy 190.290196 -93.411802) (xy 190.295817 -93.418667)
			(xy 190.310619 -93.428426) (xy 190.319152 -93.430852) (xy 190.330836 -93.432122) (xy 190.415164 -93.432122)
			(xy 190.427864 -93.430598) (xy 190.436877 -93.427903) (xy 190.452149 -93.416942) (xy 190.457582 -93.409262)
			(xy 190.475303 -93.383483) (xy 190.516076 -93.336037) (xy 190.562363 -93.293954) (xy 190.613463 -93.257867)
			(xy 190.668606 -93.228324) (xy 190.726957 -93.205769) (xy 190.787634 -93.190545) (xy 190.849721 -93.182882)
			(xy 190.881 -93.18244) (xy 190.912634 -93.182921) (xy 190.975413 -93.190769) (xy 191.036734 -93.206343)
			(xy 191.09565 -93.229404) (xy 191.15125 -93.259595) (xy 191.202675 -93.29645) (xy 191.249132 -93.339398)
			(xy 191.269874 -93.363288) (xy 191.270382 -93.363796) (xy 191.273893 -93.367703) (xy 191.282215 -93.374106)
			(xy 191.286892 -93.376496) (xy 191.287908 -93.377004) (xy 191.296798 -93.381322) (xy 191.297814 -93.381322)
			(xy 191.345566 -93.38183) (xy 191.38519 -93.382338) (xy 191.390681 -93.382272) (xy 191.401441 -93.380093)
			(xy 191.406526 -93.37802) (xy 191.416178 -93.373702) (xy 191.423544 -93.36532) (xy 191.444258 -93.342596)
			(xy 191.490272 -93.301806) (xy 191.540869 -93.266862) (xy 191.59531 -93.238274) (xy 191.652801 -93.21646)
			(xy 191.712503 -93.201738) (xy 191.773545 -93.194322) (xy 191.80429 -93.19387) (xy 191.836254 -93.19435)
			(xy 191.899678 -93.202362) (xy 191.961599 -93.218259) (xy 192.021038 -93.241792) (xy 192.077059 -93.272588)
			(xy 192.128779 -93.310164) (xy 192.175381 -93.353925) (xy 192.216131 -93.403183) (xy 192.250385 -93.457159)
			(xy 192.277605 -93.515003) (xy 192.278309 -93.517169) (xy 193.797676 -93.517169) (xy 193.797676 -93.453247)
			(xy 193.805687 -93.389829) (xy 193.821584 -93.327915) (xy 193.845116 -93.268482) (xy 193.87591 -93.212467)
			(xy 193.913483 -93.160752) (xy 193.95724 -93.114155) (xy 194.006493 -93.07341) (xy 194.060464 -93.039159)
			(xy 194.118303 -93.011942) (xy 194.179096 -92.992189) (xy 194.241886 -92.980211) (xy 194.305682 -92.976198)
			(xy 194.369478 -92.980211) (xy 194.432268 -92.992189) (xy 194.493061 -93.011942) (xy 194.5509 -93.039159)
			(xy 194.604871 -93.07341) (xy 194.654124 -93.114155) (xy 194.697881 -93.160752) (xy 194.735454 -93.212467)
			(xy 194.766248 -93.268482) (xy 194.78978 -93.327915) (xy 194.802373 -93.376961) (xy 198.754994 -93.376961)
			(xy 198.754994 -93.313039) (xy 198.763005 -93.249621) (xy 198.778902 -93.187707) (xy 198.802434 -93.128274)
			(xy 198.833228 -93.072259) (xy 198.870801 -93.020544) (xy 198.914558 -92.973947) (xy 198.963811 -92.933202)
			(xy 199.017782 -92.898951) (xy 199.075621 -92.871734) (xy 199.136414 -92.851981) (xy 199.199204 -92.840003)
			(xy 199.263 -92.83599) (xy 199.326796 -92.840003) (xy 199.389586 -92.851981) (xy 199.450379 -92.871734)
			(xy 199.508218 -92.898951) (xy 199.562189 -92.933202) (xy 199.611442 -92.973947) (xy 199.655199 -93.020544)
			(xy 199.692772 -93.072259) (xy 199.723566 -93.128274) (xy 199.747098 -93.187707) (xy 199.756887 -93.225831)
			(xy 207.208114 -93.225831) (xy 207.208114 -93.161909) (xy 207.216125 -93.098491) (xy 207.232022 -93.036577)
			(xy 207.255554 -92.977144) (xy 207.286348 -92.921129) (xy 207.323921 -92.869414) (xy 207.367678 -92.822817)
			(xy 207.416931 -92.782072) (xy 207.470902 -92.747821) (xy 207.528741 -92.720604) (xy 207.589534 -92.700851)
			(xy 207.652324 -92.688873) (xy 207.71612 -92.68486) (xy 207.779916 -92.688873) (xy 207.842706 -92.700851)
			(xy 207.903499 -92.720604) (xy 207.961338 -92.747821) (xy 208.015309 -92.782072) (xy 208.064562 -92.822817)
			(xy 208.108319 -92.869414) (xy 208.145892 -92.921129) (xy 208.176686 -92.977144) (xy 208.200218 -93.036577)
			(xy 208.216115 -93.098491) (xy 208.224126 -93.161909) (xy 208.224628 -93.19387) (xy 208.224126 -93.225831)
			(xy 208.222324 -93.240098) (xy 255.289812 -93.240098) (xy 255.290239 -93.209776) (xy 255.297452 -93.149563)
			(xy 255.311776 -93.090635) (xy 255.333007 -93.033829) (xy 255.360843 -92.979951) (xy 255.394891 -92.929767)
			(xy 255.434665 -92.883988) (xy 255.479602 -92.843265) (xy 255.529064 -92.808177) (xy 255.555496 -92.793312)
			(xy 255.562808 -92.788996) (xy 255.574229 -92.77644) (xy 255.580954 -92.760856) (xy 255.581912 -92.752418)
			(xy 255.589532 -92.654374) (xy 255.578864 -92.630752) (xy 255.56845 -92.623132) (xy 255.545406 -92.604984)
			(xy 255.504675 -92.562779) (xy 255.470876 -92.514841) (xy 255.444806 -92.462298) (xy 255.427078 -92.406386)
			(xy 255.418109 -92.348421) (xy 255.417574 -92.319094) (xy 255.418072 -92.291843) (xy 255.425829 -92.237897)
			(xy 255.441184 -92.185604) (xy 255.463825 -92.136028) (xy 255.49329 -92.090178) (xy 255.52898 -92.048988)
			(xy 255.570168 -92.013297) (xy 255.616017 -91.98383) (xy 255.665592 -91.961188) (xy 255.717885 -91.945832)
			(xy 255.771831 -91.938073) (xy 255.799082 -91.937586) (xy 255.826075 -91.93805) (xy 255.879524 -91.945655)
			(xy 255.931367 -91.960714) (xy 255.980572 -91.982927) (xy 256.026156 -92.011852) (xy 256.046986 -92.029026)
			(xy 256.055114 -92.036138) (xy 256.07518 -92.042234) (xy 256.170176 -92.031058) (xy 256.18821 -92.020644)
			(xy 256.19456 -92.012008) (xy 256.215183 -91.984969) (xy 256.262487 -91.936112) (xy 256.315876 -91.893992)
			(xy 256.3744 -91.859358) (xy 256.437016 -91.832828) (xy 256.502607 -91.814875) (xy 256.570006 -91.805818)
			(xy 256.604008 -91.805252) (xy 256.635966 -91.805834) (xy 256.699378 -91.813846) (xy 256.761287 -91.829742)
			(xy 256.820714 -91.853272) (xy 256.876724 -91.884065) (xy 256.928433 -91.921634) (xy 256.975026 -91.965389)
			(xy 257.015768 -92.014637) (xy 257.050015 -92.068604) (xy 257.07723 -92.126437) (xy 257.096981 -92.187225)
			(xy 257.108957 -92.25001) (xy 257.112971 -92.3138) (xy 257.108957 -92.37759) (xy 257.096981 -92.440375)
			(xy 257.07969 -92.493592) (xy 449.330062 -92.493592) (xy 449.334133 -92.43797) (xy 449.346259 -92.383533)
			(xy 449.366182 -92.331442) (xy 449.393478 -92.282807) (xy 449.427564 -92.238664) (xy 449.467713 -92.199955)
			(xy 449.513071 -92.167504) (xy 449.562671 -92.142003) (xy 449.615455 -92.123996) (xy 449.670298 -92.113866)
			(xy 449.726032 -92.111829) (xy 449.781469 -92.117929) (xy 449.835426 -92.132035) (xy 449.886755 -92.153847)
			(xy 449.934361 -92.182901) (xy 449.977229 -92.218576) (xy 450.014446 -92.260113) (xy 450.045219 -92.306626)
			(xy 450.068891 -92.357123) (xy 450.084959 -92.41053) (xy 450.093079 -92.465706) (xy 450.093588 -92.493592)
			(xy 450.093079 -92.521478) (xy 450.084959 -92.576654) (xy 450.068891 -92.630061) (xy 450.045219 -92.680558)
			(xy 450.014446 -92.727071) (xy 449.977229 -92.768608) (xy 449.934361 -92.804283) (xy 449.886755 -92.833337)
			(xy 449.835426 -92.855149) (xy 449.781469 -92.869255) (xy 449.726032 -92.875355) (xy 449.670298 -92.873318)
			(xy 449.615455 -92.863188) (xy 449.562671 -92.845181) (xy 449.513071 -92.81968) (xy 449.467713 -92.787229)
			(xy 449.427564 -92.74852) (xy 449.393478 -92.704377) (xy 449.366182 -92.655742) (xy 449.346259 -92.603651)
			(xy 449.334133 -92.549214) (xy 449.330062 -92.493592) (xy 257.07969 -92.493592) (xy 257.07723 -92.501163)
			(xy 257.050015 -92.558996) (xy 257.015768 -92.612963) (xy 256.975026 -92.662211) (xy 256.928433 -92.705966)
			(xy 256.876724 -92.743535) (xy 256.820714 -92.774328) (xy 256.761287 -92.797858) (xy 256.699378 -92.813754)
			(xy 256.635966 -92.821766) (xy 256.604008 -92.822268) (xy 256.57049 -92.821676) (xy 256.504035 -92.812862)
			(xy 256.439312 -92.7954) (xy 256.377443 -92.769591) (xy 256.319497 -92.735883) (xy 256.266479 -92.694859)
			(xy 256.219305 -92.647229) (xy 256.198624 -92.620846) (xy 256.192274 -92.612464) (xy 256.173986 -92.60205)
			(xy 256.078736 -92.592652) (xy 256.05867 -92.599002) (xy 256.050796 -92.60586) (xy 256.029206 -92.623386)
			(xy 256.019477 -92.631633) (xy 256.008951 -92.654829) (xy 256.00914 -92.667582) (xy 256.016506 -92.76588)
			(xy 256.030222 -92.787216) (xy 256.041652 -92.793566) (xy 256.068057 -92.808414) (xy 256.117427 -92.843527)
			(xy 256.162275 -92.884256) (xy 256.201968 -92.930024) (xy 256.235943 -92.980183) (xy 256.263719 -93.034023)
			(xy 256.284903 -93.090781) (xy 256.299194 -93.149653) (xy 256.302868 -93.180365) (xy 271.692618 -93.180365)
			(xy 271.692618 -93.116443) (xy 271.700629 -93.053025) (xy 271.716526 -92.991111) (xy 271.740058 -92.931678)
			(xy 271.770852 -92.875663) (xy 271.808425 -92.823948) (xy 271.852182 -92.777351) (xy 271.901435 -92.736606)
			(xy 271.955406 -92.702355) (xy 272.013245 -92.675138) (xy 272.074038 -92.655385) (xy 272.136828 -92.643407)
			(xy 272.200624 -92.639394) (xy 272.26442 -92.643407) (xy 272.32721 -92.655385) (xy 272.388003 -92.675138)
			(xy 272.445842 -92.702355) (xy 272.499813 -92.736606) (xy 272.549066 -92.777351) (xy 272.592823 -92.823948)
			(xy 272.630396 -92.875663) (xy 272.66119 -92.931678) (xy 272.684722 -92.991111) (xy 272.700619 -93.053025)
			(xy 272.70863 -93.116443) (xy 272.709132 -93.148404) (xy 272.70863 -93.180365) (xy 272.702405 -93.229641)
			(xy 411.398714 -93.229641) (xy 411.398714 -93.165719) (xy 411.406725 -93.102301) (xy 411.422622 -93.040387)
			(xy 411.446154 -92.980954) (xy 411.476948 -92.924939) (xy 411.514521 -92.873224) (xy 411.558278 -92.826627)
			(xy 411.607531 -92.785882) (xy 411.661502 -92.751631) (xy 411.719341 -92.724414) (xy 411.780134 -92.704661)
			(xy 411.842924 -92.692683) (xy 411.90672 -92.68867) (xy 411.970516 -92.692683) (xy 412.033306 -92.704661)
			(xy 412.094099 -92.724414) (xy 412.151938 -92.751631) (xy 412.205909 -92.785882) (xy 412.255162 -92.826627)
			(xy 412.298919 -92.873224) (xy 412.336492 -92.924939) (xy 412.367286 -92.980954) (xy 412.390818 -93.040387)
			(xy 412.406715 -93.102301) (xy 412.414726 -93.165719) (xy 412.415228 -93.19768) (xy 412.414726 -93.229641)
			(xy 412.406715 -93.293059) (xy 412.390818 -93.354973) (xy 412.367286 -93.414406) (xy 412.336492 -93.470421)
			(xy 412.298919 -93.522136) (xy 412.255162 -93.568733) (xy 412.205909 -93.609478) (xy 412.151938 -93.643729)
			(xy 412.094099 -93.670946) (xy 412.033306 -93.690699) (xy 411.970516 -93.702677) (xy 411.90672 -93.706691)
			(xy 411.842924 -93.702677) (xy 411.780134 -93.690699) (xy 411.719341 -93.670946) (xy 411.661502 -93.643729)
			(xy 411.607531 -93.609478) (xy 411.558278 -93.568733) (xy 411.514521 -93.522136) (xy 411.476948 -93.470421)
			(xy 411.446154 -93.414406) (xy 411.422622 -93.354973) (xy 411.406725 -93.293059) (xy 411.398714 -93.229641)
			(xy 272.702405 -93.229641) (xy 272.700619 -93.243783) (xy 272.684722 -93.305697) (xy 272.66119 -93.36513)
			(xy 272.630396 -93.421145) (xy 272.592823 -93.47286) (xy 272.549066 -93.519457) (xy 272.499813 -93.560202)
			(xy 272.445842 -93.594453) (xy 272.388003 -93.62167) (xy 272.32721 -93.641423) (xy 272.26442 -93.653401)
			(xy 272.200624 -93.657415) (xy 272.136828 -93.653401) (xy 272.074038 -93.641423) (xy 272.013245 -93.62167)
			(xy 271.955406 -93.594453) (xy 271.901435 -93.560202) (xy 271.852182 -93.519457) (xy 271.808425 -93.47286)
			(xy 271.770852 -93.421145) (xy 271.740058 -93.36513) (xy 271.716526 -93.305697) (xy 271.700629 -93.243783)
			(xy 271.692618 -93.180365) (xy 256.302868 -93.180365) (xy 256.306391 -93.209807) (xy 256.306828 -93.240098)
			(xy 256.306326 -93.272059) (xy 256.298315 -93.335477) (xy 256.282418 -93.397391) (xy 256.258886 -93.456824)
			(xy 256.228092 -93.512839) (xy 256.190519 -93.564554) (xy 256.146762 -93.611151) (xy 256.097509 -93.651896)
			(xy 256.043538 -93.686147) (xy 255.985699 -93.713364) (xy 255.924906 -93.733117) (xy 255.862116 -93.745095)
			(xy 255.79832 -93.749109) (xy 255.734524 -93.745095) (xy 255.671734 -93.733117) (xy 255.610941 -93.713364)
			(xy 255.553102 -93.686147) (xy 255.499131 -93.651896) (xy 255.449878 -93.611151) (xy 255.406121 -93.564554)
			(xy 255.368548 -93.512839) (xy 255.337754 -93.456824) (xy 255.314222 -93.397391) (xy 255.298325 -93.335477)
			(xy 255.290314 -93.272059) (xy 255.289812 -93.240098) (xy 208.222324 -93.240098) (xy 208.216115 -93.289249)
			(xy 208.200218 -93.351163) (xy 208.176686 -93.410596) (xy 208.145892 -93.466611) (xy 208.108319 -93.518326)
			(xy 208.064562 -93.564923) (xy 208.015309 -93.605668) (xy 207.961338 -93.639919) (xy 207.903499 -93.667136)
			(xy 207.842706 -93.686889) (xy 207.779916 -93.698867) (xy 207.71612 -93.702881) (xy 207.652324 -93.698867)
			(xy 207.589534 -93.686889) (xy 207.528741 -93.667136) (xy 207.470902 -93.639919) (xy 207.416931 -93.605668)
			(xy 207.367678 -93.564923) (xy 207.323921 -93.518326) (xy 207.286348 -93.466611) (xy 207.255554 -93.410596)
			(xy 207.232022 -93.351163) (xy 207.216125 -93.289249) (xy 207.208114 -93.225831) (xy 199.756887 -93.225831)
			(xy 199.762995 -93.249621) (xy 199.771006 -93.313039) (xy 199.771508 -93.345) (xy 199.771006 -93.376961)
			(xy 199.762995 -93.440379) (xy 199.747098 -93.502293) (xy 199.723566 -93.561726) (xy 199.692772 -93.617741)
			(xy 199.655199 -93.669456) (xy 199.611442 -93.716053) (xy 199.562189 -93.756798) (xy 199.508218 -93.791049)
			(xy 199.450379 -93.818266) (xy 199.389586 -93.838019) (xy 199.326796 -93.849997) (xy 199.263 -93.854011)
			(xy 199.199204 -93.849997) (xy 199.136414 -93.838019) (xy 199.075621 -93.818266) (xy 199.017782 -93.791049)
			(xy 198.963811 -93.756798) (xy 198.914558 -93.716053) (xy 198.870801 -93.669456) (xy 198.833228 -93.617741)
			(xy 198.802434 -93.561726) (xy 198.778902 -93.502293) (xy 198.763005 -93.440379) (xy 198.754994 -93.376961)
			(xy 194.802373 -93.376961) (xy 194.805677 -93.389829) (xy 194.813688 -93.453247) (xy 194.81419 -93.485208)
			(xy 194.813688 -93.517169) (xy 194.805677 -93.580587) (xy 194.78978 -93.642501) (xy 194.766248 -93.701934)
			(xy 194.735454 -93.757949) (xy 194.697881 -93.809664) (xy 194.654124 -93.856261) (xy 194.604871 -93.897006)
			(xy 194.5509 -93.931257) (xy 194.493061 -93.958474) (xy 194.432268 -93.978227) (xy 194.369478 -93.990205)
			(xy 194.305682 -93.994219) (xy 194.241886 -93.990205) (xy 194.179096 -93.978227) (xy 194.118303 -93.958474)
			(xy 194.060464 -93.931257) (xy 194.006493 -93.897006) (xy 193.95724 -93.856261) (xy 193.913483 -93.809664)
			(xy 193.87591 -93.757949) (xy 193.845116 -93.701934) (xy 193.821584 -93.642501) (xy 193.805687 -93.580587)
			(xy 193.797676 -93.517169) (xy 192.278309 -93.517169) (xy 192.29736 -93.575802) (xy 192.309339 -93.638598)
			(xy 192.313354 -93.7024) (xy 192.309339 -93.766202) (xy 192.29736 -93.828998) (xy 192.277605 -93.889797)
			(xy 192.250385 -93.947641) (xy 192.216131 -94.001617) (xy 192.175381 -94.050875) (xy 192.128779 -94.094636)
			(xy 192.077059 -94.132212) (xy 192.021038 -94.163008) (xy 191.961599 -94.186541) (xy 191.899678 -94.202438)
			(xy 191.836254 -94.21045) (xy 191.80429 -94.210886) (xy 191.772657 -94.210404) (xy 191.709879 -94.202554)
			(xy 191.648561 -94.186977) (xy 191.589648 -94.163913) (xy 191.534052 -94.133718) (xy 191.482631 -94.09686)
			(xy 191.436181 -94.053907) (xy 191.415416 -94.030038) (xy 191.414908 -94.02953) (xy 191.411394 -94.025628)
			(xy 191.403066 -94.019236) (xy 191.398398 -94.01683) (xy 191.397382 -94.016322) (xy 191.388492 -94.012004)
			(xy 191.387476 -94.012004) (xy 191.339724 -94.011496) (xy 191.3001 -94.010988) (xy 191.294609 -94.011055)
			(xy 191.283849 -94.013233) (xy 191.278764 -94.015306) (xy 191.269112 -94.019624) (xy 191.261746 -94.028006)
			(xy 191.241031 -94.050729) (xy 191.195016 -94.091516) (xy 191.144419 -94.126457) (xy 191.089978 -94.155042)
			(xy 191.032487 -94.176854) (xy 190.972786 -94.191574) (xy 190.911745 -94.198989) (xy 190.881 -94.199456)
			(xy 190.868278 -94.199378) (xy 190.842866 -94.198108) (xy 190.8302 -94.196916) (xy 190.79857 -94.193257)
			(xy 190.736498 -94.179061) (xy 190.676684 -94.157226) (xy 190.620063 -94.128096) (xy 190.567522 -94.092124)
			(xy 190.519884 -94.049875) (xy 190.477892 -94.002009) (xy 190.459614 -93.975936) (xy 190.457502 -93.972896)
			(xy 190.452524 -93.967417) (xy 190.449708 -93.965014) (xy 190.437516 -93.955108) (xy 190.432251 -93.952663)
			(xy 190.420965 -93.949958) (xy 190.415164 -93.949774) (xy 190.330836 -93.949774) (xy 190.318136 -93.951298)
			(xy 190.309123 -93.953992) (xy 190.29385 -93.964953) (xy 190.288418 -93.972634) (xy 190.270697 -93.998414)
			(xy 190.229924 -94.045859) (xy 190.183638 -94.087943) (xy 190.132537 -94.12403) (xy 190.077394 -94.153574)
			(xy 190.019044 -94.176128) (xy 189.958366 -94.191352) (xy 189.896279 -94.199016) (xy 189.865 -94.199456)
			(xy 189.833526 -94.198986) (xy 189.771059 -94.191221) (xy 189.710027 -94.175811) (xy 189.651362 -94.152991)
			(xy 189.595959 -94.123109) (xy 189.544666 -94.086621) (xy 189.498264 -94.044085) (xy 189.457464 -93.99615)
			(xy 189.439804 -93.970094) (xy 189.434183 -93.96323) (xy 189.41938 -93.953471) (xy 189.410848 -93.951044)
			(xy 189.399164 -93.949774) (xy 189.314836 -93.949774) (xy 189.302136 -93.951298) (xy 189.293123 -93.953992)
			(xy 189.27785 -93.964953) (xy 189.272418 -93.972634) (xy 189.254697 -93.998414) (xy 189.213924 -94.045859)
			(xy 189.167638 -94.087943) (xy 189.116537 -94.12403) (xy 189.061394 -94.153574) (xy 189.003044 -94.176128)
			(xy 188.942366 -94.191352) (xy 188.880279 -94.199016) (xy 188.849 -94.199456) (xy 188.817526 -94.198986)
			(xy 188.755059 -94.191221) (xy 188.694027 -94.175811) (xy 188.635362 -94.152991) (xy 188.579959 -94.123109)
			(xy 188.528666 -94.086621) (xy 188.482264 -94.044085) (xy 188.441464 -93.99615) (xy 188.423804 -93.970094)
			(xy 188.418183 -93.96323) (xy 188.40338 -93.953471) (xy 188.394848 -93.951044) (xy 188.383164 -93.949774)
			(xy 188.298836 -93.949774) (xy 188.286136 -93.951298) (xy 188.277123 -93.953992) (xy 188.26185 -93.964953)
			(xy 188.256418 -93.972634) (xy 188.238697 -93.998414) (xy 188.197924 -94.045859) (xy 188.151638 -94.087943)
			(xy 188.100537 -94.12403) (xy 188.045394 -94.153574) (xy 187.987044 -94.176128) (xy 187.926366 -94.191352)
			(xy 187.864279 -94.199016) (xy 187.833 -94.199456) (xy 187.801526 -94.198986) (xy 187.739059 -94.191221)
			(xy 187.678027 -94.175811) (xy 187.619362 -94.152991) (xy 187.563959 -94.123109) (xy 187.512666 -94.086621)
			(xy 187.466264 -94.044085) (xy 187.425464 -93.99615) (xy 187.407804 -93.970094) (xy 187.402183 -93.96323)
			(xy 187.38738 -93.953471) (xy 187.378848 -93.951044) (xy 187.367164 -93.949774) (xy 187.282836 -93.949774)
			(xy 187.270136 -93.951298) (xy 187.261123 -93.953992) (xy 187.24585 -93.964953) (xy 187.240418 -93.972634)
			(xy 187.222697 -93.998414) (xy 187.181924 -94.045859) (xy 187.135638 -94.087943) (xy 187.084537 -94.12403)
			(xy 187.029394 -94.153574) (xy 186.971044 -94.176128) (xy 186.910366 -94.191352) (xy 186.848279 -94.199016)
			(xy 186.817 -94.199456) (xy 186.785526 -94.198986) (xy 186.723059 -94.191221) (xy 186.662027 -94.175811)
			(xy 186.603362 -94.152991) (xy 186.547959 -94.123109) (xy 186.496666 -94.086621) (xy 186.450264 -94.044085)
			(xy 186.409464 -93.99615) (xy 186.391804 -93.970094) (xy 186.386183 -93.96323) (xy 186.37138 -93.953471)
			(xy 186.362848 -93.951044) (xy 186.351164 -93.949774) (xy 186.266836 -93.949774) (xy 186.254136 -93.951298)
			(xy 186.245123 -93.953992) (xy 186.22985 -93.964953) (xy 186.224418 -93.972634) (xy 186.206697 -93.998414)
			(xy 186.165924 -94.045859) (xy 186.119638 -94.087943) (xy 186.068537 -94.12403) (xy 186.013394 -94.153574)
			(xy 185.955044 -94.176128) (xy 185.894366 -94.191352) (xy 185.832279 -94.199016) (xy 185.801 -94.199456)
			(xy 185.770454 -94.199004) (xy 185.709803 -94.191686) (xy 185.650464 -94.177157) (xy 185.593293 -94.155625)
			(xy 185.539113 -94.1274) (xy 185.488704 -94.092888) (xy 185.442791 -94.052588) (xy 185.402035 -94.007077)
			(xy 185.384186 -93.982286) (xy 185.374788 -93.972126) (xy 185.368563 -93.967451) (xy 185.354083 -93.961756)
			(xy 185.34634 -93.96095) (xy 185.342784 -93.960696) (xy 185.259726 -93.960696) (xy 185.254646 -93.96095)
			(xy 185.254392 -93.96095) (xy 185.24601 -93.962474) (xy 185.235088 -93.967046) (xy 185.222388 -93.978476)
			(xy 185.215022 -93.986858) (xy 185.195053 -94.013834) (xy 185.149151 -94.0628) (xy 185.097205 -94.105302)
			(xy 185.04012 -94.140601) (xy 184.978888 -94.168084) (xy 184.914572 -94.187272) (xy 184.88152 -94.193106)
			(xy 184.877456 -94.193868) (xy 184.869864 -94.196055) (xy 184.856416 -94.204334) (xy 184.85104 -94.210124)
			(xy 184.845198 -94.216982) (xy 184.84215 -94.225364) (xy 184.840626 -94.229651) (xy 184.838957 -94.238595)
			(xy 184.838848 -94.243144) (xy 184.838848 -95.119909) (xy 187.324994 -95.119909) (xy 187.324994 -95.055987)
			(xy 187.333005 -94.992569) (xy 187.348902 -94.930655) (xy 187.372434 -94.871222) (xy 187.403228 -94.815207)
			(xy 187.440801 -94.763492) (xy 187.484558 -94.716895) (xy 187.533811 -94.67615) (xy 187.587782 -94.641899)
			(xy 187.645621 -94.614682) (xy 187.706414 -94.594929) (xy 187.769204 -94.582951) (xy 187.833 -94.578938)
			(xy 187.896796 -94.582951) (xy 187.959586 -94.594929) (xy 188.020379 -94.614682) (xy 188.078218 -94.641899)
			(xy 188.132189 -94.67615) (xy 188.181442 -94.716895) (xy 188.225199 -94.763492) (xy 188.262772 -94.815207)
			(xy 188.293566 -94.871222) (xy 188.317098 -94.930655) (xy 188.332995 -94.992569) (xy 188.341006 -95.055987)
			(xy 188.341508 -95.087948) (xy 188.341006 -95.119909) (xy 189.356994 -95.119909) (xy 189.356994 -95.055987)
			(xy 189.365005 -94.992569) (xy 189.380902 -94.930655) (xy 189.404434 -94.871222) (xy 189.435228 -94.815207)
			(xy 189.472801 -94.763492) (xy 189.516558 -94.716895) (xy 189.565811 -94.67615) (xy 189.619782 -94.641899)
			(xy 189.677621 -94.614682) (xy 189.738414 -94.594929) (xy 189.801204 -94.582951) (xy 189.865 -94.578938)
			(xy 189.928796 -94.582951) (xy 189.991586 -94.594929) (xy 190.052379 -94.614682) (xy 190.110218 -94.641899)
			(xy 190.164189 -94.67615) (xy 190.213442 -94.716895) (xy 190.257199 -94.763492) (xy 190.294772 -94.815207)
			(xy 190.325566 -94.871222) (xy 190.349098 -94.930655) (xy 190.364995 -94.992569) (xy 190.373006 -95.055987)
			(xy 190.373508 -95.087948) (xy 190.373006 -95.119909) (xy 191.214496 -95.119909) (xy 191.214496 -95.055987)
			(xy 191.222507 -94.992569) (xy 191.238404 -94.930655) (xy 191.261936 -94.871222) (xy 191.29273 -94.815207)
			(xy 191.330303 -94.763492) (xy 191.37406 -94.716895) (xy 191.423313 -94.67615) (xy 191.477284 -94.641899)
			(xy 191.535123 -94.614682) (xy 191.595916 -94.594929) (xy 191.658706 -94.582951) (xy 191.722502 -94.578938)
			(xy 191.786298 -94.582951) (xy 191.849088 -94.594929) (xy 191.909881 -94.614682) (xy 191.96772 -94.641899)
			(xy 192.021691 -94.67615) (xy 192.070944 -94.716895) (xy 192.114701 -94.763492) (xy 192.152274 -94.815207)
			(xy 192.183068 -94.871222) (xy 192.2066 -94.930655) (xy 192.222497 -94.992569) (xy 192.230508 -95.055987)
			(xy 192.23101 -95.087948) (xy 192.230854 -95.0979) (xy 193.631043 -95.0979) (xy 193.635057 -95.0341)
			(xy 193.647035 -94.971307) (xy 193.666789 -94.91051) (xy 193.694006 -94.852667) (xy 193.728259 -94.798693)
			(xy 193.769005 -94.749436) (xy 193.815604 -94.705675) (xy 193.86732 -94.668098) (xy 193.923337 -94.6373)
			(xy 193.982773 -94.613765) (xy 194.04469 -94.597865) (xy 194.108111 -94.58985) (xy 194.140074 -94.589346)
			(xy 194.146424 -94.589346) (xy 194.154058 -94.559375) (xy 194.175564 -94.501388) (xy 194.203943 -94.446436)
			(xy 194.238775 -94.39533) (xy 194.279547 -94.348824) (xy 194.325656 -94.307605) (xy 194.376423 -94.272281)
			(xy 194.431099 -94.243373) (xy 194.488876 -94.221308) (xy 194.548903 -94.206411) (xy 194.610292 -94.198902)
			(xy 194.641216 -94.19844) (xy 194.671682 -94.198895) (xy 194.732177 -94.20619) (xy 194.791367 -94.220661)
			(xy 194.848404 -94.242101) (xy 194.90247 -94.270203) (xy 194.952791 -94.304564) (xy 194.998645 -94.344691)
			(xy 195.039376 -94.390011) (xy 195.0744 -94.439872) (xy 195.103215 -94.493562) (xy 195.125408 -94.550309)
			(xy 195.133468 -94.579694) (xy 195.149216 -94.57944) (xy 195.181179 -94.579846) (xy 195.244602 -94.58786)
			(xy 195.30652 -94.60376) (xy 195.365957 -94.627295) (xy 195.421976 -94.658093) (xy 195.431475 -94.664995)
			(xy 202.263242 -94.664995) (xy 202.263242 -94.601073) (xy 202.271253 -94.537655) (xy 202.28715 -94.475741)
			(xy 202.310682 -94.416308) (xy 202.341476 -94.360293) (xy 202.379049 -94.308578) (xy 202.422806 -94.261981)
			(xy 202.472059 -94.221236) (xy 202.52603 -94.186985) (xy 202.583869 -94.159768) (xy 202.644662 -94.140015)
			(xy 202.707452 -94.128037) (xy 202.771248 -94.124024) (xy 202.835044 -94.128037) (xy 202.897834 -94.140015)
			(xy 202.958627 -94.159768) (xy 203.016466 -94.186985) (xy 203.070437 -94.221236) (xy 203.11969 -94.261981)
			(xy 203.163447 -94.308578) (xy 203.20102 -94.360293) (xy 203.231814 -94.416308) (xy 203.255346 -94.475741)
			(xy 203.271243 -94.537655) (xy 203.279254 -94.601073) (xy 203.279756 -94.633034) (xy 203.279254 -94.664995)
			(xy 203.271243 -94.728413) (xy 203.255346 -94.790327) (xy 203.231814 -94.84976) (xy 203.20102 -94.905775)
			(xy 203.163447 -94.95749) (xy 203.11969 -95.004087) (xy 203.070437 -95.044832) (xy 203.016466 -95.079083)
			(xy 202.958627 -95.1063) (xy 202.897834 -95.126053) (xy 202.835044 -95.138031) (xy 202.771248 -95.142045)
			(xy 202.707452 -95.138031) (xy 202.644662 -95.126053) (xy 202.583869 -95.1063) (xy 202.52603 -95.079083)
			(xy 202.472059 -95.044832) (xy 202.422806 -95.004087) (xy 202.379049 -94.95749) (xy 202.341476 -94.905775)
			(xy 202.310682 -94.84976) (xy 202.28715 -94.790327) (xy 202.271253 -94.728413) (xy 202.263242 -94.664995)
			(xy 195.431475 -94.664995) (xy 195.473693 -94.695669) (xy 195.520293 -94.739431) (xy 195.561041 -94.788688)
			(xy 195.595294 -94.842663) (xy 195.622513 -94.900506) (xy 195.642267 -94.961305) (xy 195.654245 -95.024099)
			(xy 195.658259 -95.0879) (xy 195.654245 -95.151701) (xy 195.642267 -95.214495) (xy 195.622513 -95.275294)
			(xy 195.595294 -95.333137) (xy 195.561041 -95.387112) (xy 195.520293 -95.436369) (xy 195.473693 -95.480131)
			(xy 195.421976 -95.517707) (xy 195.365957 -95.548505) (xy 195.30652 -95.57204) (xy 195.244602 -95.58794)
			(xy 195.181179 -95.595954) (xy 195.149216 -95.596456) (xy 195.118567 -95.595984) (xy 195.057712 -95.588631)
			(xy 194.998181 -95.574017) (xy 194.940839 -95.552355) (xy 194.886516 -95.523957) (xy 194.835999 -95.489237)
			(xy 194.790022 -95.448697) (xy 194.74925 -95.402925) (xy 194.731386 -95.378016) (xy 194.724274 -95.367602)
			(xy 194.701922 -95.356172) (xy 194.592448 -95.356934) (xy 194.57035 -95.369126) (xy 194.563492 -95.37954)
			(xy 194.545764 -95.405311) (xy 194.504978 -95.452737) (xy 194.458684 -95.494805) (xy 194.407582 -95.530879)
			(xy 194.352443 -95.560416) (xy 194.294099 -95.582971) (xy 194.233429 -95.598202) (xy 194.17135 -95.60588)
			(xy 194.140074 -95.606362) (xy 194.108111 -95.60595) (xy 194.04469 -95.597935) (xy 193.982773 -95.582035)
			(xy 193.923337 -95.5585) (xy 193.86732 -95.527702) (xy 193.815604 -95.490125) (xy 193.769005 -95.446364)
			(xy 193.728259 -95.397107) (xy 193.694006 -95.343133) (xy 193.666789 -95.28529) (xy 193.647035 -95.224493)
			(xy 193.635057 -95.1617) (xy 193.631043 -95.0979) (xy 192.230854 -95.0979) (xy 192.230508 -95.119909)
			(xy 192.222497 -95.183327) (xy 192.2066 -95.245241) (xy 192.183068 -95.304674) (xy 192.152274 -95.360689)
			(xy 192.114701 -95.412404) (xy 192.070944 -95.459001) (xy 192.021691 -95.499746) (xy 191.96772 -95.533997)
			(xy 191.909881 -95.561214) (xy 191.849088 -95.580967) (xy 191.786298 -95.592945) (xy 191.722502 -95.596959)
			(xy 191.658706 -95.592945) (xy 191.595916 -95.580967) (xy 191.535123 -95.561214) (xy 191.477284 -95.533997)
			(xy 191.423313 -95.499746) (xy 191.37406 -95.459001) (xy 191.330303 -95.412404) (xy 191.29273 -95.360689)
			(xy 191.261936 -95.304674) (xy 191.238404 -95.245241) (xy 191.222507 -95.183327) (xy 191.214496 -95.119909)
			(xy 190.373006 -95.119909) (xy 190.364995 -95.183327) (xy 190.349098 -95.245241) (xy 190.325566 -95.304674)
			(xy 190.294772 -95.360689) (xy 190.257199 -95.412404) (xy 190.213442 -95.459001) (xy 190.164189 -95.499746)
			(xy 190.110218 -95.533997) (xy 190.052379 -95.561214) (xy 189.991586 -95.580967) (xy 189.928796 -95.592945)
			(xy 189.865 -95.596959) (xy 189.801204 -95.592945) (xy 189.738414 -95.580967) (xy 189.677621 -95.561214)
			(xy 189.619782 -95.533997) (xy 189.565811 -95.499746) (xy 189.516558 -95.459001) (xy 189.472801 -95.412404)
			(xy 189.435228 -95.360689) (xy 189.404434 -95.304674) (xy 189.380902 -95.245241) (xy 189.365005 -95.183327)
			(xy 189.356994 -95.119909) (xy 188.341006 -95.119909) (xy 188.332995 -95.183327) (xy 188.317098 -95.245241)
			(xy 188.293566 -95.304674) (xy 188.262772 -95.360689) (xy 188.225199 -95.412404) (xy 188.181442 -95.459001)
			(xy 188.132189 -95.499746) (xy 188.078218 -95.533997) (xy 188.020379 -95.561214) (xy 187.959586 -95.580967)
			(xy 187.896796 -95.592945) (xy 187.833 -95.596959) (xy 187.769204 -95.592945) (xy 187.706414 -95.580967)
			(xy 187.645621 -95.561214) (xy 187.587782 -95.533997) (xy 187.533811 -95.499746) (xy 187.484558 -95.459001)
			(xy 187.440801 -95.412404) (xy 187.403228 -95.360689) (xy 187.372434 -95.304674) (xy 187.348902 -95.245241)
			(xy 187.333005 -95.183327) (xy 187.324994 -95.119909) (xy 184.838848 -95.119909) (xy 184.838848 -95.872808)
			(xy 200.909934 -95.872808) (xy 200.914005 -95.817186) (xy 200.926131 -95.762749) (xy 200.946054 -95.710658)
			(xy 200.97335 -95.662023) (xy 201.007436 -95.61788) (xy 201.047585 -95.579171) (xy 201.092943 -95.54672)
			(xy 201.142543 -95.521219) (xy 201.195327 -95.503212) (xy 201.25017 -95.493082) (xy 201.305904 -95.491045)
			(xy 201.361341 -95.497145) (xy 201.415298 -95.511251) (xy 201.466627 -95.533063) (xy 201.514233 -95.562117)
			(xy 201.557101 -95.597792) (xy 201.587727 -95.631973) (xy 208.731606 -95.631973) (xy 208.731606 -95.568051)
			(xy 208.739617 -95.504633) (xy 208.755514 -95.442719) (xy 208.779046 -95.383286) (xy 208.80984 -95.327271)
			(xy 208.847413 -95.275556) (xy 208.89117 -95.228959) (xy 208.940423 -95.188214) (xy 208.994394 -95.153963)
			(xy 209.052233 -95.126746) (xy 209.113026 -95.106993) (xy 209.175816 -95.095015) (xy 209.239612 -95.091002)
			(xy 209.303408 -95.095015) (xy 209.366198 -95.106993) (xy 209.426991 -95.126746) (xy 209.48483 -95.153963)
			(xy 209.538801 -95.188214) (xy 209.588054 -95.228959) (xy 209.631811 -95.275556) (xy 209.669384 -95.327271)
			(xy 209.700178 -95.383286) (xy 209.72371 -95.442719) (xy 209.739607 -95.504633) (xy 209.743308 -95.533929)
			(xy 211.12962 -95.533929) (xy 211.12962 -95.470007) (xy 211.137631 -95.406589) (xy 211.153528 -95.344675)
			(xy 211.17706 -95.285242) (xy 211.207854 -95.229227) (xy 211.245427 -95.177512) (xy 211.289184 -95.130915)
			(xy 211.338437 -95.09017) (xy 211.392408 -95.055919) (xy 211.450247 -95.028702) (xy 211.51104 -95.008949)
			(xy 211.57383 -94.996971) (xy 211.637626 -94.992958) (xy 211.701422 -94.996971) (xy 211.764212 -95.008949)
			(xy 211.825005 -95.028702) (xy 211.882844 -95.055919) (xy 211.936815 -95.09017) (xy 211.986068 -95.130915)
			(xy 212.029825 -95.177512) (xy 212.067398 -95.229227) (xy 212.098192 -95.285242) (xy 212.116504 -95.331491)
			(xy 218.026482 -95.331491) (xy 218.026482 -95.267569) (xy 218.034493 -95.204151) (xy 218.05039 -95.142237)
			(xy 218.073922 -95.082804) (xy 218.104716 -95.026789) (xy 218.142289 -94.975074) (xy 218.186046 -94.928477)
			(xy 218.235299 -94.887732) (xy 218.28927 -94.853481) (xy 218.347109 -94.826264) (xy 218.407902 -94.806511)
			(xy 218.470692 -94.794533) (xy 218.534488 -94.79052) (xy 218.598284 -94.794533) (xy 218.661074 -94.806511)
			(xy 218.721867 -94.826264) (xy 218.779706 -94.853481) (xy 218.833677 -94.887732) (xy 218.88293 -94.928477)
			(xy 218.926687 -94.975074) (xy 218.96426 -95.026789) (xy 218.995054 -95.082804) (xy 219.018586 -95.142237)
			(xy 219.034483 -95.204151) (xy 219.037061 -95.224557) (xy 219.498666 -95.224557) (xy 219.498666 -95.160635)
			(xy 219.506677 -95.097217) (xy 219.522574 -95.035303) (xy 219.546106 -94.97587) (xy 219.5769 -94.919855)
			(xy 219.614473 -94.86814) (xy 219.65823 -94.821543) (xy 219.707483 -94.780798) (xy 219.761454 -94.746547)
			(xy 219.819293 -94.71933) (xy 219.880086 -94.699577) (xy 219.942876 -94.687599) (xy 220.006672 -94.683586)
			(xy 220.070468 -94.687599) (xy 220.133258 -94.699577) (xy 220.194051 -94.71933) (xy 220.25189 -94.746547)
			(xy 220.305861 -94.780798) (xy 220.355114 -94.821543) (xy 220.398871 -94.86814) (xy 220.436444 -94.919855)
			(xy 220.467238 -94.97587) (xy 220.49077 -95.035303) (xy 220.506667 -95.097217) (xy 220.51002 -95.123762)
			(xy 232.992168 -95.123762) (xy 232.99262 -95.092852) (xy 233.000142 -95.031489) (xy 233.015045 -94.971491)
			(xy 233.03711 -94.913742) (xy 233.066012 -94.859092) (xy 233.101324 -94.808349) (xy 233.142526 -94.762259)
			(xy 233.18901 -94.721503) (xy 233.240092 -94.686681) (xy 233.295017 -94.658307) (xy 233.352976 -94.636799)
			(xy 233.413115 -94.622474) (xy 233.44378 -94.618556) (xy 233.452265 -94.617187) (xy 233.467712 -94.609675)
			(xy 233.474006 -94.603824) (xy 233.494834 -94.582996) (xy 233.500628 -94.576681) (xy 233.508039 -94.561244)
			(xy 233.509312 -94.55277) (xy 233.513188 -94.522051) (xy 233.527419 -94.46179) (xy 233.548861 -94.403703)
			(xy 233.577197 -94.348649) (xy 233.612007 -94.297443) (xy 233.652777 -94.250842) (xy 233.698904 -94.209535)
			(xy 233.749704 -94.174135) (xy 233.804426 -94.145164) (xy 233.862261 -94.123051) (xy 233.922353 -94.108124)
			(xy 233.983813 -94.100603) (xy 234.014772 -94.100142) (xy 234.045038 -94.100554) (xy 234.105141 -94.107748)
			(xy 234.163965 -94.122025) (xy 234.220679 -94.143184) (xy 234.27448 -94.170925) (xy 234.324608 -94.204856)
			(xy 234.347766 -94.224348) (xy 234.35572 -94.230502) (xy 234.374798 -94.236792) (xy 234.38485 -94.23654)
			(xy 234.467146 -94.229936) (xy 234.48518 -94.220792) (xy 234.491784 -94.213172) (xy 234.512513 -94.189376)
			(xy 234.558918 -94.146603) (xy 234.610261 -94.109903) (xy 234.665753 -94.079843) (xy 234.724539 -94.056882)
			(xy 234.785715 -94.041377) (xy 234.848341 -94.033563) (xy 234.879896 -94.033086) (xy 234.911858 -94.033579)
			(xy 234.975278 -94.04159) (xy 235.037194 -94.057487) (xy 235.09663 -94.081019) (xy 235.152647 -94.111814)
			(xy 235.201607 -94.147386) (xy 251.576332 -94.147386) (xy 251.576834 -94.115425) (xy 251.584845 -94.052007)
			(xy 251.600742 -93.990093) (xy 251.624274 -93.93066) (xy 251.655068 -93.874645) (xy 251.692641 -93.82293)
			(xy 251.736398 -93.776333) (xy 251.785651 -93.735588) (xy 251.839622 -93.701337) (xy 251.897461 -93.67412)
			(xy 251.958254 -93.654367) (xy 252.021044 -93.642389) (xy 252.08484 -93.638376) (xy 252.148636 -93.642389)
			(xy 252.211426 -93.654367) (xy 252.272219 -93.67412) (xy 252.330058 -93.701337) (xy 252.384029 -93.735588)
			(xy 252.433282 -93.776333) (xy 252.477039 -93.82293) (xy 252.514612 -93.874645) (xy 252.545406 -93.93066)
			(xy 252.568938 -93.990093) (xy 252.584835 -94.052007) (xy 252.58839 -94.080149) (xy 252.980976 -94.080149)
			(xy 252.980976 -94.025651) (xy 252.988731 -93.971707) (xy 253.004084 -93.919416) (xy 253.026721 -93.869842)
			(xy 253.056183 -93.823993) (xy 253.09187 -93.782804) (xy 253.133055 -93.747112) (xy 253.178899 -93.717645)
			(xy 253.228471 -93.695001) (xy 253.28076 -93.679641) (xy 253.334703 -93.671879) (xy 253.361952 -93.67139)
			(xy 253.388833 -93.671845) (xy 253.442063 -93.679384) (xy 253.493709 -93.694319) (xy 253.518416 -93.704918)
			(xy 253.51867 -93.704918) (xy 253.527925 -93.708581) (xy 253.5478 -93.709231) (xy 253.557278 -93.706188)
			(xy 253.624334 -93.680534) (xy 253.633595 -93.676602) (xy 253.648262 -93.662852) (xy 253.652782 -93.653864)
			(xy 253.666572 -93.62445) (xy 253.700485 -93.569043) (xy 253.741178 -93.518404) (xy 253.787987 -93.47336)
			(xy 253.840151 -93.434642) (xy 253.89682 -93.402881) (xy 253.957072 -93.378595) (xy 254.019926 -93.362179)
			(xy 254.084359 -93.353899) (xy 254.11684 -93.353382) (xy 254.148799 -93.353906) (xy 254.212212 -93.361922)
			(xy 254.27412 -93.377822) (xy 254.333548 -93.401355) (xy 254.389558 -93.43215) (xy 254.441266 -93.469723)
			(xy 254.487859 -93.513479) (xy 254.528599 -93.56273) (xy 254.562847 -93.616698) (xy 254.59006 -93.674533)
			(xy 254.609811 -93.735323) (xy 254.621787 -93.798108) (xy 254.625801 -93.8619) (xy 254.621787 -93.925692)
			(xy 254.609811 -93.988477) (xy 254.59006 -94.049267) (xy 254.562847 -94.107102) (xy 254.540477 -94.142353)
			(xy 275.700683 -94.142353) (xy 275.700683 -94.087847) (xy 275.708441 -94.033896) (xy 275.723798 -93.981599)
			(xy 275.746442 -93.932019) (xy 275.775912 -93.886167) (xy 275.811608 -93.844977) (xy 275.852803 -93.809286)
			(xy 275.898658 -93.779821) (xy 275.94824 -93.757183) (xy 276.000539 -93.741832) (xy 276.054491 -93.73408)
			(xy 276.081744 -93.73362) (xy 276.107324 -93.73406) (xy 276.158025 -93.7409) (xy 276.207358 -93.754453)
			(xy 276.254438 -93.774474) (xy 276.298422 -93.800606) (xy 276.318726 -93.81617) (xy 276.326854 -93.822774)
			(xy 276.34692 -93.828108) (xy 276.43074 -93.815662) (xy 276.440934 -93.813763) (xy 276.458634 -93.802997)
			(xy 276.46503 -93.794834) (xy 276.46503 -93.79458) (xy 276.482904 -93.769807) (xy 276.523657 -93.724298)
			(xy 276.569567 -93.683997) (xy 276.619972 -93.649485) (xy 276.674149 -93.621258) (xy 276.731316 -93.599722)
			(xy 276.790651 -93.585188) (xy 276.8513 -93.577865) (xy 276.881844 -93.57741) (xy 276.913804 -93.577879)
			(xy 276.977221 -93.585895) (xy 277.039132 -93.601796) (xy 277.098562 -93.625331) (xy 277.154575 -93.656128)
			(xy 277.206286 -93.693703) (xy 277.25288 -93.737461) (xy 277.293623 -93.786715) (xy 277.327872 -93.840686)
			(xy 277.355087 -93.898524) (xy 277.363224 -93.923569) (xy 430.839874 -93.923569) (xy 430.839874 -93.859647)
			(xy 430.847885 -93.796229) (xy 430.863782 -93.734315) (xy 430.887314 -93.674882) (xy 430.918108 -93.618867)
			(xy 430.955681 -93.567152) (xy 430.999438 -93.520555) (xy 431.048691 -93.47981) (xy 431.102662 -93.445559)
			(xy 431.160501 -93.418342) (xy 431.221294 -93.398589) (xy 431.284084 -93.386611) (xy 431.34788 -93.382598)
			(xy 431.411676 -93.386611) (xy 431.474466 -93.398589) (xy 431.535259 -93.418342) (xy 431.593098 -93.445559)
			(xy 431.647069 -93.47981) (xy 431.678157 -93.505528) (xy 440.882022 -93.505528) (xy 440.886093 -93.449906)
			(xy 440.898219 -93.395469) (xy 440.918142 -93.343378) (xy 440.945438 -93.294743) (xy 440.979524 -93.2506)
			(xy 441.019673 -93.211891) (xy 441.065031 -93.17944) (xy 441.114631 -93.153939) (xy 441.167415 -93.135932)
			(xy 441.222258 -93.125802) (xy 441.277992 -93.123765) (xy 441.333429 -93.129865) (xy 441.387386 -93.143971)
			(xy 441.438715 -93.165783) (xy 441.486321 -93.194837) (xy 441.529189 -93.230512) (xy 441.566406 -93.272049)
			(xy 441.597179 -93.318562) (xy 441.620851 -93.369059) (xy 441.636919 -93.422466) (xy 441.645039 -93.477642)
			(xy 441.645548 -93.505528) (xy 441.645474 -93.509592) (xy 449.330062 -93.509592) (xy 449.334133 -93.45397)
			(xy 449.346259 -93.399533) (xy 449.366182 -93.347442) (xy 449.393478 -93.298807) (xy 449.427564 -93.254664)
			(xy 449.467713 -93.215955) (xy 449.513071 -93.183504) (xy 449.562671 -93.158003) (xy 449.615455 -93.139996)
			(xy 449.670298 -93.129866) (xy 449.726032 -93.127829) (xy 449.781469 -93.133929) (xy 449.835426 -93.148035)
			(xy 449.886755 -93.169847) (xy 449.934361 -93.198901) (xy 449.977229 -93.234576) (xy 450.014446 -93.276113)
			(xy 450.045219 -93.322626) (xy 450.068891 -93.373123) (xy 450.084959 -93.42653) (xy 450.091345 -93.469925)
			(xy 454.093828 -93.469925) (xy 454.093828 -93.406003) (xy 454.101839 -93.342585) (xy 454.117736 -93.280671)
			(xy 454.141268 -93.221238) (xy 454.172062 -93.165223) (xy 454.209635 -93.113508) (xy 454.253392 -93.066911)
			(xy 454.302645 -93.026166) (xy 454.356616 -92.991915) (xy 454.414455 -92.964698) (xy 454.475248 -92.944945)
			(xy 454.538038 -92.932967) (xy 454.601834 -92.928954) (xy 454.66563 -92.932967) (xy 454.72842 -92.944945)
			(xy 454.789213 -92.964698) (xy 454.847052 -92.991915) (xy 454.901023 -93.026166) (xy 454.950276 -93.066911)
			(xy 454.994033 -93.113508) (xy 455.031606 -93.165223) (xy 455.0624 -93.221238) (xy 455.085932 -93.280671)
			(xy 455.093253 -93.309186) (xy 464.36991 -93.309186) (xy 464.373981 -93.253564) (xy 464.386107 -93.199127)
			(xy 464.40603 -93.147036) (xy 464.433326 -93.098401) (xy 464.467412 -93.054258) (xy 464.507561 -93.015549)
			(xy 464.552919 -92.983098) (xy 464.602519 -92.957597) (xy 464.655303 -92.93959) (xy 464.710146 -92.92946)
			(xy 464.76588 -92.927423) (xy 464.821317 -92.933523) (xy 464.875274 -92.947629) (xy 464.926603 -92.969441)
			(xy 464.974209 -92.998495) (xy 465.017077 -93.03417) (xy 465.054294 -93.075707) (xy 465.085067 -93.12222)
			(xy 465.108739 -93.172717) (xy 465.124807 -93.226124) (xy 465.132927 -93.2813) (xy 465.133436 -93.309186)
			(xy 465.132927 -93.337072) (xy 465.124807 -93.392248) (xy 465.108739 -93.445655) (xy 465.085067 -93.496152)
			(xy 465.054294 -93.542665) (xy 465.017077 -93.584202) (xy 464.974209 -93.619877) (xy 464.926603 -93.648931)
			(xy 464.875274 -93.670743) (xy 464.821317 -93.684849) (xy 464.76588 -93.690949) (xy 464.710146 -93.688912)
			(xy 464.655303 -93.678782) (xy 464.602519 -93.660775) (xy 464.552919 -93.635274) (xy 464.507561 -93.602823)
			(xy 464.467412 -93.564114) (xy 464.433326 -93.519971) (xy 464.40603 -93.471336) (xy 464.386107 -93.419245)
			(xy 464.373981 -93.364808) (xy 464.36991 -93.309186) (xy 455.093253 -93.309186) (xy 455.101829 -93.342585)
			(xy 455.10984 -93.406003) (xy 455.110342 -93.437964) (xy 455.10984 -93.469925) (xy 455.101829 -93.533343)
			(xy 455.085932 -93.595257) (xy 455.0624 -93.65469) (xy 455.031606 -93.710705) (xy 454.994033 -93.76242)
			(xy 454.950276 -93.809017) (xy 454.901023 -93.849762) (xy 454.847052 -93.884013) (xy 454.789213 -93.91123)
			(xy 454.72842 -93.930983) (xy 454.66563 -93.942961) (xy 454.601834 -93.946975) (xy 454.538038 -93.942961)
			(xy 454.475248 -93.930983) (xy 454.414455 -93.91123) (xy 454.356616 -93.884013) (xy 454.302645 -93.849762)
			(xy 454.253392 -93.809017) (xy 454.209635 -93.76242) (xy 454.172062 -93.710705) (xy 454.141268 -93.65469)
			(xy 454.117736 -93.595257) (xy 454.101839 -93.533343) (xy 454.093828 -93.469925) (xy 450.091345 -93.469925)
			(xy 450.093079 -93.481706) (xy 450.093588 -93.509592) (xy 450.093079 -93.537478) (xy 450.084959 -93.592654)
			(xy 450.068891 -93.646061) (xy 450.045219 -93.696558) (xy 450.014446 -93.743071) (xy 449.977229 -93.784608)
			(xy 449.934361 -93.820283) (xy 449.886755 -93.849337) (xy 449.835426 -93.871149) (xy 449.781469 -93.885255)
			(xy 449.726032 -93.891355) (xy 449.670298 -93.889318) (xy 449.615455 -93.879188) (xy 449.562671 -93.861181)
			(xy 449.513071 -93.83568) (xy 449.467713 -93.803229) (xy 449.427564 -93.76452) (xy 449.393478 -93.720377)
			(xy 449.366182 -93.671742) (xy 449.346259 -93.619651) (xy 449.334133 -93.565214) (xy 449.330062 -93.509592)
			(xy 441.645474 -93.509592) (xy 441.645039 -93.533414) (xy 441.636919 -93.58859) (xy 441.620851 -93.641997)
			(xy 441.597179 -93.692494) (xy 441.566406 -93.739007) (xy 441.529189 -93.780544) (xy 441.486321 -93.816219)
			(xy 441.438715 -93.845273) (xy 441.387386 -93.867085) (xy 441.333429 -93.881191) (xy 441.277992 -93.887291)
			(xy 441.222258 -93.885254) (xy 441.167415 -93.875124) (xy 441.114631 -93.857117) (xy 441.065031 -93.831616)
			(xy 441.019673 -93.799165) (xy 440.979524 -93.760456) (xy 440.945438 -93.716313) (xy 440.918142 -93.667678)
			(xy 440.898219 -93.615587) (xy 440.886093 -93.56115) (xy 440.882022 -93.505528) (xy 431.678157 -93.505528)
			(xy 431.696322 -93.520555) (xy 431.740079 -93.567152) (xy 431.777652 -93.618867) (xy 431.808446 -93.674882)
			(xy 431.831978 -93.734315) (xy 431.847875 -93.796229) (xy 431.855886 -93.859647) (xy 431.856388 -93.891608)
			(xy 431.855886 -93.923569) (xy 431.847875 -93.986987) (xy 431.831978 -94.048901) (xy 431.808446 -94.108334)
			(xy 431.777652 -94.164349) (xy 431.740079 -94.216064) (xy 431.696322 -94.262661) (xy 431.647069 -94.303406)
			(xy 431.641234 -94.307109) (xy 436.168794 -94.307109) (xy 436.168794 -94.243187) (xy 436.176805 -94.179769)
			(xy 436.192702 -94.117855) (xy 436.216234 -94.058422) (xy 436.247028 -94.002407) (xy 436.284601 -93.950692)
			(xy 436.328358 -93.904095) (xy 436.377611 -93.86335) (xy 436.431582 -93.829099) (xy 436.489421 -93.801882)
			(xy 436.550214 -93.782129) (xy 436.613004 -93.770151) (xy 436.6768 -93.766138) (xy 436.740596 -93.770151)
			(xy 436.803386 -93.782129) (xy 436.864179 -93.801882) (xy 436.922018 -93.829099) (xy 436.975989 -93.86335)
			(xy 437.025242 -93.904095) (xy 437.068999 -93.950692) (xy 437.106572 -94.002407) (xy 437.137366 -94.058422)
			(xy 437.160898 -94.117855) (xy 437.176795 -94.179769) (xy 437.184806 -94.243187) (xy 437.185308 -94.275148)
			(xy 437.184806 -94.307109) (xy 437.176795 -94.370527) (xy 437.160898 -94.432441) (xy 437.137366 -94.491874)
			(xy 437.130838 -94.503748) (xy 437.869582 -94.503748) (xy 437.873653 -94.448126) (xy 437.885779 -94.393689)
			(xy 437.905702 -94.341598) (xy 437.932998 -94.292963) (xy 437.967084 -94.24882) (xy 438.007233 -94.210111)
			(xy 438.052591 -94.17766) (xy 438.102191 -94.152159) (xy 438.154975 -94.134152) (xy 438.209818 -94.124022)
			(xy 438.265552 -94.121985) (xy 438.320989 -94.128085) (xy 438.374946 -94.142191) (xy 438.426275 -94.164003)
			(xy 438.473881 -94.193057) (xy 438.516749 -94.228732) (xy 438.553966 -94.270269) (xy 438.584739 -94.316782)
			(xy 438.608411 -94.367279) (xy 438.624479 -94.420686) (xy 438.632599 -94.475862) (xy 438.633108 -94.503748)
			(xy 438.632599 -94.531634) (xy 438.624479 -94.58681) (xy 438.608411 -94.640217) (xy 438.597371 -94.663768)
			(xy 439.713622 -94.663768) (xy 439.717693 -94.608146) (xy 439.729819 -94.553709) (xy 439.749742 -94.501618)
			(xy 439.777038 -94.452983) (xy 439.811124 -94.40884) (xy 439.851273 -94.370131) (xy 439.896631 -94.33768)
			(xy 439.946231 -94.312179) (xy 439.999015 -94.294172) (xy 440.053858 -94.284042) (xy 440.109592 -94.282005)
			(xy 440.165029 -94.288105) (xy 440.218986 -94.302211) (xy 440.270315 -94.324023) (xy 440.317921 -94.353077)
			(xy 440.360789 -94.388752) (xy 440.398006 -94.430289) (xy 440.428779 -94.476802) (xy 440.452451 -94.527299)
			(xy 440.468519 -94.580706) (xy 440.476475 -94.634769) (xy 445.752976 -94.634769) (xy 445.752976 -94.570847)
			(xy 445.760987 -94.507429) (xy 445.776884 -94.445515) (xy 445.800416 -94.386082) (xy 445.83121 -94.330067)
			(xy 445.868783 -94.278352) (xy 445.91254 -94.231755) (xy 445.961793 -94.19101) (xy 446.015764 -94.156759)
			(xy 446.073603 -94.129542) (xy 446.134396 -94.109789) (xy 446.197186 -94.097811) (xy 446.260982 -94.093798)
			(xy 446.324778 -94.097811) (xy 446.387568 -94.109789) (xy 446.448361 -94.129542) (xy 446.5062 -94.156759)
			(xy 446.560171 -94.19101) (xy 446.609424 -94.231755) (xy 446.653181 -94.278352) (xy 446.690754 -94.330067)
			(xy 446.701452 -94.349527) (xy 464.243922 -94.349527) (xy 464.243922 -94.285605) (xy 464.251933 -94.222187)
			(xy 464.26783 -94.160273) (xy 464.291362 -94.10084) (xy 464.322156 -94.044825) (xy 464.359729 -93.99311)
			(xy 464.403486 -93.946513) (xy 464.452739 -93.905768) (xy 464.50671 -93.871517) (xy 464.564549 -93.8443)
			(xy 464.625342 -93.824547) (xy 464.688132 -93.812569) (xy 464.751928 -93.808556) (xy 464.815724 -93.812569)
			(xy 464.878514 -93.824547) (xy 464.939307 -93.8443) (xy 464.997146 -93.871517) (xy 465.051117 -93.905768)
			(xy 465.10037 -93.946513) (xy 465.144127 -93.99311) (xy 465.1817 -94.044825) (xy 465.212494 -94.10084)
			(xy 465.236026 -94.160273) (xy 465.251923 -94.222187) (xy 465.259934 -94.285605) (xy 465.260436 -94.317566)
			(xy 465.259934 -94.349527) (xy 465.251923 -94.412945) (xy 465.236026 -94.474859) (xy 465.212494 -94.534292)
			(xy 465.1817 -94.590307) (xy 465.144127 -94.642022) (xy 465.10037 -94.688619) (xy 465.051117 -94.729364)
			(xy 464.997146 -94.763615) (xy 464.939307 -94.790832) (xy 464.878514 -94.810585) (xy 464.815724 -94.822563)
			(xy 464.751928 -94.826577) (xy 464.688132 -94.822563) (xy 464.625342 -94.810585) (xy 464.564549 -94.790832)
			(xy 464.50671 -94.763615) (xy 464.452739 -94.729364) (xy 464.403486 -94.688619) (xy 464.359729 -94.642022)
			(xy 464.322156 -94.590307) (xy 464.291362 -94.534292) (xy 464.26783 -94.474859) (xy 464.251933 -94.412945)
			(xy 464.243922 -94.349527) (xy 446.701452 -94.349527) (xy 446.721548 -94.386082) (xy 446.74508 -94.445515)
			(xy 446.760977 -94.507429) (xy 446.768988 -94.570847) (xy 446.76949 -94.602808) (xy 446.768988 -94.634769)
			(xy 446.760977 -94.698187) (xy 446.74508 -94.760101) (xy 446.721548 -94.819534) (xy 446.690754 -94.875549)
			(xy 446.653181 -94.927264) (xy 446.629421 -94.952566) (xy 461.97596 -94.952566) (xy 461.980031 -94.896944)
			(xy 461.992157 -94.842507) (xy 462.01208 -94.790416) (xy 462.039376 -94.741781) (xy 462.073462 -94.697638)
			(xy 462.113611 -94.658929) (xy 462.158969 -94.626478) (xy 462.208569 -94.600977) (xy 462.261353 -94.58297)
			(xy 462.316196 -94.57284) (xy 462.37193 -94.570803) (xy 462.427367 -94.576903) (xy 462.481324 -94.591009)
			(xy 462.532653 -94.612821) (xy 462.580259 -94.641875) (xy 462.623127 -94.67755) (xy 462.660344 -94.719087)
			(xy 462.691117 -94.7656) (xy 462.714789 -94.816097) (xy 462.730857 -94.869504) (xy 462.738977 -94.92468)
			(xy 462.739486 -94.952566) (xy 462.738977 -94.980452) (xy 462.730857 -95.035628) (xy 462.714789 -95.089035)
			(xy 462.691117 -95.139532) (xy 462.660344 -95.186045) (xy 462.623127 -95.227582) (xy 462.580259 -95.263257)
			(xy 462.532653 -95.292311) (xy 462.481324 -95.314123) (xy 462.427367 -95.328229) (xy 462.37193 -95.334329)
			(xy 462.316196 -95.332292) (xy 462.261353 -95.322162) (xy 462.208569 -95.304155) (xy 462.158969 -95.278654)
			(xy 462.113611 -95.246203) (xy 462.073462 -95.207494) (xy 462.039376 -95.163351) (xy 462.01208 -95.114716)
			(xy 461.992157 -95.062625) (xy 461.980031 -95.008188) (xy 461.97596 -94.952566) (xy 446.629421 -94.952566)
			(xy 446.609424 -94.973861) (xy 446.560171 -95.014606) (xy 446.5062 -95.048857) (xy 446.448361 -95.076074)
			(xy 446.387568 -95.095827) (xy 446.324778 -95.107805) (xy 446.260982 -95.111819) (xy 446.197186 -95.107805)
			(xy 446.134396 -95.095827) (xy 446.073603 -95.076074) (xy 446.015764 -95.048857) (xy 445.961793 -95.014606)
			(xy 445.91254 -94.973861) (xy 445.868783 -94.927264) (xy 445.83121 -94.875549) (xy 445.800416 -94.819534)
			(xy 445.776884 -94.760101) (xy 445.760987 -94.698187) (xy 445.752976 -94.634769) (xy 440.476475 -94.634769)
			(xy 440.476639 -94.635882) (xy 440.477148 -94.663768) (xy 440.476639 -94.691654) (xy 440.468519 -94.74683)
			(xy 440.452451 -94.800237) (xy 440.428779 -94.850734) (xy 440.398006 -94.897247) (xy 440.360789 -94.938784)
			(xy 440.317921 -94.974459) (xy 440.270315 -95.003513) (xy 440.218986 -95.025325) (xy 440.165029 -95.039431)
			(xy 440.109592 -95.045531) (xy 440.053858 -95.043494) (xy 439.999015 -95.033364) (xy 439.946231 -95.015357)
			(xy 439.896631 -94.989856) (xy 439.851273 -94.957405) (xy 439.811124 -94.918696) (xy 439.777038 -94.874553)
			(xy 439.749742 -94.825918) (xy 439.729819 -94.773827) (xy 439.717693 -94.71939) (xy 439.713622 -94.663768)
			(xy 438.597371 -94.663768) (xy 438.584739 -94.690714) (xy 438.553966 -94.737227) (xy 438.516749 -94.778764)
			(xy 438.473881 -94.814439) (xy 438.426275 -94.843493) (xy 438.374946 -94.865305) (xy 438.320989 -94.879411)
			(xy 438.265552 -94.885511) (xy 438.209818 -94.883474) (xy 438.154975 -94.873344) (xy 438.102191 -94.855337)
			(xy 438.052591 -94.829836) (xy 438.007233 -94.797385) (xy 437.967084 -94.758676) (xy 437.932998 -94.714533)
			(xy 437.905702 -94.665898) (xy 437.885779 -94.613807) (xy 437.873653 -94.55937) (xy 437.869582 -94.503748)
			(xy 437.130838 -94.503748) (xy 437.106572 -94.547889) (xy 437.068999 -94.599604) (xy 437.025242 -94.646201)
			(xy 436.975989 -94.686946) (xy 436.922018 -94.721197) (xy 436.864179 -94.748414) (xy 436.803386 -94.768167)
			(xy 436.740596 -94.780145) (xy 436.6768 -94.784159) (xy 436.613004 -94.780145) (xy 436.550214 -94.768167)
			(xy 436.489421 -94.748414) (xy 436.431582 -94.721197) (xy 436.377611 -94.686946) (xy 436.328358 -94.646201)
			(xy 436.284601 -94.599604) (xy 436.247028 -94.547889) (xy 436.216234 -94.491874) (xy 436.192702 -94.432441)
			(xy 436.176805 -94.370527) (xy 436.168794 -94.307109) (xy 431.641234 -94.307109) (xy 431.593098 -94.337657)
			(xy 431.535259 -94.364874) (xy 431.474466 -94.384627) (xy 431.411676 -94.396605) (xy 431.34788 -94.400619)
			(xy 431.284084 -94.396605) (xy 431.221294 -94.384627) (xy 431.160501 -94.364874) (xy 431.102662 -94.337657)
			(xy 431.048691 -94.303406) (xy 430.999438 -94.262661) (xy 430.955681 -94.216064) (xy 430.918108 -94.164349)
			(xy 430.887314 -94.108334) (xy 430.863782 -94.048901) (xy 430.847885 -93.986987) (xy 430.839874 -93.923569)
			(xy 277.363224 -93.923569) (xy 277.374838 -93.959317) (xy 277.386815 -94.022105) (xy 277.390829 -94.0859)
			(xy 277.386815 -94.149695) (xy 277.374838 -94.212483) (xy 277.355087 -94.273276) (xy 277.327872 -94.331114)
			(xy 277.293623 -94.385085) (xy 277.25288 -94.434339) (xy 277.206286 -94.478097) (xy 277.154575 -94.515672)
			(xy 277.098562 -94.546469) (xy 277.039132 -94.570004) (xy 276.977221 -94.585905) (xy 276.913804 -94.593921)
			(xy 276.881844 -94.594426) (xy 276.849577 -94.593969) (xy 276.785562 -94.585804) (xy 276.723095 -94.5696)
			(xy 276.663183 -94.545618) (xy 276.60679 -94.514244) (xy 276.554822 -94.475982) (xy 276.508117 -94.431448)
			(xy 276.487382 -94.40672) (xy 276.487382 -94.406466) (xy 276.48037 -94.398797) (xy 276.461892 -94.389344)
			(xy 276.451568 -94.388178) (xy 276.377654 -94.382844) (xy 276.367391 -94.382596) (xy 276.347998 -94.389284)
			(xy 276.340062 -94.395798) (xy 276.340062 -94.396052) (xy 276.339808 -94.396052) (xy 276.318573 -94.414855)
			(xy 276.27159 -94.446627) (xy 276.220421 -94.471091) (xy 276.166193 -94.487709) (xy 276.110102 -94.496114)
			(xy 276.081744 -94.496636) (xy 276.054491 -94.49612) (xy 276.000539 -94.488368) (xy 275.94824 -94.473017)
			(xy 275.898658 -94.450379) (xy 275.852803 -94.420914) (xy 275.811608 -94.385223) (xy 275.775912 -94.344033)
			(xy 275.746442 -94.298181) (xy 275.723798 -94.248601) (xy 275.708441 -94.196304) (xy 275.700683 -94.142353)
			(xy 254.540477 -94.142353) (xy 254.528599 -94.16107) (xy 254.487859 -94.210321) (xy 254.441266 -94.254077)
			(xy 254.389558 -94.29165) (xy 254.333548 -94.322445) (xy 254.27412 -94.345978) (xy 254.212212 -94.361878)
			(xy 254.148799 -94.369894) (xy 254.11684 -94.370398) (xy 254.083596 -94.36986) (xy 254.017677 -94.36117)
			(xy 253.953454 -94.34396) (xy 253.892024 -94.318523) (xy 253.834434 -94.285293) (xy 253.807722 -94.265496)
			(xy 253.799496 -94.259758) (xy 253.780116 -94.254651) (xy 253.77013 -94.25559) (xy 253.698756 -94.264988)
			(xy 253.688957 -94.2668) (xy 253.671698 -94.276715) (xy 253.665228 -94.284292) (xy 253.664974 -94.284546)
			(xy 253.646782 -94.307393) (xy 253.604675 -94.347859) (xy 253.556891 -94.381431) (xy 253.504546 -94.407324)
			(xy 253.448866 -94.424932) (xy 253.391151 -94.433845) (xy 253.361952 -94.434406) (xy 253.334703 -94.433921)
			(xy 253.28076 -94.426159) (xy 253.228471 -94.410799) (xy 253.178899 -94.388155) (xy 253.133055 -94.358688)
			(xy 253.09187 -94.322996) (xy 253.056183 -94.281807) (xy 253.026721 -94.235958) (xy 253.004084 -94.186384)
			(xy 252.988731 -94.134093) (xy 252.980976 -94.080149) (xy 252.58839 -94.080149) (xy 252.592846 -94.115425)
			(xy 252.593348 -94.147386) (xy 252.592926 -94.178128) (xy 252.585524 -94.239164) (xy 252.570815 -94.298862)
			(xy 252.549013 -94.356351) (xy 252.520437 -94.41079) (xy 252.485504 -94.461385) (xy 252.444723 -94.507398)
			(xy 252.398691 -94.548156) (xy 252.373638 -94.565978) (xy 252.36551 -94.571566) (xy 252.354588 -94.588076)
			(xy 252.33884 -94.667832) (xy 252.337388 -94.677443) (xy 252.341057 -94.696517) (xy 252.345952 -94.704916)
			(xy 252.345952 -94.70517) (xy 252.34646 -94.705678) (xy 252.361185 -94.729064) (xy 252.38445 -94.77919)
			(xy 252.400233 -94.83215) (xy 252.408203 -94.886835) (xy 252.40869 -94.914466) (xy 252.408204 -94.941717)
			(xy 252.400448 -94.995665) (xy 252.385093 -95.04796) (xy 252.37613 -95.067585) (xy 252.7018 -95.067585)
			(xy 252.7018 -95.003663) (xy 252.709811 -94.940245) (xy 252.725708 -94.878331) (xy 252.74924 -94.818898)
			(xy 252.780034 -94.762883) (xy 252.817607 -94.711168) (xy 252.861364 -94.664571) (xy 252.910617 -94.623826)
			(xy 252.964588 -94.589575) (xy 253.022427 -94.562358) (xy 253.08322 -94.542605) (xy 253.14601 -94.530627)
			(xy 253.209806 -94.526614) (xy 253.273602 -94.530627) (xy 253.336392 -94.542605) (xy 253.397185 -94.562358)
			(xy 253.455024 -94.589575) (xy 253.508995 -94.623826) (xy 253.558248 -94.664571) (xy 253.602005 -94.711168)
			(xy 253.639578 -94.762883) (xy 253.670372 -94.818898) (xy 253.693904 -94.878331) (xy 253.709801 -94.940245)
			(xy 253.717812 -95.003663) (xy 253.718314 -95.035624) (xy 253.717812 -95.067585) (xy 253.712031 -95.113348)
			(xy 436.853582 -95.113348) (xy 436.857653 -95.057726) (xy 436.869779 -95.003289) (xy 436.889702 -94.951198)
			(xy 436.916998 -94.902563) (xy 436.951084 -94.85842) (xy 436.991233 -94.819711) (xy 437.036591 -94.78726)
			(xy 437.086191 -94.761759) (xy 437.138975 -94.743752) (xy 437.193818 -94.733622) (xy 437.249552 -94.731585)
			(xy 437.304989 -94.737685) (xy 437.358946 -94.751791) (xy 437.410275 -94.773603) (xy 437.457881 -94.802657)
			(xy 437.500749 -94.838332) (xy 437.537966 -94.879869) (xy 437.568739 -94.926382) (xy 437.592411 -94.976879)
			(xy 437.608479 -95.030286) (xy 437.616599 -95.085462) (xy 437.617108 -95.113348) (xy 437.616599 -95.141234)
			(xy 437.608479 -95.19641) (xy 437.592411 -95.249817) (xy 437.568739 -95.300314) (xy 437.537966 -95.346827)
			(xy 437.500749 -95.388364) (xy 437.457881 -95.424039) (xy 437.410275 -95.453093) (xy 437.358946 -95.474905)
			(xy 437.304989 -95.489011) (xy 437.249552 -95.495111) (xy 437.193818 -95.493074) (xy 437.138975 -95.482944)
			(xy 437.086191 -95.464937) (xy 437.036591 -95.439436) (xy 436.991233 -95.406985) (xy 436.951084 -95.368276)
			(xy 436.916998 -95.324133) (xy 436.889702 -95.275498) (xy 436.869779 -95.223407) (xy 436.857653 -95.16897)
			(xy 436.853582 -95.113348) (xy 253.712031 -95.113348) (xy 253.709801 -95.131003) (xy 253.693904 -95.192917)
			(xy 253.670372 -95.25235) (xy 253.639578 -95.308365) (xy 253.602005 -95.36008) (xy 253.558248 -95.406677)
			(xy 253.508995 -95.447422) (xy 253.455024 -95.481673) (xy 253.397185 -95.50889) (xy 253.336392 -95.528643)
			(xy 253.273602 -95.540621) (xy 253.209806 -95.544635) (xy 253.14601 -95.540621) (xy 253.08322 -95.528643)
			(xy 253.022427 -95.50889) (xy 252.964588 -95.481673) (xy 252.910617 -95.447422) (xy 252.861364 -95.406677)
			(xy 252.817607 -95.36008) (xy 252.780034 -95.308365) (xy 252.74924 -95.25235) (xy 252.725708 -95.192917)
			(xy 252.709811 -95.131003) (xy 252.7018 -95.067585) (xy 252.37613 -95.067585) (xy 252.362451 -95.097537)
			(xy 252.332985 -95.143387) (xy 252.297294 -95.184578) (xy 252.256103 -95.220269) (xy 252.210253 -95.249735)
			(xy 252.160676 -95.272377) (xy 252.108381 -95.287732) (xy 252.054433 -95.295488) (xy 251.999931 -95.295488)
			(xy 251.945983 -95.287732) (xy 251.893688 -95.272377) (xy 251.844111 -95.249735) (xy 251.798261 -95.220269)
			(xy 251.75707 -95.184578) (xy 251.721379 -95.143387) (xy 251.691913 -95.097537) (xy 251.669271 -95.04796)
			(xy 251.653916 -94.995665) (xy 251.64616 -94.941717) (xy 251.645674 -94.914466) (xy 251.646187 -94.886592)
			(xy 251.654293 -94.831436) (xy 251.670342 -94.778048) (xy 251.693993 -94.727565) (xy 251.72474 -94.681063)
			(xy 251.742956 -94.659958) (xy 251.742956 -94.659704) (xy 251.749151 -94.652109) (xy 251.755806 -94.633691)
			(xy 251.75591 -94.62389) (xy 251.752354 -94.542864) (xy 251.743972 -94.52483) (xy 251.73686 -94.518226)
			(xy 251.715528 -94.49757) (xy 251.677257 -94.452168) (xy 251.644533 -94.402618) (xy 251.6178 -94.349595)
			(xy 251.597424 -94.29382) (xy 251.58368 -94.236052) (xy 251.576756 -94.177076) (xy 251.576332 -94.147386)
			(xy 235.201607 -94.147386) (xy 235.204363 -94.149388) (xy 235.250962 -94.193147) (xy 235.291709 -94.242401)
			(xy 235.325962 -94.296374) (xy 235.35318 -94.354214) (xy 235.372933 -94.41501) (xy 235.384912 -94.477802)
			(xy 235.388926 -94.5416) (xy 235.384912 -94.605398) (xy 235.372933 -94.66819) (xy 235.35318 -94.728986)
			(xy 235.325962 -94.786826) (xy 235.291709 -94.840799) (xy 235.250962 -94.890053) (xy 235.204363 -94.933812)
			(xy 235.152647 -94.971386) (xy 235.09663 -95.002181) (xy 235.037194 -95.025713) (xy 234.975278 -95.04161)
			(xy 234.911858 -95.049621) (xy 234.879896 -95.050102) (xy 234.849632 -95.049639) (xy 234.789531 -95.042454)
			(xy 234.730708 -95.028186) (xy 234.673994 -95.007036) (xy 234.620192 -94.979305) (xy 234.570062 -94.945383)
			(xy 234.546902 -94.925896) (xy 234.538962 -94.919721) (xy 234.519873 -94.913445) (xy 234.509818 -94.913704)
			(xy 234.427522 -94.920308) (xy 234.409488 -94.929452) (xy 234.402884 -94.937072) (xy 234.38179 -94.961215)
			(xy 234.334547 -95.004556) (xy 234.282232 -95.041616) (xy 234.225673 -95.071807) (xy 234.165768 -95.094649)
			(xy 234.103468 -95.109781) (xy 234.071668 -95.113856) (xy 234.063177 -95.1152) (xy 234.047733 -95.122729)
			(xy 234.041442 -95.128588) (xy 234.020614 -95.149416) (xy 234.014808 -95.155721) (xy 234.007406 -95.171166)
			(xy 234.006136 -95.179642) (xy 234.002321 -95.21037) (xy 233.988086 -95.270634) (xy 233.96664 -95.328724)
			(xy 233.938299 -95.383781) (xy 233.903483 -95.434988) (xy 233.862708 -95.48159) (xy 233.816575 -95.522896)
			(xy 233.765769 -95.558296) (xy 233.71104 -95.587264) (xy 233.653199 -95.609374) (xy 233.593102 -95.624296)
			(xy 233.531637 -95.631812) (xy 233.500676 -95.63227) (xy 233.469942 -95.631885) (xy 233.408922 -95.624473)
			(xy 233.349241 -95.609759) (xy 233.291768 -95.587959) (xy 233.237343 -95.559391) (xy 233.186757 -95.52447)
			(xy 233.14075 -95.483706) (xy 233.099992 -95.437694) (xy 233.065077 -95.387104) (xy 233.036515 -95.332675)
			(xy 233.014722 -95.2752) (xy 233.000016 -95.215517) (xy 232.992611 -95.154496) (xy 232.992168 -95.123762)
			(xy 220.51002 -95.123762) (xy 220.514678 -95.160635) (xy 220.51518 -95.192596) (xy 220.514678 -95.224557)
			(xy 220.506667 -95.287975) (xy 220.49077 -95.349889) (xy 220.467238 -95.409322) (xy 220.436444 -95.465337)
			(xy 220.398871 -95.517052) (xy 220.355114 -95.563649) (xy 220.305861 -95.604394) (xy 220.25189 -95.638645)
			(xy 220.194051 -95.665862) (xy 220.133258 -95.685615) (xy 220.070468 -95.697593) (xy 220.006672 -95.701607)
			(xy 219.942876 -95.697593) (xy 219.880086 -95.685615) (xy 219.819293 -95.665862) (xy 219.761454 -95.638645)
			(xy 219.707483 -95.604394) (xy 219.65823 -95.563649) (xy 219.614473 -95.517052) (xy 219.5769 -95.465337)
			(xy 219.546106 -95.409322) (xy 219.522574 -95.349889) (xy 219.506677 -95.287975) (xy 219.498666 -95.224557)
			(xy 219.037061 -95.224557) (xy 219.042494 -95.267569) (xy 219.042996 -95.29953) (xy 219.042494 -95.331491)
			(xy 219.034483 -95.394909) (xy 219.018586 -95.456823) (xy 218.995054 -95.516256) (xy 218.96426 -95.572271)
			(xy 218.926687 -95.623986) (xy 218.88293 -95.670583) (xy 218.833677 -95.711328) (xy 218.779706 -95.745579)
			(xy 218.721867 -95.772796) (xy 218.661074 -95.792549) (xy 218.598284 -95.804527) (xy 218.534488 -95.808541)
			(xy 218.470692 -95.804527) (xy 218.407902 -95.792549) (xy 218.347109 -95.772796) (xy 218.28927 -95.745579)
			(xy 218.235299 -95.711328) (xy 218.186046 -95.670583) (xy 218.142289 -95.623986) (xy 218.104716 -95.572271)
			(xy 218.073922 -95.516256) (xy 218.05039 -95.456823) (xy 218.034493 -95.394909) (xy 218.026482 -95.331491)
			(xy 212.116504 -95.331491) (xy 212.121724 -95.344675) (xy 212.137621 -95.406589) (xy 212.145632 -95.470007)
			(xy 212.146134 -95.501968) (xy 212.145632 -95.533929) (xy 212.137621 -95.597347) (xy 212.121724 -95.659261)
			(xy 212.098192 -95.718694) (xy 212.067398 -95.774709) (xy 212.029825 -95.826424) (xy 211.986068 -95.873021)
			(xy 211.936815 -95.913766) (xy 211.882844 -95.948017) (xy 211.825005 -95.975234) (xy 211.764212 -95.994987)
			(xy 211.701422 -96.006965) (xy 211.637626 -96.010979) (xy 211.57383 -96.006965) (xy 211.51104 -95.994987)
			(xy 211.450247 -95.975234) (xy 211.392408 -95.948017) (xy 211.338437 -95.913766) (xy 211.289184 -95.873021)
			(xy 211.245427 -95.826424) (xy 211.207854 -95.774709) (xy 211.17706 -95.718694) (xy 211.153528 -95.659261)
			(xy 211.137631 -95.597347) (xy 211.12962 -95.533929) (xy 209.743308 -95.533929) (xy 209.747618 -95.568051)
			(xy 209.74812 -95.600012) (xy 209.747618 -95.631973) (xy 209.739607 -95.695391) (xy 209.72371 -95.757305)
			(xy 209.700178 -95.816738) (xy 209.669384 -95.872753) (xy 209.631811 -95.924468) (xy 209.588054 -95.971065)
			(xy 209.538801 -96.01181) (xy 209.48483 -96.046061) (xy 209.441253 -96.066567) (xy 214.991944 -96.066567)
			(xy 214.991944 -96.002645) (xy 214.999955 -95.939227) (xy 215.015852 -95.877313) (xy 215.039384 -95.81788)
			(xy 215.070178 -95.761865) (xy 215.107751 -95.71015) (xy 215.151508 -95.663553) (xy 215.200761 -95.622808)
			(xy 215.254732 -95.588557) (xy 215.312571 -95.56134) (xy 215.373364 -95.541587) (xy 215.436154 -95.529609)
			(xy 215.49995 -95.525596) (xy 215.563746 -95.529609) (xy 215.626536 -95.541587) (xy 215.687329 -95.56134)
			(xy 215.745168 -95.588557) (xy 215.799139 -95.622808) (xy 215.848392 -95.663553) (xy 215.892149 -95.71015)
			(xy 215.929722 -95.761865) (xy 215.960516 -95.81788) (xy 215.984048 -95.877313) (xy 215.991098 -95.904769)
			(xy 442.597534 -95.904769) (xy 442.597534 -95.840847) (xy 442.605545 -95.777429) (xy 442.621442 -95.715515)
			(xy 442.644974 -95.656082) (xy 442.675768 -95.600067) (xy 442.713341 -95.548352) (xy 442.757098 -95.501755)
			(xy 442.806351 -95.46101) (xy 442.860322 -95.426759) (xy 442.918161 -95.399542) (xy 442.978954 -95.379789)
			(xy 443.041744 -95.367811) (xy 443.10554 -95.363798) (xy 443.169336 -95.367811) (xy 443.232126 -95.379789)
			(xy 443.292919 -95.399542) (xy 443.350758 -95.426759) (xy 443.404729 -95.46101) (xy 443.453982 -95.501755)
			(xy 443.497739 -95.548352) (xy 443.535312 -95.600067) (xy 443.566106 -95.656082) (xy 443.589638 -95.715515)
			(xy 443.605535 -95.777429) (xy 443.613546 -95.840847) (xy 443.614048 -95.872808) (xy 443.613546 -95.904769)
			(xy 449.127874 -95.904769) (xy 449.127874 -95.840847) (xy 449.135885 -95.777429) (xy 449.151782 -95.715515)
			(xy 449.175314 -95.656082) (xy 449.206108 -95.600067) (xy 449.243681 -95.548352) (xy 449.287438 -95.501755)
			(xy 449.336691 -95.46101) (xy 449.390662 -95.426759) (xy 449.448501 -95.399542) (xy 449.509294 -95.379789)
			(xy 449.572084 -95.367811) (xy 449.63588 -95.363798) (xy 449.699676 -95.367811) (xy 449.762466 -95.379789)
			(xy 449.823259 -95.399542) (xy 449.881098 -95.426759) (xy 449.935069 -95.46101) (xy 449.984322 -95.501755)
			(xy 450.028079 -95.548352) (xy 450.065652 -95.600067) (xy 450.096446 -95.656082) (xy 450.119978 -95.715515)
			(xy 450.135875 -95.777429) (xy 450.143886 -95.840847) (xy 450.144388 -95.872808) (xy 450.143886 -95.904769)
			(xy 450.135875 -95.968187) (xy 450.119978 -96.030101) (xy 450.096446 -96.089534) (xy 450.065652 -96.145549)
			(xy 450.028079 -96.197264) (xy 449.984322 -96.243861) (xy 449.935069 -96.284606) (xy 449.890411 -96.312947)
			(xy 453.202034 -96.312947) (xy 453.202034 -96.249025) (xy 453.210045 -96.185607) (xy 453.225942 -96.123693)
			(xy 453.249474 -96.06426) (xy 453.280268 -96.008245) (xy 453.317841 -95.95653) (xy 453.361598 -95.909933)
			(xy 453.410851 -95.869188) (xy 453.464822 -95.834937) (xy 453.522661 -95.80772) (xy 453.583454 -95.787967)
			(xy 453.646244 -95.775989) (xy 453.71004 -95.771976) (xy 453.773836 -95.775989) (xy 453.836626 -95.787967)
			(xy 453.897419 -95.80772) (xy 453.955258 -95.834937) (xy 454.009229 -95.869188) (xy 454.058482 -95.909933)
			(xy 454.102239 -95.95653) (xy 454.139812 -96.008245) (xy 454.170606 -96.06426) (xy 454.194138 -96.123693)
			(xy 454.210035 -96.185607) (xy 454.218046 -96.249025) (xy 454.218548 -96.280986) (xy 454.218046 -96.312947)
			(xy 454.210035 -96.376365) (xy 454.194166 -96.438169) (xy 463.97392 -96.438169) (xy 463.97392 -96.374247)
			(xy 463.981931 -96.310829) (xy 463.997828 -96.248915) (xy 464.02136 -96.189482) (xy 464.052154 -96.133467)
			(xy 464.089727 -96.081752) (xy 464.133484 -96.035155) (xy 464.182737 -95.99441) (xy 464.236708 -95.960159)
			(xy 464.294547 -95.932942) (xy 464.35534 -95.913189) (xy 464.41813 -95.901211) (xy 464.481926 -95.897198)
			(xy 464.545722 -95.901211) (xy 464.608512 -95.913189) (xy 464.669305 -95.932942) (xy 464.727144 -95.960159)
			(xy 464.781115 -95.99441) (xy 464.830368 -96.035155) (xy 464.874125 -96.081752) (xy 464.911698 -96.133467)
			(xy 464.942492 -96.189482) (xy 464.966024 -96.248915) (xy 464.981921 -96.310829) (xy 464.989932 -96.374247)
			(xy 464.990434 -96.406208) (xy 464.989932 -96.438169) (xy 464.981921 -96.501587) (xy 464.966024 -96.563501)
			(xy 464.942492 -96.622934) (xy 464.911698 -96.678949) (xy 464.874125 -96.730664) (xy 464.830368 -96.777261)
			(xy 464.781115 -96.818006) (xy 464.727144 -96.852257) (xy 464.669305 -96.879474) (xy 464.608512 -96.899227)
			(xy 464.545722 -96.911205) (xy 464.481926 -96.915219) (xy 464.41813 -96.911205) (xy 464.35534 -96.899227)
			(xy 464.294547 -96.879474) (xy 464.236708 -96.852257) (xy 464.182737 -96.818006) (xy 464.133484 -96.777261)
			(xy 464.089727 -96.730664) (xy 464.052154 -96.678949) (xy 464.02136 -96.622934) (xy 463.997828 -96.563501)
			(xy 463.981931 -96.501587) (xy 463.97392 -96.438169) (xy 454.194166 -96.438169) (xy 454.194138 -96.438279)
			(xy 454.170606 -96.497712) (xy 454.139812 -96.553727) (xy 454.102239 -96.605442) (xy 454.058482 -96.652039)
			(xy 454.009229 -96.692784) (xy 453.955258 -96.727035) (xy 453.897419 -96.754252) (xy 453.836626 -96.774005)
			(xy 453.773836 -96.785983) (xy 453.71004 -96.789997) (xy 453.646244 -96.785983) (xy 453.583454 -96.774005)
			(xy 453.522661 -96.754252) (xy 453.464822 -96.727035) (xy 453.410851 -96.692784) (xy 453.361598 -96.652039)
			(xy 453.317841 -96.605442) (xy 453.280268 -96.553727) (xy 453.249474 -96.497712) (xy 453.225942 -96.438279)
			(xy 453.210045 -96.376365) (xy 453.202034 -96.312947) (xy 449.890411 -96.312947) (xy 449.881098 -96.318857)
			(xy 449.823259 -96.346074) (xy 449.762466 -96.365827) (xy 449.699676 -96.377805) (xy 449.63588 -96.381819)
			(xy 449.572084 -96.377805) (xy 449.509294 -96.365827) (xy 449.448501 -96.346074) (xy 449.390662 -96.318857)
			(xy 449.336691 -96.284606) (xy 449.287438 -96.243861) (xy 449.243681 -96.197264) (xy 449.206108 -96.145549)
			(xy 449.175314 -96.089534) (xy 449.151782 -96.030101) (xy 449.135885 -95.968187) (xy 449.127874 -95.904769)
			(xy 443.613546 -95.904769) (xy 443.605535 -95.968187) (xy 443.589638 -96.030101) (xy 443.566106 -96.089534)
			(xy 443.535312 -96.145549) (xy 443.497739 -96.197264) (xy 443.453982 -96.243861) (xy 443.404729 -96.284606)
			(xy 443.350758 -96.318857) (xy 443.292919 -96.346074) (xy 443.232126 -96.365827) (xy 443.169336 -96.377805)
			(xy 443.10554 -96.381819) (xy 443.041744 -96.377805) (xy 442.978954 -96.365827) (xy 442.918161 -96.346074)
			(xy 442.860322 -96.318857) (xy 442.806351 -96.284606) (xy 442.757098 -96.243861) (xy 442.713341 -96.197264)
			(xy 442.675768 -96.145549) (xy 442.644974 -96.089534) (xy 442.621442 -96.030101) (xy 442.605545 -95.968187)
			(xy 442.597534 -95.904769) (xy 215.991098 -95.904769) (xy 215.999945 -95.939227) (xy 216.007956 -96.002645)
			(xy 216.008458 -96.034606) (xy 216.007956 -96.066567) (xy 215.999945 -96.129985) (xy 215.984048 -96.191899)
			(xy 215.960516 -96.251332) (xy 215.929722 -96.307347) (xy 215.892149 -96.359062) (xy 215.848392 -96.405659)
			(xy 215.799139 -96.446404) (xy 215.745168 -96.480655) (xy 215.687329 -96.507872) (xy 215.626536 -96.527625)
			(xy 215.563746 -96.539603) (xy 215.49995 -96.543617) (xy 215.436154 -96.539603) (xy 215.373364 -96.527625)
			(xy 215.312571 -96.507872) (xy 215.254732 -96.480655) (xy 215.200761 -96.446404) (xy 215.151508 -96.405659)
			(xy 215.107751 -96.359062) (xy 215.070178 -96.307347) (xy 215.039384 -96.251332) (xy 215.015852 -96.191899)
			(xy 214.999955 -96.129985) (xy 214.991944 -96.066567) (xy 209.441253 -96.066567) (xy 209.426991 -96.073278)
			(xy 209.366198 -96.093031) (xy 209.303408 -96.105009) (xy 209.239612 -96.109023) (xy 209.175816 -96.105009)
			(xy 209.113026 -96.093031) (xy 209.052233 -96.073278) (xy 208.994394 -96.046061) (xy 208.940423 -96.01181)
			(xy 208.89117 -95.971065) (xy 208.847413 -95.924468) (xy 208.80984 -95.872753) (xy 208.779046 -95.816738)
			(xy 208.755514 -95.757305) (xy 208.739617 -95.695391) (xy 208.731606 -95.631973) (xy 201.587727 -95.631973)
			(xy 201.594318 -95.639329) (xy 201.625091 -95.685842) (xy 201.648763 -95.736339) (xy 201.664831 -95.789746)
			(xy 201.672951 -95.844922) (xy 201.67346 -95.872808) (xy 201.672951 -95.900694) (xy 201.664831 -95.95587)
			(xy 201.648763 -96.009277) (xy 201.625091 -96.059774) (xy 201.594318 -96.106287) (xy 201.557101 -96.147824)
			(xy 201.514233 -96.183499) (xy 201.466627 -96.212553) (xy 201.415298 -96.234365) (xy 201.361341 -96.248471)
			(xy 201.305904 -96.254571) (xy 201.25017 -96.252534) (xy 201.195327 -96.242404) (xy 201.142543 -96.224397)
			(xy 201.092943 -96.198896) (xy 201.047585 -96.166445) (xy 201.007436 -96.127736) (xy 200.97335 -96.083593)
			(xy 200.946054 -96.034958) (xy 200.926131 -95.982867) (xy 200.914005 -95.92843) (xy 200.909934 -95.872808)
			(xy 184.838848 -95.872808) (xy 184.838848 -96.811041) (xy 207.303872 -96.811041) (xy 207.303872 -96.747119)
			(xy 207.311883 -96.683701) (xy 207.32778 -96.621787) (xy 207.351312 -96.562354) (xy 207.382106 -96.506339)
			(xy 207.419679 -96.454624) (xy 207.463436 -96.408027) (xy 207.512689 -96.367282) (xy 207.56666 -96.333031)
			(xy 207.624499 -96.305814) (xy 207.685292 -96.286061) (xy 207.748082 -96.274083) (xy 207.811878 -96.27007)
			(xy 207.875674 -96.274083) (xy 207.938464 -96.286061) (xy 207.999257 -96.305814) (xy 208.057096 -96.333031)
			(xy 208.111067 -96.367282) (xy 208.16032 -96.408027) (xy 208.204077 -96.454624) (xy 208.24165 -96.506339)
			(xy 208.272444 -96.562354) (xy 208.295976 -96.621787) (xy 208.311873 -96.683701) (xy 208.319884 -96.747119)
			(xy 208.320386 -96.77908) (xy 208.319884 -96.811041) (xy 208.311873 -96.874459) (xy 208.295976 -96.936373)
			(xy 208.272444 -96.995806) (xy 208.24165 -97.051821) (xy 208.238576 -97.056052) (xy 212.17634 -97.056052)
			(xy 212.17634 -97.001548) (xy 212.184096 -96.947598) (xy 212.199451 -96.895302) (xy 212.222091 -96.845722)
			(xy 212.251557 -96.799869) (xy 212.287247 -96.758676) (xy 212.328437 -96.722981) (xy 212.374287 -96.69351)
			(xy 212.423864 -96.670865) (xy 212.476159 -96.655505) (xy 212.530108 -96.647743) (xy 212.55736 -96.647254)
			(xy 212.584562 -96.647705) (xy 212.638414 -96.655428) (xy 212.690622 -96.670724) (xy 212.740128 -96.693282)
			(xy 212.785928 -96.722644) (xy 212.827091 -96.758215) (xy 212.862783 -96.799273) (xy 212.89228 -96.844986)
			(xy 212.90407 -96.869504) (xy 212.910582 -96.882338) (xy 212.929387 -96.9041) (xy 212.953514 -96.919757)
			(xy 212.981048 -96.928067) (xy 213.009808 -96.928372) (xy 213.037512 -96.920648) (xy 213.061965 -96.905506)
			(xy 213.071964 -96.895158) (xy 213.092682 -96.872735) (xy 213.138574 -96.83247) (xy 213.188956 -96.79799)
			(xy 213.243105 -96.76979) (xy 213.30024 -96.748277) (xy 213.35954 -96.73376) (xy 213.420152 -96.726447)
			(xy 213.450678 -96.725994) (xy 213.482641 -96.72647) (xy 213.546064 -96.734479) (xy 213.607983 -96.750375)
			(xy 213.667422 -96.773906) (xy 213.723442 -96.804701) (xy 213.775161 -96.842275) (xy 213.821762 -96.886035)
			(xy 213.862512 -96.93529) (xy 213.896766 -96.989265) (xy 213.923985 -97.047107) (xy 213.94374 -97.107905)
			(xy 213.945738 -97.118381) (xy 220.774254 -97.118381) (xy 220.774254 -97.054459) (xy 220.782265 -96.991041)
			(xy 220.798162 -96.929127) (xy 220.821694 -96.869694) (xy 220.852488 -96.813679) (xy 220.890061 -96.761964)
			(xy 220.933818 -96.715367) (xy 220.983071 -96.674622) (xy 221.037042 -96.640371) (xy 221.094881 -96.613154)
			(xy 221.155674 -96.593401) (xy 221.218464 -96.581423) (xy 221.28226 -96.57741) (xy 221.346056 -96.581423)
			(xy 221.408846 -96.593401) (xy 221.469639 -96.613154) (xy 221.527478 -96.640371) (xy 221.581449 -96.674622)
			(xy 221.630702 -96.715367) (xy 221.674459 -96.761964) (xy 221.712032 -96.813679) (xy 221.742826 -96.869694)
			(xy 221.766358 -96.929127) (xy 221.782255 -96.991041) (xy 221.790266 -97.054459) (xy 221.790768 -97.08642)
			(xy 221.790266 -97.118381) (xy 221.782255 -97.181799) (xy 221.766358 -97.243713) (xy 221.742826 -97.303146)
			(xy 221.712032 -97.359161) (xy 221.674459 -97.410876) (xy 221.630702 -97.457473) (xy 221.581449 -97.498218)
			(xy 221.527478 -97.532469) (xy 221.469639 -97.559686) (xy 221.408846 -97.579439) (xy 221.346056 -97.591417)
			(xy 221.28226 -97.595431) (xy 221.218464 -97.591417) (xy 221.155674 -97.579439) (xy 221.094881 -97.559686)
			(xy 221.037042 -97.532469) (xy 220.983071 -97.498218) (xy 220.933818 -97.457473) (xy 220.890061 -97.410876)
			(xy 220.852488 -97.359161) (xy 220.821694 -97.303146) (xy 220.798162 -97.243713) (xy 220.782265 -97.181799)
			(xy 220.774254 -97.118381) (xy 213.945738 -97.118381) (xy 213.955719 -97.170699) (xy 213.959734 -97.2345)
			(xy 213.955719 -97.298301) (xy 213.94374 -97.361095) (xy 213.923985 -97.421893) (xy 213.896766 -97.479735)
			(xy 213.862512 -97.53371) (xy 213.821762 -97.582965) (xy 213.775161 -97.626725) (xy 213.723442 -97.664299)
			(xy 213.667422 -97.695094) (xy 213.607983 -97.718625) (xy 213.546064 -97.734521) (xy 213.482641 -97.74253)
			(xy 213.450678 -97.74301) (xy 213.417802 -97.742519) (xy 213.3526 -97.734042) (xy 213.289034 -97.717231)
			(xy 213.228165 -97.692368) (xy 213.171008 -97.659868) (xy 213.118516 -97.620271) (xy 213.071566 -97.57424)
			(xy 213.030941 -97.522541) (xy 212.997317 -97.466037) (xy 212.971257 -97.405671) (xy 212.961728 -97.374202)
			(xy 212.957341 -97.360474) (xy 212.941974 -97.336103) (xy 212.92042 -97.316985) (xy 212.89439 -97.304635)
			(xy 212.865948 -97.300035) (xy 212.837352 -97.303549) (xy 212.81087 -97.314898) (xy 212.799422 -97.323656)
			(xy 212.778848 -97.339936) (xy 212.734118 -97.367355) (xy 212.686053 -97.388386) (xy 212.635561 -97.402634)
			(xy 212.583592 -97.40983) (xy 212.55736 -97.41027) (xy 212.530108 -97.409857) (xy 212.476159 -97.402095)
			(xy 212.423864 -97.386735) (xy 212.374287 -97.36409) (xy 212.328437 -97.334619) (xy 212.287247 -97.298924)
			(xy 212.251557 -97.257731) (xy 212.222091 -97.211878) (xy 212.199451 -97.162298) (xy 212.184096 -97.110002)
			(xy 212.17634 -97.056052) (xy 208.238576 -97.056052) (xy 208.204077 -97.103536) (xy 208.16032 -97.150133)
			(xy 208.111067 -97.190878) (xy 208.057096 -97.225129) (xy 207.999257 -97.252346) (xy 207.938464 -97.272099)
			(xy 207.875674 -97.284077) (xy 207.811878 -97.288091) (xy 207.748082 -97.284077) (xy 207.685292 -97.272099)
			(xy 207.624499 -97.252346) (xy 207.56666 -97.225129) (xy 207.512689 -97.190878) (xy 207.463436 -97.150133)
			(xy 207.419679 -97.103536) (xy 207.382106 -97.051821) (xy 207.351312 -96.995806) (xy 207.32778 -96.936373)
			(xy 207.311883 -96.874459) (xy 207.303872 -96.811041) (xy 184.838848 -96.811041) (xy 184.838848 -97.7138)
			(xy 184.839223 -97.72216) (xy 184.844653 -97.737979) (xy 184.849516 -97.744788) (xy 184.85104 -97.746566)
			(xy 184.855866 -97.752408) (xy 184.870852 -97.761552) (xy 184.88025 -97.76333) (xy 184.913274 -97.770183)
			(xy 184.977276 -97.791462) (xy 185.037902 -97.821019) (xy 185.094085 -97.858334) (xy 185.14484 -97.902753)
			(xy 185.189273 -97.953494) (xy 185.208418 -97.981262) (xy 185.213942 -97.988848) (xy 185.229186 -97.999768)
			(xy 185.238136 -98.002598) (xy 185.250836 -98.004122) (xy 185.335164 -98.004122) (xy 185.347864 -98.002598)
			(xy 185.356877 -97.999903) (xy 185.372149 -97.988942) (xy 185.377582 -97.981262) (xy 185.395303 -97.955483)
			(xy 185.436076 -97.908037) (xy 185.482363 -97.865954) (xy 185.533463 -97.829867) (xy 185.588606 -97.800324)
			(xy 185.646957 -97.777769) (xy 185.707634 -97.762545) (xy 185.769721 -97.754882) (xy 185.801 -97.75444)
			(xy 185.832474 -97.75491) (xy 185.894941 -97.762675) (xy 185.955973 -97.778085) (xy 186.014639 -97.800905)
			(xy 186.070041 -97.830787) (xy 186.121335 -97.867275) (xy 186.167737 -97.90981) (xy 186.208537 -97.957745)
			(xy 186.226196 -97.983802) (xy 186.231817 -97.990667) (xy 186.246619 -98.000426) (xy 186.255152 -98.002852)
			(xy 186.266836 -98.004122) (xy 186.351164 -98.004122) (xy 186.363864 -98.002598) (xy 186.372877 -97.999903)
			(xy 186.388149 -97.988942) (xy 186.393582 -97.981262) (xy 186.411303 -97.955483) (xy 186.452076 -97.908037)
			(xy 186.498363 -97.865954) (xy 186.549463 -97.829867) (xy 186.604606 -97.800324) (xy 186.662957 -97.777769)
			(xy 186.723634 -97.762545) (xy 186.785721 -97.754882) (xy 186.817 -97.75444) (xy 186.848287 -97.75492)
			(xy 186.910389 -97.762599) (xy 186.97108 -97.777841) (xy 187.029441 -97.800416) (xy 187.08459 -97.829982)
			(xy 187.135695 -97.866092) (xy 187.181982 -97.908201) (xy 187.222751 -97.955672) (xy 187.257387 -98.007787)
			(xy 187.285365 -98.063759) (xy 187.306263 -98.122741) (xy 187.319765 -98.183842) (xy 187.323222 -98.214942)
			(xy 187.323222 -98.215196) (xy 187.323476 -98.217228) (xy 187.32445 -98.223147) (xy 187.328813 -98.234316)
			(xy 187.332112 -98.239326) (xy 187.335922 -98.244152) (xy 187.340451 -98.248879) (xy 187.351383 -98.256074)
			(xy 187.357512 -98.258376) (xy 187.426092 -98.281744) (xy 187.433071 -98.283895) (xy 187.447653 -98.284542)
			(xy 187.454794 -98.283014) (xy 187.461906 -98.281236) (xy 187.474098 -98.274124) (xy 187.479178 -98.26879)
			(xy 187.503237 -98.244492) (xy 187.556739 -98.201912) (xy 187.615462 -98.166881) (xy 187.678347 -98.140029)
			(xy 187.744262 -98.121841) (xy 187.812019 -98.112645) (xy 187.846208 -98.112072) (xy 187.846716 -98.112072)
			(xy 187.854082 -98.112326) (xy 187.854844 -98.112326) (xy 187.871608 -98.112072) (xy 187.906235 -98.112657)
			(xy 187.974847 -98.122055) (xy 188.041551 -98.140675) (xy 188.10511 -98.168174) (xy 188.164351 -98.204042)
			(xy 188.191648 -98.225356) (xy 188.194442 -98.227642) (xy 188.206888 -98.233992) (xy 188.214762 -98.236024)
			(xy 188.227462 -98.23831) (xy 188.280294 -98.220276) (xy 188.280548 -98.220276) (xy 188.32576 -98.205036)
			(xy 188.329501 -98.203255) (xy 188.336398 -98.198666) (xy 188.339476 -98.195892) (xy 188.344048 -98.191066)
			(xy 188.347096 -98.18751) (xy 188.352938 -98.176588) (xy 188.354462 -98.170238) (xy 188.362084 -98.140293)
			(xy 188.383617 -98.082375) (xy 188.41201 -98.027492) (xy 188.446844 -97.976454) (xy 188.487605 -97.930012)
			(xy 188.533692 -97.888852) (xy 188.584428 -97.853579) (xy 188.639063 -97.824714) (xy 188.696794 -97.802681)
			(xy 188.756769 -97.787805) (xy 188.818104 -97.780306) (xy 188.849 -97.77984) (xy 188.882833 -97.78039)
			(xy 188.949901 -97.789356) (xy 189.015187 -97.807141) (xy 189.077536 -97.833431) (xy 189.135846 -97.867762)
			(xy 189.189084 -97.909526) (xy 189.23631 -97.957986) (xy 189.256924 -97.984818) (xy 189.257178 -97.985072)
			(xy 189.260957 -97.98982) (xy 189.270329 -97.997525) (xy 189.27572 -98.000312) (xy 189.281816 -98.003106)
			(xy 189.292992 -98.005392) (xy 189.305184 -98.004884) (xy 189.385448 -98.00209) (xy 189.391052 -98.001483)
			(xy 189.401817 -97.998151) (xy 189.406784 -97.995486) (xy 189.411864 -97.992438) (xy 189.4205 -97.98431)
			(xy 189.424056 -97.978722) (xy 189.441621 -97.952036) (xy 189.482387 -97.902845) (xy 189.528991 -97.859144)
			(xy 189.580699 -97.821621) (xy 189.636697 -97.790866) (xy 189.696105 -97.767364) (xy 189.757988 -97.751484)
			(xy 189.821372 -97.743475) (xy 189.853316 -97.74301) (xy 189.887067 -97.743562) (xy 189.953974 -97.752495)
			(xy 190.019111 -97.770202) (xy 190.081333 -97.796372) (xy 190.139546 -97.830543) (xy 190.192725 -97.872117)
			(xy 190.239937 -97.920361) (xy 190.28035 -97.974427) (xy 190.297308 -98.003614) (xy 190.304928 -98.014028)
			(xy 190.318898 -98.028506) (xy 190.32474 -98.032062) (xy 190.330836 -98.03384) (xy 190.344298 -98.035618)
			(xy 190.364618 -98.035872) (xy 190.433452 -98.036634) (xy 190.440162 -98.036477) (xy 190.453156 -98.033135)
			(xy 190.459106 -98.03003) (xy 190.471044 -98.023172) (xy 190.475362 -98.015298) (xy 190.477394 -98.011996)
			(xy 190.477902 -98.01098) (xy 190.48456 -97.99948) (xy 190.498919 -97.977117) (xy 190.506604 -97.966276)
			(xy 190.525286 -97.941071) (xy 190.567885 -97.895009) (xy 190.615825 -97.854536) (xy 190.668378 -97.820266)
			(xy 190.724748 -97.792719) (xy 190.784077 -97.772314) (xy 190.845466 -97.75936) (xy 190.876682 -97.756218)
			(xy 190.896494 -97.754694) (xy 190.900558 -97.75444) (xy 190.923672 -97.75444) (xy 190.955991 -97.755165)
			(xy 191.020057 -97.763798) (xy 191.082512 -97.780484) (xy 191.142348 -97.804952) (xy 191.198599 -97.836809)
			(xy 191.250358 -97.87554) (xy 191.296789 -97.920521) (xy 191.317372 -97.945448) (xy 191.324484 -97.952814)
			(xy 191.33312 -97.959926) (xy 191.341248 -97.965514) (xy 191.353694 -97.971864) (xy 191.356742 -97.973388)
			(xy 191.362169 -97.975972) (xy 191.373848 -97.978796) (xy 191.379856 -97.978976) (xy 191.436752 -97.978976)
			(xy 191.442761 -97.978808) (xy 191.454443 -97.975983) (xy 191.459866 -97.973388) (xy 191.462914 -97.971864)
			(xy 191.47536 -97.965514) (xy 191.483488 -97.959926) (xy 191.492124 -97.952814) (xy 191.499236 -97.945448)
			(xy 191.520002 -97.920321) (xy 191.566887 -97.875034) (xy 191.619171 -97.836103) (xy 191.675998 -97.804166)
			(xy 191.736437 -97.779747) (xy 191.7995 -97.763243) (xy 191.864153 -97.754926) (xy 191.896746 -97.75444)
			(xy 191.897 -97.75444) (xy 191.928474 -97.75491) (xy 191.990941 -97.762675) (xy 192.051973 -97.778085)
			(xy 192.110639 -97.800905) (xy 192.166041 -97.830787) (xy 192.217335 -97.867275) (xy 192.263737 -97.90981)
			(xy 192.304537 -97.957745) (xy 192.322196 -97.983802) (xy 192.327817 -97.990667) (xy 192.342619 -98.000426)
			(xy 192.351152 -98.002852) (xy 192.362836 -98.004122) (xy 192.447164 -98.004122) (xy 192.459864 -98.002598)
			(xy 192.468877 -97.999903) (xy 192.484149 -97.988942) (xy 192.489582 -97.981262) (xy 192.507303 -97.955483)
			(xy 192.548076 -97.908037) (xy 192.594363 -97.865954) (xy 192.645463 -97.829867) (xy 192.700606 -97.800324)
			(xy 192.758957 -97.777769) (xy 192.819634 -97.762545) (xy 192.881721 -97.754882) (xy 192.913 -97.75444)
			(xy 192.944474 -97.75491) (xy 193.006941 -97.762675) (xy 193.067973 -97.778085) (xy 193.126639 -97.800905)
			(xy 193.182041 -97.830787) (xy 193.233335 -97.867275) (xy 193.279737 -97.90981) (xy 193.320537 -97.957745)
			(xy 193.338196 -97.983802) (xy 193.343817 -97.990667) (xy 193.358619 -98.000426) (xy 193.367152 -98.002852)
			(xy 193.378836 -98.004122) (xy 193.463164 -98.004122) (xy 193.475864 -98.002598) (xy 193.484877 -97.999903)
			(xy 193.500149 -97.988942) (xy 193.505582 -97.981262) (xy 193.523303 -97.955483) (xy 193.564076 -97.908037)
			(xy 193.610363 -97.865954) (xy 193.661463 -97.829867) (xy 193.716606 -97.800324) (xy 193.774957 -97.777769)
			(xy 193.835634 -97.762545) (xy 193.897721 -97.754882) (xy 193.929 -97.75444) (xy 193.960474 -97.75491)
			(xy 194.022941 -97.762675) (xy 194.083973 -97.778085) (xy 194.142639 -97.800905) (xy 194.198041 -97.830787)
			(xy 194.249335 -97.867275) (xy 194.295737 -97.90981) (xy 194.336537 -97.957745) (xy 194.354196 -97.983802)
			(xy 194.359817 -97.990667) (xy 194.374619 -98.000426) (xy 194.383152 -98.002852) (xy 194.394836 -98.004122)
			(xy 194.479164 -98.004122) (xy 194.491864 -98.002598) (xy 194.500877 -97.999903) (xy 194.516149 -97.988942)
			(xy 194.521582 -97.981262) (xy 194.539303 -97.955483) (xy 194.580076 -97.908037) (xy 194.626363 -97.865954)
			(xy 194.677463 -97.829867) (xy 194.732606 -97.800324) (xy 194.790957 -97.777769) (xy 194.851634 -97.762545)
			(xy 194.913721 -97.754882) (xy 194.945 -97.75444) (xy 194.975375 -97.754882) (xy 195.035693 -97.762116)
			(xy 195.09472 -97.776482) (xy 195.151616 -97.797776) (xy 195.205572 -97.825693) (xy 195.255819 -97.859837)
			(xy 195.301642 -97.899722) (xy 195.34239 -97.94478) (xy 195.36029 -97.969324) (xy 195.368164 -97.978214)
			(xy 195.377562 -97.986342) (xy 195.38696 -97.992946) (xy 195.40093 -98.000312) (xy 195.405757 -98.002719)
			(xy 195.416133 -98.005659) (xy 195.421504 -98.006154) (xy 195.484496 -98.006154) (xy 195.487544 -98.006154)
			(xy 195.492918 -98.005674) (xy 195.503299 -98.002737) (xy 195.508118 -98.000312) (xy 195.522088 -97.992946)
			(xy 195.531486 -97.986342) (xy 195.540884 -97.978214) (xy 195.548758 -97.969324) (xy 195.566663 -97.944783)
			(xy 195.607409 -97.899721) (xy 195.653231 -97.859832) (xy 195.703476 -97.825683) (xy 195.757431 -97.797761)
			(xy 195.814327 -97.776462) (xy 195.873354 -97.762091) (xy 195.933672 -97.75485) (xy 195.964048 -97.75444)
			(xy 195.994776 -97.754907) (xy 196.055783 -97.76232) (xy 196.115452 -97.777033) (xy 196.172913 -97.798832)
			(xy 196.227327 -97.827397) (xy 196.277901 -97.862313) (xy 196.323898 -97.90307) (xy 196.364647 -97.949074)
			(xy 196.399553 -97.999655) (xy 196.428108 -98.054075) (xy 196.449895 -98.111539) (xy 196.464597 -98.171211)
			(xy 196.471999 -98.23222) (xy 196.472556 -98.262948) (xy 196.472477 -98.27567) (xy 196.471205 -98.301082)
			(xy 196.470016 -98.313748) (xy 196.46636 -98.34538) (xy 196.452169 -98.407456) (xy 196.430339 -98.467274)
			(xy 196.42935 -98.469196) (xy 205.756508 -98.469196) (xy 205.760579 -98.413574) (xy 205.772705 -98.359137)
			(xy 205.792628 -98.307046) (xy 205.819924 -98.258411) (xy 205.85401 -98.214268) (xy 205.894159 -98.175559)
			(xy 205.939517 -98.143108) (xy 205.989117 -98.117607) (xy 206.041901 -98.0996) (xy 206.096744 -98.08947)
			(xy 206.152478 -98.087433) (xy 206.207915 -98.093533) (xy 206.261872 -98.107639) (xy 206.313201 -98.129451)
			(xy 206.360807 -98.158505) (xy 206.385231 -98.178831) (xy 236.573054 -98.178831) (xy 236.573054 -98.114909)
			(xy 236.581065 -98.051491) (xy 236.596962 -97.989577) (xy 236.620494 -97.930144) (xy 236.651288 -97.874129)
			(xy 236.688861 -97.822414) (xy 236.732618 -97.775817) (xy 236.781871 -97.735072) (xy 236.835842 -97.700821)
			(xy 236.893681 -97.673604) (xy 236.954474 -97.653851) (xy 237.017264 -97.641873) (xy 237.08106 -97.63786)
			(xy 237.144856 -97.641873) (xy 237.207646 -97.653851) (xy 237.268439 -97.673604) (xy 237.326278 -97.700821)
			(xy 237.380249 -97.735072) (xy 237.429502 -97.775817) (xy 237.473259 -97.822414) (xy 237.510832 -97.874129)
			(xy 237.541626 -97.930144) (xy 237.565158 -97.989577) (xy 237.581055 -98.051491) (xy 237.589066 -98.114909)
			(xy 237.589568 -98.14687) (xy 237.589497 -98.1514) (xy 238.235331 -98.1514) (xy 238.239344 -98.087613)
			(xy 238.25132 -98.024832) (xy 238.271069 -97.964047) (xy 238.29828 -97.906216) (xy 238.332525 -97.852251)
			(xy 238.373262 -97.803004) (xy 238.419851 -97.75925) (xy 238.471555 -97.72168) (xy 238.52756 -97.690886)
			(xy 238.586984 -97.667354) (xy 238.648887 -97.651455) (xy 238.712296 -97.643439) (xy 238.744252 -97.642934)
			(xy 238.7752 -97.643378) (xy 238.836636 -97.650904) (xy 238.896707 -97.665826) (xy 238.954524 -97.687923)
			(xy 239.009234 -97.71687) (xy 239.060029 -97.752239) (xy 239.106159 -97.793508) (xy 239.146943 -97.840067)
			(xy 239.181779 -97.891229) (xy 239.196372 -97.918524) (xy 239.202722 -97.93097) (xy 239.225582 -97.945448)
			(xy 239.32769 -97.949512) (xy 239.336631 -97.949529) (xy 239.353666 -97.944143) (xy 239.367827 -97.933249)
			(xy 239.372902 -97.92589) (xy 239.372902 -97.925636) (xy 239.390414 -97.898587) (xy 239.431129 -97.848645)
			(xy 239.477828 -97.804246) (xy 239.529761 -97.766103) (xy 239.586098 -97.734827) (xy 239.645934 -97.710919)
			(xy 239.708311 -97.694762) (xy 239.77223 -97.686614) (xy 239.804448 -97.686114) (xy 239.836251 -97.68657)
			(xy 239.899361 -97.694498) (xy 239.96099 -97.710236) (xy 240.020174 -97.733538) (xy 240.075989 -97.764041)
			(xy 240.127563 -97.801268) (xy 240.174091 -97.844638) (xy 240.194846 -97.86874) (xy 240.202212 -97.877376)
			(xy 240.222532 -97.887028) (xy 240.324132 -97.886266) (xy 240.344452 -97.876614) (xy 240.351564 -97.867724)
			(xy 240.372278 -97.842912) (xy 240.419031 -97.798279) (xy 240.471063 -97.759928) (xy 240.527534 -97.72848)
			(xy 240.587535 -97.70444) (xy 240.650098 -97.688197) (xy 240.714215 -97.680011) (xy 240.746534 -97.67951)
			(xy 240.778495 -97.679978) (xy 240.841912 -97.687993) (xy 240.903824 -97.703894) (xy 240.963256 -97.727428)
			(xy 241.01927 -97.758225) (xy 241.070982 -97.795799) (xy 241.117577 -97.839558) (xy 241.158321 -97.888812)
			(xy 241.19257 -97.942783) (xy 241.219786 -98.000622) (xy 241.239538 -98.061415) (xy 241.251515 -98.124205)
			(xy 241.255529 -98.188) (xy 241.251515 -98.251795) (xy 241.239538 -98.314585) (xy 241.219786 -98.375378)
			(xy 241.19257 -98.433217) (xy 241.158321 -98.487188) (xy 241.123653 -98.529097) (xy 248.587254 -98.529097)
			(xy 248.587254 -98.465175) (xy 248.595265 -98.401757) (xy 248.611162 -98.339843) (xy 248.634694 -98.28041)
			(xy 248.665488 -98.224395) (xy 248.703061 -98.17268) (xy 248.746818 -98.126083) (xy 248.796071 -98.085338)
			(xy 248.850042 -98.051087) (xy 248.907881 -98.02387) (xy 248.968674 -98.004117) (xy 249.031464 -97.992139)
			(xy 249.09526 -97.988126) (xy 249.159056 -97.992139) (xy 249.221846 -98.004117) (xy 249.282639 -98.02387)
			(xy 249.340478 -98.051087) (xy 249.394449 -98.085338) (xy 249.443702 -98.126083) (xy 249.487459 -98.17268)
			(xy 249.525032 -98.224395) (xy 249.555826 -98.28041) (xy 249.579358 -98.339843) (xy 249.595255 -98.401757)
			(xy 249.603266 -98.465175) (xy 249.603768 -98.497136) (xy 249.603266 -98.529097) (xy 249.595255 -98.592515)
			(xy 249.579358 -98.654429) (xy 249.555826 -98.713862) (xy 249.525032 -98.769877) (xy 249.487459 -98.821592)
			(xy 249.443702 -98.868189) (xy 249.423381 -98.885) (xy 249.850683 -98.885) (xy 249.854697 -98.821206)
			(xy 249.866674 -98.758417) (xy 249.886426 -98.697625) (xy 249.913641 -98.639787) (xy 249.94789 -98.585817)
			(xy 249.988634 -98.536564) (xy 250.035229 -98.492806) (xy 250.08694 -98.455233) (xy 250.142953 -98.424437)
			(xy 250.202384 -98.400903) (xy 250.264296 -98.385004) (xy 250.327712 -98.37699) (xy 250.359672 -98.376486)
			(xy 250.393004 -98.377021) (xy 250.459098 -98.385728) (xy 250.523487 -98.402998) (xy 250.585068 -98.428534)
			(xy 250.642783 -98.461897) (xy 250.695644 -98.502516) (xy 250.742744 -98.549695) (xy 250.783275 -98.602624)
			(xy 250.800362 -98.631248) (xy 250.807732 -98.643254) (xy 250.827924 -98.662889) (xy 250.852709 -98.676268)
			(xy 250.880203 -98.682373) (xy 250.908321 -98.680742) (xy 250.934925 -98.671498) (xy 250.957997 -98.655344)
			(xy 250.96724 -98.64471) (xy 250.985454 -98.623045) (xy 251.02721 -98.584838) (xy 251.074151 -98.553216)
			(xy 251.125248 -98.528875) (xy 251.17938 -98.512347) (xy 251.235359 -98.503996) (xy 251.263658 -98.503486)
			(xy 251.290912 -98.503958) (xy 251.344867 -98.51171) (xy 251.397169 -98.527063) (xy 251.446754 -98.549702)
			(xy 251.492611 -98.579169) (xy 251.533808 -98.614862) (xy 251.569506 -98.656055) (xy 251.598977 -98.701909)
			(xy 251.621623 -98.751492) (xy 251.636734 -98.802952) (xy 267.698728 -98.802952) (xy 267.699238 -98.770246)
			(xy 267.70762 -98.705373) (xy 267.724253 -98.642111) (xy 267.74886 -98.581504) (xy 267.781037 -98.524554)
			(xy 267.820252 -98.4722) (xy 267.865857 -98.425307) (xy 267.917099 -98.384651) (xy 267.944854 -98.367342)
			(xy 267.954806 -98.360554) (xy 267.967543 -98.340151) (xy 267.969238 -98.328226) (xy 267.976096 -98.246184)
			(xy 267.976498 -98.234062) (xy 267.967335 -98.211643) (xy 267.95857 -98.203258) (xy 267.938066 -98.185106)
			(xy 267.902066 -98.143838) (xy 267.872338 -98.097846) (xy 267.849491 -98.048077) (xy 267.833996 -97.995551)
			(xy 267.82617 -97.94135) (xy 267.826174 -97.886587) (xy 267.834009 -97.832387) (xy 267.849513 -97.779865)
			(xy 267.872368 -97.730099) (xy 267.902104 -97.684112) (xy 267.93811 -97.642849) (xy 267.95857 -97.624646)
			(xy 267.967303 -97.616244) (xy 267.976445 -97.593835) (xy 267.976096 -97.58172) (xy 267.969238 -97.499678)
			(xy 267.967544 -97.487752) (xy 267.954814 -97.467339) (xy 267.944854 -97.460562) (xy 267.917118 -97.443224)
			(xy 267.86588 -97.402568) (xy 267.820277 -97.355678) (xy 267.781062 -97.303328) (xy 267.748883 -97.246382)
			(xy 267.72427 -97.185781) (xy 267.70763 -97.122524) (xy 267.699237 -97.057656) (xy 267.698728 -97.024952)
			(xy 267.69923 -96.992991) (xy 267.707241 -96.929573) (xy 267.723138 -96.867659) (xy 267.74667 -96.808226)
			(xy 267.777464 -96.752211) (xy 267.815037 -96.700496) (xy 267.858794 -96.653899) (xy 267.908047 -96.613154)
			(xy 267.962018 -96.578903) (xy 268.019857 -96.551686) (xy 268.08065 -96.531933) (xy 268.14344 -96.519955)
			(xy 268.207236 -96.515942) (xy 268.271032 -96.519955) (xy 268.333822 -96.531933) (xy 268.394615 -96.551686)
			(xy 268.428757 -96.567752) (xy 270.799814 -96.567752) (xy 270.800316 -96.535791) (xy 270.808327 -96.472373)
			(xy 270.824224 -96.410459) (xy 270.847756 -96.351026) (xy 270.87855 -96.295011) (xy 270.916123 -96.243296)
			(xy 270.95988 -96.196699) (xy 271.009133 -96.155954) (xy 271.063104 -96.121703) (xy 271.120943 -96.094486)
			(xy 271.181736 -96.074733) (xy 271.244526 -96.062755) (xy 271.308322 -96.058742) (xy 271.372118 -96.062755)
			(xy 271.434908 -96.074733) (xy 271.495701 -96.094486) (xy 271.55354 -96.121703) (xy 271.607511 -96.155954)
			(xy 271.656764 -96.196699) (xy 271.700521 -96.243296) (xy 271.738094 -96.295011) (xy 271.768888 -96.351026)
			(xy 271.79242 -96.410459) (xy 271.808317 -96.472373) (xy 271.816328 -96.535791) (xy 271.81683 -96.567752)
			(xy 271.816343 -96.600459) (xy 271.80796 -96.665333) (xy 271.791325 -96.728597) (xy 271.766715 -96.789205)
			(xy 271.734535 -96.846156) (xy 271.695316 -96.898509) (xy 271.649707 -96.9454) (xy 271.598461 -96.986055)
			(xy 271.570704 -97.003362) (xy 271.560742 -97.010138) (xy 271.548012 -97.03055) (xy 271.54632 -97.042478)
			(xy 271.539462 -97.12452) (xy 271.539038 -97.136644) (xy 271.548214 -97.159065) (xy 271.556988 -97.167446)
			(xy 271.577467 -97.185626) (xy 271.613467 -97.226891) (xy 271.643196 -97.27288) (xy 271.666043 -97.322648)
			(xy 271.681537 -97.375172) (xy 271.683377 -97.387918) (xy 272.212308 -97.387918) (xy 272.21281 -97.360312)
			(xy 272.220766 -97.305676) (xy 272.236517 -97.252758) (xy 272.259731 -97.202663) (xy 272.289925 -97.156438)
			(xy 272.326467 -97.115048) (xy 272.368594 -97.079359) (xy 272.415427 -97.050116) (xy 272.465985 -97.02793)
			(xy 272.49247 -97.020126) (xy 272.505841 -97.016013) (xy 272.529795 -97.00158) (xy 272.548925 -96.981181)
			(xy 272.561793 -96.956351) (xy 272.56743 -96.928959) (xy 272.565412 -96.901066) (xy 272.555891 -96.874771)
			(xy 272.548096 -96.863154) (xy 272.530186 -96.837233) (xy 272.500208 -96.781815) (xy 272.477315 -96.723115)
			(xy 272.461859 -96.662033) (xy 272.454077 -96.599509) (xy 272.453608 -96.568006) (xy 272.453608 -96.567752)
			(xy 272.45411 -96.535791) (xy 272.462121 -96.472373) (xy 272.478018 -96.410459) (xy 272.50155 -96.351026)
			(xy 272.532344 -96.295011) (xy 272.569917 -96.243296) (xy 272.613674 -96.196699) (xy 272.662927 -96.155954)
			(xy 272.716898 -96.121703) (xy 272.774737 -96.094486) (xy 272.83553 -96.074733) (xy 272.89832 -96.062755)
			(xy 272.962116 -96.058742) (xy 273.025912 -96.062755) (xy 273.088702 -96.074733) (xy 273.149495 -96.094486)
			(xy 273.207334 -96.121703) (xy 273.261305 -96.155954) (xy 273.310558 -96.196699) (xy 273.354315 -96.243296)
			(xy 273.391888 -96.295011) (xy 273.422682 -96.351026) (xy 273.446214 -96.410459) (xy 273.462111 -96.472373)
			(xy 273.470122 -96.535791) (xy 273.470624 -96.567752) (xy 273.470188 -96.598791) (xy 273.463263 -96.655382)
			(xy 288.974782 -96.655382) (xy 288.978853 -96.59976) (xy 288.990979 -96.545323) (xy 289.010902 -96.493232)
			(xy 289.038198 -96.444597) (xy 289.072284 -96.400454) (xy 289.112433 -96.361745) (xy 289.157791 -96.329294)
			(xy 289.207391 -96.303793) (xy 289.260175 -96.285786) (xy 289.315018 -96.275656) (xy 289.370752 -96.273619)
			(xy 289.426189 -96.279719) (xy 289.480146 -96.293825) (xy 289.531475 -96.315637) (xy 289.579081 -96.344691)
			(xy 289.621949 -96.380366) (xy 289.659166 -96.421903) (xy 289.689939 -96.468416) (xy 289.713611 -96.518913)
			(xy 289.729679 -96.57232) (xy 289.737799 -96.627496) (xy 289.738308 -96.655382) (xy 289.737799 -96.683268)
			(xy 289.729679 -96.738444) (xy 289.713611 -96.791851) (xy 289.689939 -96.842348) (xy 289.659166 -96.888861)
			(xy 289.621949 -96.930398) (xy 289.579081 -96.966073) (xy 289.531475 -96.995127) (xy 289.480146 -97.016939)
			(xy 289.426189 -97.031045) (xy 289.370752 -97.037145) (xy 289.315018 -97.035108) (xy 289.260175 -97.024978)
			(xy 289.207391 -97.006971) (xy 289.157791 -96.98147) (xy 289.112433 -96.949019) (xy 289.072284 -96.91031)
			(xy 289.038198 -96.866167) (xy 289.010902 -96.817532) (xy 288.990979 -96.765441) (xy 288.978853 -96.711004)
			(xy 288.974782 -96.655382) (xy 273.463263 -96.655382) (xy 273.462648 -96.660409) (xy 273.447662 -96.720651)
			(xy 273.425453 -96.77862) (xy 273.396351 -96.833454) (xy 273.36079 -96.884337) (xy 273.319298 -96.930511)
			(xy 273.272494 -96.971291) (xy 273.221072 -97.006068) (xy 273.165799 -97.034327) (xy 273.107496 -97.055645)
			(xy 273.047032 -97.069707) (xy 273.016218 -97.073466) (xy 273.002408 -97.075475) (xy 272.976535 -97.085896)
			(xy 272.954443 -97.102925) (xy 272.937778 -97.125292) (xy 272.927781 -97.151332) (xy 272.925197 -97.179105)
			(xy 272.930217 -97.206543) (xy 272.935954 -97.219262) (xy 272.948356 -97.245631) (xy 272.965906 -97.301194)
			(xy 272.974777 -97.358783) (xy 272.975013 -97.371365) (xy 273.405594 -97.371365) (xy 273.405594 -97.307443)
			(xy 273.413605 -97.244025) (xy 273.429502 -97.182111) (xy 273.453034 -97.122678) (xy 273.483828 -97.066663)
			(xy 273.521401 -97.014948) (xy 273.565158 -96.968351) (xy 273.614411 -96.927606) (xy 273.668382 -96.893355)
			(xy 273.726221 -96.866138) (xy 273.787014 -96.846385) (xy 273.849804 -96.834407) (xy 273.9136 -96.830394)
			(xy 273.977396 -96.834407) (xy 274.040186 -96.846385) (xy 274.100979 -96.866138) (xy 274.158818 -96.893355)
			(xy 274.212789 -96.927606) (xy 274.262042 -96.968351) (xy 274.305799 -97.014948) (xy 274.343372 -97.066663)
			(xy 274.374166 -97.122678) (xy 274.397698 -97.182111) (xy 274.413595 -97.244025) (xy 274.421606 -97.307443)
			(xy 274.422108 -97.339404) (xy 274.421606 -97.371365) (xy 274.413595 -97.434783) (xy 274.397698 -97.496697)
			(xy 274.374166 -97.55613) (xy 274.343372 -97.612145) (xy 274.305799 -97.66386) (xy 274.262042 -97.710457)
			(xy 274.212789 -97.751202) (xy 274.158818 -97.785453) (xy 274.100979 -97.81267) (xy 274.040186 -97.832423)
			(xy 273.977396 -97.844401) (xy 273.9136 -97.848415) (xy 273.849804 -97.844401) (xy 273.787014 -97.832423)
			(xy 273.726221 -97.81267) (xy 273.668382 -97.785453) (xy 273.614411 -97.751202) (xy 273.565158 -97.710457)
			(xy 273.521401 -97.66386) (xy 273.483828 -97.612145) (xy 273.453034 -97.55613) (xy 273.429502 -97.496697)
			(xy 273.413605 -97.434783) (xy 273.405594 -97.371365) (xy 272.975013 -97.371365) (xy 272.975324 -97.387918)
			(xy 272.974838 -97.415169) (xy 272.967082 -97.469117) (xy 272.951727 -97.521412) (xy 272.929085 -97.570989)
			(xy 272.899619 -97.616839) (xy 272.863928 -97.65803) (xy 272.822737 -97.693721) (xy 272.776887 -97.723187)
			(xy 272.72731 -97.745829) (xy 272.675015 -97.761184) (xy 272.621067 -97.76894) (xy 272.566565 -97.76894)
			(xy 272.512617 -97.761184) (xy 272.460322 -97.745829) (xy 272.410745 -97.723187) (xy 272.364895 -97.693721)
			(xy 272.323704 -97.65803) (xy 272.288013 -97.616839) (xy 272.258547 -97.570989) (xy 272.235905 -97.521412)
			(xy 272.22055 -97.469117) (xy 272.212794 -97.415169) (xy 272.212308 -97.387918) (xy 271.683377 -97.387918)
			(xy 271.689361 -97.429371) (xy 271.68983 -97.456752) (xy 271.689344 -97.484003) (xy 271.681588 -97.537951)
			(xy 271.666233 -97.590246) (xy 271.643591 -97.639823) (xy 271.614125 -97.685673) (xy 271.578434 -97.726864)
			(xy 271.537243 -97.762555) (xy 271.491393 -97.792021) (xy 271.441816 -97.814663) (xy 271.389521 -97.830018)
			(xy 271.335573 -97.837774) (xy 271.281071 -97.837774) (xy 271.227123 -97.830018) (xy 271.174828 -97.814663)
			(xy 271.125251 -97.792021) (xy 271.079401 -97.762555) (xy 271.03821 -97.726864) (xy 271.002519 -97.685673)
			(xy 270.973053 -97.639823) (xy 270.950411 -97.590246) (xy 270.935056 -97.537951) (xy 270.9273 -97.484003)
			(xy 270.926814 -97.456752) (xy 270.9273 -97.429374) (xy 270.935134 -97.37518) (xy 270.950634 -97.322663)
			(xy 270.973482 -97.272901) (xy 271.003208 -97.226915) (xy 271.039202 -97.185651) (xy 271.059656 -97.167446)
			(xy 271.068387 -97.159042) (xy 271.07753 -97.136634) (xy 271.077182 -97.12452) (xy 271.070324 -97.042478)
			(xy 271.068635 -97.03055) (xy 271.055901 -97.010138) (xy 271.04594 -97.003362) (xy 271.018201 -96.986029)
			(xy 270.966963 -96.945372) (xy 270.921361 -96.898481) (xy 270.882147 -96.84613) (xy 270.849968 -96.789184)
			(xy 270.825356 -96.728582) (xy 270.808716 -96.665325) (xy 270.800323 -96.600456) (xy 270.799814 -96.567752)
			(xy 268.428757 -96.567752) (xy 268.452454 -96.578903) (xy 268.506425 -96.613154) (xy 268.555678 -96.653899)
			(xy 268.599435 -96.700496) (xy 268.637008 -96.752211) (xy 268.667802 -96.808226) (xy 268.691334 -96.867659)
			(xy 268.707231 -96.929573) (xy 268.715242 -96.992991) (xy 268.715744 -97.024952) (xy 268.71525 -97.057659)
			(xy 268.706867 -97.122533) (xy 268.690234 -97.185796) (xy 268.665624 -97.246403) (xy 268.633445 -97.303354)
			(xy 268.594227 -97.355707) (xy 268.548619 -97.402599) (xy 268.497375 -97.443254) (xy 268.469618 -97.460562)
			(xy 268.459659 -97.467341) (xy 268.446927 -97.487751) (xy 268.445234 -97.499678) (xy 268.438376 -97.58172)
			(xy 268.437948 -97.593844) (xy 268.447126 -97.616266) (xy 268.455902 -97.624646) (xy 268.476307 -97.642903)
			(xy 268.5123 -97.68416) (xy 268.542024 -97.730139) (xy 268.56487 -97.779895) (xy 268.580368 -97.832406)
			(xy 268.5882 -97.886594) (xy 268.588205 -97.941344) (xy 268.584459 -97.967292) (xy 288.974782 -97.967292)
			(xy 288.978853 -97.91167) (xy 288.990979 -97.857233) (xy 289.010902 -97.805142) (xy 289.038198 -97.756507)
			(xy 289.072284 -97.712364) (xy 289.112433 -97.673655) (xy 289.157791 -97.641204) (xy 289.207391 -97.615703)
			(xy 289.260175 -97.597696) (xy 289.315018 -97.587566) (xy 289.370752 -97.585529) (xy 289.426189 -97.591629)
			(xy 289.480146 -97.605735) (xy 289.531475 -97.627547) (xy 289.579081 -97.656601) (xy 289.621949 -97.692276)
			(xy 289.659166 -97.733813) (xy 289.689939 -97.780326) (xy 289.713611 -97.830823) (xy 289.729679 -97.88423)
			(xy 289.737799 -97.939406) (xy 289.737973 -97.948961) (xy 312.927994 -97.948961) (xy 312.927994 -97.885039)
			(xy 312.936005 -97.821621) (xy 312.951902 -97.759707) (xy 312.975434 -97.700274) (xy 313.006228 -97.644259)
			(xy 313.043801 -97.592544) (xy 313.087558 -97.545947) (xy 313.136811 -97.505202) (xy 313.190782 -97.470951)
			(xy 313.248621 -97.443734) (xy 313.309414 -97.423981) (xy 313.372204 -97.412003) (xy 313.436 -97.40799)
			(xy 313.499796 -97.412003) (xy 313.517116 -97.415307) (xy 412.241994 -97.415307) (xy 412.241994 -97.351385)
			(xy 412.250005 -97.287967) (xy 412.265902 -97.226053) (xy 412.289434 -97.16662) (xy 412.320228 -97.110605)
			(xy 412.357801 -97.05889) (xy 412.401558 -97.012293) (xy 412.450811 -96.971548) (xy 412.504782 -96.937297)
			(xy 412.562621 -96.91008) (xy 412.623414 -96.890327) (xy 412.686204 -96.878349) (xy 412.75 -96.874336)
			(xy 412.813796 -96.878349) (xy 412.876586 -96.890327) (xy 412.909434 -96.901) (xy 414.272982 -96.901)
			(xy 414.277053 -96.845378) (xy 414.289179 -96.790941) (xy 414.309102 -96.73885) (xy 414.336398 -96.690215)
			(xy 414.370484 -96.646072) (xy 414.410633 -96.607363) (xy 414.455991 -96.574912) (xy 414.505591 -96.549411)
			(xy 414.558375 -96.531404) (xy 414.613218 -96.521274) (xy 414.668952 -96.519237) (xy 414.724389 -96.525337)
			(xy 414.778346 -96.539443) (xy 414.829675 -96.561255) (xy 414.877281 -96.590309) (xy 414.920149 -96.625984)
			(xy 414.957366 -96.667521) (xy 414.988139 -96.714034) (xy 415.011811 -96.764531) (xy 415.027879 -96.817938)
			(xy 415.035999 -96.873114) (xy 415.036508 -96.901) (xy 415.035999 -96.928886) (xy 415.027879 -96.984062)
			(xy 415.011811 -97.037469) (xy 414.988139 -97.087966) (xy 414.957366 -97.134479) (xy 414.920149 -97.176016)
			(xy 414.877281 -97.211691) (xy 414.829675 -97.240745) (xy 414.778346 -97.262557) (xy 414.724389 -97.276663)
			(xy 414.668952 -97.282763) (xy 414.613218 -97.280726) (xy 414.558375 -97.270596) (xy 414.505591 -97.252589)
			(xy 414.455991 -97.227088) (xy 414.410633 -97.194637) (xy 414.370484 -97.155928) (xy 414.336398 -97.111785)
			(xy 414.309102 -97.06315) (xy 414.289179 -97.011059) (xy 414.277053 -96.956622) (xy 414.272982 -96.901)
			(xy 412.909434 -96.901) (xy 412.937379 -96.91008) (xy 412.995218 -96.937297) (xy 413.049189 -96.971548)
			(xy 413.098442 -97.012293) (xy 413.142199 -97.05889) (xy 413.179772 -97.110605) (xy 413.210566 -97.16662)
			(xy 413.234098 -97.226053) (xy 413.249995 -97.287967) (xy 413.258006 -97.351385) (xy 413.258508 -97.383346)
			(xy 413.258006 -97.415307) (xy 413.249995 -97.478725) (xy 413.234098 -97.540639) (xy 413.210566 -97.600072)
			(xy 413.179772 -97.656087) (xy 413.142199 -97.707802) (xy 413.098442 -97.754399) (xy 413.049189 -97.795144)
			(xy 412.995218 -97.829395) (xy 412.937379 -97.856612) (xy 412.876586 -97.876365) (xy 412.813796 -97.888343)
			(xy 412.75 -97.892357) (xy 412.686204 -97.888343) (xy 412.623414 -97.876365) (xy 412.562621 -97.856612)
			(xy 412.504782 -97.829395) (xy 412.450811 -97.795144) (xy 412.401558 -97.754399) (xy 412.357801 -97.707802)
			(xy 412.320228 -97.656087) (xy 412.289434 -97.600072) (xy 412.265902 -97.540639) (xy 412.250005 -97.478725)
			(xy 412.241994 -97.415307) (xy 313.517116 -97.415307) (xy 313.562586 -97.423981) (xy 313.623379 -97.443734)
			(xy 313.681218 -97.470951) (xy 313.735189 -97.505202) (xy 313.784442 -97.545947) (xy 313.828199 -97.592544)
			(xy 313.865772 -97.644259) (xy 313.896566 -97.700274) (xy 313.920098 -97.759707) (xy 313.935995 -97.821621)
			(xy 313.944006 -97.885039) (xy 313.944508 -97.917) (xy 313.944006 -97.948961) (xy 313.935995 -98.012379)
			(xy 313.920098 -98.074293) (xy 313.896566 -98.133726) (xy 313.865772 -98.189741) (xy 313.828199 -98.241456)
			(xy 313.784442 -98.288053) (xy 313.735189 -98.328798) (xy 313.681218 -98.363049) (xy 313.623379 -98.390266)
			(xy 313.562586 -98.410019) (xy 313.499796 -98.421997) (xy 313.436 -98.426011) (xy 313.372204 -98.421997)
			(xy 313.309414 -98.410019) (xy 313.248621 -98.390266) (xy 313.190782 -98.363049) (xy 313.136811 -98.328798)
			(xy 313.087558 -98.288053) (xy 313.043801 -98.241456) (xy 313.006228 -98.189741) (xy 312.975434 -98.133726)
			(xy 312.951902 -98.074293) (xy 312.936005 -98.012379) (xy 312.927994 -97.948961) (xy 289.737973 -97.948961)
			(xy 289.738308 -97.967292) (xy 289.737799 -97.995178) (xy 289.729679 -98.050354) (xy 289.713611 -98.103761)
			(xy 289.689939 -98.154258) (xy 289.659166 -98.200771) (xy 289.621949 -98.242308) (xy 289.579081 -98.277983)
			(xy 289.531475 -98.307037) (xy 289.480146 -98.328849) (xy 289.426189 -98.342955) (xy 289.370752 -98.349055)
			(xy 289.315018 -98.347018) (xy 289.260175 -98.336888) (xy 289.207391 -98.318881) (xy 289.157791 -98.29338)
			(xy 289.112433 -98.260929) (xy 289.072284 -98.22222) (xy 289.038198 -98.178077) (xy 289.010902 -98.129442)
			(xy 288.990979 -98.077351) (xy 288.978853 -98.022914) (xy 288.974782 -97.967292) (xy 268.584459 -97.967292)
			(xy 268.580382 -97.995533) (xy 268.564892 -98.048046) (xy 268.542055 -98.097806) (xy 268.512338 -98.14379)
			(xy 268.476352 -98.185053) (xy 268.455902 -98.203258) (xy 268.447163 -98.211654) (xy 268.438026 -98.234068)
			(xy 268.438376 -98.246184) (xy 268.445234 -98.328226) (xy 268.446938 -98.34015) (xy 268.459662 -98.360562)
			(xy 268.469618 -98.367342) (xy 268.497349 -98.384687) (xy 268.548589 -98.425341) (xy 268.594193 -98.47223)
			(xy 268.614943 -98.49993) (xy 272.350738 -98.49993) (xy 272.35124 -98.467969) (xy 272.359251 -98.404551)
			(xy 272.375148 -98.342637) (xy 272.39868 -98.283204) (xy 272.429474 -98.227189) (xy 272.467047 -98.175474)
			(xy 272.510804 -98.128877) (xy 272.560057 -98.088132) (xy 272.614028 -98.053881) (xy 272.671867 -98.026664)
			(xy 272.73266 -98.006911) (xy 272.79545 -97.994933) (xy 272.859246 -97.99092) (xy 272.923042 -97.994933)
			(xy 272.985832 -98.006911) (xy 273.046625 -98.026664) (xy 273.104464 -98.053881) (xy 273.158435 -98.088132)
			(xy 273.207688 -98.128877) (xy 273.251445 -98.175474) (xy 273.289018 -98.227189) (xy 273.319812 -98.283204)
			(xy 273.343344 -98.342637) (xy 273.359241 -98.404551) (xy 273.367252 -98.467969) (xy 273.367754 -98.49993)
			(xy 273.367266 -98.531705) (xy 273.359344 -98.594759) (xy 273.343628 -98.656335) (xy 273.320362 -98.715473)
			(xy 273.28991 -98.771251) (xy 273.252744 -98.822801) (xy 273.209446 -98.869318) (xy 273.185382 -98.890074)
			(xy 273.176486 -98.898396) (xy 273.167066 -98.920821) (xy 273.167348 -98.933) (xy 273.17446 -99.027488)
			(xy 273.18716 -99.048316) (xy 273.197828 -99.054666) (xy 273.226138 -99.072814) (xy 273.276474 -99.117397)
			(xy 273.297904 -99.143312) (xy 273.306259 -99.152799) (xy 273.329462 -99.162773) (xy 273.3421 -99.162362)
			(xy 273.439382 -99.15398) (xy 273.460718 -99.14001) (xy 273.466814 -99.12858) (xy 273.481682 -99.10215)
			(xy 273.516771 -99.05269) (xy 273.557494 -99.007755) (xy 273.603273 -98.967982) (xy 273.653457 -98.933936)
			(xy 273.707334 -98.906101) (xy 273.764139 -98.884871) (xy 273.823066 -98.870548) (xy 273.883279 -98.863335)
			(xy 273.9136 -98.862896) (xy 273.945561 -98.86339) (xy 274.00898 -98.871402) (xy 274.070894 -98.887298)
			(xy 274.130328 -98.91083) (xy 274.186344 -98.941625) (xy 274.203081 -98.953785) (xy 319.44538 -98.953785)
			(xy 319.44538 -98.889863) (xy 319.453391 -98.826445) (xy 319.469288 -98.764531) (xy 319.49282 -98.705098)
			(xy 319.523614 -98.649083) (xy 319.561187 -98.597368) (xy 319.604944 -98.550771) (xy 319.654197 -98.510026)
			(xy 319.708168 -98.475775) (xy 319.766007 -98.448558) (xy 319.8268 -98.428805) (xy 319.88959 -98.416827)
			(xy 319.953386 -98.412814) (xy 320.017182 -98.416827) (xy 320.079972 -98.428805) (xy 320.140765 -98.448558)
			(xy 320.198604 -98.475775) (xy 320.252575 -98.510026) (xy 320.301828 -98.550771) (xy 320.345585 -98.597368)
			(xy 320.383158 -98.649083) (xy 320.413952 -98.705098) (xy 320.437484 -98.764531) (xy 320.453381 -98.826445)
			(xy 320.461392 -98.889863) (xy 320.461894 -98.921824) (xy 320.461475 -98.9485) (xy 328.552762 -98.9485)
			(xy 328.556777 -98.884699) (xy 328.568756 -98.821903) (xy 328.588511 -98.761105) (xy 328.615731 -98.703262)
			(xy 328.649986 -98.649287) (xy 328.690736 -98.600031) (xy 328.737339 -98.556271) (xy 328.789058 -98.518696)
			(xy 328.845079 -98.487901) (xy 328.904519 -98.46437) (xy 328.966438 -98.448475) (xy 329.029862 -98.440465)
			(xy 329.061826 -98.439986) (xy 329.094099 -98.440496) (xy 329.158125 -98.448671) (xy 329.220602 -98.464885)
			(xy 329.280523 -98.488878) (xy 329.336924 -98.520264) (xy 329.388899 -98.558538) (xy 329.4126 -98.580448)
			(xy 329.420523 -98.587329) (xy 329.440206 -98.594542) (xy 329.4507 -98.594418) (xy 329.535536 -98.589592)
			(xy 329.554332 -98.57994) (xy 329.560936 -98.571812) (xy 329.581686 -98.547521) (xy 329.628284 -98.503816)
			(xy 329.679989 -98.466291) (xy 329.735986 -98.435537) (xy 329.795394 -98.412037) (xy 329.857277 -98.396162)
			(xy 329.920661 -98.388162) (xy 329.952604 -98.387662) (xy 329.983515 -98.388125) (xy 330.044881 -98.395627)
			(xy 330.104886 -98.410507) (xy 330.162647 -98.432545) (xy 330.217312 -98.461419) (xy 330.268078 -98.496701)
			(xy 330.29144 -98.516948) (xy 330.298044 -98.523044) (xy 330.315824 -98.529902) (xy 330.402184 -98.529902)
			(xy 330.419964 -98.523044) (xy 330.426568 -98.516948) (xy 330.449929 -98.4967) (xy 330.500693 -98.461416)
			(xy 330.555358 -98.432543) (xy 330.61312 -98.410508) (xy 330.673127 -98.395635) (xy 330.734493 -98.388143)
			(xy 330.796315 -98.388143) (xy 330.857681 -98.395635) (xy 330.917688 -98.410508) (xy 330.97545 -98.432543)
			(xy 331.030115 -98.461416) (xy 331.080879 -98.4967) (xy 331.10424 -98.516948) (xy 331.110844 -98.523044)
			(xy 331.128624 -98.529902) (xy 331.214984 -98.529902) (xy 331.232764 -98.523044) (xy 331.239368 -98.516948)
			(xy 331.262742 -98.496714) (xy 331.313499 -98.461418) (xy 331.36816 -98.432535) (xy 331.42592 -98.410491)
			(xy 331.485925 -98.395613) (xy 331.547293 -98.388118) (xy 331.578204 -98.387662) (xy 331.610163 -98.388224)
			(xy 331.673577 -98.396236) (xy 331.735487 -98.412132) (xy 331.794916 -98.435662) (xy 331.850928 -98.466455)
			(xy 331.902638 -98.504025) (xy 331.949232 -98.54778) (xy 331.98466 -98.590605) (xy 434.775861 -98.590605)
			(xy 434.779871 -98.526834) (xy 434.791838 -98.464067) (xy 434.811575 -98.403294) (xy 434.838769 -98.345472)
			(xy 434.872993 -98.291513) (xy 434.913708 -98.242266) (xy 434.936646 -98.220022) (xy 434.944266 -98.21291)
			(xy 434.952648 -98.193606) (xy 434.952648 -98.09861) (xy 434.944266 -98.079306) (xy 434.936646 -98.072194)
			(xy 434.913715 -98.049942) (xy 434.873 -98.000696) (xy 434.838775 -97.946737) (xy 434.811579 -97.888916)
			(xy 434.791841 -97.828144) (xy 434.779873 -97.765377) (xy 434.775861 -97.701605) (xy 434.779871 -97.637834)
			(xy 434.791838 -97.575067) (xy 434.811575 -97.514294) (xy 434.838769 -97.456472) (xy 434.872993 -97.402513)
			(xy 434.913708 -97.353266) (xy 434.936646 -97.331022) (xy 434.944266 -97.32391) (xy 434.952648 -97.304606)
			(xy 434.952648 -97.20961) (xy 434.944266 -97.190306) (xy 434.936646 -97.183194) (xy 434.915308 -97.16258)
			(xy 434.877099 -97.117189) (xy 434.84443 -97.06766) (xy 434.817746 -97.014667) (xy 434.797408 -96.958929)
			(xy 434.783694 -96.901203) (xy 434.77679 -96.842274) (xy 434.776372 -96.812608) (xy 434.776864 -96.781878)
			(xy 434.784271 -96.720866) (xy 434.798978 -96.661191) (xy 434.820771 -96.603725) (xy 434.849331 -96.549304)
			(xy 434.884243 -96.498722) (xy 434.924998 -96.452718) (xy 434.971 -96.411961) (xy 435.02158 -96.377046)
			(xy 435.075999 -96.348482) (xy 435.133465 -96.326686) (xy 435.193138 -96.311976) (xy 435.25415 -96.304565)
			(xy 435.28488 -96.3041) (xy 435.314546 -96.304545) (xy 435.373475 -96.311438) (xy 435.431202 -96.325143)
			(xy 435.48694 -96.345476) (xy 435.539933 -96.372159) (xy 435.58946 -96.404829) (xy 435.634846 -96.443042)
			(xy 435.655466 -96.464374) (xy 435.662578 -96.471994) (xy 435.681882 -96.480376) (xy 435.776878 -96.480376)
			(xy 435.796182 -96.471994) (xy 435.803294 -96.464374) (xy 435.82392 -96.443047) (xy 435.869308 -96.404836)
			(xy 435.918834 -96.372165) (xy 435.971825 -96.345479) (xy 436.027562 -96.32514) (xy 436.085286 -96.311425)
			(xy 436.144214 -96.304519) (xy 436.17388 -96.3041) (xy 436.204612 -96.304556) (xy 436.265628 -96.311963)
			(xy 436.325306 -96.32667) (xy 436.382777 -96.348464) (xy 436.437201 -96.377027) (xy 436.487786 -96.411941)
			(xy 436.533793 -96.452699) (xy 436.574551 -96.498705) (xy 436.609467 -96.549289) (xy 436.638031 -96.603712)
			(xy 436.659826 -96.661182) (xy 436.674535 -96.72086) (xy 436.681943 -96.781876) (xy 436.682388 -96.812608)
			(xy 436.681966 -96.842274) (xy 436.67507 -96.901205) (xy 436.66136 -96.958932) (xy 436.641024 -97.014671)
			(xy 436.614338 -97.067664) (xy 436.581664 -97.117189) (xy 436.543447 -97.162575) (xy 436.522114 -97.183194)
			(xy 436.514494 -97.190306) (xy 436.506112 -97.20961) (xy 436.506112 -97.304606) (xy 436.514494 -97.32391)
			(xy 436.522114 -97.331022) (xy 436.545062 -97.353257) (xy 436.585781 -97.402504) (xy 436.616002 -97.450148)
			(xy 437.894982 -97.450148) (xy 437.899053 -97.394526) (xy 437.911179 -97.340089) (xy 437.931102 -97.287998)
			(xy 437.958398 -97.239363) (xy 437.992484 -97.19522) (xy 438.032633 -97.156511) (xy 438.077991 -97.12406)
			(xy 438.127591 -97.098559) (xy 438.180375 -97.080552) (xy 438.235218 -97.070422) (xy 438.290952 -97.068385)
			(xy 438.346389 -97.074485) (xy 438.400346 -97.088591) (xy 438.451675 -97.110403) (xy 438.499281 -97.139457)
			(xy 438.542149 -97.175132) (xy 438.579366 -97.216669) (xy 438.610139 -97.263182) (xy 438.621084 -97.286529)
			(xy 442.564514 -97.286529) (xy 442.564514 -97.222607) (xy 442.572525 -97.159189) (xy 442.588422 -97.097275)
			(xy 442.611954 -97.037842) (xy 442.642748 -96.981827) (xy 442.680321 -96.930112) (xy 442.724078 -96.883515)
			(xy 442.773331 -96.84277) (xy 442.827302 -96.808519) (xy 442.885141 -96.781302) (xy 442.945934 -96.761549)
			(xy 443.008724 -96.749571) (xy 443.07252 -96.745558) (xy 443.136316 -96.749571) (xy 443.199106 -96.761549)
			(xy 443.259899 -96.781302) (xy 443.317738 -96.808519) (xy 443.371709 -96.84277) (xy 443.420962 -96.883515)
			(xy 443.464719 -96.930112) (xy 443.502292 -96.981827) (xy 443.533086 -97.037842) (xy 443.556618 -97.097275)
			(xy 443.572515 -97.159189) (xy 443.580526 -97.222607) (xy 443.581028 -97.254568) (xy 443.580526 -97.286529)
			(xy 443.578601 -97.301769) (xy 449.127874 -97.301769) (xy 449.127874 -97.237847) (xy 449.135885 -97.174429)
			(xy 449.151782 -97.112515) (xy 449.175314 -97.053082) (xy 449.206108 -96.997067) (xy 449.243681 -96.945352)
			(xy 449.287438 -96.898755) (xy 449.336691 -96.85801) (xy 449.390662 -96.823759) (xy 449.448501 -96.796542)
			(xy 449.509294 -96.776789) (xy 449.572084 -96.764811) (xy 449.63588 -96.760798) (xy 449.699676 -96.764811)
			(xy 449.762466 -96.776789) (xy 449.823259 -96.796542) (xy 449.881098 -96.823759) (xy 449.935069 -96.85801)
			(xy 449.984322 -96.898755) (xy 450.028079 -96.945352) (xy 450.065652 -96.997067) (xy 450.096446 -97.053082)
			(xy 450.119978 -97.112515) (xy 450.135875 -97.174429) (xy 450.143886 -97.237847) (xy 450.144388 -97.269808)
			(xy 450.143886 -97.301769) (xy 450.135875 -97.365187) (xy 450.119978 -97.427101) (xy 450.096446 -97.486534)
			(xy 450.065652 -97.542549) (xy 450.028079 -97.594264) (xy 449.984322 -97.640861) (xy 449.935069 -97.681606)
			(xy 449.881098 -97.715857) (xy 449.823259 -97.743074) (xy 449.762466 -97.762827) (xy 449.699676 -97.774805)
			(xy 449.63588 -97.778819) (xy 449.572084 -97.774805) (xy 449.509294 -97.762827) (xy 449.448501 -97.743074)
			(xy 449.390662 -97.715857) (xy 449.336691 -97.681606) (xy 449.287438 -97.640861) (xy 449.243681 -97.594264)
			(xy 449.206108 -97.542549) (xy 449.175314 -97.486534) (xy 449.151782 -97.427101) (xy 449.135885 -97.365187)
			(xy 449.127874 -97.301769) (xy 443.578601 -97.301769) (xy 443.572515 -97.349947) (xy 443.556618 -97.411861)
			(xy 443.533086 -97.471294) (xy 443.502292 -97.527309) (xy 443.464719 -97.579024) (xy 443.420962 -97.625621)
			(xy 443.371709 -97.666366) (xy 443.317738 -97.700617) (xy 443.259899 -97.727834) (xy 443.199106 -97.747587)
			(xy 443.136316 -97.759565) (xy 443.07252 -97.763579) (xy 443.008724 -97.759565) (xy 442.945934 -97.747587)
			(xy 442.885141 -97.727834) (xy 442.827302 -97.700617) (xy 442.773331 -97.666366) (xy 442.724078 -97.625621)
			(xy 442.680321 -97.579024) (xy 442.642748 -97.527309) (xy 442.611954 -97.471294) (xy 442.588422 -97.411861)
			(xy 442.572525 -97.349947) (xy 442.564514 -97.286529) (xy 438.621084 -97.286529) (xy 438.633811 -97.313679)
			(xy 438.649879 -97.367086) (xy 438.657999 -97.422262) (xy 438.658508 -97.450148) (xy 438.657999 -97.478034)
			(xy 438.649879 -97.53321) (xy 438.633811 -97.586617) (xy 438.610139 -97.637114) (xy 438.579366 -97.683627)
			(xy 438.542149 -97.725164) (xy 438.499281 -97.760839) (xy 438.451675 -97.789893) (xy 438.400346 -97.811705)
			(xy 438.346389 -97.825811) (xy 438.290952 -97.831911) (xy 438.235218 -97.829874) (xy 438.180375 -97.819744)
			(xy 438.127591 -97.801737) (xy 438.077991 -97.776236) (xy 438.032633 -97.743785) (xy 437.992484 -97.705076)
			(xy 437.958398 -97.660933) (xy 437.931102 -97.612298) (xy 437.911179 -97.560207) (xy 437.899053 -97.50577)
			(xy 437.894982 -97.450148) (xy 436.616002 -97.450148) (xy 436.620008 -97.456464) (xy 436.647206 -97.514287)
			(xy 436.666944 -97.575062) (xy 436.678913 -97.637831) (xy 436.682923 -97.701605) (xy 436.678911 -97.765379)
			(xy 436.666941 -97.828148) (xy 436.647202 -97.888923) (xy 436.643693 -97.896383) (xy 456.16596 -97.896383)
			(xy 456.16596 -97.832461) (xy 456.173971 -97.769043) (xy 456.189868 -97.707129) (xy 456.2134 -97.647696)
			(xy 456.244194 -97.591681) (xy 456.281767 -97.539966) (xy 456.325524 -97.493369) (xy 456.374777 -97.452624)
			(xy 456.428748 -97.418373) (xy 456.486587 -97.391156) (xy 456.54738 -97.371403) (xy 456.61017 -97.359425)
			(xy 456.673966 -97.355412) (xy 456.737762 -97.359425) (xy 456.800552 -97.371403) (xy 456.861345 -97.391156)
			(xy 456.919184 -97.418373) (xy 456.973155 -97.452624) (xy 457.022408 -97.493369) (xy 457.066165 -97.539966)
			(xy 457.103738 -97.591681) (xy 457.134532 -97.647696) (xy 457.158064 -97.707129) (xy 457.173961 -97.769043)
			(xy 457.181972 -97.832461) (xy 457.182474 -97.864422) (xy 457.561948 -97.864422) (xy 457.566019 -97.8088)
			(xy 457.578145 -97.754363) (xy 457.598068 -97.702272) (xy 457.625364 -97.653637) (xy 457.65945 -97.609494)
			(xy 457.699599 -97.570785) (xy 457.744957 -97.538334) (xy 457.794557 -97.512833) (xy 457.847341 -97.494826)
			(xy 457.902184 -97.484696) (xy 457.957918 -97.482659) (xy 458.013355 -97.488759) (xy 458.067312 -97.502865)
			(xy 458.118641 -97.524677) (xy 458.166247 -97.553731) (xy 458.209115 -97.589406) (xy 458.246332 -97.630943)
			(xy 458.277105 -97.677456) (xy 458.300777 -97.727953) (xy 458.316845 -97.78136) (xy 458.324965 -97.836536)
			(xy 458.325474 -97.864422) (xy 458.324965 -97.892308) (xy 458.316845 -97.947484) (xy 458.300777 -98.000891)
			(xy 458.277105 -98.051388) (xy 458.246332 -98.097901) (xy 458.209115 -98.139438) (xy 458.166247 -98.175113)
			(xy 458.118641 -98.204167) (xy 458.067312 -98.225979) (xy 458.013355 -98.240085) (xy 457.957918 -98.246185)
			(xy 457.902184 -98.244148) (xy 457.847341 -98.234018) (xy 457.794557 -98.216011) (xy 457.744957 -98.19051)
			(xy 457.699599 -98.158059) (xy 457.65945 -98.11935) (xy 457.625364 -98.075207) (xy 457.598068 -98.026572)
			(xy 457.578145 -97.974481) (xy 457.566019 -97.920044) (xy 457.561948 -97.864422) (xy 457.182474 -97.864422)
			(xy 457.181972 -97.896383) (xy 457.173961 -97.959801) (xy 457.158064 -98.021715) (xy 457.134532 -98.081148)
			(xy 457.103738 -98.137163) (xy 457.066165 -98.188878) (xy 457.022408 -98.235475) (xy 456.973155 -98.27622)
			(xy 456.919184 -98.310471) (xy 456.861345 -98.337688) (xy 456.800552 -98.357441) (xy 456.737762 -98.369419)
			(xy 456.673966 -98.373433) (xy 456.61017 -98.369419) (xy 456.54738 -98.357441) (xy 456.486587 -98.337688)
			(xy 456.428748 -98.310471) (xy 456.374777 -98.27622) (xy 456.325524 -98.235475) (xy 456.281767 -98.188878)
			(xy 456.244194 -98.137163) (xy 456.2134 -98.081148) (xy 456.189868 -98.021715) (xy 456.173971 -97.959801)
			(xy 456.16596 -97.896383) (xy 436.643693 -97.896383) (xy 436.620003 -97.946746) (xy 436.585774 -98.000705)
			(xy 436.545055 -98.049951) (xy 436.522114 -98.072194) (xy 436.514494 -98.079306) (xy 436.506112 -98.09861)
			(xy 436.506112 -98.193606) (xy 436.514494 -98.21291) (xy 436.522114 -98.220022) (xy 436.545062 -98.242257)
			(xy 436.585781 -98.291504) (xy 436.620008 -98.345464) (xy 436.647206 -98.403287) (xy 436.666944 -98.464062)
			(xy 436.678913 -98.526831) (xy 436.68131 -98.564954) (xy 462.064606 -98.564954) (xy 462.068677 -98.509332)
			(xy 462.080803 -98.454895) (xy 462.100726 -98.402804) (xy 462.128022 -98.354169) (xy 462.162108 -98.310026)
			(xy 462.202257 -98.271317) (xy 462.247615 -98.238866) (xy 462.297215 -98.213365) (xy 462.349999 -98.195358)
			(xy 462.404842 -98.185228) (xy 462.460576 -98.183191) (xy 462.516013 -98.189291) (xy 462.56997 -98.203397)
			(xy 462.621299 -98.225209) (xy 462.668905 -98.254263) (xy 462.711773 -98.289938) (xy 462.74899 -98.331475)
			(xy 462.779763 -98.377988) (xy 462.803435 -98.428485) (xy 462.819503 -98.481892) (xy 462.827623 -98.537068)
			(xy 462.828132 -98.564954) (xy 462.827623 -98.59284) (xy 462.819503 -98.648016) (xy 462.803435 -98.701423)
			(xy 462.779763 -98.75192) (xy 462.74899 -98.798433) (xy 462.711773 -98.83997) (xy 462.668905 -98.875645)
			(xy 462.621299 -98.904699) (xy 462.56997 -98.926511) (xy 462.516013 -98.940617) (xy 462.460576 -98.946717)
			(xy 462.404842 -98.94468) (xy 462.349999 -98.93455) (xy 462.297215 -98.916543) (xy 462.247615 -98.891042)
			(xy 462.202257 -98.858591) (xy 462.162108 -98.819882) (xy 462.128022 -98.775739) (xy 462.100726 -98.727104)
			(xy 462.080803 -98.675013) (xy 462.068677 -98.620576) (xy 462.064606 -98.564954) (xy 436.68131 -98.564954)
			(xy 436.682923 -98.590605) (xy 436.678911 -98.654379) (xy 436.666941 -98.717148) (xy 436.647202 -98.777923)
			(xy 436.620003 -98.835746) (xy 436.585774 -98.889705) (xy 436.545055 -98.938951) (xy 436.522114 -98.961194)
			(xy 436.514494 -98.968306) (xy 436.506112 -98.98761) (xy 436.506112 -99.082606) (xy 436.514494 -99.10191)
			(xy 436.522114 -99.109022) (xy 436.543452 -99.129636) (xy 436.581663 -99.175026) (xy 436.614333 -99.224555)
			(xy 436.641017 -99.277548) (xy 436.661354 -99.333286) (xy 436.675068 -99.391012) (xy 436.681971 -99.449942)
			(xy 436.682388 -99.479608) (xy 436.68197 -99.510341) (xy 436.67456 -99.571359) (xy 436.659849 -99.631039)
			(xy 436.638051 -99.68851) (xy 436.609486 -99.742935) (xy 436.574568 -99.79352) (xy 436.533807 -99.839527)
			(xy 436.487798 -99.880285) (xy 436.437211 -99.9152) (xy 436.382784 -99.943763) (xy 436.325312 -99.965557)
			(xy 436.265631 -99.980265) (xy 436.204613 -99.987672) (xy 436.17388 -99.988116) (xy 436.144214 -99.987693)
			(xy 436.085283 -99.980796) (xy 436.027557 -99.967086) (xy 435.971818 -99.94675) (xy 435.918826 -99.920064)
			(xy 435.8693 -99.887391) (xy 435.823914 -99.849175) (xy 435.803294 -99.827842) (xy 435.796182 -99.820222)
			(xy 435.776878 -99.81184) (xy 435.681882 -99.81184) (xy 435.662578 -99.820222) (xy 435.655466 -99.827842)
			(xy 435.634863 -99.849191) (xy 435.58947 -99.8874) (xy 435.53994 -99.920068) (xy 435.486945 -99.946751)
			(xy 435.431205 -99.967086) (xy 435.373477 -99.980798) (xy 435.314547 -99.987699) (xy 435.28488 -99.988116)
			(xy 435.254149 -99.987663) (xy 435.193135 -99.980252) (xy 435.133459 -99.965541) (xy 435.075992 -99.943745)
			(xy 435.02157 -99.915181) (xy 434.970988 -99.880265) (xy 434.924984 -99.839508) (xy 434.884227 -99.793502)
			(xy 434.849313 -99.74292) (xy 434.82075 -99.688497) (xy 434.798955 -99.631029) (xy 434.784246 -99.571353)
			(xy 434.776837 -99.510339) (xy 434.776372 -99.479608) (xy 434.776818 -99.449942) (xy 434.783711 -99.391013)
			(xy 434.797418 -99.333287) (xy 434.81775 -99.277549) (xy 434.844433 -99.224556) (xy 434.877102 -99.175029)
			(xy 434.915315 -99.129642) (xy 434.936646 -99.109022) (xy 434.944266 -99.10191) (xy 434.952648 -99.082606)
			(xy 434.952648 -98.98761) (xy 434.944266 -98.968306) (xy 434.936646 -98.961194) (xy 434.913715 -98.938942)
			(xy 434.873 -98.889696) (xy 434.838775 -98.835737) (xy 434.811579 -98.777916) (xy 434.791841 -98.717144)
			(xy 434.779873 -98.654377) (xy 434.775861 -98.590605) (xy 331.98466 -98.590605) (xy 331.989975 -98.59703)
			(xy 332.024224 -98.650998) (xy 332.051438 -98.708833) (xy 332.07119 -98.769622) (xy 332.083167 -98.832408)
			(xy 332.087181 -98.8962) (xy 332.083167 -98.959992) (xy 332.07119 -99.022778) (xy 332.051438 -99.083567)
			(xy 332.024224 -99.141402) (xy 331.989975 -99.19537) (xy 331.949232 -99.24462) (xy 331.902638 -99.288375)
			(xy 331.850928 -99.325945) (xy 331.794916 -99.356738) (xy 331.735487 -99.380268) (xy 331.673577 -99.396164)
			(xy 331.610163 -99.404176) (xy 331.578204 -99.404678) (xy 331.547293 -99.4042) (xy 331.485929 -99.3967)
			(xy 331.425924 -99.381822) (xy 331.368164 -99.359786) (xy 331.313498 -99.330916) (xy 331.262731 -99.295637)
			(xy 331.239368 -99.275392) (xy 331.232764 -99.269296) (xy 331.214984 -99.262438) (xy 331.128624 -99.262438)
			(xy 331.110844 -99.269296) (xy 331.10424 -99.275392) (xy 331.080879 -99.29564) (xy 331.030115 -99.330924)
			(xy 330.97545 -99.359797) (xy 330.917688 -99.381832) (xy 330.857681 -99.396705) (xy 330.796315 -99.404197)
			(xy 330.734493 -99.404197) (xy 330.673127 -99.396705) (xy 330.61312 -99.381832) (xy 330.555358 -99.359797)
			(xy 330.500693 -99.330924) (xy 330.449929 -99.29564) (xy 330.426568 -99.275392) (xy 330.419964 -99.269296)
			(xy 330.402184 -99.262438) (xy 330.315824 -99.262438) (xy 330.298044 -99.269296) (xy 330.29144 -99.275392)
			(xy 330.268068 -99.295628) (xy 330.21731 -99.330923) (xy 330.162649 -99.359805) (xy 330.104889 -99.381848)
			(xy 330.044883 -99.396727) (xy 329.983516 -99.404221) (xy 329.952604 -99.404678) (xy 329.920331 -99.404159)
			(xy 329.856305 -99.395987) (xy 329.793828 -99.379775) (xy 329.733907 -99.355784) (xy 329.677505 -99.324399)
			(xy 329.625531 -99.286126) (xy 329.60183 -99.264216) (xy 329.5939 -99.257345) (xy 329.574222 -99.250128)
			(xy 329.56373 -99.250246) (xy 329.478894 -99.255072) (xy 329.460098 -99.264724) (xy 329.453494 -99.272852)
			(xy 329.432743 -99.297142) (xy 329.386143 -99.340844) (xy 329.334438 -99.378368) (xy 329.278441 -99.409121)
			(xy 329.219034 -99.432621) (xy 329.157152 -99.448498) (xy 329.093769 -99.4565) (xy 329.061826 -99.457002)
			(xy 329.029862 -99.456535) (xy 328.966438 -99.448525) (xy 328.904519 -99.43263) (xy 328.845079 -99.409099)
			(xy 328.789058 -99.378304) (xy 328.737339 -99.340729) (xy 328.690736 -99.296969) (xy 328.649986 -99.247713)
			(xy 328.615731 -99.193738) (xy 328.588511 -99.135895) (xy 328.568756 -99.075097) (xy 328.556777 -99.012301)
			(xy 328.552762 -98.9485) (xy 320.461475 -98.9485) (xy 320.461392 -98.953785) (xy 320.453381 -99.017203)
			(xy 320.437484 -99.079117) (xy 320.413952 -99.13855) (xy 320.383158 -99.194565) (xy 320.345585 -99.24628)
			(xy 320.301828 -99.292877) (xy 320.252575 -99.333622) (xy 320.198604 -99.367873) (xy 320.140765 -99.39509)
			(xy 320.079972 -99.414843) (xy 320.017182 -99.426821) (xy 319.953386 -99.430835) (xy 319.88959 -99.426821)
			(xy 319.8268 -99.414843) (xy 319.766007 -99.39509) (xy 319.708168 -99.367873) (xy 319.654197 -99.333622)
			(xy 319.604944 -99.292877) (xy 319.561187 -99.24628) (xy 319.523614 -99.194565) (xy 319.49282 -99.13855)
			(xy 319.469288 -99.079117) (xy 319.453391 -99.017203) (xy 319.44538 -98.953785) (xy 274.203081 -98.953785)
			(xy 274.238058 -98.979198) (xy 274.284656 -99.022956) (xy 274.325401 -99.072209) (xy 274.359653 -99.12618)
			(xy 274.38687 -99.184019) (xy 274.406623 -99.244813) (xy 274.418601 -99.307604) (xy 274.422615 -99.3714)
			(xy 274.418601 -99.435196) (xy 274.406623 -99.497987) (xy 274.38687 -99.558781) (xy 274.359653 -99.61662)
			(xy 274.325401 -99.670591) (xy 274.284656 -99.719844) (xy 274.238058 -99.763602) (xy 274.186344 -99.801175)
			(xy 274.130328 -99.83197) (xy 274.070894 -99.855502) (xy 274.00898 -99.871398) (xy 273.945561 -99.87941)
			(xy 273.9136 -99.879912) (xy 273.880115 -99.879413) (xy 273.813726 -99.870615) (xy 273.749065 -99.853184)
			(xy 273.687248 -99.827422) (xy 273.629346 -99.793773) (xy 273.576358 -99.75282) (xy 273.529199 -99.70527)
			(xy 273.488686 -99.651944) (xy 273.47164 -99.623118) (xy 273.46529 -99.611942) (xy 273.4437 -99.598226)
			(xy 273.333464 -99.591114) (xy 273.310604 -99.601274) (xy 273.30273 -99.611688) (xy 273.284581 -99.634652)
			(xy 273.242422 -99.675252) (xy 273.194557 -99.708938) (xy 273.142109 -99.734919) (xy 273.086309 -99.752586)
			(xy 273.028465 -99.761524) (xy 272.9992 -99.762056) (xy 272.971951 -99.761522) (xy 272.918007 -99.753767)
			(xy 272.865716 -99.738414) (xy 272.816142 -99.715777) (xy 272.770294 -99.686315) (xy 272.729105 -99.650629)
			(xy 272.693414 -99.609444) (xy 272.663946 -99.5636) (xy 272.641302 -99.514029) (xy 272.625943 -99.46174)
			(xy 272.618181 -99.407797) (xy 272.617692 -99.380548) (xy 272.618134 -99.35352) (xy 272.625777 -99.300005)
			(xy 272.64089 -99.248104) (xy 272.663169 -99.198851) (xy 272.69217 -99.153232) (xy 272.709386 -99.13239)
			(xy 272.716776 -99.122735) (xy 272.722484 -99.099139) (xy 272.720308 -99.087178) (xy 272.700496 -99.006914)
			(xy 272.696939 -98.995408) (xy 272.681164 -98.977251) (xy 272.67027 -98.972116) (xy 272.670016 -98.971862)
			(xy 272.639004 -98.958878) (xy 272.580437 -98.925861) (xy 272.526734 -98.885413) (xy 272.47883 -98.838239)
			(xy 272.437563 -98.785162) (xy 272.403652 -98.727108) (xy 272.37769 -98.665091) (xy 272.360129 -98.600193)
			(xy 272.351276 -98.533546) (xy 272.350738 -98.49993) (xy 268.614943 -98.49993) (xy 268.633408 -98.524579)
			(xy 268.665589 -98.581523) (xy 268.690202 -98.642124) (xy 268.706842 -98.70538) (xy 268.715235 -98.770248)
			(xy 268.715744 -98.802952) (xy 268.715242 -98.834913) (xy 268.707231 -98.898331) (xy 268.691334 -98.960245)
			(xy 268.678588 -98.992436) (xy 271.10004 -98.992436) (xy 271.104111 -98.936814) (xy 271.116237 -98.882377)
			(xy 271.13616 -98.830286) (xy 271.163456 -98.781651) (xy 271.197542 -98.737508) (xy 271.237691 -98.698799)
			(xy 271.283049 -98.666348) (xy 271.332649 -98.640847) (xy 271.385433 -98.62284) (xy 271.440276 -98.61271)
			(xy 271.49601 -98.610673) (xy 271.551447 -98.616773) (xy 271.605404 -98.630879) (xy 271.656733 -98.652691)
			(xy 271.704339 -98.681745) (xy 271.747207 -98.71742) (xy 271.784424 -98.758957) (xy 271.815197 -98.80547)
			(xy 271.838869 -98.855967) (xy 271.854937 -98.909374) (xy 271.863057 -98.96455) (xy 271.863566 -98.992436)
			(xy 271.863057 -99.020322) (xy 271.854937 -99.075498) (xy 271.838869 -99.128905) (xy 271.815197 -99.179402)
			(xy 271.784424 -99.225915) (xy 271.747207 -99.267452) (xy 271.704339 -99.303127) (xy 271.656733 -99.332181)
			(xy 271.605404 -99.353993) (xy 271.551447 -99.368099) (xy 271.49601 -99.374199) (xy 271.440276 -99.372162)
			(xy 271.385433 -99.362032) (xy 271.332649 -99.344025) (xy 271.283049 -99.318524) (xy 271.237691 -99.286073)
			(xy 271.197542 -99.247364) (xy 271.163456 -99.203221) (xy 271.13616 -99.154586) (xy 271.116237 -99.102495)
			(xy 271.104111 -99.048058) (xy 271.10004 -98.992436) (xy 268.678588 -98.992436) (xy 268.667802 -99.019678)
			(xy 268.637008 -99.075693) (xy 268.599435 -99.127408) (xy 268.555678 -99.174005) (xy 268.506425 -99.21475)
			(xy 268.452454 -99.249001) (xy 268.394615 -99.276218) (xy 268.333822 -99.295971) (xy 268.271032 -99.307949)
			(xy 268.207236 -99.311963) (xy 268.14344 -99.307949) (xy 268.08065 -99.295971) (xy 268.019857 -99.276218)
			(xy 267.962018 -99.249001) (xy 267.908047 -99.21475) (xy 267.858794 -99.174005) (xy 267.815037 -99.127408)
			(xy 267.777464 -99.075693) (xy 267.74667 -99.019678) (xy 267.723138 -98.960245) (xy 267.707241 -98.898331)
			(xy 267.69923 -98.834913) (xy 267.698728 -98.802952) (xy 251.636734 -98.802952) (xy 251.636981 -98.803792)
			(xy 251.644739 -98.857746) (xy 251.644739 -98.912254) (xy 251.636981 -98.966208) (xy 251.621623 -99.018508)
			(xy 251.598977 -99.068091) (xy 251.569506 -99.113945) (xy 251.533808 -99.155138) (xy 251.492611 -99.190831)
			(xy 251.446754 -99.220298) (xy 251.397169 -99.242937) (xy 251.344867 -99.25829) (xy 251.290912 -99.266042)
			(xy 251.263658 -99.266502) (xy 251.235362 -99.265941) (xy 251.179392 -99.257582) (xy 251.125268 -99.241055)
			(xy 251.074176 -99.216721) (xy 251.027235 -99.185113) (xy 250.985472 -99.146922) (xy 250.96724 -99.125278)
			(xy 250.95801 -99.114619) (xy 250.934956 -99.098406) (xy 250.908343 -99.089124) (xy 250.880206 -99.087484)
			(xy 250.852696 -99.093611) (xy 250.827914 -99.107037) (xy 250.807756 -99.126735) (xy 250.800362 -99.13874)
			(xy 250.783319 -99.167392) (xy 250.742779 -99.220318) (xy 250.695671 -99.267494) (xy 250.642804 -99.308111)
			(xy 250.585082 -99.341472) (xy 250.523497 -99.367005) (xy 250.459104 -99.384274) (xy 250.393006 -99.392981)
			(xy 250.359672 -99.393502) (xy 250.327712 -99.39301) (xy 250.264296 -99.384996) (xy 250.202384 -99.369097)
			(xy 250.142953 -99.345563) (xy 250.08694 -99.314767) (xy 250.035229 -99.277194) (xy 249.988634 -99.233436)
			(xy 249.94789 -99.184183) (xy 249.913641 -99.130213) (xy 249.886426 -99.072375) (xy 249.866674 -99.011583)
			(xy 249.854697 -98.948794) (xy 249.850683 -98.885) (xy 249.423381 -98.885) (xy 249.394449 -98.908934)
			(xy 249.340478 -98.943185) (xy 249.282639 -98.970402) (xy 249.221846 -98.990155) (xy 249.159056 -99.002133)
			(xy 249.09526 -99.006147) (xy 249.031464 -99.002133) (xy 248.968674 -98.990155) (xy 248.907881 -98.970402)
			(xy 248.850042 -98.943185) (xy 248.796071 -98.908934) (xy 248.746818 -98.868189) (xy 248.703061 -98.821592)
			(xy 248.665488 -98.769877) (xy 248.634694 -98.713862) (xy 248.611162 -98.654429) (xy 248.595265 -98.592515)
			(xy 248.587254 -98.529097) (xy 241.123653 -98.529097) (xy 241.117577 -98.536442) (xy 241.070982 -98.580201)
			(xy 241.01927 -98.617775) (xy 240.963256 -98.648572) (xy 240.903824 -98.672106) (xy 240.841912 -98.688007)
			(xy 240.778495 -98.696022) (xy 240.746534 -98.696526) (xy 240.714733 -98.695998) (xy 240.651626 -98.688081)
			(xy 240.59 -98.672354) (xy 240.530817 -98.649063) (xy 240.475001 -98.618571) (xy 240.423425 -98.581355)
			(xy 240.376893 -98.537997) (xy 240.356136 -98.5139) (xy 240.34877 -98.505264) (xy 240.32845 -98.495612)
			(xy 240.22685 -98.496374) (xy 240.20653 -98.506026) (xy 240.199418 -98.514916) (xy 240.178644 -98.539676)
			(xy 240.131903 -98.584315) (xy 240.079883 -98.622671) (xy 240.023422 -98.654127) (xy 239.96343 -98.678175)
			(xy 239.900875 -98.694428) (xy 239.836764 -98.702624) (xy 239.804448 -98.70313) (xy 239.773502 -98.702651)
			(xy 239.712068 -98.695127) (xy 239.652 -98.680207) (xy 239.594184 -98.658113) (xy 239.539475 -98.62917)
			(xy 239.48868 -98.593806) (xy 239.442549 -98.552542) (xy 239.401763 -98.505989) (xy 239.366924 -98.454832)
			(xy 239.352328 -98.42754) (xy 239.345978 -98.415094) (xy 239.323118 -98.400616) (xy 239.22101 -98.396552)
			(xy 239.21207 -98.396551) (xy 239.195038 -98.401932) (xy 239.180876 -98.412819) (xy 239.175798 -98.420174)
			(xy 239.175798 -98.420428) (xy 239.158308 -98.447491) (xy 239.117588 -98.497431) (xy 239.070885 -98.541827)
			(xy 239.018947 -98.579967) (xy 238.962608 -98.611241) (xy 238.90277 -98.635147) (xy 238.840391 -98.651303)
			(xy 238.776471 -98.65945) (xy 238.744252 -98.65995) (xy 238.712296 -98.659361) (xy 238.648887 -98.651345)
			(xy 238.586984 -98.635446) (xy 238.52756 -98.611914) (xy 238.471555 -98.58112) (xy 238.419851 -98.54355)
			(xy 238.373262 -98.499796) (xy 238.332525 -98.450549) (xy 238.29828 -98.396584) (xy 238.271069 -98.338753)
			(xy 238.25132 -98.277968) (xy 238.239344 -98.215187) (xy 238.235331 -98.1514) (xy 237.589497 -98.1514)
			(xy 237.589066 -98.178831) (xy 237.581055 -98.242249) (xy 237.565158 -98.304163) (xy 237.541626 -98.363596)
			(xy 237.510832 -98.419611) (xy 237.473259 -98.471326) (xy 237.429502 -98.517923) (xy 237.380249 -98.558668)
			(xy 237.326278 -98.592919) (xy 237.268439 -98.620136) (xy 237.207646 -98.639889) (xy 237.144856 -98.651867)
			(xy 237.08106 -98.655881) (xy 237.017264 -98.651867) (xy 236.954474 -98.639889) (xy 236.893681 -98.620136)
			(xy 236.835842 -98.592919) (xy 236.781871 -98.558668) (xy 236.732618 -98.517923) (xy 236.688861 -98.471326)
			(xy 236.651288 -98.419611) (xy 236.620494 -98.363596) (xy 236.596962 -98.304163) (xy 236.581065 -98.242249)
			(xy 236.573054 -98.178831) (xy 206.385231 -98.178831) (xy 206.403675 -98.19418) (xy 206.440892 -98.235717)
			(xy 206.471665 -98.28223) (xy 206.495337 -98.332727) (xy 206.511405 -98.386134) (xy 206.519525 -98.44131)
			(xy 206.520034 -98.469196) (xy 206.519525 -98.497082) (xy 206.511405 -98.552258) (xy 206.495337 -98.605665)
			(xy 206.471665 -98.656162) (xy 206.440892 -98.702675) (xy 206.403675 -98.744212) (xy 206.360807 -98.779887)
			(xy 206.313201 -98.808941) (xy 206.261872 -98.830753) (xy 206.207915 -98.844859) (xy 206.152478 -98.850959)
			(xy 206.096744 -98.848922) (xy 206.041901 -98.838792) (xy 205.989117 -98.820785) (xy 205.939517 -98.795284)
			(xy 205.894159 -98.762833) (xy 205.85401 -98.724124) (xy 205.819924 -98.679981) (xy 205.792628 -98.631346)
			(xy 205.772705 -98.579255) (xy 205.760579 -98.524818) (xy 205.756508 -98.469196) (xy 196.42935 -98.469196)
			(xy 196.401212 -98.523899) (xy 196.365243 -98.576445) (xy 196.322996 -98.624089) (xy 196.27513 -98.666085)
			(xy 196.249036 -98.684334) (xy 196.245994 -98.686444) (xy 196.240511 -98.691419) (xy 196.238114 -98.69424)
			(xy 196.228208 -98.706432) (xy 196.225767 -98.711698) (xy 196.223073 -98.722984) (xy 196.222874 -98.728784)
			(xy 196.222874 -98.813112) (xy 196.224398 -98.825812) (xy 196.227099 -98.834821) (xy 196.238068 -98.850081)
			(xy 196.245734 -98.85553) (xy 196.264911 -98.868596) (xy 196.301036 -98.897725) (xy 196.31787 -98.913696)
			(xy 196.331202 -98.926851) (xy 196.356117 -98.954821) (xy 196.367654 -98.969576) (xy 196.368416 -98.970592)
			(xy 196.37121 -98.974148) (xy 196.379338 -98.981006) (xy 196.40423 -98.993706) (xy 196.409657 -98.99629)
			(xy 196.421336 -98.999117) (xy 196.427344 -98.999294) (xy 196.485256 -98.999294) (xy 196.491265 -98.999126)
			(xy 196.502947 -98.996301) (xy 196.50837 -98.993706) (xy 196.533262 -98.981006) (xy 196.54139 -98.974148)
			(xy 196.544184 -98.970592) (xy 196.544946 -98.969576) (xy 196.565625 -98.943448) (xy 196.612715 -98.896305)
			(xy 196.665561 -98.855717) (xy 196.723256 -98.82238) (xy 196.784811 -98.796866) (xy 196.849172 -98.779613)
			(xy 196.915235 -98.770915) (xy 196.948552 -98.77044) (xy 196.980513 -98.770918) (xy 197.043932 -98.778924)
			(xy 197.105848 -98.794816) (xy 197.165283 -98.818343) (xy 197.221301 -98.849135) (xy 197.273018 -98.886704)
			(xy 197.319617 -98.93046) (xy 197.360365 -98.979711) (xy 197.394618 -99.033682) (xy 197.421837 -99.09152)
			(xy 197.441591 -99.152314) (xy 197.445349 -99.172014) (xy 213.45093 -99.172014) (xy 213.455001 -99.116392)
			(xy 213.467127 -99.061955) (xy 213.48705 -99.009864) (xy 213.514346 -98.961229) (xy 213.548432 -98.917086)
			(xy 213.588581 -98.878377) (xy 213.633939 -98.845926) (xy 213.683539 -98.820425) (xy 213.736323 -98.802418)
			(xy 213.791166 -98.792288) (xy 213.8469 -98.790251) (xy 213.902337 -98.796351) (xy 213.956294 -98.810457)
			(xy 214.007623 -98.832269) (xy 214.055229 -98.861323) (xy 214.098097 -98.896998) (xy 214.135314 -98.938535)
			(xy 214.166087 -98.985048) (xy 214.189759 -99.035545) (xy 214.205827 -99.088952) (xy 214.213947 -99.144128)
			(xy 214.214456 -99.172014) (xy 214.213947 -99.1999) (xy 214.205827 -99.255076) (xy 214.189759 -99.308483)
			(xy 214.166087 -99.35898) (xy 214.135314 -99.405493) (xy 214.098097 -99.44703) (xy 214.055229 -99.482705)
			(xy 214.007623 -99.511759) (xy 213.956294 -99.533571) (xy 213.902337 -99.547677) (xy 213.8469 -99.553777)
			(xy 213.791166 -99.55174) (xy 213.736323 -99.54161) (xy 213.683539 -99.523603) (xy 213.633939 -99.498102)
			(xy 213.588581 -99.465651) (xy 213.548432 -99.426942) (xy 213.514346 -99.382799) (xy 213.48705 -99.334164)
			(xy 213.467127 -99.282073) (xy 213.455001 -99.227636) (xy 213.45093 -99.172014) (xy 197.445349 -99.172014)
			(xy 197.45357 -99.215104) (xy 197.457584 -99.2789) (xy 197.45357 -99.342696) (xy 197.441591 -99.405486)
			(xy 197.421837 -99.46628) (xy 197.394618 -99.524118) (xy 197.360365 -99.578089) (xy 197.319617 -99.62734)
			(xy 197.273018 -99.671096) (xy 197.221301 -99.708665) (xy 197.165283 -99.739457) (xy 197.105848 -99.762984)
			(xy 197.043932 -99.778876) (xy 196.980513 -99.786882) (xy 196.948552 -99.787456) (xy 196.915238 -99.786931)
			(xy 196.849182 -99.778226) (xy 196.784828 -99.760971) (xy 196.723278 -99.735462) (xy 196.665584 -99.702135)
			(xy 196.612736 -99.661561) (xy 196.565638 -99.614434) (xy 196.544946 -99.58832) (xy 196.544184 -99.587304)
			(xy 196.54139 -99.583748) (xy 196.533262 -99.57689) (xy 196.50837 -99.56419) (xy 196.502943 -99.561606)
			(xy 196.491264 -99.55878) (xy 196.485256 -99.558602) (xy 196.427344 -99.558602) (xy 196.421335 -99.55877)
			(xy 196.409653 -99.561595) (xy 196.40423 -99.56419) (xy 196.379338 -99.57689) (xy 196.37121 -99.583748)
			(xy 196.368416 -99.587304) (xy 196.367654 -99.58832) (xy 196.346975 -99.614448) (xy 196.299885 -99.661592)
			(xy 196.24704 -99.70218) (xy 196.189345 -99.735517) (xy 196.127789 -99.761031) (xy 196.063428 -99.778285)
			(xy 195.997365 -99.786983) (xy 195.964048 -99.787456) (xy 195.933672 -99.787017) (xy 195.873351 -99.779788)
			(xy 195.81432 -99.765426) (xy 195.75742 -99.744136) (xy 195.70346 -99.716221) (xy 195.653209 -99.682079)
			(xy 195.607381 -99.642196) (xy 195.56663 -99.597138) (xy 195.548758 -99.572572) (xy 195.540884 -99.563682)
			(xy 195.531486 -99.555554) (xy 195.522088 -99.54895) (xy 195.508118 -99.541584) (xy 195.503292 -99.539173)
			(xy 195.492917 -99.536223) (xy 195.487544 -99.535742) (xy 195.424552 -99.535742) (xy 195.421504 -99.535742)
			(xy 195.416131 -99.536227) (xy 195.405756 -99.539173) (xy 195.40093 -99.541584) (xy 195.38696 -99.54895)
			(xy 195.377562 -99.555554) (xy 195.368164 -99.563682) (xy 195.36029 -99.572572) (xy 195.342384 -99.597112)
			(xy 195.301637 -99.642169) (xy 195.255815 -99.682054) (xy 195.205568 -99.716197) (xy 195.151613 -99.744115)
			(xy 195.094718 -99.765408) (xy 195.035692 -99.779774) (xy 194.975375 -99.787008) (xy 194.945 -99.787456)
			(xy 194.914268 -99.786992) (xy 194.853252 -99.779584) (xy 194.793574 -99.764876) (xy 194.736103 -99.743081)
			(xy 194.681678 -99.714519) (xy 194.631093 -99.679605) (xy 194.585085 -99.638849) (xy 194.544324 -99.592845)
			(xy 194.509406 -99.542263) (xy 194.480838 -99.487841) (xy 194.459039 -99.430372) (xy 194.444324 -99.370695)
			(xy 194.43691 -99.30968) (xy 194.436492 -99.278948) (xy 194.436572 -99.266226) (xy 194.437844 -99.240814)
			(xy 194.439032 -99.228148) (xy 194.442688 -99.196516) (xy 194.456878 -99.134439) (xy 194.478706 -99.074619)
			(xy 194.507832 -99.017992) (xy 194.543799 -98.965444) (xy 194.586044 -98.917797) (xy 194.633907 -98.875796)
			(xy 194.660012 -98.857562) (xy 194.663056 -98.855454) (xy 194.668543 -98.850483) (xy 194.670934 -98.847656)
			(xy 194.68084 -98.835464) (xy 194.683278 -98.830198) (xy 194.685969 -98.818912) (xy 194.686174 -98.813112)
			(xy 194.686174 -98.728784) (xy 194.68465 -98.716084) (xy 194.681951 -98.707073) (xy 194.670988 -98.691806)
			(xy 194.663314 -98.686366) (xy 194.635609 -98.667279) (xy 194.584999 -98.62295) (xy 194.540677 -98.572334)
			(xy 194.521582 -98.544634) (xy 194.516057 -98.537048) (xy 194.500813 -98.526129) (xy 194.491864 -98.523298)
			(xy 194.479164 -98.521774) (xy 194.394836 -98.521774) (xy 194.382136 -98.523298) (xy 194.373123 -98.525992)
			(xy 194.35785 -98.536953) (xy 194.352418 -98.544634) (xy 194.334697 -98.570414) (xy 194.293924 -98.617859)
			(xy 194.247638 -98.659943) (xy 194.196537 -98.69603) (xy 194.141394 -98.725574) (xy 194.083044 -98.748128)
			(xy 194.022366 -98.763352) (xy 193.960279 -98.771016) (xy 193.929 -98.771456) (xy 193.897526 -98.770986)
			(xy 193.835059 -98.763221) (xy 193.774027 -98.747811) (xy 193.715362 -98.724991) (xy 193.659959 -98.695109)
			(xy 193.608666 -98.658621) (xy 193.562264 -98.616085) (xy 193.521464 -98.56815) (xy 193.503804 -98.542094)
			(xy 193.498183 -98.53523) (xy 193.48338 -98.525471) (xy 193.474848 -98.523044) (xy 193.463164 -98.521774)
			(xy 193.378836 -98.521774) (xy 193.366136 -98.523298) (xy 193.357123 -98.525992) (xy 193.34185 -98.536953)
			(xy 193.336418 -98.544634) (xy 193.31905 -98.56991) (xy 193.279191 -98.616519) (xy 193.256916 -98.637598)
			(xy 193.244221 -98.649043) (xy 193.21753 -98.670399) (xy 193.203576 -98.68027) (xy 193.197734 -98.685604)
			(xy 193.192838 -98.691187) (xy 193.186252 -98.704487) (xy 193.18478 -98.711766) (xy 193.18478 -98.712274)
			(xy 193.184018 -98.720402) (xy 193.184018 -98.80346) (xy 193.184526 -98.81108) (xy 193.186554 -98.821219)
			(xy 193.197439 -98.838776) (xy 193.205608 -98.845116) (xy 193.230256 -98.862989) (xy 193.275525 -98.903705)
			(xy 193.315603 -98.949539) (xy 193.349918 -98.999834) (xy 193.377976 -99.053869) (xy 193.399375 -99.11087)
			(xy 193.41381 -99.17002) (xy 193.421072 -99.230471) (xy 193.421508 -99.260914) (xy 193.421043 -99.291644)
			(xy 193.413633 -99.352657) (xy 193.398923 -99.412332) (xy 193.377128 -99.469798) (xy 193.348564 -99.524219)
			(xy 193.31365 -99.574799) (xy 193.272893 -99.620803) (xy 193.226888 -99.661558) (xy 193.176307 -99.696472)
			(xy 193.121885 -99.725033) (xy 193.064418 -99.746827) (xy 193.004743 -99.761536) (xy 192.94373 -99.768944)
			(xy 192.913 -99.769422) (xy 192.882285 -99.768959) (xy 192.821302 -99.761557) (xy 192.761656 -99.74686)
			(xy 192.704215 -99.725084) (xy 192.649816 -99.696545) (xy 192.599253 -99.66166) (xy 192.553261 -99.620936)
			(xy 192.512512 -99.574966) (xy 192.494662 -99.549966) (xy 192.492122 -99.54641) (xy 192.488671 -99.542469)
			(xy 192.480474 -99.535949) (xy 192.475866 -99.533456) (xy 192.475612 -99.533456) (xy 192.470278 -99.530662)
			(xy 192.459356 -99.527868) (xy 192.363344 -99.529392) (xy 192.358864 -99.529918) (xy 192.350176 -99.532345)
			(xy 192.346072 -99.534218) (xy 192.33261 -99.541838) (xy 192.3288 -99.54768) (xy 192.325498 -99.553014)
			(xy 192.30791 -99.579575) (xy 192.267135 -99.62852) (xy 192.220567 -99.671991) (xy 192.168936 -99.709306)
			(xy 192.113048 -99.739882) (xy 192.05378 -99.763239) (xy 191.99206 -99.779013) (xy 191.928852 -99.786955)
			(xy 191.897 -99.787456) (xy 191.865526 -99.786986) (xy 191.803059 -99.779221) (xy 191.742027 -99.763811)
			(xy 191.683362 -99.740991) (xy 191.627959 -99.711109) (xy 191.576666 -99.674621) (xy 191.530264 -99.632085)
			(xy 191.489464 -99.58415) (xy 191.471804 -99.558094) (xy 191.466183 -99.55123) (xy 191.45138 -99.541471)
			(xy 191.442848 -99.539044) (xy 191.431164 -99.537774) (xy 191.346836 -99.537774) (xy 191.334136 -99.539298)
			(xy 191.325123 -99.541992) (xy 191.30985 -99.552953) (xy 191.304418 -99.560634) (xy 191.286697 -99.586414)
			(xy 191.245924 -99.633859) (xy 191.199638 -99.675943) (xy 191.148537 -99.71203) (xy 191.093394 -99.741574)
			(xy 191.035044 -99.764128) (xy 190.974366 -99.779352) (xy 190.912279 -99.787016) (xy 190.881 -99.787456)
			(xy 190.849526 -99.786986) (xy 190.787059 -99.779221) (xy 190.726027 -99.763811) (xy 190.667362 -99.740991)
			(xy 190.611959 -99.711109) (xy 190.560666 -99.674621) (xy 190.514264 -99.632085) (xy 190.473464 -99.58415)
			(xy 190.455804 -99.558094) (xy 190.450183 -99.55123) (xy 190.43538 -99.541471) (xy 190.426848 -99.539044)
			(xy 190.415164 -99.537774) (xy 190.330836 -99.537774) (xy 190.318136 -99.539298) (xy 190.309123 -99.541992)
			(xy 190.29385 -99.552953) (xy 190.288418 -99.560634) (xy 190.270697 -99.586414) (xy 190.229924 -99.633859)
			(xy 190.183638 -99.675943) (xy 190.132537 -99.71203) (xy 190.077394 -99.741574) (xy 190.019044 -99.764128)
			(xy 189.958366 -99.779352) (xy 189.896279 -99.787016) (xy 189.865 -99.787456) (xy 189.833526 -99.786986)
			(xy 189.771059 -99.779221) (xy 189.710027 -99.763811) (xy 189.651362 -99.740991) (xy 189.595959 -99.711109)
			(xy 189.544666 -99.674621) (xy 189.498264 -99.632085) (xy 189.457464 -99.58415) (xy 189.439804 -99.558094)
			(xy 189.434183 -99.55123) (xy 189.41938 -99.541471) (xy 189.410848 -99.539044) (xy 189.399164 -99.537774)
			(xy 189.314836 -99.537774) (xy 189.302136 -99.539298) (xy 189.293123 -99.541992) (xy 189.27785 -99.552953)
			(xy 189.272418 -99.560634) (xy 189.254697 -99.586414) (xy 189.213924 -99.633859) (xy 189.167638 -99.675943)
			(xy 189.116537 -99.71203) (xy 189.061394 -99.741574) (xy 189.003044 -99.764128) (xy 188.942366 -99.779352)
			(xy 188.880279 -99.787016) (xy 188.849 -99.787456) (xy 188.848746 -99.787456) (xy 188.816151 -99.786957)
			(xy 188.75149 -99.778669) (xy 188.688419 -99.762183) (xy 188.627972 -99.737772) (xy 188.571141 -99.705835)
			(xy 188.518859 -99.666896) (xy 188.471982 -99.621593) (xy 188.451236 -99.596448) (xy 188.444124 -99.589082)
			(xy 188.435488 -99.58197) (xy 188.42736 -99.576382) (xy 188.414914 -99.570032) (xy 188.411866 -99.568508)
			(xy 188.406439 -99.565924) (xy 188.39476 -99.563097) (xy 188.388752 -99.56292) (xy 188.331856 -99.56292)
			(xy 188.325846 -99.563087) (xy 188.314164 -99.56591) (xy 188.308742 -99.568508) (xy 188.305694 -99.570032)
			(xy 188.293248 -99.576382) (xy 188.28512 -99.58197) (xy 188.276484 -99.589082) (xy 188.269372 -99.596448)
			(xy 188.248607 -99.621575) (xy 188.201721 -99.666864) (xy 188.149437 -99.705796) (xy 188.092611 -99.737733)
			(xy 188.032172 -99.762154) (xy 187.969109 -99.778659) (xy 187.904455 -99.786977) (xy 187.871862 -99.787456)
			(xy 187.871608 -99.787456) (xy 187.838176 -99.786926) (xy 187.771889 -99.778164) (xy 187.707323 -99.760788)
			(xy 187.645591 -99.735099) (xy 187.587759 -99.701541) (xy 187.560966 -99.681538) (xy 187.536957 -99.662462)
			(xy 187.493237 -99.619462) (xy 187.455015 -99.57151) (xy 187.438538 -99.545648) (xy 187.438538 -99.54514)
			(xy 187.438284 -99.54514) (xy 187.435318 -99.54058) (xy 187.42776 -99.532758) (xy 187.423298 -99.529646)
			(xy 187.419488 -99.52736) (xy 187.417456 -99.526344) (xy 187.400184 -99.516438) (xy 187.394307 -99.513293)
			(xy 187.381445 -99.509813) (xy 187.374784 -99.50958) (xy 187.313824 -99.50958) (xy 187.307155 -99.509771)
			(xy 187.294278 -99.51324) (xy 187.288424 -99.516438) (xy 187.271152 -99.526344) (xy 187.26912 -99.52736)
			(xy 187.26531 -99.529646) (xy 187.260871 -99.532785) (xy 187.253313 -99.540598) (xy 187.250324 -99.54514)
			(xy 187.25007 -99.545394) (xy 187.232654 -99.572722) (xy 187.191953 -99.62315) (xy 187.145177 -99.667999)
			(xy 187.093082 -99.706544) (xy 187.036514 -99.738159) (xy 186.976388 -99.762334) (xy 186.913679 -99.778675)
			(xy 186.849402 -99.786919) (xy 186.817 -99.787456) (xy 186.786268 -99.786992) (xy 186.725252 -99.779584)
			(xy 186.665574 -99.764876) (xy 186.608103 -99.743081) (xy 186.553678 -99.714519) (xy 186.503093 -99.679605)
			(xy 186.457085 -99.638849) (xy 186.416324 -99.592845) (xy 186.381406 -99.542263) (xy 186.352838 -99.487841)
			(xy 186.331039 -99.430372) (xy 186.316324 -99.370695) (xy 186.30891 -99.30968) (xy 186.308492 -99.278948)
			(xy 186.308572 -99.266226) (xy 186.309844 -99.240814) (xy 186.311032 -99.228148) (xy 186.314688 -99.196516)
			(xy 186.328878 -99.134439) (xy 186.350706 -99.074619) (xy 186.379832 -99.017992) (xy 186.415799 -98.965444)
			(xy 186.458044 -98.917797) (xy 186.505907 -98.875796) (xy 186.532012 -98.857562) (xy 186.535056 -98.855454)
			(xy 186.540543 -98.850483) (xy 186.542934 -98.847656) (xy 186.55284 -98.835464) (xy 186.555278 -98.830198)
			(xy 186.557969 -98.818912) (xy 186.558174 -98.813112) (xy 186.558174 -98.728784) (xy 186.55665 -98.716084)
			(xy 186.553951 -98.707073) (xy 186.542988 -98.691806) (xy 186.535314 -98.686366) (xy 186.507609 -98.667279)
			(xy 186.456999 -98.62295) (xy 186.412677 -98.572334) (xy 186.393582 -98.544634) (xy 186.388057 -98.537048)
			(xy 186.372813 -98.526129) (xy 186.363864 -98.523298) (xy 186.351164 -98.521774) (xy 186.266836 -98.521774)
			(xy 186.254136 -98.523298) (xy 186.245123 -98.525992) (xy 186.22985 -98.536953) (xy 186.224418 -98.544634)
			(xy 186.206697 -98.570414) (xy 186.165924 -98.617859) (xy 186.119638 -98.659943) (xy 186.068537 -98.69603)
			(xy 186.013394 -98.725574) (xy 185.955044 -98.748128) (xy 185.894366 -98.763352) (xy 185.832279 -98.771016)
			(xy 185.801 -98.771456) (xy 185.769526 -98.770986) (xy 185.707059 -98.763221) (xy 185.646027 -98.747811)
			(xy 185.587362 -98.724991) (xy 185.531959 -98.695109) (xy 185.480666 -98.658621) (xy 185.434264 -98.616085)
			(xy 185.393464 -98.56815) (xy 185.375804 -98.542094) (xy 185.370183 -98.53523) (xy 185.35538 -98.525471)
			(xy 185.346848 -98.523044) (xy 185.335164 -98.521774) (xy 185.250836 -98.521774) (xy 185.238136 -98.523298)
			(xy 185.229123 -98.525992) (xy 185.21385 -98.536953) (xy 185.208418 -98.544634) (xy 185.189281 -98.572406)
			(xy 185.14483 -98.62313) (xy 185.094069 -98.667539) (xy 185.037887 -98.704854) (xy 184.977268 -98.734422)
			(xy 184.913275 -98.755723) (xy 184.88025 -98.762566) (xy 184.877456 -98.763074) (xy 184.870048 -98.765127)
			(xy 184.856864 -98.773015) (xy 184.851548 -98.778568) (xy 184.84469 -98.786696) (xy 184.84469 -98.78695)
			(xy 184.841896 -98.794824) (xy 184.840484 -98.799002) (xy 184.838946 -98.807687) (xy 184.838848 -98.812096)
			(xy 184.838848 -98.859848) (xy 184.83923 -98.868205) (xy 184.844672 -98.884015) (xy 184.849516 -98.890836)
			(xy 184.85485 -98.89744) (xy 184.86882 -98.906584) (xy 184.877456 -98.90887) (xy 184.904606 -98.916171)
			(xy 184.956559 -98.937658) (xy 185.004794 -98.96654) (xy 185.048267 -99.002189) (xy 185.086036 -99.043834)
			(xy 185.117282 -99.090572) (xy 185.141328 -99.141391) (xy 185.157654 -99.195189) (xy 185.165905 -99.250801)
			(xy 185.165903 -99.307022) (xy 185.157649 -99.362633) (xy 185.14132 -99.416431) (xy 185.11727 -99.467248)
			(xy 185.086021 -99.513984) (xy 185.04825 -99.555627) (xy 185.004775 -99.591274) (xy 184.956538 -99.620152)
			(xy 184.904584 -99.641637) (xy 184.877456 -99.649026) (xy 184.874916 -99.649788) (xy 184.867495 -99.652279)
			(xy 184.854555 -99.661071) (xy 184.849516 -99.66706) (xy 184.843928 -99.674172) (xy 184.841388 -99.682046)
			(xy 184.840226 -99.68588) (xy 184.838957 -99.693789) (xy 184.838848 -99.697794) (xy 184.838848 -100.705623)
			(xy 198.754486 -100.705623) (xy 198.754486 -100.641701) (xy 198.762497 -100.578283) (xy 198.778394 -100.516369)
			(xy 198.801926 -100.456936) (xy 198.83272 -100.400921) (xy 198.870293 -100.349206) (xy 198.91405 -100.302609)
			(xy 198.963303 -100.261864) (xy 199.017274 -100.227613) (xy 199.075113 -100.200396) (xy 199.135906 -100.180643)
			(xy 199.198696 -100.168665) (xy 199.262492 -100.164652) (xy 199.326288 -100.168665) (xy 199.389078 -100.180643)
			(xy 199.449871 -100.200396) (xy 199.50771 -100.227613) (xy 199.561681 -100.261864) (xy 199.610934 -100.302609)
			(xy 199.654691 -100.349206) (xy 199.692264 -100.400921) (xy 199.723058 -100.456936) (xy 199.735939 -100.489469)
			(xy 204.069944 -100.489469) (xy 204.069944 -100.425547) (xy 204.077955 -100.362129) (xy 204.093852 -100.300215)
			(xy 204.117384 -100.240782) (xy 204.148178 -100.184767) (xy 204.185751 -100.133052) (xy 204.229508 -100.086455)
			(xy 204.278761 -100.04571) (xy 204.332732 -100.011459) (xy 204.390571 -99.984242) (xy 204.451364 -99.964489)
			(xy 204.514154 -99.952511) (xy 204.57795 -99.948498) (xy 204.641746 -99.952511) (xy 204.704536 -99.964489)
			(xy 204.765329 -99.984242) (xy 204.823168 -100.011459) (xy 204.877139 -100.04571) (xy 204.926392 -100.086455)
			(xy 204.970149 -100.133052) (xy 205.007722 -100.184767) (xy 205.032523 -100.229881) (xy 253.319274 -100.229881)
			(xy 253.319274 -100.165959) (xy 253.327285 -100.102541) (xy 253.343182 -100.040627) (xy 253.366714 -99.981194)
			(xy 253.397508 -99.925179) (xy 253.435081 -99.873464) (xy 253.478838 -99.826867) (xy 253.528091 -99.786122)
			(xy 253.582062 -99.751871) (xy 253.639901 -99.724654) (xy 253.700694 -99.704901) (xy 253.763484 -99.692923)
			(xy 253.82728 -99.68891) (xy 253.891076 -99.692923) (xy 253.953866 -99.704901) (xy 254.014659 -99.724654)
			(xy 254.072498 -99.751871) (xy 254.126469 -99.786122) (xy 254.175722 -99.826867) (xy 254.219479 -99.873464)
			(xy 254.257052 -99.925179) (xy 254.287846 -99.981194) (xy 254.311378 -100.040627) (xy 254.327275 -100.102541)
			(xy 254.335286 -100.165959) (xy 254.335788 -100.19792) (xy 254.335286 -100.229881) (xy 254.327275 -100.293299)
			(xy 254.311378 -100.355213) (xy 254.287846 -100.414646) (xy 254.257052 -100.470661) (xy 254.219479 -100.522376)
			(xy 254.175722 -100.568973) (xy 254.126469 -100.609718) (xy 254.084582 -100.6363) (xy 255.208792 -100.6363)
			(xy 255.212806 -100.572504) (xy 255.224784 -100.509715) (xy 255.244537 -100.448921) (xy 255.271754 -100.391083)
			(xy 255.306005 -100.337112) (xy 255.34675 -100.28786) (xy 255.393347 -100.244102) (xy 255.445061 -100.20653)
			(xy 255.501076 -100.175736) (xy 255.56051 -100.152205) (xy 255.622423 -100.136308) (xy 255.685841 -100.128297)
			(xy 255.717802 -100.127816) (xy 255.74766 -100.12821) (xy 255.806965 -100.135208) (xy 255.865041 -100.149109)
			(xy 255.921088 -100.16972) (xy 255.974332 -100.196758) (xy 256.024042 -100.229849) (xy 256.06953 -100.268538)
			(xy 256.090166 -100.290122) (xy 256.096516 -100.29698) (xy 256.112772 -100.305108) (xy 256.188464 -100.312982)
			(xy 256.197678 -100.313538) (xy 256.215517 -100.308859) (xy 256.223262 -100.303838) (xy 256.247514 -100.28742)
			(xy 256.299986 -100.261414) (xy 256.355815 -100.243728) (xy 256.41369 -100.234777) (xy 256.442972 -100.234242)
			(xy 256.47023 -100.234603) (xy 256.524191 -100.242358) (xy 256.576499 -100.257713) (xy 256.626089 -100.280357)
			(xy 256.671952 -100.309828) (xy 256.713153 -100.345527) (xy 256.748855 -100.386726) (xy 256.778329 -100.432586)
			(xy 256.800977 -100.482175) (xy 256.816336 -100.534482) (xy 256.824095 -100.588442) (xy 256.824095 -100.642958)
			(xy 256.816336 -100.696918) (xy 256.800977 -100.749225) (xy 256.778329 -100.798814) (xy 256.748855 -100.844674)
			(xy 256.713153 -100.885873) (xy 256.671952 -100.921572) (xy 256.626089 -100.951043) (xy 256.576499 -100.973687)
			(xy 256.524191 -100.989042) (xy 256.47023 -100.996797) (xy 256.442972 -100.997258) (xy 256.4164 -100.996777)
			(xy 256.36377 -100.98941) (xy 256.312672 -100.974808) (xy 256.264096 -100.953254) (xy 256.241296 -100.9396)
			(xy 256.233332 -100.935039) (xy 256.215357 -100.931397) (xy 256.206244 -100.932488) (xy 256.140204 -100.943156)
			(xy 256.131222 -100.944986) (xy 256.115337 -100.954111) (xy 256.109216 -100.960936) (xy 256.088464 -100.98519)
			(xy 256.048749 -101.022404) (xy 260.660388 -101.022404) (xy 260.660825 -100.995572) (xy 260.668318 -100.942434)
			(xy 260.683186 -100.890872) (xy 260.705134 -100.841902) (xy 260.73373 -100.796492) (xy 260.768408 -100.755539)
			(xy 260.808485 -100.719851) (xy 260.853168 -100.690133) (xy 260.901575 -100.666971) (xy 260.952751 -100.650822)
			(xy 261.005685 -100.642007) (xy 261.032498 -100.640896) (xy 261.046722 -100.640642) (xy 261.070344 -100.625402)
			(xy 261.116318 -100.531168) (xy 261.119968 -100.522619) (xy 261.121582 -100.504119) (xy 261.116481 -100.486264)
			(xy 261.111238 -100.47859) (xy 261.092106 -100.452148) (xy 261.060064 -100.395287) (xy 261.03556 -100.334794)
			(xy 261.018997 -100.271663) (xy 261.010647 -100.206932) (xy 261.010146 -100.174298) (xy 261.010573 -100.143172)
			(xy 261.018192 -100.081386) (xy 261.03329 -100.020992) (xy 261.055642 -99.96289) (xy 261.084916 -99.907948)
			(xy 261.120672 -99.856988) (xy 261.162378 -99.81077) (xy 261.20941 -99.769984) (xy 261.261065 -99.735241)
			(xy 261.316574 -99.707057) (xy 261.34568 -99.696016) (xy 261.35584 -99.69246) (xy 261.37108 -99.678236)
			(xy 261.404354 -99.600258) (xy 261.408022 -99.590479) (xy 261.407874 -99.569613) (xy 261.4041 -99.559872)
			(xy 261.4041 -99.559618) (xy 261.393906 -99.53534) (xy 261.379532 -99.484684) (xy 261.372282 -99.43253)
			(xy 261.371842 -99.406202) (xy 261.371842 -99.405948) (xy 261.372328 -99.378697) (xy 261.380084 -99.324749)
			(xy 261.395439 -99.272454) (xy 261.418081 -99.222877) (xy 261.447547 -99.177027) (xy 261.483238 -99.135836)
			(xy 261.524429 -99.100145) (xy 261.570279 -99.070679) (xy 261.619856 -99.048037) (xy 261.672151 -99.032682)
			(xy 261.726099 -99.024926) (xy 261.780601 -99.024926) (xy 261.834549 -99.032682) (xy 261.886844 -99.048037)
			(xy 261.936421 -99.070679) (xy 261.982271 -99.100145) (xy 262.023462 -99.135836) (xy 262.059153 -99.177027)
			(xy 262.088619 -99.222877) (xy 262.111261 -99.272454) (xy 262.126616 -99.324749) (xy 262.134372 -99.378697)
			(xy 262.134858 -99.405948) (xy 262.13437 -99.433417) (xy 262.126496 -99.487789) (xy 262.110903 -99.540468)
			(xy 262.087914 -99.590365) (xy 262.058004 -99.636448) (xy 262.021793 -99.677764) (xy 261.980029 -99.713457)
			(xy 261.957058 -99.728528) (xy 261.948168 -99.734116) (xy 261.936484 -99.751388) (xy 261.918196 -99.845368)
			(xy 261.923022 -99.865688) (xy 261.929372 -99.874324) (xy 261.947878 -99.900518) (xy 261.978893 -99.956654)
			(xy 262.002596 -100.016248) (xy 262.018608 -100.078352) (xy 262.026676 -100.141977) (xy 262.027162 -100.174044)
			(xy 262.027162 -100.174298) (xy 262.02676 -100.205032) (xy 262.019351 -100.266051) (xy 262.00464 -100.325733)
			(xy 261.982843 -100.383206) (xy 261.954276 -100.437632) (xy 261.919356 -100.488218) (xy 261.878594 -100.534225)
			(xy 261.832583 -100.574984) (xy 261.781994 -100.609898) (xy 261.727565 -100.638461) (xy 261.670091 -100.660253)
			(xy 261.610408 -100.674959) (xy 261.549388 -100.682363) (xy 261.518654 -100.682806) (xy 261.5184 -100.682806)
			(xy 261.50638 -100.682738) (xy 261.482366 -100.681593) (xy 261.470394 -100.68052) (xy 261.45617 -100.678996)
			(xy 261.43077 -100.691442) (xy 261.366254 -100.791518) (xy 261.365636 -100.8146) (xy 271.813321 -100.8146)
			(xy 271.817335 -100.750809) (xy 271.829312 -100.688024) (xy 271.849063 -100.627235) (xy 271.876277 -100.569401)
			(xy 271.910525 -100.515433) (xy 271.951267 -100.466184) (xy 271.997861 -100.422429) (xy 272.04957 -100.384859)
			(xy 272.105581 -100.354066) (xy 272.165009 -100.330535) (xy 272.226918 -100.314639) (xy 272.290331 -100.306626)
			(xy 272.32229 -100.306124) (xy 272.354854 -100.306659) (xy 272.419454 -100.31494) (xy 272.482466 -100.331405)
			(xy 272.542859 -100.355785) (xy 272.599642 -100.387681) (xy 272.626074 -100.406708) (xy 272.634976 -100.412758)
			(xy 272.655959 -100.417458) (xy 272.67702 -100.413121) (xy 272.686018 -100.407216) (xy 272.71206 -100.389097)
			(xy 272.767755 -100.358718) (xy 272.8268 -100.335512) (xy 272.888275 -100.319839) (xy 272.951223 -100.311944)
			(xy 272.982944 -100.311458) (xy 273.014901 -100.312031) (xy 273.078311 -100.320046) (xy 273.140216 -100.335945)
			(xy 273.19964 -100.359478) (xy 273.23611 -100.37953) (xy 274.848064 -100.37953) (xy 274.852135 -100.323908)
			(xy 274.864261 -100.269471) (xy 274.884184 -100.21738) (xy 274.91148 -100.168745) (xy 274.945566 -100.124602)
			(xy 274.985715 -100.085893) (xy 275.031073 -100.053442) (xy 275.080673 -100.027941) (xy 275.133457 -100.009934)
			(xy 275.1883 -99.999804) (xy 275.244034 -99.997767) (xy 275.299471 -100.003867) (xy 275.306096 -100.005599)
			(xy 323.490584 -100.005599) (xy 323.490584 -99.941677) (xy 323.498595 -99.878259) (xy 323.514492 -99.816345)
			(xy 323.538024 -99.756912) (xy 323.568818 -99.700897) (xy 323.606391 -99.649182) (xy 323.650148 -99.602585)
			(xy 323.699401 -99.56184) (xy 323.753372 -99.527589) (xy 323.811211 -99.500372) (xy 323.872004 -99.480619)
			(xy 323.934794 -99.468641) (xy 323.99859 -99.464628) (xy 324.062386 -99.468641) (xy 324.125176 -99.480619)
			(xy 324.185969 -99.500372) (xy 324.243808 -99.527589) (xy 324.297779 -99.56184) (xy 324.347032 -99.602585)
			(xy 324.390789 -99.649182) (xy 324.428362 -99.700897) (xy 324.459156 -99.756912) (xy 324.482688 -99.816345)
			(xy 324.487455 -99.834911) (xy 413.932872 -99.834911) (xy 413.932872 -99.770989) (xy 413.940883 -99.707571)
			(xy 413.95678 -99.645657) (xy 413.980312 -99.586224) (xy 414.011106 -99.530209) (xy 414.048679 -99.478494)
			(xy 414.092436 -99.431897) (xy 414.141689 -99.391152) (xy 414.19566 -99.356901) (xy 414.253499 -99.329684)
			(xy 414.314292 -99.309931) (xy 414.377082 -99.297953) (xy 414.440878 -99.29394) (xy 414.504674 -99.297953)
			(xy 414.567464 -99.309931) (xy 414.628257 -99.329684) (xy 414.686096 -99.356901) (xy 414.740067 -99.391152)
			(xy 414.78932 -99.431897) (xy 414.833077 -99.478494) (xy 414.87065 -99.530209) (xy 414.901444 -99.586224)
			(xy 414.924976 -99.645657) (xy 414.940873 -99.707571) (xy 414.948884 -99.770989) (xy 414.949386 -99.80295)
			(xy 414.948884 -99.834911) (xy 414.940873 -99.898329) (xy 414.924976 -99.960243) (xy 414.901444 -100.019676)
			(xy 414.87065 -100.075691) (xy 414.833077 -100.127406) (xy 414.78932 -100.174003) (xy 414.740067 -100.214748)
			(xy 414.686096 -100.248999) (xy 414.661319 -100.260658) (xy 419.380922 -100.260658) (xy 419.384993 -100.205036)
			(xy 419.397119 -100.150599) (xy 419.417042 -100.098508) (xy 419.444338 -100.049873) (xy 419.478424 -100.00573)
			(xy 419.518573 -99.967021) (xy 419.563931 -99.93457) (xy 419.613531 -99.909069) (xy 419.666315 -99.891062)
			(xy 419.721158 -99.880932) (xy 419.776892 -99.878895) (xy 419.832329 -99.884995) (xy 419.886286 -99.899101)
			(xy 419.937615 -99.920913) (xy 419.985221 -99.949967) (xy 420.028089 -99.985642) (xy 420.065306 -100.027179)
			(xy 420.096079 -100.073692) (xy 420.119751 -100.124189) (xy 420.135819 -100.177596) (xy 420.143939 -100.232772)
			(xy 420.144448 -100.260658) (xy 421.158922 -100.260658) (xy 421.162993 -100.205036) (xy 421.175119 -100.150599)
			(xy 421.195042 -100.098508) (xy 421.222338 -100.049873) (xy 421.256424 -100.00573) (xy 421.296573 -99.967021)
			(xy 421.341931 -99.93457) (xy 421.391531 -99.909069) (xy 421.444315 -99.891062) (xy 421.499158 -99.880932)
			(xy 421.554892 -99.878895) (xy 421.610329 -99.884995) (xy 421.664286 -99.899101) (xy 421.715615 -99.920913)
			(xy 421.763221 -99.949967) (xy 421.806089 -99.985642) (xy 421.843306 -100.027179) (xy 421.874079 -100.073692)
			(xy 421.897751 -100.124189) (xy 421.913819 -100.177596) (xy 421.921939 -100.232772) (xy 421.922448 -100.260658)
			(xy 422.174922 -100.260658) (xy 422.178993 -100.205036) (xy 422.191119 -100.150599) (xy 422.211042 -100.098508)
			(xy 422.238338 -100.049873) (xy 422.272424 -100.00573) (xy 422.312573 -99.967021) (xy 422.357931 -99.93457)
			(xy 422.407531 -99.909069) (xy 422.460315 -99.891062) (xy 422.515158 -99.880932) (xy 422.570892 -99.878895)
			(xy 422.626329 -99.884995) (xy 422.680286 -99.899101) (xy 422.731615 -99.920913) (xy 422.779221 -99.949967)
			(xy 422.822089 -99.985642) (xy 422.859306 -100.027179) (xy 422.890079 -100.073692) (xy 422.913751 -100.124189)
			(xy 422.929819 -100.177596) (xy 422.937939 -100.232772) (xy 422.938448 -100.260658) (xy 422.937939 -100.288544)
			(xy 422.929819 -100.34372) (xy 422.913751 -100.397127) (xy 422.890079 -100.447624) (xy 422.859306 -100.494137)
			(xy 422.822089 -100.535674) (xy 422.779221 -100.571349) (xy 422.731615 -100.600403) (xy 422.680286 -100.622215)
			(xy 422.626329 -100.636321) (xy 422.570892 -100.642421) (xy 422.515158 -100.640384) (xy 422.460315 -100.630254)
			(xy 422.407531 -100.612247) (xy 422.357931 -100.586746) (xy 422.312573 -100.554295) (xy 422.272424 -100.515586)
			(xy 422.238338 -100.471443) (xy 422.211042 -100.422808) (xy 422.191119 -100.370717) (xy 422.178993 -100.31628)
			(xy 422.174922 -100.260658) (xy 421.922448 -100.260658) (xy 421.921939 -100.288544) (xy 421.913819 -100.34372)
			(xy 421.897751 -100.397127) (xy 421.874079 -100.447624) (xy 421.843306 -100.494137) (xy 421.806089 -100.535674)
			(xy 421.763221 -100.571349) (xy 421.715615 -100.600403) (xy 421.664286 -100.622215) (xy 421.610329 -100.636321)
			(xy 421.554892 -100.642421) (xy 421.499158 -100.640384) (xy 421.444315 -100.630254) (xy 421.391531 -100.612247)
			(xy 421.341931 -100.586746) (xy 421.296573 -100.554295) (xy 421.256424 -100.515586) (xy 421.222338 -100.471443)
			(xy 421.195042 -100.422808) (xy 421.175119 -100.370717) (xy 421.162993 -100.31628) (xy 421.158922 -100.260658)
			(xy 420.144448 -100.260658) (xy 420.143939 -100.288544) (xy 420.135819 -100.34372) (xy 420.119751 -100.397127)
			(xy 420.096079 -100.447624) (xy 420.065306 -100.494137) (xy 420.028089 -100.535674) (xy 419.985221 -100.571349)
			(xy 419.937615 -100.600403) (xy 419.886286 -100.622215) (xy 419.832329 -100.636321) (xy 419.776892 -100.642421)
			(xy 419.721158 -100.640384) (xy 419.666315 -100.630254) (xy 419.613531 -100.612247) (xy 419.563931 -100.586746)
			(xy 419.518573 -100.554295) (xy 419.478424 -100.515586) (xy 419.444338 -100.471443) (xy 419.417042 -100.422808)
			(xy 419.397119 -100.370717) (xy 419.384993 -100.31628) (xy 419.380922 -100.260658) (xy 414.661319 -100.260658)
			(xy 414.628257 -100.276216) (xy 414.567464 -100.295969) (xy 414.504674 -100.307947) (xy 414.440878 -100.311961)
			(xy 414.377082 -100.307947) (xy 414.314292 -100.295969) (xy 414.253499 -100.276216) (xy 414.19566 -100.248999)
			(xy 414.141689 -100.214748) (xy 414.092436 -100.174003) (xy 414.048679 -100.127406) (xy 414.011106 -100.075691)
			(xy 413.980312 -100.019676) (xy 413.95678 -99.960243) (xy 413.940883 -99.898329) (xy 413.932872 -99.834911)
			(xy 324.487455 -99.834911) (xy 324.498585 -99.878259) (xy 324.506596 -99.941677) (xy 324.507098 -99.973638)
			(xy 324.506596 -100.005599) (xy 324.498585 -100.069017) (xy 324.482688 -100.130931) (xy 324.459156 -100.190364)
			(xy 324.428362 -100.246379) (xy 324.390789 -100.298094) (xy 324.347032 -100.344691) (xy 324.297779 -100.385436)
			(xy 324.243808 -100.419687) (xy 324.185969 -100.446904) (xy 324.125176 -100.466657) (xy 324.062386 -100.478635)
			(xy 323.99859 -100.482649) (xy 323.934794 -100.478635) (xy 323.872004 -100.466657) (xy 323.811211 -100.446904)
			(xy 323.753372 -100.419687) (xy 323.699401 -100.385436) (xy 323.650148 -100.344691) (xy 323.606391 -100.298094)
			(xy 323.568818 -100.246379) (xy 323.538024 -100.190364) (xy 323.514492 -100.130931) (xy 323.498595 -100.069017)
			(xy 323.490584 -100.005599) (xy 275.306096 -100.005599) (xy 275.353428 -100.017973) (xy 275.404757 -100.039785)
			(xy 275.452363 -100.068839) (xy 275.495231 -100.104514) (xy 275.532448 -100.146051) (xy 275.563221 -100.192564)
			(xy 275.586893 -100.243061) (xy 275.602961 -100.296468) (xy 275.611081 -100.351644) (xy 275.61159 -100.37953)
			(xy 275.611081 -100.407416) (xy 275.60898 -100.421694) (xy 279.51125 -100.421694) (xy 279.515321 -100.366072)
			(xy 279.527447 -100.311635) (xy 279.54737 -100.259544) (xy 279.574666 -100.210909) (xy 279.608752 -100.166766)
			(xy 279.648901 -100.128057) (xy 279.694259 -100.095606) (xy 279.743859 -100.070105) (xy 279.796643 -100.052098)
			(xy 279.851486 -100.041968) (xy 279.90722 -100.039931) (xy 279.962657 -100.046031) (xy 280.016614 -100.060137)
			(xy 280.067943 -100.081949) (xy 280.115549 -100.111003) (xy 280.158417 -100.146678) (xy 280.195634 -100.188215)
			(xy 280.226407 -100.234728) (xy 280.250079 -100.285225) (xy 280.266147 -100.338632) (xy 280.274267 -100.393808)
			(xy 280.274776 -100.421694) (xy 280.274267 -100.44958) (xy 280.266147 -100.504756) (xy 280.250079 -100.558163)
			(xy 280.226407 -100.60866) (xy 280.195634 -100.655173) (xy 280.158417 -100.69671) (xy 280.115549 -100.732385)
			(xy 280.067943 -100.761439) (xy 280.016614 -100.783251) (xy 279.962657 -100.797357) (xy 279.90722 -100.803457)
			(xy 279.851486 -100.80142) (xy 279.796643 -100.79129) (xy 279.743859 -100.773283) (xy 279.694259 -100.747782)
			(xy 279.648901 -100.715331) (xy 279.608752 -100.676622) (xy 279.574666 -100.632479) (xy 279.54737 -100.583844)
			(xy 279.527447 -100.531753) (xy 279.515321 -100.477316) (xy 279.51125 -100.421694) (xy 275.60898 -100.421694)
			(xy 275.602961 -100.462592) (xy 275.586893 -100.515999) (xy 275.563221 -100.566496) (xy 275.532448 -100.613009)
			(xy 275.495231 -100.654546) (xy 275.452363 -100.690221) (xy 275.404757 -100.719275) (xy 275.353428 -100.741087)
			(xy 275.299471 -100.755193) (xy 275.244034 -100.761293) (xy 275.1883 -100.759256) (xy 275.133457 -100.749126)
			(xy 275.080673 -100.731119) (xy 275.031073 -100.705618) (xy 274.985715 -100.673167) (xy 274.945566 -100.634458)
			(xy 274.91148 -100.590315) (xy 274.884184 -100.54168) (xy 274.864261 -100.489589) (xy 274.852135 -100.435152)
			(xy 274.848064 -100.37953) (xy 273.23611 -100.37953) (xy 273.255647 -100.390272) (xy 273.307353 -100.427843)
			(xy 273.353942 -100.471597) (xy 273.394681 -100.520845) (xy 273.428926 -100.574811) (xy 273.456138 -100.632643)
			(xy 273.475888 -100.69343) (xy 273.487864 -100.756212) (xy 273.491877 -100.82) (xy 273.487864 -100.883788)
			(xy 273.475888 -100.94657) (xy 273.456138 -101.007357) (xy 273.428926 -101.065189) (xy 273.394681 -101.119155)
			(xy 273.353942 -101.168403) (xy 273.307353 -101.212157) (xy 273.255647 -101.249728) (xy 273.19964 -101.280522)
			(xy 273.140216 -101.304055) (xy 273.078311 -101.319954) (xy 273.014901 -101.327969) (xy 272.982944 -101.328474)
			(xy 272.950379 -101.327974) (xy 272.885778 -101.319685) (xy 272.822765 -101.303212) (xy 272.762373 -101.278824)
			(xy 272.705591 -101.24692) (xy 272.67916 -101.22789) (xy 272.670243 -101.221861) (xy 272.649269 -101.217143)
			(xy 272.628211 -101.221476) (xy 272.619216 -101.227382) (xy 272.593194 -101.24553) (xy 272.537493 -101.275904)
			(xy 272.478443 -101.299105) (xy 272.416964 -101.314771) (xy 272.354012 -101.322658) (xy 272.32229 -101.32314)
			(xy 272.290331 -101.322574) (xy 272.226918 -101.314561) (xy 272.165009 -101.298665) (xy 272.105581 -101.275134)
			(xy 272.04957 -101.244341) (xy 271.997861 -101.206771) (xy 271.951267 -101.163016) (xy 271.910525 -101.113767)
			(xy 271.876277 -101.059799) (xy 271.849063 -101.001965) (xy 271.829312 -100.941176) (xy 271.817335 -100.878391)
			(xy 271.813321 -100.8146) (xy 261.365636 -100.8146) (xy 261.365492 -100.819966) (xy 261.372604 -100.832158)
			(xy 261.384659 -100.853954) (xy 261.403666 -100.899993) (xy 261.416519 -100.948115) (xy 261.423001 -100.9975)
			(xy 261.423404 -101.022404) (xy 261.422918 -101.049655) (xy 261.415162 -101.103603) (xy 261.399807 -101.155898)
			(xy 261.377165 -101.205475) (xy 261.347699 -101.251325) (xy 261.312008 -101.292516) (xy 261.270817 -101.328207)
			(xy 261.224967 -101.357673) (xy 261.17539 -101.380315) (xy 261.123095 -101.39567) (xy 261.069147 -101.403426)
			(xy 261.014645 -101.403426) (xy 260.960697 -101.39567) (xy 260.908402 -101.380315) (xy 260.858825 -101.357673)
			(xy 260.812975 -101.328207) (xy 260.771784 -101.292516) (xy 260.736093 -101.251325) (xy 260.706627 -101.205475)
			(xy 260.683985 -101.155898) (xy 260.66863 -101.103603) (xy 260.660874 -101.049655) (xy 260.660388 -101.022404)
			(xy 256.048749 -101.022404) (xy 256.041884 -101.028837) (xy 255.990208 -101.066312) (xy 255.934248 -101.097024)
			(xy 255.874884 -101.120491) (xy 255.813051 -101.136343) (xy 255.749719 -101.144333) (xy 255.717802 -101.144832)
			(xy 255.685841 -101.144303) (xy 255.622423 -101.136292) (xy 255.56051 -101.120395) (xy 255.501076 -101.096864)
			(xy 255.445061 -101.06607) (xy 255.393347 -101.028498) (xy 255.34675 -100.98474) (xy 255.306005 -100.935488)
			(xy 255.271754 -100.881517) (xy 255.244537 -100.823679) (xy 255.224784 -100.762885) (xy 255.212806 -100.700096)
			(xy 255.208792 -100.6363) (xy 254.084582 -100.6363) (xy 254.072498 -100.643969) (xy 254.014659 -100.671186)
			(xy 253.953866 -100.690939) (xy 253.891076 -100.702917) (xy 253.82728 -100.706931) (xy 253.763484 -100.702917)
			(xy 253.700694 -100.690939) (xy 253.639901 -100.671186) (xy 253.582062 -100.643969) (xy 253.528091 -100.609718)
			(xy 253.478838 -100.568973) (xy 253.435081 -100.522376) (xy 253.397508 -100.470661) (xy 253.366714 -100.414646)
			(xy 253.343182 -100.355213) (xy 253.327285 -100.293299) (xy 253.319274 -100.229881) (xy 205.032523 -100.229881)
			(xy 205.038516 -100.240782) (xy 205.062048 -100.300215) (xy 205.077945 -100.362129) (xy 205.085956 -100.425547)
			(xy 205.086458 -100.457508) (xy 205.085956 -100.489469) (xy 205.077945 -100.552887) (xy 205.062048 -100.614801)
			(xy 205.038516 -100.674234) (xy 205.007722 -100.730249) (xy 204.970149 -100.781964) (xy 204.926392 -100.828561)
			(xy 204.877139 -100.869306) (xy 204.823168 -100.903557) (xy 204.765329 -100.930774) (xy 204.704536 -100.950527)
			(xy 204.641746 -100.962505) (xy 204.57795 -100.966519) (xy 204.514154 -100.962505) (xy 204.451364 -100.950527)
			(xy 204.390571 -100.930774) (xy 204.332732 -100.903557) (xy 204.278761 -100.869306) (xy 204.229508 -100.828561)
			(xy 204.185751 -100.781964) (xy 204.148178 -100.730249) (xy 204.117384 -100.674234) (xy 204.093852 -100.614801)
			(xy 204.077955 -100.552887) (xy 204.069944 -100.489469) (xy 199.735939 -100.489469) (xy 199.74659 -100.516369)
			(xy 199.762487 -100.578283) (xy 199.770498 -100.641701) (xy 199.771 -100.673662) (xy 199.770498 -100.705623)
			(xy 199.762487 -100.769041) (xy 199.74659 -100.830955) (xy 199.723058 -100.890388) (xy 199.692264 -100.946403)
			(xy 199.654691 -100.998118) (xy 199.610934 -101.044715) (xy 199.561681 -101.08546) (xy 199.50771 -101.119711)
			(xy 199.449871 -101.146928) (xy 199.389078 -101.166681) (xy 199.326288 -101.178659) (xy 199.262492 -101.182673)
			(xy 199.198696 -101.178659) (xy 199.135906 -101.166681) (xy 199.075113 -101.146928) (xy 199.017274 -101.119711)
			(xy 198.963303 -101.08546) (xy 198.91405 -101.044715) (xy 198.870293 -100.998118) (xy 198.83272 -100.946403)
			(xy 198.801926 -100.890388) (xy 198.778394 -100.830955) (xy 198.762497 -100.769041) (xy 198.754486 -100.705623)
			(xy 184.838848 -100.705623) (xy 184.838848 -101.279198) (xy 185.243227 -101.279198) (xy 185.247197 -101.217356)
			(xy 185.259043 -101.156529) (xy 185.27857 -101.097717) (xy 185.305457 -101.041884) (xy 185.339264 -100.989948)
			(xy 185.379434 -100.942762) (xy 185.425309 -100.9011) (xy 185.476135 -100.865646) (xy 185.531077 -100.836983)
			(xy 185.589233 -100.815581) (xy 185.649649 -100.801791) (xy 185.711332 -100.795841) (xy 185.773269 -100.797827)
			(xy 185.834444 -100.807717) (xy 185.893852 -100.82535) (xy 185.950518 -100.850434) (xy 186.003511 -100.882558)
			(xy 186.05196 -100.921195) (xy 186.095071 -100.965711) (xy 186.132136 -101.015374) (xy 186.162545 -101.069369)
			(xy 186.185801 -101.12681) (xy 186.201519 -101.186753) (xy 186.209444 -101.248213) (xy 186.20994 -101.279198)
			(xy 186.209444 -101.310183) (xy 186.201519 -101.371643) (xy 186.185801 -101.431586) (xy 186.173576 -101.461781)
			(xy 186.308994 -101.461781) (xy 186.308994 -101.397859) (xy 186.317005 -101.334441) (xy 186.332902 -101.272527)
			(xy 186.356434 -101.213094) (xy 186.387228 -101.157079) (xy 186.424801 -101.105364) (xy 186.468558 -101.058767)
			(xy 186.517811 -101.018022) (xy 186.571782 -100.983771) (xy 186.629621 -100.956554) (xy 186.690414 -100.936801)
			(xy 186.753204 -100.924823) (xy 186.817 -100.92081) (xy 186.880796 -100.924823) (xy 186.943586 -100.936801)
			(xy 187.004379 -100.956554) (xy 187.062218 -100.983771) (xy 187.116189 -101.018022) (xy 187.165442 -101.058767)
			(xy 187.209199 -101.105364) (xy 187.246772 -101.157079) (xy 187.277566 -101.213094) (xy 187.283625 -101.228398)
			(xy 218.585032 -101.228398) (xy 218.589103 -101.172776) (xy 218.601229 -101.118339) (xy 218.621152 -101.066248)
			(xy 218.648448 -101.017613) (xy 218.682534 -100.97347) (xy 218.722683 -100.934761) (xy 218.768041 -100.90231)
			(xy 218.817641 -100.876809) (xy 218.870425 -100.858802) (xy 218.925268 -100.848672) (xy 218.981002 -100.846635)
			(xy 219.036439 -100.852735) (xy 219.090396 -100.866841) (xy 219.141725 -100.888653) (xy 219.189331 -100.917707)
			(xy 219.232199 -100.953382) (xy 219.269416 -100.994919) (xy 219.300189 -101.041432) (xy 219.323861 -101.091929)
			(xy 219.339929 -101.145336) (xy 219.348049 -101.200512) (xy 219.348558 -101.228398) (xy 219.348049 -101.256284)
			(xy 219.339929 -101.31146) (xy 219.323861 -101.364867) (xy 219.302839 -101.409711) (xy 319.559172 -101.409711)
			(xy 319.559172 -101.345789) (xy 319.567183 -101.282371) (xy 319.58308 -101.220457) (xy 319.606612 -101.161024)
			(xy 319.637406 -101.105009) (xy 319.674979 -101.053294) (xy 319.718736 -101.006697) (xy 319.767989 -100.965952)
			(xy 319.82196 -100.931701) (xy 319.879799 -100.904484) (xy 319.940592 -100.884731) (xy 320.003382 -100.872753)
			(xy 320.067178 -100.86874) (xy 320.130974 -100.872753) (xy 320.193764 -100.884731) (xy 320.254557 -100.904484)
			(xy 320.312396 -100.931701) (xy 320.366367 -100.965952) (xy 320.41562 -101.006697) (xy 320.459377 -101.053294)
			(xy 320.487868 -101.092508) (xy 413.87344 -101.092508) (xy 413.877511 -101.036886) (xy 413.889637 -100.982449)
			(xy 413.90956 -100.930358) (xy 413.936856 -100.881723) (xy 413.970942 -100.83758) (xy 414.011091 -100.798871)
			(xy 414.056449 -100.76642) (xy 414.106049 -100.740919) (xy 414.158833 -100.722912) (xy 414.213676 -100.712782)
			(xy 414.26941 -100.710745) (xy 414.324847 -100.716845) (xy 414.378804 -100.730951) (xy 414.430133 -100.752763)
			(xy 414.477739 -100.781817) (xy 414.520607 -100.817492) (xy 414.557824 -100.859029) (xy 414.588597 -100.905542)
			(xy 414.612269 -100.956039) (xy 414.628337 -101.009446) (xy 414.636457 -101.064622) (xy 414.636966 -101.092508)
			(xy 414.636734 -101.105208) (xy 461.934558 -101.105208) (xy 461.938629 -101.049586) (xy 461.950755 -100.995149)
			(xy 461.970678 -100.943058) (xy 461.997974 -100.894423) (xy 462.03206 -100.85028) (xy 462.072209 -100.811571)
			(xy 462.117567 -100.77912) (xy 462.167167 -100.753619) (xy 462.219951 -100.735612) (xy 462.274794 -100.725482)
			(xy 462.330528 -100.723445) (xy 462.385965 -100.729545) (xy 462.439922 -100.743651) (xy 462.491251 -100.765463)
			(xy 462.538857 -100.794517) (xy 462.581725 -100.830192) (xy 462.618942 -100.871729) (xy 462.649715 -100.918242)
			(xy 462.673387 -100.968739) (xy 462.689455 -101.022146) (xy 462.697575 -101.077322) (xy 462.698084 -101.105208)
			(xy 462.697575 -101.133094) (xy 462.689455 -101.18827) (xy 462.673387 -101.241677) (xy 462.649715 -101.292174)
			(xy 462.618942 -101.338687) (xy 462.581725 -101.380224) (xy 462.538857 -101.415899) (xy 462.491251 -101.444953)
			(xy 462.439922 -101.466765) (xy 462.385965 -101.480871) (xy 462.330528 -101.486971) (xy 462.274794 -101.484934)
			(xy 462.219951 -101.474804) (xy 462.167167 -101.456797) (xy 462.117567 -101.431296) (xy 462.072209 -101.398845)
			(xy 462.03206 -101.360136) (xy 461.997974 -101.315993) (xy 461.970678 -101.267358) (xy 461.950755 -101.215267)
			(xy 461.938629 -101.16083) (xy 461.934558 -101.105208) (xy 414.636734 -101.105208) (xy 414.636457 -101.120394)
			(xy 414.628337 -101.17557) (xy 414.612269 -101.228977) (xy 414.588597 -101.279474) (xy 414.557824 -101.325987)
			(xy 414.520607 -101.367524) (xy 414.477739 -101.403199) (xy 414.430133 -101.432253) (xy 414.378804 -101.454065)
			(xy 414.324847 -101.468171) (xy 414.26941 -101.474271) (xy 414.213676 -101.472234) (xy 414.158833 -101.462104)
			(xy 414.106049 -101.444097) (xy 414.056449 -101.418596) (xy 414.011091 -101.386145) (xy 413.970942 -101.347436)
			(xy 413.936856 -101.303293) (xy 413.90956 -101.254658) (xy 413.889637 -101.202567) (xy 413.877511 -101.14813)
			(xy 413.87344 -101.092508) (xy 320.487868 -101.092508) (xy 320.49695 -101.105009) (xy 320.527744 -101.161024)
			(xy 320.551276 -101.220457) (xy 320.567173 -101.282371) (xy 320.575184 -101.345789) (xy 320.575686 -101.37775)
			(xy 320.575184 -101.409711) (xy 320.567173 -101.473129) (xy 320.560489 -101.499162) (xy 416.746942 -101.499162)
			(xy 416.751013 -101.44354) (xy 416.763139 -101.389103) (xy 416.783062 -101.337012) (xy 416.810358 -101.288377)
			(xy 416.844444 -101.244234) (xy 416.884593 -101.205525) (xy 416.929951 -101.173074) (xy 416.979551 -101.147573)
			(xy 417.032335 -101.129566) (xy 417.087178 -101.119436) (xy 417.142912 -101.117399) (xy 417.198349 -101.123499)
			(xy 417.252306 -101.137605) (xy 417.303635 -101.159417) (xy 417.351241 -101.188471) (xy 417.394109 -101.224146)
			(xy 417.431326 -101.265683) (xy 417.462099 -101.312196) (xy 417.485771 -101.362693) (xy 417.501839 -101.4161)
			(xy 417.509959 -101.471276) (xy 417.510468 -101.499162) (xy 417.509959 -101.527048) (xy 417.501839 -101.582224)
			(xy 417.485771 -101.635631) (xy 417.462099 -101.686128) (xy 417.431326 -101.732641) (xy 417.394109 -101.774178)
			(xy 417.351241 -101.809853) (xy 417.303635 -101.838907) (xy 417.252306 -101.860719) (xy 417.198349 -101.874825)
			(xy 417.142912 -101.880925) (xy 417.087178 -101.878888) (xy 417.032335 -101.868758) (xy 416.979551 -101.850751)
			(xy 416.929951 -101.82525) (xy 416.884593 -101.792799) (xy 416.844444 -101.75409) (xy 416.810358 -101.709947)
			(xy 416.783062 -101.661312) (xy 416.763139 -101.609221) (xy 416.751013 -101.554784) (xy 416.746942 -101.499162)
			(xy 320.560489 -101.499162) (xy 320.551276 -101.535043) (xy 320.527744 -101.594476) (xy 320.49695 -101.650491)
			(xy 320.459377 -101.702206) (xy 320.41562 -101.748803) (xy 320.366367 -101.789548) (xy 320.312396 -101.823799)
			(xy 320.254557 -101.851016) (xy 320.193764 -101.870769) (xy 320.130974 -101.882747) (xy 320.083246 -101.88575)
			(xy 328.11034 -101.88575) (xy 328.114411 -101.830128) (xy 328.126537 -101.775691) (xy 328.14646 -101.7236)
			(xy 328.173756 -101.674965) (xy 328.207842 -101.630822) (xy 328.247991 -101.592113) (xy 328.293349 -101.559662)
			(xy 328.342949 -101.534161) (xy 328.395733 -101.516154) (xy 328.450576 -101.506024) (xy 328.50631 -101.503987)
			(xy 328.561747 -101.510087) (xy 328.615704 -101.524193) (xy 328.667033 -101.546005) (xy 328.714639 -101.575059)
			(xy 328.757507 -101.610734) (xy 328.794724 -101.652271) (xy 328.825497 -101.698784) (xy 328.849169 -101.749281)
			(xy 328.865237 -101.802688) (xy 328.873357 -101.857864) (xy 328.873866 -101.88575) (xy 328.873357 -101.913636)
			(xy 328.865237 -101.968812) (xy 328.849169 -102.022219) (xy 328.825497 -102.072716) (xy 328.794724 -102.119229)
			(xy 328.757507 -102.160766) (xy 328.714639 -102.196441) (xy 328.667033 -102.225495) (xy 328.615704 -102.247307)
			(xy 328.561747 -102.261413) (xy 328.50631 -102.267513) (xy 328.450576 -102.265476) (xy 328.395733 -102.255346)
			(xy 328.342949 -102.237339) (xy 328.293349 -102.211838) (xy 328.247991 -102.179387) (xy 328.207842 -102.140678)
			(xy 328.173756 -102.096535) (xy 328.14646 -102.0479) (xy 328.126537 -101.995809) (xy 328.114411 -101.941372)
			(xy 328.11034 -101.88575) (xy 320.083246 -101.88575) (xy 320.067178 -101.886761) (xy 320.003382 -101.882747)
			(xy 319.940592 -101.870769) (xy 319.879799 -101.851016) (xy 319.82196 -101.823799) (xy 319.767989 -101.789548)
			(xy 319.718736 -101.748803) (xy 319.674979 -101.702206) (xy 319.637406 -101.650491) (xy 319.606612 -101.594476)
			(xy 319.58308 -101.535043) (xy 319.567183 -101.473129) (xy 319.559172 -101.409711) (xy 219.302839 -101.409711)
			(xy 219.300189 -101.415364) (xy 219.269416 -101.461877) (xy 219.232199 -101.503414) (xy 219.189331 -101.539089)
			(xy 219.141725 -101.568143) (xy 219.090396 -101.589955) (xy 219.036439 -101.604061) (xy 218.981002 -101.610161)
			(xy 218.925268 -101.608124) (xy 218.870425 -101.597994) (xy 218.817641 -101.579987) (xy 218.768041 -101.554486)
			(xy 218.722683 -101.522035) (xy 218.682534 -101.483326) (xy 218.648448 -101.439183) (xy 218.621152 -101.390548)
			(xy 218.601229 -101.338457) (xy 218.589103 -101.28402) (xy 218.585032 -101.228398) (xy 187.283625 -101.228398)
			(xy 187.301098 -101.272527) (xy 187.316995 -101.334441) (xy 187.325006 -101.397859) (xy 187.325508 -101.42982)
			(xy 187.325006 -101.461781) (xy 187.316995 -101.525199) (xy 187.301098 -101.587113) (xy 187.277566 -101.646546)
			(xy 187.246772 -101.702561) (xy 187.209199 -101.754276) (xy 187.165442 -101.800873) (xy 187.116189 -101.841618)
			(xy 187.062218 -101.875869) (xy 187.004379 -101.903086) (xy 186.943586 -101.922839) (xy 186.880796 -101.934817)
			(xy 186.817 -101.938831) (xy 186.753204 -101.934817) (xy 186.690414 -101.922839) (xy 186.629621 -101.903086)
			(xy 186.571782 -101.875869) (xy 186.517811 -101.841618) (xy 186.468558 -101.800873) (xy 186.424801 -101.754276)
			(xy 186.387228 -101.702561) (xy 186.356434 -101.646546) (xy 186.332902 -101.587113) (xy 186.317005 -101.525199)
			(xy 186.308994 -101.461781) (xy 186.173576 -101.461781) (xy 186.162545 -101.489027) (xy 186.132136 -101.543022)
			(xy 186.095071 -101.592685) (xy 186.05196 -101.637201) (xy 186.003511 -101.675838) (xy 185.950518 -101.707962)
			(xy 185.893852 -101.733046) (xy 185.834444 -101.750679) (xy 185.773269 -101.760569) (xy 185.711332 -101.762555)
			(xy 185.649649 -101.756605) (xy 185.589233 -101.742815) (xy 185.531077 -101.721413) (xy 185.476135 -101.69275)
			(xy 185.425309 -101.657296) (xy 185.379434 -101.615634) (xy 185.339264 -101.568448) (xy 185.305457 -101.516512)
			(xy 185.27857 -101.460679) (xy 185.259043 -101.401867) (xy 185.247197 -101.34104) (xy 185.243227 -101.279198)
			(xy 184.838848 -101.279198) (xy 184.838848 -102.164853) (xy 192.404994 -102.164853) (xy 192.404994 -102.100931)
			(xy 192.413005 -102.037513) (xy 192.428902 -101.975599) (xy 192.452434 -101.916166) (xy 192.483228 -101.860151)
			(xy 192.520801 -101.808436) (xy 192.564558 -101.761839) (xy 192.613811 -101.721094) (xy 192.667782 -101.686843)
			(xy 192.725621 -101.659626) (xy 192.786414 -101.639873) (xy 192.849204 -101.627895) (xy 192.913 -101.623882)
			(xy 192.976796 -101.627895) (xy 193.039586 -101.639873) (xy 193.100379 -101.659626) (xy 193.158218 -101.686843)
			(xy 193.212189 -101.721094) (xy 193.261442 -101.761839) (xy 193.305199 -101.808436) (xy 193.342772 -101.860151)
			(xy 193.373566 -101.916166) (xy 193.397098 -101.975599) (xy 193.404735 -102.005341) (xy 194.436994 -102.005341)
			(xy 194.436994 -101.941419) (xy 194.445005 -101.878001) (xy 194.460902 -101.816087) (xy 194.484434 -101.756654)
			(xy 194.515228 -101.700639) (xy 194.552801 -101.648924) (xy 194.596558 -101.602327) (xy 194.645811 -101.561582)
			(xy 194.699782 -101.527331) (xy 194.757621 -101.500114) (xy 194.818414 -101.480361) (xy 194.881204 -101.468383)
			(xy 194.945 -101.46437) (xy 195.008796 -101.468383) (xy 195.071586 -101.480361) (xy 195.132379 -101.500114)
			(xy 195.190218 -101.527331) (xy 195.244189 -101.561582) (xy 195.293442 -101.602327) (xy 195.337199 -101.648924)
			(xy 195.374772 -101.700639) (xy 195.405566 -101.756654) (xy 195.429098 -101.816087) (xy 195.444995 -101.878001)
			(xy 195.453006 -101.941419) (xy 195.453508 -101.97338) (xy 195.453006 -102.005341) (xy 195.444995 -102.068759)
			(xy 195.429098 -102.130673) (xy 195.405566 -102.190106) (xy 195.374772 -102.246121) (xy 195.337199 -102.297836)
			(xy 195.293442 -102.344433) (xy 195.244189 -102.385178) (xy 195.190218 -102.419429) (xy 195.132379 -102.446646)
			(xy 195.071586 -102.466399) (xy 195.008796 -102.478377) (xy 194.945 -102.482391) (xy 194.881204 -102.478377)
			(xy 194.818414 -102.466399) (xy 194.757621 -102.446646) (xy 194.699782 -102.419429) (xy 194.645811 -102.385178)
			(xy 194.596558 -102.344433) (xy 194.552801 -102.297836) (xy 194.515228 -102.246121) (xy 194.484434 -102.190106)
			(xy 194.460902 -102.130673) (xy 194.445005 -102.068759) (xy 194.436994 -102.005341) (xy 193.404735 -102.005341)
			(xy 193.412995 -102.037513) (xy 193.421006 -102.100931) (xy 193.421508 -102.132892) (xy 193.421006 -102.164853)
			(xy 193.412995 -102.228271) (xy 193.397098 -102.290185) (xy 193.373566 -102.349618) (xy 193.342772 -102.405633)
			(xy 193.305199 -102.457348) (xy 193.274255 -102.4903) (xy 197.004338 -102.4903) (xy 197.008353 -102.426494)
			(xy 197.020334 -102.363694) (xy 197.040091 -102.302891) (xy 197.067313 -102.245044) (xy 197.101572 -102.191066)
			(xy 197.142326 -102.141807) (xy 197.188933 -102.098044) (xy 197.240657 -102.060469) (xy 197.296683 -102.029673)
			(xy 197.356128 -102.006142) (xy 197.418053 -101.990247) (xy 197.481482 -101.98224) (xy 197.513448 -101.981762)
			(xy 197.547399 -101.982325) (xy 197.614694 -101.991392) (xy 197.680184 -102.009332) (xy 197.742705 -102.035826)
			(xy 197.801145 -102.070403) (xy 197.828154 -102.090982) (xy 197.83725 -102.097483) (xy 197.858997 -102.102583)
			(xy 197.880857 -102.097994) (xy 197.89013 -102.091744) (xy 197.916621 -102.072567) (xy 197.973552 -102.040384)
			(xy 198.034137 -102.015758) (xy 198.097378 -101.999096) (xy 198.162231 -101.990672) (xy 198.19493 -101.990144)
			(xy 198.226887 -101.990744) (xy 198.290296 -101.998758) (xy 198.352201 -102.014655) (xy 198.411625 -102.038186)
			(xy 198.467632 -102.068979) (xy 198.519338 -102.106548) (xy 198.565928 -102.150302) (xy 198.606666 -102.199549)
			(xy 198.640912 -102.253514) (xy 198.668124 -102.311345) (xy 198.687874 -102.372131) (xy 198.699849 -102.434912)
			(xy 198.703863 -102.4987) (xy 198.703181 -102.509531) (xy 199.281028 -102.509531) (xy 199.281028 -102.445609)
			(xy 199.289039 -102.382191) (xy 199.304936 -102.320277) (xy 199.328468 -102.260844) (xy 199.359262 -102.204829)
			(xy 199.396835 -102.153114) (xy 199.440592 -102.106517) (xy 199.489845 -102.065772) (xy 199.543816 -102.031521)
			(xy 199.601655 -102.004304) (xy 199.662448 -101.984551) (xy 199.725238 -101.972573) (xy 199.789034 -101.96856)
			(xy 199.85283 -101.972573) (xy 199.91562 -101.984551) (xy 199.976413 -102.004304) (xy 200.030975 -102.029979)
			(xy 209.876638 -102.029979) (xy 209.876638 -101.966057) (xy 209.884649 -101.902639) (xy 209.900546 -101.840725)
			(xy 209.924078 -101.781292) (xy 209.954872 -101.725277) (xy 209.992445 -101.673562) (xy 210.036202 -101.626965)
			(xy 210.085455 -101.58622) (xy 210.139426 -101.551969) (xy 210.197265 -101.524752) (xy 210.258058 -101.504999)
			(xy 210.320848 -101.493021) (xy 210.384644 -101.489008) (xy 210.44844 -101.493021) (xy 210.51123 -101.504999)
			(xy 210.572023 -101.524752) (xy 210.629862 -101.551969) (xy 210.683833 -101.58622) (xy 210.733086 -101.626965)
			(xy 210.776843 -101.673562) (xy 210.814416 -101.725277) (xy 210.84521 -101.781292) (xy 210.868742 -101.840725)
			(xy 210.884639 -101.902639) (xy 210.89265 -101.966057) (xy 210.8929 -101.982) (xy 211.435184 -101.982)
			(xy 211.439198 -101.918203) (xy 211.451176 -101.855412) (xy 211.47093 -101.794618) (xy 211.498147 -101.736779)
			(xy 211.532399 -101.682807) (xy 211.573145 -101.633554) (xy 211.619743 -101.589795) (xy 211.671458 -101.552223)
			(xy 211.727474 -101.521428) (xy 211.786909 -101.497897) (xy 211.848823 -101.482) (xy 211.912242 -101.473989)
			(xy 211.944204 -101.473508) (xy 211.974137 -101.473958) (xy 212.033588 -101.480998) (xy 212.091802 -101.494967)
			(xy 212.147974 -101.515673) (xy 212.201327 -101.542829) (xy 212.251123 -101.576061) (xy 212.296674 -101.614908)
			(xy 212.31733 -101.636576) (xy 212.324442 -101.644196) (xy 212.343492 -101.652578) (xy 212.438488 -101.653848)
			(xy 212.457538 -101.64572) (xy 212.46465 -101.638354) (xy 212.488706 -101.614408) (xy 212.542027 -101.572411)
			(xy 212.600461 -101.537879) (xy 212.662969 -101.511427) (xy 212.72844 -101.493524) (xy 212.795711 -101.484489)
			(xy 212.829648 -101.483922) (xy 212.860381 -101.484311) (xy 212.921399 -101.491725) (xy 212.981078 -101.50644)
			(xy 213.038548 -101.528242) (xy 213.092972 -101.556811) (xy 213.143555 -101.591732) (xy 213.18956 -101.632495)
			(xy 213.230316 -101.678507) (xy 213.265229 -101.729095) (xy 213.29379 -101.783523) (xy 213.315583 -101.840997)
			(xy 213.330289 -101.900678) (xy 213.333255 -101.92512) (xy 215.454482 -101.92512) (xy 215.458553 -101.869498)
			(xy 215.470679 -101.815061) (xy 215.490602 -101.76297) (xy 215.517898 -101.714335) (xy 215.551984 -101.670192)
			(xy 215.592133 -101.631483) (xy 215.637491 -101.599032) (xy 215.687091 -101.573531) (xy 215.739875 -101.555524)
			(xy 215.794718 -101.545394) (xy 215.850452 -101.543357) (xy 215.905889 -101.549457) (xy 215.959846 -101.563563)
			(xy 216.011175 -101.585375) (xy 216.058781 -101.614429) (xy 216.101649 -101.650104) (xy 216.138866 -101.691641)
			(xy 216.169639 -101.738154) (xy 216.193311 -101.788651) (xy 216.209379 -101.842058) (xy 216.217499 -101.897234)
			(xy 216.218008 -101.92512) (xy 216.217499 -101.953006) (xy 216.209379 -102.008182) (xy 216.193311 -102.061589)
			(xy 216.169639 -102.112086) (xy 216.138866 -102.158599) (xy 216.101649 -102.200136) (xy 216.058781 -102.235811)
			(xy 216.011175 -102.264865) (xy 215.959846 -102.286677) (xy 215.905889 -102.300783) (xy 215.850452 -102.306883)
			(xy 215.794718 -102.304846) (xy 215.739875 -102.294716) (xy 215.687091 -102.276709) (xy 215.637491 -102.251208)
			(xy 215.592133 -102.218757) (xy 215.551984 -102.180048) (xy 215.517898 -102.135905) (xy 215.490602 -102.08727)
			(xy 215.470679 -102.035179) (xy 215.458553 -101.980742) (xy 215.454482 -101.92512) (xy 213.333255 -101.92512)
			(xy 213.337694 -101.961697) (xy 213.338156 -101.99243) (xy 213.337625 -102.026235) (xy 213.328658 -102.093248)
			(xy 213.310885 -102.158481) (xy 213.284621 -102.220782) (xy 213.25033 -102.279051) (xy 213.208616 -102.332259)
			(xy 213.160216 -102.379467) (xy 213.133432 -102.4001) (xy 213.124366 -102.407504) (xy 213.113665 -102.428298)
			(xy 213.112858 -102.439978) (xy 213.111588 -102.532434) (xy 213.121494 -102.553516) (xy 213.130638 -102.560882)
			(xy 213.155756 -102.58163) (xy 213.201026 -102.628483) (xy 213.222156 -102.656851) (xy 216.456254 -102.656851)
			(xy 216.456254 -102.592929) (xy 216.464265 -102.529511) (xy 216.480162 -102.467597) (xy 216.503694 -102.408164)
			(xy 216.534488 -102.352149) (xy 216.572061 -102.300434) (xy 216.615818 -102.253837) (xy 216.665071 -102.213092)
			(xy 216.719042 -102.178841) (xy 216.776881 -102.151624) (xy 216.837674 -102.131871) (xy 216.900464 -102.119893)
			(xy 216.96426 -102.11588) (xy 217.028056 -102.119893) (xy 217.090846 -102.131871) (xy 217.151639 -102.151624)
			(xy 217.209478 -102.178841) (xy 217.263449 -102.213092) (xy 217.312702 -102.253837) (xy 217.356459 -102.300434)
			(xy 217.394032 -102.352149) (xy 217.424826 -102.408164) (xy 217.448358 -102.467597) (xy 217.464255 -102.529511)
			(xy 217.472266 -102.592929) (xy 217.472768 -102.62489) (xy 217.472266 -102.656851) (xy 217.464255 -102.720269)
			(xy 217.448358 -102.782183) (xy 217.424826 -102.841616) (xy 217.406174 -102.875545) (xy 255.985004 -102.875545)
			(xy 255.985004 -102.811623) (xy 255.993015 -102.748205) (xy 256.008912 -102.686291) (xy 256.032444 -102.626858)
			(xy 256.063238 -102.570843) (xy 256.100811 -102.519128) (xy 256.144568 -102.472531) (xy 256.193821 -102.431786)
			(xy 256.247792 -102.397535) (xy 256.305631 -102.370318) (xy 256.366424 -102.350565) (xy 256.429214 -102.338587)
			(xy 256.49301 -102.334574) (xy 256.556806 -102.338587) (xy 256.619596 -102.350565) (xy 256.680389 -102.370318)
			(xy 256.738228 -102.397535) (xy 256.759813 -102.411233) (xy 274.539958 -102.411233) (xy 274.539958 -102.347311)
			(xy 274.547969 -102.283893) (xy 274.563866 -102.221979) (xy 274.587398 -102.162546) (xy 274.618192 -102.106531)
			(xy 274.655765 -102.054816) (xy 274.699522 -102.008219) (xy 274.748775 -101.967474) (xy 274.802746 -101.933223)
			(xy 274.860585 -101.906006) (xy 274.921378 -101.886253) (xy 274.984168 -101.874275) (xy 275.047964 -101.870262)
			(xy 275.11176 -101.874275) (xy 275.17455 -101.886253) (xy 275.235343 -101.906006) (xy 275.293182 -101.933223)
			(xy 275.347153 -101.967474) (xy 275.396406 -102.008219) (xy 275.440163 -102.054816) (xy 275.470757 -102.096925)
			(xy 284.384586 -102.096925) (xy 284.387193 -102.033894) (xy 284.397576 -101.971671) (xy 284.415575 -101.911209)
			(xy 284.440916 -101.853438) (xy 284.473207 -101.799245) (xy 284.511954 -101.749463) (xy 284.556561 -101.704855)
			(xy 284.606344 -101.666108) (xy 284.660536 -101.633817) (xy 284.718307 -101.608476) (xy 284.778769 -101.590476)
			(xy 284.840992 -101.580093) (xy 284.904023 -101.577486) (xy 284.966891 -101.582696) (xy 285.028633 -101.595642)
			(xy 285.088299 -101.616126) (xy 285.144973 -101.643833) (xy 285.197784 -101.678337) (xy 285.245922 -101.719109)
			(xy 285.288647 -101.765522) (xy 285.325303 -101.816864) (xy 285.355327 -101.872345) (xy 285.378258 -101.931114)
			(xy 285.393743 -101.992268) (xy 285.401545 -102.054868) (xy 285.40202 -102.08641) (xy 285.401853 -102.104315)
			(xy 285.399308 -102.140035) (xy 285.39694 -102.157784) (xy 285.395162 -102.169722) (xy 285.402528 -102.19182)
			(xy 285.474918 -102.266496) (xy 285.497016 -102.27437) (xy 285.5087 -102.2731) (xy 285.522499 -102.271674)
			(xy 285.5502 -102.270152) (xy 285.564072 -102.270052) (xy 285.56458 -102.270052) (xy 285.595891 -102.27051)
			(xy 285.658037 -102.278209) (xy 285.718768 -102.293479) (xy 285.777165 -102.316091) (xy 285.832343 -102.345702)
			(xy 285.883468 -102.381863) (xy 285.929767 -102.424029) (xy 285.970538 -102.471559) (xy 285.988252 -102.497382)
			(xy 285.994348 -102.506526) (xy 286.012128 -102.517956) (xy 286.097472 -102.53091) (xy 286.108062 -102.532057)
			(xy 286.12858 -102.52639) (xy 286.137096 -102.519988) (xy 286.157585 -102.50392) (xy 286.202096 -102.476901)
			(xy 286.249868 -102.456186) (xy 286.300013 -102.44216) (xy 286.351599 -102.435084) (xy 286.377634 -102.434644)
			(xy 286.40488 -102.435228) (xy 286.458817 -102.442988) (xy 286.511101 -102.458344) (xy 286.560668 -102.480984)
			(xy 286.606508 -102.510448) (xy 286.624208 -102.525787) (xy 297.695868 -102.525787) (xy 297.695868 -102.461865)
			(xy 297.703879 -102.398447) (xy 297.719776 -102.336533) (xy 297.743308 -102.2771) (xy 297.774102 -102.221085)
			(xy 297.811675 -102.16937) (xy 297.855432 -102.122773) (xy 297.904685 -102.082028) (xy 297.958656 -102.047777)
			(xy 298.016495 -102.02056) (xy 298.077288 -102.000807) (xy 298.140078 -101.988829) (xy 298.203874 -101.984816)
			(xy 298.26767 -101.988829) (xy 298.33046 -102.000807) (xy 298.391253 -102.02056) (xy 298.449092 -102.047777)
			(xy 298.503063 -102.082028) (xy 298.552316 -102.122773) (xy 298.596073 -102.16937) (xy 298.633646 -102.221085)
			(xy 298.658866 -102.266961) (xy 299.465994 -102.266961) (xy 299.465994 -102.203039) (xy 299.474005 -102.139621)
			(xy 299.489902 -102.077707) (xy 299.513434 -102.018274) (xy 299.544228 -101.962259) (xy 299.581801 -101.910544)
			(xy 299.625558 -101.863947) (xy 299.674811 -101.823202) (xy 299.728782 -101.788951) (xy 299.786621 -101.761734)
			(xy 299.847414 -101.741981) (xy 299.910204 -101.730003) (xy 299.974 -101.72599) (xy 300.037796 -101.730003)
			(xy 300.100586 -101.741981) (xy 300.161379 -101.761734) (xy 300.219218 -101.788951) (xy 300.273189 -101.823202)
			(xy 300.322442 -101.863947) (xy 300.366199 -101.910544) (xy 300.403772 -101.962259) (xy 300.434566 -102.018274)
			(xy 300.458098 -102.077707) (xy 300.473995 -102.139621) (xy 300.482006 -102.203039) (xy 300.482508 -102.235)
			(xy 300.482006 -102.266961) (xy 300.473995 -102.330379) (xy 300.458098 -102.392293) (xy 300.434566 -102.451726)
			(xy 300.403772 -102.507741) (xy 300.366199 -102.559456) (xy 300.322442 -102.606053) (xy 300.273189 -102.646798)
			(xy 300.219218 -102.681049) (xy 300.161379 -102.708266) (xy 300.110764 -102.724712) (xy 324.127874 -102.724712)
			(xy 324.131945 -102.66909) (xy 324.144071 -102.614653) (xy 324.163994 -102.562562) (xy 324.19129 -102.513927)
			(xy 324.225376 -102.469784) (xy 324.265525 -102.431075) (xy 324.310883 -102.398624) (xy 324.360483 -102.373123)
			(xy 324.413267 -102.355116) (xy 324.46811 -102.344986) (xy 324.523844 -102.342949) (xy 324.579281 -102.349049)
			(xy 324.633238 -102.363155) (xy 324.684567 -102.384967) (xy 324.732173 -102.414021) (xy 324.775041 -102.449696)
			(xy 324.812258 -102.491233) (xy 324.843031 -102.537746) (xy 324.866703 -102.588243) (xy 324.882771 -102.64165)
			(xy 324.883139 -102.644151) (xy 429.36896 -102.644151) (xy 429.36896 -102.580229) (xy 429.376971 -102.516811)
			(xy 429.392868 -102.454897) (xy 429.4164 -102.395464) (xy 429.447194 -102.339449) (xy 429.484767 -102.287734)
			(xy 429.528524 -102.241137) (xy 429.577777 -102.200392) (xy 429.631748 -102.166141) (xy 429.689587 -102.138924)
			(xy 429.75038 -102.119171) (xy 429.81317 -102.107193) (xy 429.876966 -102.10318) (xy 429.940762 -102.107193)
			(xy 430.003552 -102.119171) (xy 430.064345 -102.138924) (xy 430.122184 -102.166141) (xy 430.176155 -102.200392)
			(xy 430.225408 -102.241137) (xy 430.269165 -102.287734) (xy 430.306738 -102.339449) (xy 430.337532 -102.395464)
			(xy 430.361064 -102.454897) (xy 430.376961 -102.516811) (xy 430.384972 -102.580229) (xy 430.385474 -102.61219)
			(xy 430.384972 -102.644151) (xy 430.380731 -102.677722) (xy 432.043078 -102.677722) (xy 432.04358 -102.645761)
			(xy 432.051591 -102.582343) (xy 432.067488 -102.520429) (xy 432.09102 -102.460996) (xy 432.121814 -102.404981)
			(xy 432.159387 -102.353266) (xy 432.203144 -102.306669) (xy 432.252397 -102.265924) (xy 432.306368 -102.231673)
			(xy 432.364207 -102.204456) (xy 432.425 -102.184703) (xy 432.48779 -102.172725) (xy 432.551586 -102.168712)
			(xy 432.615382 -102.172725) (xy 432.678172 -102.184703) (xy 432.738965 -102.204456) (xy 432.796804 -102.231673)
			(xy 432.850775 -102.265924) (xy 432.900028 -102.306669) (xy 432.943785 -102.353266) (xy 432.981358 -102.404981)
			(xy 433.012152 -102.460996) (xy 433.035684 -102.520429) (xy 433.051581 -102.582343) (xy 433.057688 -102.630689)
			(xy 454.788772 -102.630689) (xy 454.788772 -102.566767) (xy 454.796783 -102.503349) (xy 454.81268 -102.441435)
			(xy 454.836212 -102.382002) (xy 454.867006 -102.325987) (xy 454.904579 -102.274272) (xy 454.948336 -102.227675)
			(xy 454.997589 -102.18693) (xy 455.05156 -102.152679) (xy 455.109399 -102.125462) (xy 455.170192 -102.105709)
			(xy 455.232982 -102.093731) (xy 455.296778 -102.089718) (xy 455.360574 -102.093731) (xy 455.423364 -102.105709)
			(xy 455.484157 -102.125462) (xy 455.541996 -102.152679) (xy 455.595967 -102.18693) (xy 455.64522 -102.227675)
			(xy 455.688977 -102.274272) (xy 455.72655 -102.325987) (xy 455.757344 -102.382002) (xy 455.780876 -102.441435)
			(xy 455.796773 -102.503349) (xy 455.804784 -102.566767) (xy 455.805286 -102.598728) (xy 455.804784 -102.630689)
			(xy 455.796773 -102.694107) (xy 455.780876 -102.756021) (xy 455.757344 -102.815454) (xy 455.72655 -102.871469)
			(xy 455.688977 -102.923184) (xy 455.64522 -102.969781) (xy 455.595967 -103.010526) (xy 455.541996 -103.044777)
			(xy 455.484157 -103.071994) (xy 455.423364 -103.091747) (xy 455.360574 -103.103725) (xy 455.296778 -103.107739)
			(xy 455.232982 -103.103725) (xy 455.170192 -103.091747) (xy 455.109399 -103.071994) (xy 455.05156 -103.044777)
			(xy 454.997589 -103.010526) (xy 454.948336 -102.969781) (xy 454.904579 -102.923184) (xy 454.867006 -102.871469)
			(xy 454.836212 -102.815454) (xy 454.81268 -102.756021) (xy 454.796783 -102.694107) (xy 454.788772 -102.630689)
			(xy 433.057688 -102.630689) (xy 433.059592 -102.645761) (xy 433.060094 -102.677722) (xy 433.059733 -102.705851)
			(xy 433.053512 -102.761764) (xy 433.041147 -102.816646) (xy 433.022791 -102.869825) (xy 433.011072 -102.8954)
			(xy 433.011072 -102.895654) (xy 433.00713 -102.905248) (xy 433.006475 -102.925961) (xy 433.009802 -102.935786)
			(xy 433.041298 -103.01478) (xy 433.056538 -103.029766) (xy 433.066444 -103.033576) (xy 433.090314 -103.04327)
			(xy 433.135416 -103.068173) (xy 433.176761 -103.098911) (xy 433.213601 -103.134927) (xy 433.229766 -103.154988)
			(xy 433.2374 -103.163768) (xy 433.25828 -103.173967) (xy 433.269898 -103.174546) (xy 433.349654 -103.174546)
			(xy 433.361291 -103.174043) (xy 433.382201 -103.16383) (xy 433.389786 -103.154988) (xy 433.407982 -103.132509)
			(xy 433.450001 -103.092774) (xy 433.497535 -103.059835) (xy 433.549495 -103.034446) (xy 433.604692 -103.017188)
			(xy 433.66186 -103.008458) (xy 433.690776 -103.007922) (xy 433.71803 -103.008378) (xy 433.771982 -103.016132)
			(xy 433.824282 -103.031487) (xy 433.873864 -103.054129) (xy 433.919719 -103.083597) (xy 433.960913 -103.119292)
			(xy 433.996607 -103.160486) (xy 434.026074 -103.206341) (xy 434.048715 -103.255923) (xy 434.064069 -103.308223)
			(xy 434.071823 -103.362176) (xy 434.072284 -103.38943) (xy 434.071802 -103.417261) (xy 434.063703 -103.47233)
			(xy 434.047696 -103.525641) (xy 434.024119 -103.576063) (xy 433.993473 -103.622529) (xy 433.972322 -103.646224)
			(xy 455.669648 -103.646224) (xy 455.673719 -103.590602) (xy 455.685845 -103.536165) (xy 455.705768 -103.484074)
			(xy 455.733064 -103.435439) (xy 455.76715 -103.391296) (xy 455.807299 -103.352587) (xy 455.852657 -103.320136)
			(xy 455.902257 -103.294635) (xy 455.955041 -103.276628) (xy 456.009884 -103.266498) (xy 456.065618 -103.264461)
			(xy 456.121055 -103.270561) (xy 456.175012 -103.284667) (xy 456.226341 -103.306479) (xy 456.273947 -103.335533)
			(xy 456.316815 -103.371208) (xy 456.354032 -103.412745) (xy 456.384805 -103.459258) (xy 456.408477 -103.509755)
			(xy 456.424545 -103.563162) (xy 456.432665 -103.618338) (xy 456.433174 -103.646224) (xy 456.432665 -103.67411)
			(xy 456.424545 -103.729286) (xy 456.408477 -103.782693) (xy 456.384805 -103.83319) (xy 456.354032 -103.879703)
			(xy 456.316815 -103.92124) (xy 456.273947 -103.956915) (xy 456.226341 -103.985969) (xy 456.175012 -104.007781)
			(xy 456.121055 -104.021887) (xy 456.065618 -104.027987) (xy 456.009884 -104.02595) (xy 455.955041 -104.01582)
			(xy 455.902257 -103.997813) (xy 455.852657 -103.972312) (xy 455.807299 -103.939861) (xy 455.76715 -103.901152)
			(xy 455.733064 -103.857009) (xy 455.705768 -103.808374) (xy 455.685845 -103.756283) (xy 455.673719 -103.701846)
			(xy 455.669648 -103.646224) (xy 433.972322 -103.646224) (xy 433.956406 -103.664054) (xy 433.935378 -103.682292)
			(xy 433.925218 -103.690674) (xy 433.91582 -103.71582) (xy 433.933854 -103.82885) (xy 433.950872 -103.849678)
			(xy 433.963064 -103.854504) (xy 433.991144 -103.866101) (xy 434.044576 -103.895016) (xy 434.094184 -103.93009)
			(xy 434.13926 -103.970824) (xy 434.179162 -104.016637) (xy 434.213323 -104.066878) (xy 434.241256 -104.12083)
			(xy 434.262563 -104.177725) (xy 434.27694 -104.236754) (xy 434.284183 -104.297075) (xy 434.284628 -104.327452)
			(xy 434.284617 -104.328171) (xy 454.774294 -104.328171) (xy 454.774294 -104.264249) (xy 454.782305 -104.200831)
			(xy 454.798202 -104.138917) (xy 454.821734 -104.079484) (xy 454.852528 -104.023469) (xy 454.890101 -103.971754)
			(xy 454.933858 -103.925157) (xy 454.983111 -103.884412) (xy 455.037082 -103.850161) (xy 455.094921 -103.822944)
			(xy 455.155714 -103.803191) (xy 455.218504 -103.791213) (xy 455.2823 -103.7872) (xy 455.346096 -103.791213)
			(xy 455.408886 -103.803191) (xy 455.469679 -103.822944) (xy 455.527518 -103.850161) (xy 455.581489 -103.884412)
			(xy 455.630742 -103.925157) (xy 455.674499 -103.971754) (xy 455.712072 -104.023469) (xy 455.742866 -104.079484)
			(xy 455.766398 -104.138917) (xy 455.782295 -104.200831) (xy 455.788472 -104.249728) (xy 461.738978 -104.249728)
			(xy 461.743049 -104.194106) (xy 461.755175 -104.139669) (xy 461.775098 -104.087578) (xy 461.802394 -104.038943)
			(xy 461.83648 -103.9948) (xy 461.876629 -103.956091) (xy 461.921987 -103.92364) (xy 461.971587 -103.898139)
			(xy 462.024371 -103.880132) (xy 462.079214 -103.870002) (xy 462.134948 -103.867965) (xy 462.190385 -103.874065)
			(xy 462.244342 -103.888171) (xy 462.295671 -103.909983) (xy 462.343277 -103.939037) (xy 462.386145 -103.974712)
			(xy 462.423362 -104.016249) (xy 462.454135 -104.062762) (xy 462.477807 -104.113259) (xy 462.493875 -104.166666)
			(xy 462.501995 -104.221842) (xy 462.502504 -104.249728) (xy 462.501995 -104.277614) (xy 462.493875 -104.33279)
			(xy 462.477807 -104.386197) (xy 462.454135 -104.436694) (xy 462.423362 -104.483207) (xy 462.386145 -104.524744)
			(xy 462.343277 -104.560419) (xy 462.295671 -104.589473) (xy 462.244342 -104.611285) (xy 462.190385 -104.625391)
			(xy 462.134948 -104.631491) (xy 462.079214 -104.629454) (xy 462.024371 -104.619324) (xy 461.971587 -104.601317)
			(xy 461.921987 -104.575816) (xy 461.876629 -104.543365) (xy 461.83648 -104.504656) (xy 461.802394 -104.460513)
			(xy 461.775098 -104.411878) (xy 461.755175 -104.359787) (xy 461.743049 -104.30535) (xy 461.738978 -104.249728)
			(xy 455.788472 -104.249728) (xy 455.790306 -104.264249) (xy 455.790808 -104.29621) (xy 455.790306 -104.328171)
			(xy 455.782295 -104.391589) (xy 455.766398 -104.453503) (xy 455.742866 -104.512936) (xy 455.712072 -104.568951)
			(xy 455.674499 -104.620666) (xy 455.630742 -104.667263) (xy 455.581489 -104.708008) (xy 455.527518 -104.742259)
			(xy 455.469679 -104.769476) (xy 455.408886 -104.789229) (xy 455.346096 -104.801207) (xy 455.2823 -104.805221)
			(xy 455.218504 -104.801207) (xy 455.155714 -104.789229) (xy 455.094921 -104.769476) (xy 455.037082 -104.742259)
			(xy 454.983111 -104.708008) (xy 454.933858 -104.667263) (xy 454.890101 -104.620666) (xy 454.852528 -104.568951)
			(xy 454.821734 -104.512936) (xy 454.798202 -104.453503) (xy 454.782305 -104.391589) (xy 454.774294 -104.328171)
			(xy 434.284617 -104.328171) (xy 434.284126 -104.359413) (xy 434.276115 -104.422831) (xy 434.260218 -104.484745)
			(xy 434.236686 -104.544178) (xy 434.205892 -104.600193) (xy 434.168319 -104.651908) (xy 434.124562 -104.698505)
			(xy 434.075309 -104.73925) (xy 434.021338 -104.773501) (xy 433.963499 -104.800718) (xy 433.902706 -104.820471)
			(xy 433.839916 -104.832449) (xy 433.77612 -104.836463) (xy 433.712324 -104.832449) (xy 433.649534 -104.820471)
			(xy 433.588741 -104.800718) (xy 433.530902 -104.773501) (xy 433.476931 -104.73925) (xy 433.427678 -104.698505)
			(xy 433.383921 -104.651908) (xy 433.346348 -104.600193) (xy 433.315554 -104.544178) (xy 433.292022 -104.484745)
			(xy 433.276125 -104.422831) (xy 433.268114 -104.359413) (xy 433.267612 -104.327452) (xy 433.268107 -104.295254)
			(xy 433.276225 -104.231373) (xy 433.292349 -104.16903) (xy 433.316222 -104.109223) (xy 433.34746 -104.052913)
			(xy 433.385564 -104.001001) (xy 433.429921 -103.954319) (xy 433.479821 -103.913617) (xy 433.50688 -103.89616)
			(xy 433.51831 -103.889048) (xy 433.53101 -103.86568) (xy 433.52847 -103.750872) (xy 433.515008 -103.728012)
			(xy 433.50307 -103.721408) (xy 433.481413 -103.708739) (xy 433.441321 -103.678572) (xy 433.405533 -103.643405)
			(xy 433.389786 -103.623872) (xy 433.382231 -103.615103) (xy 433.361467 -103.604925) (xy 433.349908 -103.604314)
			(xy 433.269898 -103.604314) (xy 433.258267 -103.604862) (xy 433.237357 -103.615044) (xy 433.229766 -103.623872)
			(xy 433.211587 -103.646366) (xy 433.169566 -103.686102) (xy 433.122029 -103.71904) (xy 433.070065 -103.744427)
			(xy 433.014865 -103.761681) (xy 432.957693 -103.770406) (xy 432.928776 -103.770938) (xy 432.901526 -103.770445)
			(xy 432.84758 -103.762686) (xy 432.795287 -103.747329) (xy 432.745712 -103.724687) (xy 432.699863 -103.695221)
			(xy 432.658674 -103.659531) (xy 432.622982 -103.618342) (xy 432.593516 -103.572494) (xy 432.570873 -103.522919)
			(xy 432.555516 -103.470626) (xy 432.547756 -103.41668) (xy 432.547268 -103.38943) (xy 432.5476 -103.367773)
			(xy 432.552566 -103.324742) (xy 432.557174 -103.303578) (xy 432.557174 -103.303324) (xy 432.558956 -103.293133)
			(xy 432.555148 -103.272816) (xy 432.549808 -103.263954) (xy 432.507644 -103.201724) (xy 432.501426 -103.193437)
			(xy 432.483996 -103.18228) (xy 432.473862 -103.180134) (xy 432.473354 -103.180134) (xy 432.441064 -103.174642)
			(xy 432.37817 -103.156344) (xy 432.318147 -103.130121) (xy 432.261989 -103.096406) (xy 432.210625 -103.055758)
			(xy 432.164908 -103.00885) (xy 432.125593 -102.95646) (xy 432.093332 -102.899454) (xy 432.06866 -102.838776)
			(xy 432.051985 -102.775433) (xy 432.043582 -102.710473) (xy 432.043078 -102.677722) (xy 430.380731 -102.677722)
			(xy 430.376961 -102.707569) (xy 430.361064 -102.769483) (xy 430.337532 -102.828916) (xy 430.306738 -102.884931)
			(xy 430.269165 -102.936646) (xy 430.225408 -102.983243) (xy 430.176155 -103.023988) (xy 430.122184 -103.058239)
			(xy 430.064345 -103.085456) (xy 430.003552 -103.105209) (xy 429.940762 -103.117187) (xy 429.876966 -103.121201)
			(xy 429.81317 -103.117187) (xy 429.75038 -103.105209) (xy 429.689587 -103.085456) (xy 429.631748 -103.058239)
			(xy 429.577777 -103.023988) (xy 429.528524 -102.983243) (xy 429.484767 -102.936646) (xy 429.447194 -102.884931)
			(xy 429.4164 -102.828916) (xy 429.392868 -102.769483) (xy 429.376971 -102.707569) (xy 429.36896 -102.644151)
			(xy 324.883139 -102.644151) (xy 324.890891 -102.696826) (xy 324.8914 -102.724712) (xy 324.890891 -102.752598)
			(xy 324.882771 -102.807774) (xy 324.866703 -102.861181) (xy 324.843031 -102.911678) (xy 324.812258 -102.958191)
			(xy 324.775041 -102.999728) (xy 324.732173 -103.035403) (xy 324.684567 -103.064457) (xy 324.633238 -103.086269)
			(xy 324.579281 -103.100375) (xy 324.523844 -103.106475) (xy 324.46811 -103.104438) (xy 324.413267 -103.094308)
			(xy 324.360483 -103.076301) (xy 324.310883 -103.0508) (xy 324.265525 -103.018349) (xy 324.225376 -102.97964)
			(xy 324.19129 -102.935497) (xy 324.163994 -102.886862) (xy 324.144071 -102.834771) (xy 324.131945 -102.780334)
			(xy 324.127874 -102.724712) (xy 300.110764 -102.724712) (xy 300.100586 -102.728019) (xy 300.037796 -102.739997)
			(xy 299.974 -102.744011) (xy 299.910204 -102.739997) (xy 299.847414 -102.728019) (xy 299.786621 -102.708266)
			(xy 299.728782 -102.681049) (xy 299.674811 -102.646798) (xy 299.625558 -102.606053) (xy 299.581801 -102.559456)
			(xy 299.544228 -102.507741) (xy 299.513434 -102.451726) (xy 299.489902 -102.392293) (xy 299.474005 -102.330379)
			(xy 299.465994 -102.266961) (xy 298.658866 -102.266961) (xy 298.66444 -102.2771) (xy 298.687972 -102.336533)
			(xy 298.703869 -102.398447) (xy 298.71188 -102.461865) (xy 298.712382 -102.493826) (xy 298.71188 -102.525787)
			(xy 298.703869 -102.589205) (xy 298.687972 -102.651119) (xy 298.66444 -102.710552) (xy 298.633646 -102.766567)
			(xy 298.596073 -102.818282) (xy 298.552316 -102.864879) (xy 298.503063 -102.905624) (xy 298.449092 -102.939875)
			(xy 298.391253 -102.967092) (xy 298.33046 -102.986845) (xy 298.26767 -102.998823) (xy 298.203874 -103.002837)
			(xy 298.140078 -102.998823) (xy 298.077288 -102.986845) (xy 298.016495 -102.967092) (xy 297.958656 -102.939875)
			(xy 297.904685 -102.905624) (xy 297.855432 -102.864879) (xy 297.811675 -102.818282) (xy 297.774102 -102.766567)
			(xy 297.743308 -102.710552) (xy 297.719776 -102.651119) (xy 297.703879 -102.589205) (xy 297.695868 -102.525787)
			(xy 286.624208 -102.525787) (xy 286.647689 -102.546135) (xy 286.683373 -102.587319) (xy 286.712832 -102.633162)
			(xy 286.735468 -102.68273) (xy 286.750819 -102.735016) (xy 286.758574 -102.788954) (xy 286.758574 -102.843446)
			(xy 286.750819 -102.897384) (xy 286.735468 -102.94967) (xy 286.712832 -102.999238) (xy 286.683373 -103.045081)
			(xy 286.647689 -103.086265) (xy 286.606508 -103.121952) (xy 286.560668 -103.151416) (xy 286.511101 -103.174056)
			(xy 286.458817 -103.189412) (xy 286.40488 -103.197172) (xy 286.377634 -103.19766) (xy 286.348049 -103.197123)
			(xy 286.28959 -103.18798) (xy 286.233243 -103.169922) (xy 286.180358 -103.143383) (xy 286.132204 -103.108999)
			(xy 286.11068 -103.088694) (xy 286.10306 -103.081074) (xy 286.082994 -103.073708) (xy 285.98622 -103.079296)
			(xy 285.96717 -103.089202) (xy 285.960566 -103.097584) (xy 285.939821 -103.122521) (xy 285.893033 -103.16745)
			(xy 285.840911 -103.206063) (xy 285.784301 -103.237734) (xy 285.724123 -103.261947) (xy 285.661354 -103.278311)
			(xy 285.597013 -103.286558) (xy 285.56458 -103.287068) (xy 285.533846 -103.286681) (xy 285.472826 -103.279269)
			(xy 285.413145 -103.264556) (xy 285.355672 -103.242757) (xy 285.301246 -103.214188) (xy 285.250661 -103.179267)
			(xy 285.204654 -103.138504) (xy 285.163895 -103.092492) (xy 285.128981 -103.041902) (xy 285.100419 -102.987473)
			(xy 285.078626 -102.929998) (xy 285.06392 -102.870315) (xy 285.056515 -102.809294) (xy 285.056072 -102.77856)
			(xy 285.056246 -102.760655) (xy 285.058787 -102.724935) (xy 285.061152 -102.707186) (xy 285.06293 -102.695248)
			(xy 285.055564 -102.67315) (xy 284.983174 -102.598474) (xy 284.961076 -102.5906) (xy 284.949392 -102.59187)
			(xy 284.935593 -102.593288) (xy 284.907892 -102.594815) (xy 284.89402 -102.594918) (xy 284.893512 -102.594918)
			(xy 284.86197 -102.594445) (xy 284.79937 -102.586643) (xy 284.738216 -102.571158) (xy 284.679447 -102.548228)
			(xy 284.623965 -102.518204) (xy 284.572624 -102.481549) (xy 284.526211 -102.438824) (xy 284.485439 -102.390686)
			(xy 284.450934 -102.337874) (xy 284.423227 -102.2812) (xy 284.402743 -102.221535) (xy 284.389796 -102.159793)
			(xy 284.384586 -102.096925) (xy 275.470757 -102.096925) (xy 275.477736 -102.106531) (xy 275.50853 -102.162546)
			(xy 275.532062 -102.221979) (xy 275.547959 -102.283893) (xy 275.55597 -102.347311) (xy 275.556472 -102.379272)
			(xy 275.55597 -102.411233) (xy 275.547959 -102.474651) (xy 275.532062 -102.536565) (xy 275.50853 -102.595998)
			(xy 275.477736 -102.652013) (xy 275.440163 -102.703728) (xy 275.396406 -102.750325) (xy 275.347153 -102.79107)
			(xy 275.293182 -102.825321) (xy 275.235343 -102.852538) (xy 275.17455 -102.872291) (xy 275.11176 -102.884269)
			(xy 275.047964 -102.888283) (xy 274.984168 -102.884269) (xy 274.921378 -102.872291) (xy 274.860585 -102.852538)
			(xy 274.802746 -102.825321) (xy 274.748775 -102.79107) (xy 274.699522 -102.750325) (xy 274.655765 -102.703728)
			(xy 274.618192 -102.652013) (xy 274.587398 -102.595998) (xy 274.563866 -102.536565) (xy 274.547969 -102.474651)
			(xy 274.539958 -102.411233) (xy 256.759813 -102.411233) (xy 256.792199 -102.431786) (xy 256.841452 -102.472531)
			(xy 256.885209 -102.519128) (xy 256.922782 -102.570843) (xy 256.953576 -102.626858) (xy 256.977108 -102.686291)
			(xy 256.993005 -102.748205) (xy 257.001016 -102.811623) (xy 257.001518 -102.843584) (xy 257.001402 -102.85095)
			(xy 259.059932 -102.85095) (xy 259.064003 -102.795328) (xy 259.076129 -102.740891) (xy 259.096052 -102.6888)
			(xy 259.123348 -102.640165) (xy 259.157434 -102.596022) (xy 259.197583 -102.557313) (xy 259.242941 -102.524862)
			(xy 259.292541 -102.499361) (xy 259.345325 -102.481354) (xy 259.400168 -102.471224) (xy 259.455902 -102.469187)
			(xy 259.511339 -102.475287) (xy 259.565296 -102.489393) (xy 259.616625 -102.511205) (xy 259.664231 -102.540259)
			(xy 259.707099 -102.575934) (xy 259.744316 -102.617471) (xy 259.775089 -102.663984) (xy 259.798761 -102.714481)
			(xy 259.814829 -102.767888) (xy 259.822949 -102.823064) (xy 259.823458 -102.85095) (xy 259.822949 -102.878836)
			(xy 259.814829 -102.934012) (xy 259.798761 -102.987419) (xy 259.775089 -103.037916) (xy 259.744316 -103.084429)
			(xy 259.707099 -103.125966) (xy 259.664231 -103.161641) (xy 259.616625 -103.190695) (xy 259.565296 -103.212507)
			(xy 259.511339 -103.226613) (xy 259.455902 -103.232713) (xy 259.400168 -103.230676) (xy 259.345325 -103.220546)
			(xy 259.292541 -103.202539) (xy 259.242941 -103.177038) (xy 259.197583 -103.144587) (xy 259.157434 -103.105878)
			(xy 259.123348 -103.061735) (xy 259.096052 -103.0131) (xy 259.076129 -102.961009) (xy 259.064003 -102.906572)
			(xy 259.059932 -102.85095) (xy 257.001402 -102.85095) (xy 257.001016 -102.875545) (xy 256.993005 -102.938963)
			(xy 256.977108 -103.000877) (xy 256.953576 -103.06031) (xy 256.922782 -103.116325) (xy 256.885209 -103.16804)
			(xy 256.841452 -103.214637) (xy 256.792199 -103.255382) (xy 256.764683 -103.272844) (xy 264.004296 -103.272844)
			(xy 264.008367 -103.217222) (xy 264.020493 -103.162785) (xy 264.040416 -103.110694) (xy 264.067712 -103.062059)
			(xy 264.101798 -103.017916) (xy 264.141947 -102.979207) (xy 264.187305 -102.946756) (xy 264.236905 -102.921255)
			(xy 264.289689 -102.903248) (xy 264.344532 -102.893118) (xy 264.400266 -102.891081) (xy 264.455703 -102.897181)
			(xy 264.50966 -102.911287) (xy 264.560989 -102.933099) (xy 264.608595 -102.962153) (xy 264.651463 -102.997828)
			(xy 264.68868 -103.039365) (xy 264.719453 -103.085878) (xy 264.743125 -103.136375) (xy 264.759193 -103.189782)
			(xy 264.767313 -103.244958) (xy 264.767822 -103.272844) (xy 264.767313 -103.30073) (xy 264.766713 -103.304805)
			(xy 266.083536 -103.304805) (xy 266.083536 -103.240883) (xy 266.091547 -103.177465) (xy 266.107444 -103.115551)
			(xy 266.130976 -103.056118) (xy 266.16177 -103.000103) (xy 266.199343 -102.948388) (xy 266.2431 -102.901791)
			(xy 266.292353 -102.861046) (xy 266.346324 -102.826795) (xy 266.404163 -102.799578) (xy 266.464956 -102.779825)
			(xy 266.527746 -102.767847) (xy 266.591542 -102.763834) (xy 266.655338 -102.767847) (xy 266.718128 -102.779825)
			(xy 266.778921 -102.799578) (xy 266.83676 -102.826795) (xy 266.890731 -102.861046) (xy 266.939984 -102.901791)
			(xy 266.983741 -102.948388) (xy 267.021314 -103.000103) (xy 267.052108 -103.056118) (xy 267.07564 -103.115551)
			(xy 267.091537 -103.177465) (xy 267.099548 -103.240883) (xy 267.099946 -103.26624) (xy 269.227806 -103.26624)
			(xy 269.231877 -103.210618) (xy 269.244003 -103.156181) (xy 269.263926 -103.10409) (xy 269.291222 -103.055455)
			(xy 269.325308 -103.011312) (xy 269.365457 -102.972603) (xy 269.410815 -102.940152) (xy 269.460415 -102.914651)
			(xy 269.513199 -102.896644) (xy 269.568042 -102.886514) (xy 269.623776 -102.884477) (xy 269.679213 -102.890577)
			(xy 269.73317 -102.904683) (xy 269.784499 -102.926495) (xy 269.832105 -102.955549) (xy 269.874973 -102.991224)
			(xy 269.91219 -103.032761) (xy 269.942963 -103.079274) (xy 269.966635 -103.129771) (xy 269.982703 -103.183178)
			(xy 269.990823 -103.238354) (xy 269.991332 -103.26624) (xy 269.990823 -103.294126) (xy 269.982703 -103.349302)
			(xy 269.966635 -103.402709) (xy 269.962977 -103.410512) (xy 319.71564 -103.410512) (xy 319.719711 -103.35489)
			(xy 319.731837 -103.300453) (xy 319.75176 -103.248362) (xy 319.779056 -103.199727) (xy 319.813142 -103.155584)
			(xy 319.853291 -103.116875) (xy 319.898649 -103.084424) (xy 319.948249 -103.058923) (xy 320.001033 -103.040916)
			(xy 320.055876 -103.030786) (xy 320.11161 -103.028749) (xy 320.167047 -103.034849) (xy 320.221004 -103.048955)
			(xy 320.272333 -103.070767) (xy 320.319939 -103.099821) (xy 320.362807 -103.135496) (xy 320.400024 -103.177033)
			(xy 320.430797 -103.223546) (xy 320.454469 -103.274043) (xy 320.470537 -103.32745) (xy 320.478657 -103.382626)
			(xy 320.479166 -103.410512) (xy 320.478657 -103.438398) (xy 320.470537 -103.493574) (xy 320.454469 -103.546981)
			(xy 320.430797 -103.597478) (xy 320.400024 -103.643991) (xy 320.362807 -103.685528) (xy 320.319939 -103.721203)
			(xy 320.272333 -103.750257) (xy 320.221004 -103.772069) (xy 320.167047 -103.786175) (xy 320.11161 -103.792275)
			(xy 320.055876 -103.790238) (xy 320.001033 -103.780108) (xy 319.948249 -103.762101) (xy 319.898649 -103.7366)
			(xy 319.853291 -103.704149) (xy 319.813142 -103.66544) (xy 319.779056 -103.621297) (xy 319.75176 -103.572662)
			(xy 319.731837 -103.520571) (xy 319.719711 -103.466134) (xy 319.71564 -103.410512) (xy 269.962977 -103.410512)
			(xy 269.942963 -103.453206) (xy 269.91219 -103.499719) (xy 269.874973 -103.541256) (xy 269.832105 -103.576931)
			(xy 269.784499 -103.605985) (xy 269.73317 -103.627797) (xy 269.679213 -103.641903) (xy 269.623776 -103.648003)
			(xy 269.568042 -103.645966) (xy 269.513199 -103.635836) (xy 269.460415 -103.617829) (xy 269.410815 -103.592328)
			(xy 269.365457 -103.559877) (xy 269.325308 -103.521168) (xy 269.291222 -103.477025) (xy 269.263926 -103.42839)
			(xy 269.244003 -103.376299) (xy 269.231877 -103.321862) (xy 269.227806 -103.26624) (xy 267.099946 -103.26624)
			(xy 267.10005 -103.272844) (xy 267.099548 -103.304805) (xy 267.091537 -103.368223) (xy 267.07564 -103.430137)
			(xy 267.052108 -103.48957) (xy 267.021314 -103.545585) (xy 266.983741 -103.5973) (xy 266.939984 -103.643897)
			(xy 266.890731 -103.684642) (xy 266.83676 -103.718893) (xy 266.778921 -103.74611) (xy 266.718128 -103.765863)
			(xy 266.655338 -103.777841) (xy 266.591542 -103.781855) (xy 266.527746 -103.777841) (xy 266.464956 -103.765863)
			(xy 266.404163 -103.74611) (xy 266.346324 -103.718893) (xy 266.292353 -103.684642) (xy 266.2431 -103.643897)
			(xy 266.199343 -103.5973) (xy 266.16177 -103.545585) (xy 266.130976 -103.48957) (xy 266.107444 -103.430137)
			(xy 266.091547 -103.368223) (xy 266.083536 -103.304805) (xy 264.766713 -103.304805) (xy 264.759193 -103.355906)
			(xy 264.743125 -103.409313) (xy 264.719453 -103.45981) (xy 264.68868 -103.506323) (xy 264.651463 -103.54786)
			(xy 264.608595 -103.583535) (xy 264.560989 -103.612589) (xy 264.50966 -103.634401) (xy 264.455703 -103.648507)
			(xy 264.400266 -103.654607) (xy 264.344532 -103.65257) (xy 264.289689 -103.64244) (xy 264.236905 -103.624433)
			(xy 264.187305 -103.598932) (xy 264.141947 -103.566481) (xy 264.101798 -103.527772) (xy 264.067712 -103.483629)
			(xy 264.040416 -103.434994) (xy 264.020493 -103.382903) (xy 264.008367 -103.328466) (xy 264.004296 -103.272844)
			(xy 256.764683 -103.272844) (xy 256.738228 -103.289633) (xy 256.680389 -103.31685) (xy 256.619596 -103.336603)
			(xy 256.556806 -103.348581) (xy 256.49301 -103.352595) (xy 256.429214 -103.348581) (xy 256.366424 -103.336603)
			(xy 256.305631 -103.31685) (xy 256.247792 -103.289633) (xy 256.193821 -103.255382) (xy 256.144568 -103.214637)
			(xy 256.100811 -103.16804) (xy 256.063238 -103.116325) (xy 256.032444 -103.06031) (xy 256.008912 -103.000877)
			(xy 255.993015 -102.938963) (xy 255.985004 -102.875545) (xy 217.406174 -102.875545) (xy 217.394032 -102.897631)
			(xy 217.356459 -102.949346) (xy 217.312702 -102.995943) (xy 217.263449 -103.036688) (xy 217.209478 -103.070939)
			(xy 217.151639 -103.098156) (xy 217.090846 -103.117909) (xy 217.028056 -103.129887) (xy 216.96426 -103.133901)
			(xy 216.900464 -103.129887) (xy 216.837674 -103.117909) (xy 216.776881 -103.098156) (xy 216.719042 -103.070939)
			(xy 216.665071 -103.036688) (xy 216.615818 -102.995943) (xy 216.572061 -102.949346) (xy 216.534488 -102.897631)
			(xy 216.503694 -102.841616) (xy 216.480162 -102.782183) (xy 216.464265 -102.720269) (xy 216.456254 -102.656851)
			(xy 213.222156 -102.656851) (xy 213.239944 -102.680731) (xy 213.271873 -102.737521) (xy 213.296291 -102.797923)
			(xy 213.312797 -102.860947) (xy 213.321123 -102.925563) (xy 213.321646 -102.958138) (xy 213.321137 -102.991192)
			(xy 213.312572 -103.056744) (xy 213.295579 -103.120631) (xy 213.270444 -103.181775) (xy 213.237593 -103.239143)
			(xy 213.197579 -103.291767) (xy 213.151079 -103.338758) (xy 213.125304 -103.359458) (xy 213.12505 -103.359712)
			(xy 213.118212 -103.365573) (xy 213.10876 -103.380882) (xy 213.105212 -103.398521) (xy 213.106254 -103.407464)
			(xy 213.120224 -103.495348) (xy 213.121981 -103.504198) (xy 213.130763 -103.519947) (xy 213.144422 -103.531719)
			(xy 213.152736 -103.535226) (xy 213.15299 -103.535226) (xy 213.182015 -103.546314) (xy 213.237378 -103.574522)
			(xy 213.28889 -103.609267) (xy 213.335784 -103.650031) (xy 213.37736 -103.696206) (xy 213.413 -103.747103)
			(xy 213.416614 -103.7539) (xy 249.580709 -103.7539) (xy 249.584723 -103.690109) (xy 249.596699 -103.627324)
			(xy 249.61645 -103.566535) (xy 249.643664 -103.5087) (xy 249.677911 -103.454733) (xy 249.718652 -103.405483)
			(xy 249.765244 -103.361727) (xy 249.816953 -103.324155) (xy 249.872963 -103.293361) (xy 249.93239 -103.269829)
			(xy 249.994299 -103.25393) (xy 250.057711 -103.245916) (xy 250.08967 -103.245412) (xy 250.089924 -103.245412)
			(xy 250.123355 -103.245949) (xy 250.189641 -103.254713) (xy 250.254207 -103.272088) (xy 250.315939 -103.297774)
			(xy 250.373773 -103.331328) (xy 250.400566 -103.35133) (xy 250.407927 -103.356503) (xy 250.425098 -103.361837)
			(xy 250.434094 -103.361744) (xy 250.464066 -103.360474) (xy 250.473101 -103.359652) (xy 250.489758 -103.352488)
			(xy 250.496578 -103.346504) (xy 250.520256 -103.324876) (xy 250.572054 -103.287067) (xy 250.628196 -103.256072)
			(xy 250.68779 -103.232383) (xy 250.74989 -103.216378) (xy 250.813509 -103.208309) (xy 250.845574 -103.20782)
			(xy 250.877539 -103.208243) (xy 250.940966 -103.216253) (xy 251.002888 -103.232149) (xy 251.06233 -103.255681)
			(xy 251.118354 -103.286478) (xy 251.170076 -103.324054) (xy 251.21668 -103.367816) (xy 251.257432 -103.417074)
			(xy 251.291688 -103.471051) (xy 251.318909 -103.528897) (xy 251.338665 -103.589698) (xy 251.350645 -103.652496)
			(xy 251.35466 -103.7163) (xy 251.350645 -103.780104) (xy 251.338665 -103.842902) (xy 251.325734 -103.882698)
			(xy 325.287892 -103.882698) (xy 325.291963 -103.827076) (xy 325.304089 -103.772639) (xy 325.324012 -103.720548)
			(xy 325.351308 -103.671913) (xy 325.385394 -103.62777) (xy 325.425543 -103.589061) (xy 325.470901 -103.55661)
			(xy 325.520501 -103.531109) (xy 325.573285 -103.513102) (xy 325.628128 -103.502972) (xy 325.683862 -103.500935)
			(xy 325.739299 -103.507035) (xy 325.793256 -103.521141) (xy 325.844585 -103.542953) (xy 325.892191 -103.572007)
			(xy 325.935059 -103.607682) (xy 325.972276 -103.649219) (xy 326.003049 -103.695732) (xy 326.026721 -103.746229)
			(xy 326.042789 -103.799636) (xy 326.050909 -103.854812) (xy 326.051418 -103.882698) (xy 326.050909 -103.910584)
			(xy 326.042789 -103.96576) (xy 326.026721 -104.019167) (xy 326.003049 -104.069664) (xy 325.972276 -104.116177)
			(xy 325.935059 -104.157714) (xy 325.892191 -104.193389) (xy 325.844585 -104.222443) (xy 325.793256 -104.244255)
			(xy 325.739299 -104.258361) (xy 325.683862 -104.264461) (xy 325.628128 -104.262424) (xy 325.573285 -104.252294)
			(xy 325.520501 -104.234287) (xy 325.470901 -104.208786) (xy 325.425543 -104.176335) (xy 325.385394 -104.137626)
			(xy 325.351308 -104.093483) (xy 325.324012 -104.044848) (xy 325.304089 -103.992757) (xy 325.291963 -103.93832)
			(xy 325.287892 -103.882698) (xy 251.325734 -103.882698) (xy 251.318909 -103.903703) (xy 251.291688 -103.961549)
			(xy 251.257432 -104.015526) (xy 251.21668 -104.064784) (xy 251.170076 -104.108546) (xy 251.118354 -104.146122)
			(xy 251.06233 -104.176919) (xy 251.002888 -104.200451) (xy 250.940966 -104.216347) (xy 250.877539 -104.224357)
			(xy 250.845574 -104.224836) (xy 250.84532 -104.224836) (xy 250.811889 -104.224286) (xy 250.745603 -104.215526)
			(xy 250.681037 -104.198155) (xy 250.619305 -104.172472) (xy 250.561471 -104.13892) (xy 250.534678 -104.118918)
			(xy 250.527303 -104.113769) (xy 250.510143 -104.108419) (xy 250.50115 -104.108504) (xy 250.471178 -104.109774)
			(xy 250.462144 -104.110605) (xy 250.445486 -104.117762) (xy 250.438666 -104.123744) (xy 250.415019 -104.145407)
			(xy 250.363213 -104.183211) (xy 250.307065 -104.2142) (xy 250.247465 -104.237882) (xy 250.18536 -104.253881)
			(xy 250.121736 -104.261942) (xy 250.08967 -104.262428) (xy 250.057711 -104.261884) (xy 249.994299 -104.25387)
			(xy 249.93239 -104.237971) (xy 249.872963 -104.214439) (xy 249.816953 -104.183645) (xy 249.765244 -104.146073)
			(xy 249.718652 -104.102317) (xy 249.677911 -104.053067) (xy 249.643664 -103.9991) (xy 249.61645 -103.941265)
			(xy 249.596699 -103.880476) (xy 249.584723 -103.817691) (xy 249.580709 -103.7539) (xy 213.416614 -103.7539)
			(xy 213.44217 -103.801965) (xy 213.464438 -103.859972) (xy 213.479469 -103.920261) (xy 213.487042 -103.981933)
			(xy 213.487508 -104.013) (xy 213.487006 -104.044961) (xy 213.478995 -104.108379) (xy 213.463098 -104.170293)
			(xy 213.439566 -104.229726) (xy 213.408772 -104.285741) (xy 213.371199 -104.337456) (xy 213.327442 -104.384053)
			(xy 213.278189 -104.424798) (xy 213.224218 -104.459049) (xy 213.166379 -104.486266) (xy 213.105586 -104.506019)
			(xy 213.042796 -104.517997) (xy 212.979 -104.522011) (xy 212.915204 -104.517997) (xy 212.852414 -104.506019)
			(xy 212.791621 -104.486266) (xy 212.733782 -104.459049) (xy 212.679811 -104.424798) (xy 212.630558 -104.384053)
			(xy 212.586801 -104.337456) (xy 212.549228 -104.285741) (xy 212.518434 -104.229726) (xy 212.494902 -104.170293)
			(xy 212.479005 -104.108379) (xy 212.470994 -104.044961) (xy 212.470492 -104.013) (xy 212.471052 -103.979948)
			(xy 212.479611 -103.914399) (xy 212.496597 -103.850514) (xy 212.521724 -103.789371) (xy 212.554567 -103.732002)
			(xy 212.594572 -103.679377) (xy 212.641063 -103.632383) (xy 212.666834 -103.61168) (xy 212.667088 -103.611426)
			(xy 212.673968 -103.60561) (xy 212.683407 -103.590278) (xy 212.686937 -103.572622) (xy 212.685884 -103.563674)
			(xy 212.671914 -103.47579) (xy 212.670172 -103.466937) (xy 212.66138 -103.451191) (xy 212.647716 -103.43942)
			(xy 212.639402 -103.435912) (xy 212.639148 -103.435912) (xy 212.61011 -103.424855) (xy 212.554744 -103.396646)
			(xy 212.503229 -103.3619) (xy 212.456334 -103.321133) (xy 212.414757 -103.274955) (xy 212.379118 -103.224053)
			(xy 212.34995 -103.169187) (xy 212.327686 -103.111175) (xy 212.312659 -103.050882) (xy 212.305093 -102.989207)
			(xy 212.30463 -102.958138) (xy 212.305217 -102.924335) (xy 212.314175 -102.857324) (xy 212.331939 -102.792093)
			(xy 212.358193 -102.729793) (xy 212.392476 -102.671523) (xy 212.434182 -102.618314) (xy 212.482574 -102.571103)
			(xy 212.509354 -102.550468) (xy 212.518387 -102.543031) (xy 212.529107 -102.522261) (xy 212.529928 -102.51059)
			(xy 212.531198 -102.418134) (xy 212.521292 -102.397052) (xy 212.512148 -102.389686) (xy 212.49741 -102.377654)
			(xy 212.469568 -102.351718) (xy 212.456522 -102.33787) (xy 212.44941 -102.33025) (xy 212.43036 -102.321868)
			(xy 212.335364 -102.320598) (xy 212.316314 -102.328726) (xy 212.309202 -102.336092) (xy 212.285177 -102.36007)
			(xy 212.231848 -102.402062) (xy 212.173407 -102.436589) (xy 212.110893 -102.463035) (xy 212.045417 -102.480932)
			(xy 211.978143 -102.48996) (xy 211.944204 -102.490524) (xy 211.912242 -102.490011) (xy 211.848823 -102.482)
			(xy 211.786909 -102.466103) (xy 211.727474 -102.442572) (xy 211.671458 -102.411777) (xy 211.619743 -102.374205)
			(xy 211.573145 -102.330446) (xy 211.532399 -102.281193) (xy 211.498147 -102.227221) (xy 211.47093 -102.169382)
			(xy 211.451176 -102.108588) (xy 211.439198 -102.045797) (xy 211.435184 -101.982) (xy 210.8929 -101.982)
			(xy 210.893152 -101.998018) (xy 210.89265 -102.029979) (xy 210.884639 -102.093397) (xy 210.868742 -102.155311)
			(xy 210.84521 -102.214744) (xy 210.814416 -102.270759) (xy 210.776843 -102.322474) (xy 210.733086 -102.369071)
			(xy 210.683833 -102.409816) (xy 210.629862 -102.444067) (xy 210.572023 -102.471284) (xy 210.51123 -102.491037)
			(xy 210.44844 -102.503015) (xy 210.384644 -102.507029) (xy 210.320848 -102.503015) (xy 210.258058 -102.491037)
			(xy 210.197265 -102.471284) (xy 210.139426 -102.444067) (xy 210.085455 -102.409816) (xy 210.036202 -102.369071)
			(xy 209.992445 -102.322474) (xy 209.954872 -102.270759) (xy 209.924078 -102.214744) (xy 209.900546 -102.155311)
			(xy 209.884649 -102.093397) (xy 209.876638 -102.029979) (xy 200.030975 -102.029979) (xy 200.034252 -102.031521)
			(xy 200.088223 -102.065772) (xy 200.137476 -102.106517) (xy 200.181233 -102.153114) (xy 200.218806 -102.204829)
			(xy 200.2496 -102.260844) (xy 200.273132 -102.320277) (xy 200.289029 -102.382191) (xy 200.29704 -102.445609)
			(xy 200.297542 -102.47757) (xy 200.29704 -102.509531) (xy 200.289029 -102.572949) (xy 200.273132 -102.634863)
			(xy 200.267946 -102.647961) (xy 201.929994 -102.647961) (xy 201.929994 -102.584039) (xy 201.938005 -102.520621)
			(xy 201.953902 -102.458707) (xy 201.977434 -102.399274) (xy 202.008228 -102.343259) (xy 202.045801 -102.291544)
			(xy 202.089558 -102.244947) (xy 202.138811 -102.204202) (xy 202.192782 -102.169951) (xy 202.250621 -102.142734)
			(xy 202.311414 -102.122981) (xy 202.374204 -102.111003) (xy 202.438 -102.10699) (xy 202.501796 -102.111003)
			(xy 202.564586 -102.122981) (xy 202.625379 -102.142734) (xy 202.683218 -102.169951) (xy 202.737189 -102.204202)
			(xy 202.786442 -102.244947) (xy 202.830199 -102.291544) (xy 202.867772 -102.343259) (xy 202.898566 -102.399274)
			(xy 202.922098 -102.458707) (xy 202.937995 -102.520621) (xy 202.946006 -102.584039) (xy 202.946508 -102.616)
			(xy 202.946094 -102.642373) (xy 203.558642 -102.642373) (xy 203.558642 -102.578451) (xy 203.566653 -102.515033)
			(xy 203.58255 -102.453119) (xy 203.606082 -102.393686) (xy 203.636876 -102.337671) (xy 203.674449 -102.285956)
			(xy 203.718206 -102.239359) (xy 203.767459 -102.198614) (xy 203.82143 -102.164363) (xy 203.879269 -102.137146)
			(xy 203.940062 -102.117393) (xy 204.002852 -102.105415) (xy 204.066648 -102.101402) (xy 204.130444 -102.105415)
			(xy 204.193234 -102.117393) (xy 204.254027 -102.137146) (xy 204.311866 -102.164363) (xy 204.365837 -102.198614)
			(xy 204.41509 -102.239359) (xy 204.458847 -102.285956) (xy 204.49642 -102.337671) (xy 204.527214 -102.393686)
			(xy 204.550746 -102.453119) (xy 204.566643 -102.515033) (xy 204.574654 -102.578451) (xy 204.574876 -102.5926)
			(xy 206.030621 -102.5926) (xy 206.034635 -102.528809) (xy 206.046612 -102.466023) (xy 206.066363 -102.405234)
			(xy 206.093578 -102.3474) (xy 206.127826 -102.293433) (xy 206.168568 -102.244183) (xy 206.215161 -102.200428)
			(xy 206.266871 -102.162858) (xy 206.322882 -102.132065) (xy 206.382311 -102.108535) (xy 206.44422 -102.092638)
			(xy 206.507633 -102.084626) (xy 206.539592 -102.084124) (xy 206.570248 -102.08459) (xy 206.631116 -102.091959)
			(xy 206.690656 -102.106592) (xy 206.748006 -102.128275) (xy 206.802334 -102.156695) (xy 206.852851 -102.19144)
			(xy 206.876142 -102.211378) (xy 206.883585 -102.217429) (xy 206.901603 -102.223962) (xy 206.911194 -102.224078)
			(xy 206.942436 -102.223316) (xy 206.952036 -102.222591) (xy 206.96966 -102.214872) (xy 206.976726 -102.20833)
			(xy 207.000621 -102.185292) (xy 207.05336 -102.144988) (xy 207.110895 -102.111889) (xy 207.172248 -102.086559)
			(xy 207.236375 -102.069428) (xy 207.302186 -102.060787) (xy 207.335374 -102.060248) (xy 207.366763 -102.06067)
			(xy 207.429062 -102.06841) (xy 207.489934 -102.083763) (xy 207.548452 -102.106496) (xy 207.603725 -102.136262)
			(xy 207.654911 -102.172608) (xy 207.701232 -102.214981) (xy 207.721962 -102.238556) (xy 207.729582 -102.247446)
			(xy 207.75041 -102.256844) (xy 207.852772 -102.253796) (xy 207.873092 -102.243382) (xy 207.880204 -102.234238)
			(xy 207.900845 -102.207954) (xy 207.947942 -102.160534) (xy 208.00085 -102.119699) (xy 208.058655 -102.086153)
			(xy 208.120359 -102.060476) (xy 208.184897 -102.043111) (xy 208.251155 -102.034358) (xy 208.284572 -102.033832)
			(xy 208.316538 -102.034231) (xy 208.379966 -102.042241) (xy 208.44189 -102.058137) (xy 208.501334 -102.08167)
			(xy 208.557359 -102.112467) (xy 208.609082 -102.150044) (xy 208.655688 -102.193807) (xy 208.696441 -102.243066)
			(xy 208.730698 -102.297045) (xy 208.75792 -102.354892) (xy 208.777677 -102.415695) (xy 208.789657 -102.478494)
			(xy 208.793672 -102.5423) (xy 208.789657 -102.606106) (xy 208.777677 -102.668905) (xy 208.75792 -102.729708)
			(xy 208.730698 -102.787555) (xy 208.696441 -102.841534) (xy 208.655688 -102.890793) (xy 208.609082 -102.934556)
			(xy 208.557359 -102.972133) (xy 208.524676 -102.990099) (xy 208.953856 -102.990099) (xy 208.953856 -102.926177)
			(xy 208.961867 -102.862759) (xy 208.977764 -102.800845) (xy 209.001296 -102.741412) (xy 209.03209 -102.685397)
			(xy 209.069663 -102.633682) (xy 209.11342 -102.587085) (xy 209.162673 -102.54634) (xy 209.216644 -102.512089)
			(xy 209.274483 -102.484872) (xy 209.335276 -102.465119) (xy 209.398066 -102.453141) (xy 209.461862 -102.449128)
			(xy 209.525658 -102.453141) (xy 209.588448 -102.465119) (xy 209.649241 -102.484872) (xy 209.70708 -102.512089)
			(xy 209.761051 -102.54634) (xy 209.810304 -102.587085) (xy 209.854061 -102.633682) (xy 209.891634 -102.685397)
			(xy 209.922428 -102.741412) (xy 209.94596 -102.800845) (xy 209.961857 -102.862759) (xy 209.969868 -102.926177)
			(xy 209.97037 -102.958138) (xy 209.969868 -102.990099) (xy 209.961857 -103.053517) (xy 209.94596 -103.115431)
			(xy 209.922428 -103.174864) (xy 209.891634 -103.230879) (xy 209.854061 -103.282594) (xy 209.810304 -103.329191)
			(xy 209.761051 -103.369936) (xy 209.70708 -103.404187) (xy 209.649241 -103.431404) (xy 209.588448 -103.451157)
			(xy 209.525658 -103.463135) (xy 209.461862 -103.467149) (xy 209.398066 -103.463135) (xy 209.335276 -103.451157)
			(xy 209.274483 -103.431404) (xy 209.216644 -103.404187) (xy 209.162673 -103.369936) (xy 209.11342 -103.329191)
			(xy 209.069663 -103.282594) (xy 209.03209 -103.230879) (xy 209.001296 -103.174864) (xy 208.977764 -103.115431)
			(xy 208.961867 -103.053517) (xy 208.953856 -102.990099) (xy 208.524676 -102.990099) (xy 208.501334 -103.00293)
			(xy 208.44189 -103.026463) (xy 208.379966 -103.042359) (xy 208.316538 -103.050369) (xy 208.284572 -103.050848)
			(xy 208.253184 -103.050396) (xy 208.190886 -103.042661) (xy 208.130015 -103.027313) (xy 208.071497 -103.004585)
			(xy 208.016224 -102.974824) (xy 207.965037 -102.938482) (xy 207.918715 -102.896113) (xy 207.897984 -102.87254)
			(xy 207.890364 -102.86365) (xy 207.869536 -102.854252) (xy 207.767174 -102.8573) (xy 207.746854 -102.867714)
			(xy 207.739742 -102.876858) (xy 207.719073 -102.90312) (xy 207.671981 -102.95054) (xy 207.619078 -102.991377)
			(xy 207.561278 -103.024926) (xy 207.499578 -103.050607) (xy 207.435044 -103.067977) (xy 207.368789 -103.076735)
			(xy 207.335374 -103.077264) (xy 207.304717 -103.076821) (xy 207.243848 -103.069448) (xy 207.184307 -103.054811)
			(xy 207.126958 -103.033123) (xy 207.07263 -103.004699) (xy 207.022114 -102.969951) (xy 206.998824 -102.95001)
			(xy 206.991393 -102.943942) (xy 206.973366 -102.937419) (xy 206.963772 -102.93731) (xy 206.93253 -102.938072)
			(xy 206.922935 -102.938833) (xy 206.90531 -102.946527) (xy 206.89824 -102.953058) (xy 206.874358 -102.97611)
			(xy 206.821617 -103.016413) (xy 206.764079 -103.04951) (xy 206.702724 -103.074838) (xy 206.638594 -103.091966)
			(xy 206.572781 -103.100603) (xy 206.539592 -103.10114) (xy 206.507633 -103.100574) (xy 206.44422 -103.092562)
			(xy 206.382311 -103.076665) (xy 206.322882 -103.053135) (xy 206.266871 -103.022342) (xy 206.215161 -102.984772)
			(xy 206.168568 -102.941017) (xy 206.127826 -102.891767) (xy 206.093578 -102.8378) (xy 206.066363 -102.779966)
			(xy 206.046612 -102.719177) (xy 206.034635 -102.656391) (xy 206.030621 -102.5926) (xy 204.574876 -102.5926)
			(xy 204.575156 -102.610412) (xy 204.574654 -102.642373) (xy 204.566643 -102.705791) (xy 204.550746 -102.767705)
			(xy 204.527214 -102.827138) (xy 204.49642 -102.883153) (xy 204.458847 -102.934868) (xy 204.41509 -102.981465)
			(xy 204.365837 -103.02221) (xy 204.311866 -103.056461) (xy 204.254027 -103.083678) (xy 204.193234 -103.103431)
			(xy 204.130444 -103.115409) (xy 204.066648 -103.119423) (xy 204.002852 -103.115409) (xy 203.940062 -103.103431)
			(xy 203.879269 -103.083678) (xy 203.82143 -103.056461) (xy 203.767459 -103.02221) (xy 203.718206 -102.981465)
			(xy 203.674449 -102.934868) (xy 203.636876 -102.883153) (xy 203.606082 -102.827138) (xy 203.58255 -102.767705)
			(xy 203.566653 -102.705791) (xy 203.558642 -102.642373) (xy 202.946094 -102.642373) (xy 202.946006 -102.647961)
			(xy 202.937995 -102.711379) (xy 202.922098 -102.773293) (xy 202.898566 -102.832726) (xy 202.867772 -102.888741)
			(xy 202.830199 -102.940456) (xy 202.786442 -102.987053) (xy 202.737189 -103.027798) (xy 202.683218 -103.062049)
			(xy 202.625379 -103.089266) (xy 202.564586 -103.109019) (xy 202.501796 -103.120997) (xy 202.438 -103.125011)
			(xy 202.374204 -103.120997) (xy 202.311414 -103.109019) (xy 202.250621 -103.089266) (xy 202.192782 -103.062049)
			(xy 202.138811 -103.027798) (xy 202.089558 -102.987053) (xy 202.045801 -102.940456) (xy 202.008228 -102.888741)
			(xy 201.977434 -102.832726) (xy 201.953902 -102.773293) (xy 201.938005 -102.711379) (xy 201.929994 -102.647961)
			(xy 200.267946 -102.647961) (xy 200.2496 -102.694296) (xy 200.218806 -102.750311) (xy 200.181233 -102.802026)
			(xy 200.137476 -102.848623) (xy 200.088223 -102.889368) (xy 200.034252 -102.923619) (xy 199.976413 -102.950836)
			(xy 199.91562 -102.970589) (xy 199.85283 -102.982567) (xy 199.789034 -102.986581) (xy 199.725238 -102.982567)
			(xy 199.662448 -102.970589) (xy 199.601655 -102.950836) (xy 199.543816 -102.923619) (xy 199.489845 -102.889368)
			(xy 199.440592 -102.848623) (xy 199.396835 -102.802026) (xy 199.359262 -102.750311) (xy 199.328468 -102.694296)
			(xy 199.304936 -102.634863) (xy 199.289039 -102.572949) (xy 199.281028 -102.509531) (xy 198.703181 -102.509531)
			(xy 198.699849 -102.562488) (xy 198.687874 -102.625269) (xy 198.668124 -102.686055) (xy 198.640912 -102.743886)
			(xy 198.606666 -102.797851) (xy 198.565928 -102.847098) (xy 198.519338 -102.890852) (xy 198.467632 -102.928421)
			(xy 198.411625 -102.959214) (xy 198.352201 -102.982745) (xy 198.290296 -102.998642) (xy 198.226887 -103.006656)
			(xy 198.19493 -103.00716) (xy 198.160979 -103.006605) (xy 198.093684 -102.997535) (xy 198.028194 -102.979593)
			(xy 197.965673 -102.953097) (xy 197.907233 -102.91852) (xy 197.880224 -102.89794) (xy 197.871083 -102.891515)
			(xy 197.849365 -102.886401) (xy 197.827523 -102.890953) (xy 197.818248 -102.897178) (xy 197.791766 -102.916368)
			(xy 197.734832 -102.948548) (xy 197.674244 -102.973171) (xy 197.611002 -102.98983) (xy 197.546147 -102.998251)
			(xy 197.513448 -102.998778) (xy 197.481482 -102.99836) (xy 197.418053 -102.990353) (xy 197.356128 -102.974458)
			(xy 197.296683 -102.950927) (xy 197.240657 -102.920131) (xy 197.188933 -102.882556) (xy 197.142326 -102.838793)
			(xy 197.101572 -102.789534) (xy 197.067313 -102.735556) (xy 197.040091 -102.677709) (xy 197.020334 -102.616906)
			(xy 197.008353 -102.554106) (xy 197.004338 -102.4903) (xy 193.274255 -102.4903) (xy 193.261442 -102.503945)
			(xy 193.212189 -102.54469) (xy 193.158218 -102.578941) (xy 193.100379 -102.606158) (xy 193.039586 -102.625911)
			(xy 192.976796 -102.637889) (xy 192.913 -102.641903) (xy 192.849204 -102.637889) (xy 192.786414 -102.625911)
			(xy 192.725621 -102.606158) (xy 192.667782 -102.578941) (xy 192.613811 -102.54469) (xy 192.564558 -102.503945)
			(xy 192.520801 -102.457348) (xy 192.483228 -102.405633) (xy 192.452434 -102.349618) (xy 192.428902 -102.290185)
			(xy 192.413005 -102.228271) (xy 192.404994 -102.164853) (xy 184.838848 -102.164853) (xy 184.838848 -103.197363)
			(xy 189.38976 -103.197363) (xy 189.38976 -103.133441) (xy 189.397771 -103.070023) (xy 189.413668 -103.008109)
			(xy 189.4372 -102.948676) (xy 189.467994 -102.892661) (xy 189.505567 -102.840946) (xy 189.549324 -102.794349)
			(xy 189.598577 -102.753604) (xy 189.652548 -102.719353) (xy 189.710387 -102.692136) (xy 189.77118 -102.672383)
			(xy 189.83397 -102.660405) (xy 189.897766 -102.656392) (xy 189.961562 -102.660405) (xy 190.024352 -102.672383)
			(xy 190.085145 -102.692136) (xy 190.142984 -102.719353) (xy 190.196955 -102.753604) (xy 190.246208 -102.794349)
			(xy 190.289965 -102.840946) (xy 190.327538 -102.892661) (xy 190.358332 -102.948676) (xy 190.381864 -103.008109)
			(xy 190.397761 -103.070023) (xy 190.405772 -103.133441) (xy 190.406274 -103.165402) (xy 190.405772 -103.197363)
			(xy 190.397761 -103.260781) (xy 190.381864 -103.322695) (xy 190.358332 -103.382128) (xy 190.327538 -103.438143)
			(xy 190.289965 -103.489858) (xy 190.246208 -103.536455) (xy 190.196955 -103.5772) (xy 190.142984 -103.611451)
			(xy 190.085145 -103.638668) (xy 190.024352 -103.658421) (xy 189.961562 -103.670399) (xy 189.897766 -103.674413)
			(xy 189.83397 -103.670399) (xy 189.77118 -103.658421) (xy 189.710387 -103.638668) (xy 189.652548 -103.611451)
			(xy 189.598577 -103.5772) (xy 189.549324 -103.536455) (xy 189.505567 -103.489858) (xy 189.467994 -103.438143)
			(xy 189.4372 -103.382128) (xy 189.413668 -103.322695) (xy 189.397771 -103.260781) (xy 189.38976 -103.197363)
			(xy 184.838848 -103.197363) (xy 184.838848 -103.857763) (xy 191.835526 -103.857763) (xy 191.835526 -103.793841)
			(xy 191.843537 -103.730423) (xy 191.859434 -103.668509) (xy 191.882966 -103.609076) (xy 191.91376 -103.553061)
			(xy 191.951333 -103.501346) (xy 191.99509 -103.454749) (xy 192.044343 -103.414004) (xy 192.098314 -103.379753)
			(xy 192.156153 -103.352536) (xy 192.216946 -103.332783) (xy 192.279736 -103.320805) (xy 192.343532 -103.316792)
			(xy 192.407328 -103.320805) (xy 192.470118 -103.332783) (xy 192.530911 -103.352536) (xy 192.58875 -103.379753)
			(xy 192.642721 -103.414004) (xy 192.691974 -103.454749) (xy 192.735731 -103.501346) (xy 192.773304 -103.553061)
			(xy 192.804098 -103.609076) (xy 192.82763 -103.668509) (xy 192.843527 -103.730423) (xy 192.851538 -103.793841)
			(xy 192.85204 -103.825802) (xy 192.851538 -103.857763) (xy 192.843527 -103.921181) (xy 192.82763 -103.983095)
			(xy 192.804098 -104.042528) (xy 192.773304 -104.098543) (xy 192.735731 -104.150258) (xy 192.691974 -104.196855)
			(xy 192.681766 -104.2053) (xy 195.111367 -104.2053) (xy 195.115381 -104.141502) (xy 195.127359 -104.078711)
			(xy 195.147112 -104.017916) (xy 195.174329 -103.960076) (xy 195.208581 -103.906103) (xy 195.249327 -103.856848)
			(xy 195.295924 -103.813089) (xy 195.347639 -103.775514) (xy 195.403655 -103.744718) (xy 195.46309 -103.721185)
			(xy 195.525005 -103.705286) (xy 195.588424 -103.697273) (xy 195.620386 -103.69677) (xy 195.62064 -103.69677)
			(xy 195.654756 -103.697347) (xy 195.722374 -103.706479) (xy 195.788167 -103.724561) (xy 195.819776 -103.73741)
			(xy 195.828666 -103.74122) (xy 195.847716 -103.741728) (xy 195.931028 -103.71201) (xy 195.945506 -103.699564)
			(xy 195.949824 -103.690928) (xy 195.964451 -103.663746) (xy 195.999302 -103.612797) (xy 196.040064 -103.566441)
			(xy 196.086138 -103.525361) (xy 196.136846 -103.49016) (xy 196.191443 -103.461357) (xy 196.249125 -103.439375)
			(xy 196.309044 -103.424538) (xy 196.370318 -103.417063) (xy 196.401182 -103.416608) (xy 196.433146 -103.417056)
			(xy 196.49657 -103.425066) (xy 196.558491 -103.440963) (xy 196.61793 -103.464495) (xy 196.673952 -103.495291)
			(xy 196.725671 -103.532866) (xy 196.772274 -103.576627) (xy 196.813024 -103.625884) (xy 196.847279 -103.679859)
			(xy 196.874499 -103.737703) (xy 196.894254 -103.798502) (xy 196.906233 -103.861298) (xy 196.910248 -103.9251)
			(xy 196.906233 -103.988902) (xy 196.903292 -104.004321) (xy 198.439018 -104.004321) (xy 198.439018 -103.940399)
			(xy 198.447029 -103.876981) (xy 198.462926 -103.815067) (xy 198.486458 -103.755634) (xy 198.517252 -103.699619)
			(xy 198.554825 -103.647904) (xy 198.598582 -103.601307) (xy 198.647835 -103.560562) (xy 198.701806 -103.526311)
			(xy 198.759645 -103.499094) (xy 198.820438 -103.479341) (xy 198.883228 -103.467363) (xy 198.947024 -103.46335)
			(xy 199.01082 -103.467363) (xy 199.07361 -103.479341) (xy 199.134403 -103.499094) (xy 199.192242 -103.526311)
			(xy 199.246213 -103.560562) (xy 199.295466 -103.601307) (xy 199.339223 -103.647904) (xy 199.376796 -103.699619)
			(xy 199.40759 -103.755634) (xy 199.431122 -103.815067) (xy 199.447019 -103.876981) (xy 199.45503 -103.940399)
			(xy 199.455532 -103.97236) (xy 199.45503 -104.004321) (xy 199.447019 -104.067739) (xy 199.431122 -104.129653)
			(xy 199.40759 -104.189086) (xy 199.376796 -104.245101) (xy 199.339223 -104.296816) (xy 199.295466 -104.343413)
			(xy 199.246213 -104.384158) (xy 199.192242 -104.418409) (xy 199.134403 -104.445626) (xy 199.07361 -104.465379)
			(xy 199.01082 -104.477357) (xy 198.947024 -104.481371) (xy 198.883228 -104.477357) (xy 198.820438 -104.465379)
			(xy 198.759645 -104.445626) (xy 198.701806 -104.418409) (xy 198.647835 -104.384158) (xy 198.598582 -104.343413)
			(xy 198.554825 -104.296816) (xy 198.517252 -104.245101) (xy 198.486458 -104.189086) (xy 198.462926 -104.129653)
			(xy 198.447029 -104.067739) (xy 198.439018 -104.004321) (xy 196.903292 -104.004321) (xy 196.894254 -104.051698)
			(xy 196.874499 -104.112497) (xy 196.847279 -104.170341) (xy 196.813024 -104.224316) (xy 196.772274 -104.273573)
			(xy 196.725671 -104.317334) (xy 196.673952 -104.354909) (xy 196.61793 -104.385705) (xy 196.558491 -104.409237)
			(xy 196.49657 -104.425134) (xy 196.433146 -104.433144) (xy 196.401182 -104.433624) (xy 196.400928 -104.433624)
			(xy 196.366812 -104.433058) (xy 196.299193 -104.423922) (xy 196.2334 -104.405836) (xy 196.201792 -104.392984)
			(xy 196.192902 -104.389174) (xy 196.173852 -104.388666) (xy 196.09054 -104.418384) (xy 196.076062 -104.43083)
			(xy 196.071744 -104.439466) (xy 196.057138 -104.46666) (xy 196.022285 -104.51761) (xy 195.981521 -104.563966)
			(xy 195.959947 -104.5832) (xy 215.776298 -104.5832) (xy 215.780312 -104.519404) (xy 215.79229 -104.456614)
			(xy 215.812044 -104.39582) (xy 215.839261 -104.337982) (xy 215.873513 -104.284011) (xy 215.91426 -104.234758)
			(xy 215.960858 -104.191001) (xy 216.012573 -104.15343) (xy 216.068589 -104.122636) (xy 216.128024 -104.099106)
			(xy 216.189938 -104.083211) (xy 216.253357 -104.075202) (xy 216.285318 -104.074722) (xy 216.316584 -104.075152)
			(xy 216.378645 -104.082811) (xy 216.439298 -104.098024) (xy 216.497627 -104.12056) (xy 216.552752 -104.15008)
			(xy 216.603841 -104.186138) (xy 216.650122 -104.228189) (xy 216.690895 -104.275599) (xy 216.725547 -104.327652)
			(xy 216.739978 -104.355392) (xy 216.744271 -104.363283) (xy 216.757271 -104.375656) (xy 216.765378 -104.379522)
			(xy 216.793064 -104.391206) (xy 216.801386 -104.394465) (xy 216.819217 -104.395505) (xy 216.827862 -104.393238)
			(xy 216.864186 -104.382806) (xy 216.93892 -104.371592) (xy 216.976706 -104.370886) (xy 217.007437 -104.37135)
			(xy 217.06845 -104.378759) (xy 217.128126 -104.393469) (xy 217.185594 -104.415264) (xy 217.240015 -104.443827)
			(xy 217.290597 -104.478741) (xy 217.336602 -104.519498) (xy 217.377359 -104.565503) (xy 217.378695 -104.567439)
			(xy 219.157798 -104.567439) (xy 219.157798 -104.503517) (xy 219.165809 -104.440099) (xy 219.181706 -104.378185)
			(xy 219.205238 -104.318752) (xy 219.236032 -104.262737) (xy 219.273605 -104.211022) (xy 219.317362 -104.164425)
			(xy 219.366615 -104.12368) (xy 219.420586 -104.089429) (xy 219.478425 -104.062212) (xy 219.539218 -104.042459)
			(xy 219.602008 -104.030481) (xy 219.665804 -104.026468) (xy 219.7296 -104.030481) (xy 219.79239 -104.042459)
			(xy 219.853183 -104.062212) (xy 219.911022 -104.089429) (xy 219.964993 -104.12368) (xy 220.014246 -104.164425)
			(xy 220.058003 -104.211022) (xy 220.095576 -104.262737) (xy 220.12637 -104.318752) (xy 220.149902 -104.378185)
			(xy 220.165799 -104.440099) (xy 220.17381 -104.503517) (xy 220.173876 -104.507749) (xy 271.967446 -104.507749)
			(xy 271.967446 -104.443827) (xy 271.975457 -104.380409) (xy 271.991354 -104.318495) (xy 272.014886 -104.259062)
			(xy 272.04568 -104.203047) (xy 272.083253 -104.151332) (xy 272.12701 -104.104735) (xy 272.176263 -104.06399)
			(xy 272.230234 -104.029739) (xy 272.288073 -104.002522) (xy 272.348866 -103.982769) (xy 272.411656 -103.970791)
			(xy 272.475452 -103.966778) (xy 272.539248 -103.970791) (xy 272.602038 -103.982769) (xy 272.662831 -104.002522)
			(xy 272.72067 -104.029739) (xy 272.774641 -104.06399) (xy 272.823894 -104.104735) (xy 272.867651 -104.151332)
			(xy 272.905224 -104.203047) (xy 272.936018 -104.259062) (xy 272.95955 -104.318495) (xy 272.975447 -104.380409)
			(xy 272.983458 -104.443827) (xy 272.98396 -104.475788) (xy 273.282154 -104.475788) (xy 273.286225 -104.420166)
			(xy 273.298351 -104.365729) (xy 273.318274 -104.313638) (xy 273.34557 -104.265003) (xy 273.379656 -104.22086)
			(xy 273.419805 -104.182151) (xy 273.465163 -104.1497) (xy 273.514763 -104.124199) (xy 273.567547 -104.106192)
			(xy 273.62239 -104.096062) (xy 273.678124 -104.094025) (xy 273.733561 -104.100125) (xy 273.787518 -104.114231)
			(xy 273.838847 -104.136043) (xy 273.886453 -104.165097) (xy 273.929321 -104.200772) (xy 273.966538 -104.242309)
			(xy 273.997311 -104.288822) (xy 274.020983 -104.339319) (xy 274.037051 -104.392726) (xy 274.042023 -104.426512)
			(xy 319.71564 -104.426512) (xy 319.719711 -104.37089) (xy 319.731837 -104.316453) (xy 319.75176 -104.264362)
			(xy 319.779056 -104.215727) (xy 319.813142 -104.171584) (xy 319.853291 -104.132875) (xy 319.898649 -104.100424)
			(xy 319.948249 -104.074923) (xy 320.001033 -104.056916) (xy 320.055876 -104.046786) (xy 320.11161 -104.044749)
			(xy 320.167047 -104.050849) (xy 320.221004 -104.064955) (xy 320.272333 -104.086767) (xy 320.319939 -104.115821)
			(xy 320.362807 -104.151496) (xy 320.400024 -104.193033) (xy 320.430797 -104.239546) (xy 320.454469 -104.290043)
			(xy 320.470537 -104.34345) (xy 320.478657 -104.398626) (xy 320.479166 -104.426512) (xy 320.478657 -104.454398)
			(xy 320.478057 -104.458473) (xy 322.031354 -104.458473) (xy 322.031354 -104.394551) (xy 322.039365 -104.331133)
			(xy 322.055262 -104.269219) (xy 322.078794 -104.209786) (xy 322.109588 -104.153771) (xy 322.147161 -104.102056)
			(xy 322.190918 -104.055459) (xy 322.240171 -104.014714) (xy 322.294142 -103.980463) (xy 322.351981 -103.953246)
			(xy 322.412774 -103.933493) (xy 322.475564 -103.921515) (xy 322.53936 -103.917502) (xy 322.603156 -103.921515)
			(xy 322.665946 -103.933493) (xy 322.726739 -103.953246) (xy 322.784578 -103.980463) (xy 322.838549 -104.014714)
			(xy 322.887802 -104.055459) (xy 322.931559 -104.102056) (xy 322.969132 -104.153771) (xy 322.999926 -104.209786)
			(xy 323.023458 -104.269219) (xy 323.031693 -104.30129) (xy 326.80275 -104.30129) (xy 326.803319 -104.256769)
			(xy 326.812222 -104.168172) (xy 326.829929 -104.080908) (xy 326.856262 -103.995848) (xy 326.890958 -103.913843)
			(xy 326.93367 -103.835713) (xy 326.983971 -103.762239) (xy 327.041358 -103.694156) (xy 327.105258 -103.632145)
			(xy 327.139808 -103.60406) (xy 327.150526 -103.594991) (xy 327.16699 -103.572264) (xy 327.176632 -103.545908)
			(xy 327.178721 -103.517922) (xy 327.173099 -103.490427) (xy 327.160192 -103.465507) (xy 327.140978 -103.445052)
			(xy 327.116914 -103.430612) (xy 327.103486 -103.426514) (xy 327.076901 -103.418735) (xy 327.026105 -103.396649)
			(xy 326.979034 -103.367454) (xy 326.936678 -103.331762) (xy 326.899925 -103.290322) (xy 326.869548 -103.244006)
			(xy 326.846184 -103.193785) (xy 326.830325 -103.140714) (xy 326.822302 -103.085909) (xy 326.8218 -103.058214)
			(xy 326.822286 -103.030963) (xy 326.830042 -102.977015) (xy 326.845397 -102.92472) (xy 326.868039 -102.875143)
			(xy 326.897505 -102.829293) (xy 326.933196 -102.788102) (xy 326.974387 -102.752411) (xy 327.020237 -102.722945)
			(xy 327.069814 -102.700303) (xy 327.122109 -102.684948) (xy 327.176057 -102.677192) (xy 327.230559 -102.677192)
			(xy 327.284507 -102.684948) (xy 327.336802 -102.700303) (xy 327.386379 -102.722945) (xy 327.432229 -102.752411)
			(xy 327.47342 -102.788102) (xy 327.509111 -102.829293) (xy 327.538577 -102.875143) (xy 327.561219 -102.92472)
			(xy 327.576574 -102.977015) (xy 327.58433 -103.030963) (xy 327.584816 -103.058214) (xy 327.584816 -103.058468)
			(xy 327.584347 -103.084967) (xy 327.576986 -103.137451) (xy 327.562443 -103.188415) (xy 327.540997 -103.23688)
			(xy 327.527412 -103.259636) (xy 327.520383 -103.271808) (xy 327.512535 -103.298782) (xy 327.512348 -103.326873)
			(xy 327.519836 -103.35395) (xy 327.534431 -103.377953) (xy 327.555023 -103.397062) (xy 327.58005 -103.409823)
			(xy 327.60761 -103.415269) (xy 327.621646 -103.414576) (xy 327.639206 -103.413263) (xy 327.674395 -103.411867)
			(xy 327.692004 -103.411782) (xy 327.692258 -103.411782) (xy 327.734186 -103.412232) (xy 327.81767 -103.420119)
			(xy 327.900041 -103.435829) (xy 327.980568 -103.45922) (xy 328.058536 -103.490086) (xy 328.133254 -103.528153)
			(xy 328.204057 -103.573082) (xy 328.270318 -103.624475) (xy 328.312144 -103.66375) (xy 328.859894 -103.66375)
			(xy 328.863965 -103.608128) (xy 328.876091 -103.553691) (xy 328.896014 -103.5016) (xy 328.92331 -103.452965)
			(xy 328.957396 -103.408822) (xy 328.997545 -103.370113) (xy 329.042903 -103.337662) (xy 329.092503 -103.312161)
			(xy 329.145287 -103.294154) (xy 329.20013 -103.284024) (xy 329.255864 -103.281987) (xy 329.311301 -103.288087)
			(xy 329.365258 -103.302193) (xy 329.416587 -103.324005) (xy 329.464193 -103.353059) (xy 329.507061 -103.388734)
			(xy 329.544278 -103.430271) (xy 329.575051 -103.476784) (xy 329.576609 -103.480108) (xy 419.431722 -103.480108)
			(xy 419.435793 -103.424486) (xy 419.447919 -103.370049) (xy 419.467842 -103.317958) (xy 419.495138 -103.269323)
			(xy 419.529224 -103.22518) (xy 419.569373 -103.186471) (xy 419.614731 -103.15402) (xy 419.664331 -103.128519)
			(xy 419.717115 -103.110512) (xy 419.771958 -103.100382) (xy 419.827692 -103.098345) (xy 419.883129 -103.104445)
			(xy 419.937086 -103.118551) (xy 419.988415 -103.140363) (xy 420.036021 -103.169417) (xy 420.078889 -103.205092)
			(xy 420.116106 -103.246629) (xy 420.146879 -103.293142) (xy 420.154252 -103.308869) (xy 430.570888 -103.308869)
			(xy 430.570888 -103.244947) (xy 430.578899 -103.181529) (xy 430.594796 -103.119615) (xy 430.618328 -103.060182)
			(xy 430.649122 -103.004167) (xy 430.686695 -102.952452) (xy 430.730452 -102.905855) (xy 430.779705 -102.86511)
			(xy 430.833676 -102.830859) (xy 430.891515 -102.803642) (xy 430.952308 -102.783889) (xy 431.015098 -102.771911)
			(xy 431.078894 -102.767898) (xy 431.14269 -102.771911) (xy 431.20548 -102.783889) (xy 431.266273 -102.803642)
			(xy 431.324112 -102.830859) (xy 431.378083 -102.86511) (xy 431.427336 -102.905855) (xy 431.471093 -102.952452)
			(xy 431.508666 -103.004167) (xy 431.53946 -103.060182) (xy 431.562992 -103.119615) (xy 431.578889 -103.181529)
			(xy 431.5869 -103.244947) (xy 431.587402 -103.276908) (xy 431.5869 -103.308869) (xy 431.578889 -103.372287)
			(xy 431.562992 -103.434201) (xy 431.53946 -103.493634) (xy 431.508666 -103.549649) (xy 431.471093 -103.601364)
			(xy 431.427336 -103.647961) (xy 431.378083 -103.688706) (xy 431.324112 -103.722957) (xy 431.266273 -103.750174)
			(xy 431.20548 -103.769927) (xy 431.14269 -103.781905) (xy 431.078894 -103.785919) (xy 431.015098 -103.781905)
			(xy 430.952308 -103.769927) (xy 430.891515 -103.750174) (xy 430.833676 -103.722957) (xy 430.779705 -103.688706)
			(xy 430.730452 -103.647961) (xy 430.686695 -103.601364) (xy 430.649122 -103.549649) (xy 430.618328 -103.493634)
			(xy 430.594796 -103.434201) (xy 430.578899 -103.372287) (xy 430.570888 -103.308869) (xy 420.154252 -103.308869)
			(xy 420.170551 -103.343639) (xy 420.186619 -103.397046) (xy 420.194739 -103.452222) (xy 420.195248 -103.480108)
			(xy 420.194739 -103.507994) (xy 420.186619 -103.56317) (xy 420.170551 -103.616577) (xy 420.146879 -103.667074)
			(xy 420.116106 -103.713587) (xy 420.078889 -103.755124) (xy 420.036021 -103.790799) (xy 419.988415 -103.819853)
			(xy 419.937086 -103.841665) (xy 419.883129 -103.855771) (xy 419.827692 -103.861871) (xy 419.771958 -103.859834)
			(xy 419.717115 -103.849704) (xy 419.664331 -103.831697) (xy 419.614731 -103.806196) (xy 419.569373 -103.773745)
			(xy 419.529224 -103.735036) (xy 419.495138 -103.690893) (xy 419.467842 -103.642258) (xy 419.447919 -103.590167)
			(xy 419.435793 -103.53573) (xy 419.431722 -103.480108) (xy 329.576609 -103.480108) (xy 329.598723 -103.527281)
			(xy 329.614791 -103.580688) (xy 329.622911 -103.635864) (xy 329.62342 -103.66375) (xy 329.622911 -103.691636)
			(xy 329.614791 -103.746812) (xy 329.598723 -103.800219) (xy 329.575051 -103.850716) (xy 329.544278 -103.897229)
			(xy 329.507061 -103.938766) (xy 329.464193 -103.974441) (xy 329.416587 -104.003495) (xy 329.365258 -104.025307)
			(xy 329.311301 -104.039413) (xy 329.255864 -104.045513) (xy 329.20013 -104.043476) (xy 329.145287 -104.033346)
			(xy 329.092503 -104.015339) (xy 329.042903 -103.989838) (xy 328.997545 -103.957387) (xy 328.957396 -103.918678)
			(xy 328.92331 -103.874535) (xy 328.896014 -103.8259) (xy 328.876091 -103.773809) (xy 328.863965 -103.719372)
			(xy 328.859894 -103.66375) (xy 328.312144 -103.66375) (xy 328.331448 -103.681876) (xy 328.386906 -103.744775)
			(xy 328.436197 -103.812614) (xy 328.478886 -103.88479) (xy 328.514592 -103.960664) (xy 328.543 -104.039561)
			(xy 328.563856 -104.120782) (xy 328.576977 -104.203605) (xy 328.582244 -104.287295) (xy 328.579613 -104.371109)
			(xy 328.569105 -104.454304) (xy 328.550814 -104.53614) (xy 328.524903 -104.615893) (xy 328.491602 -104.692852)
			(xy 328.451206 -104.766336) (xy 328.404073 -104.835693) (xy 328.350623 -104.900306) (xy 328.291329 -104.959602)
			(xy 328.226718 -105.013054) (xy 328.157364 -105.060189) (xy 328.083881 -105.100588) (xy 328.006922 -105.133892)
			(xy 327.927171 -105.159806) (xy 327.845335 -105.178099) (xy 327.762141 -105.18861) (xy 327.678327 -105.191245)
			(xy 327.594637 -105.18598) (xy 327.511813 -105.172863) (xy 327.430592 -105.152009) (xy 327.351694 -105.123604)
			(xy 327.275819 -105.0879) (xy 327.203641 -105.045215) (xy 327.1358 -104.995926) (xy 327.072899 -104.940471)
			(xy 327.015496 -104.879342) (xy 326.9641 -104.813083) (xy 326.919168 -104.742281) (xy 326.881099 -104.667565)
			(xy 326.85023 -104.589598) (xy 326.826836 -104.509072) (xy 326.811124 -104.426701) (xy 326.803233 -104.343218)
			(xy 326.80275 -104.30129) (xy 323.031693 -104.30129) (xy 323.039355 -104.331133) (xy 323.047366 -104.394551)
			(xy 323.047868 -104.426512) (xy 323.047366 -104.458473) (xy 323.039355 -104.521891) (xy 323.023458 -104.583805)
			(xy 322.999926 -104.643238) (xy 322.969132 -104.699253) (xy 322.931559 -104.750968) (xy 322.887802 -104.797565)
			(xy 322.838549 -104.83831) (xy 322.784578 -104.872561) (xy 322.726739 -104.899778) (xy 322.665946 -104.919531)
			(xy 322.603156 -104.931509) (xy 322.53936 -104.935523) (xy 322.475564 -104.931509) (xy 322.412774 -104.919531)
			(xy 322.351981 -104.899778) (xy 322.294142 -104.872561) (xy 322.240171 -104.83831) (xy 322.190918 -104.797565)
			(xy 322.147161 -104.750968) (xy 322.109588 -104.699253) (xy 322.078794 -104.643238) (xy 322.055262 -104.583805)
			(xy 322.039365 -104.521891) (xy 322.031354 -104.458473) (xy 320.478057 -104.458473) (xy 320.470537 -104.509574)
			(xy 320.454469 -104.562981) (xy 320.430797 -104.613478) (xy 320.400024 -104.659991) (xy 320.362807 -104.701528)
			(xy 320.319939 -104.737203) (xy 320.272333 -104.766257) (xy 320.221004 -104.788069) (xy 320.167047 -104.802175)
			(xy 320.11161 -104.808275) (xy 320.055876 -104.806238) (xy 320.001033 -104.796108) (xy 319.948249 -104.778101)
			(xy 319.898649 -104.7526) (xy 319.853291 -104.720149) (xy 319.813142 -104.68144) (xy 319.779056 -104.637297)
			(xy 319.75176 -104.588662) (xy 319.731837 -104.536571) (xy 319.719711 -104.482134) (xy 319.71564 -104.426512)
			(xy 274.042023 -104.426512) (xy 274.045171 -104.447902) (xy 274.04568 -104.475788) (xy 274.045171 -104.503674)
			(xy 274.037051 -104.55885) (xy 274.020983 -104.612257) (xy 273.997311 -104.662754) (xy 273.966538 -104.709267)
			(xy 273.929321 -104.750804) (xy 273.886453 -104.786479) (xy 273.838847 -104.815533) (xy 273.787518 -104.837345)
			(xy 273.733561 -104.851451) (xy 273.678124 -104.857551) (xy 273.62239 -104.855514) (xy 273.567547 -104.845384)
			(xy 273.514763 -104.827377) (xy 273.465163 -104.801876) (xy 273.419805 -104.769425) (xy 273.379656 -104.730716)
			(xy 273.34557 -104.686573) (xy 273.318274 -104.637938) (xy 273.298351 -104.585847) (xy 273.286225 -104.53141)
			(xy 273.282154 -104.475788) (xy 272.98396 -104.475788) (xy 272.983458 -104.507749) (xy 272.975447 -104.571167)
			(xy 272.95955 -104.633081) (xy 272.936018 -104.692514) (xy 272.905224 -104.748529) (xy 272.867651 -104.800244)
			(xy 272.823894 -104.846841) (xy 272.774641 -104.887586) (xy 272.72067 -104.921837) (xy 272.662831 -104.949054)
			(xy 272.602038 -104.968807) (xy 272.539248 -104.980785) (xy 272.475452 -104.984799) (xy 272.411656 -104.980785)
			(xy 272.348866 -104.968807) (xy 272.288073 -104.949054) (xy 272.230234 -104.921837) (xy 272.176263 -104.887586)
			(xy 272.12701 -104.846841) (xy 272.083253 -104.800244) (xy 272.04568 -104.748529) (xy 272.014886 -104.692514)
			(xy 271.991354 -104.633081) (xy 271.975457 -104.571167) (xy 271.967446 -104.507749) (xy 220.173876 -104.507749)
			(xy 220.174312 -104.535478) (xy 220.17381 -104.567439) (xy 220.165799 -104.630857) (xy 220.149902 -104.692771)
			(xy 220.12637 -104.752204) (xy 220.095576 -104.808219) (xy 220.058003 -104.859934) (xy 220.014246 -104.906531)
			(xy 219.964993 -104.947276) (xy 219.916265 -104.9782) (xy 221.111062 -104.9782) (xy 221.115133 -104.922578)
			(xy 221.127259 -104.868141) (xy 221.147182 -104.81605) (xy 221.174478 -104.767415) (xy 221.208564 -104.723272)
			(xy 221.248713 -104.684563) (xy 221.294071 -104.652112) (xy 221.343671 -104.626611) (xy 221.396455 -104.608604)
			(xy 221.451298 -104.598474) (xy 221.507032 -104.596437) (xy 221.562469 -104.602537) (xy 221.616426 -104.616643)
			(xy 221.667755 -104.638455) (xy 221.715361 -104.667509) (xy 221.758229 -104.703184) (xy 221.795446 -104.744721)
			(xy 221.826219 -104.791234) (xy 221.849891 -104.841731) (xy 221.865959 -104.895138) (xy 221.874079 -104.950314)
			(xy 221.874588 -104.9782) (xy 221.874079 -105.006086) (xy 221.865959 -105.061262) (xy 221.849891 -105.114669)
			(xy 221.826219 -105.165166) (xy 221.798338 -105.207308) (xy 416.720272 -105.207308) (xy 416.724343 -105.151686)
			(xy 416.736469 -105.097249) (xy 416.756392 -105.045158) (xy 416.783688 -104.996523) (xy 416.817774 -104.95238)
			(xy 416.857923 -104.913671) (xy 416.903281 -104.88122) (xy 416.952881 -104.855719) (xy 417.005665 -104.837712)
			(xy 417.060508 -104.827582) (xy 417.116242 -104.825545) (xy 417.171679 -104.831645) (xy 417.225636 -104.845751)
			(xy 417.276965 -104.867563) (xy 417.324571 -104.896617) (xy 417.367439 -104.932292) (xy 417.404656 -104.973829)
			(xy 417.435429 -105.020342) (xy 417.459101 -105.070839) (xy 417.475169 -105.124246) (xy 417.483289 -105.179422)
			(xy 417.483798 -105.207308) (xy 417.483289 -105.235194) (xy 417.475169 -105.29037) (xy 417.459101 -105.343777)
			(xy 417.435429 -105.394274) (xy 417.404656 -105.440787) (xy 417.367439 -105.482324) (xy 417.324571 -105.517999)
			(xy 417.276965 -105.547053) (xy 417.225636 -105.568865) (xy 417.171679 -105.582971) (xy 417.116242 -105.589071)
			(xy 417.060508 -105.587034) (xy 417.005665 -105.576904) (xy 416.952881 -105.558897) (xy 416.903281 -105.533396)
			(xy 416.857923 -105.500945) (xy 416.817774 -105.462236) (xy 416.783688 -105.418093) (xy 416.756392 -105.369458)
			(xy 416.736469 -105.317367) (xy 416.724343 -105.26293) (xy 416.720272 -105.207308) (xy 221.798338 -105.207308)
			(xy 221.795446 -105.211679) (xy 221.758229 -105.253216) (xy 221.715361 -105.288891) (xy 221.667755 -105.317945)
			(xy 221.616426 -105.339757) (xy 221.562469 -105.353863) (xy 221.507032 -105.359963) (xy 221.451298 -105.357926)
			(xy 221.396455 -105.347796) (xy 221.343671 -105.329789) (xy 221.294071 -105.304288) (xy 221.248713 -105.271837)
			(xy 221.208564 -105.233128) (xy 221.174478 -105.188985) (xy 221.147182 -105.14035) (xy 221.127259 -105.088259)
			(xy 221.115133 -105.033822) (xy 221.111062 -104.9782) (xy 219.916265 -104.9782) (xy 219.911022 -104.981527)
			(xy 219.853183 -105.008744) (xy 219.79239 -105.028497) (xy 219.7296 -105.040475) (xy 219.665804 -105.044489)
			(xy 219.602008 -105.040475) (xy 219.539218 -105.028497) (xy 219.478425 -105.008744) (xy 219.420586 -104.981527)
			(xy 219.366615 -104.947276) (xy 219.317362 -104.906531) (xy 219.273605 -104.859934) (xy 219.236032 -104.808219)
			(xy 219.205238 -104.752204) (xy 219.181706 -104.692771) (xy 219.165809 -104.630857) (xy 219.157798 -104.567439)
			(xy 217.378695 -104.567439) (xy 217.412273 -104.616085) (xy 217.440836 -104.670506) (xy 217.462631 -104.727974)
			(xy 217.477341 -104.78765) (xy 217.48475 -104.848663) (xy 217.485214 -104.879394) (xy 217.485214 -104.879902)
			(xy 217.484761 -104.910138) (xy 217.477554 -104.97018) (xy 217.463279 -105.028944) (xy 217.442136 -105.085601)
			(xy 217.414424 -105.139351) (xy 217.397838 -105.164636) (xy 217.390726 -105.175304) (xy 217.387932 -105.200196)
			(xy 217.428826 -105.30205) (xy 217.44813 -105.318306) (xy 217.460576 -105.320846) (xy 217.491186 -105.327906)
			(xy 217.550496 -105.34861) (xy 217.606804 -105.376464) (xy 217.659251 -105.411041) (xy 217.70704 -105.451815)
			(xy 217.749443 -105.498166) (xy 217.785812 -105.549388) (xy 217.815596 -105.604699) (xy 217.838338 -105.663258)
			(xy 217.853694 -105.724172) (xy 217.86143 -105.786514) (xy 217.861896 -105.817924) (xy 217.861394 -105.849885)
			(xy 217.856357 -105.889763) (xy 271.967446 -105.889763) (xy 271.967446 -105.825841) (xy 271.975457 -105.762423)
			(xy 271.991354 -105.700509) (xy 272.014886 -105.641076) (xy 272.04568 -105.585061) (xy 272.083253 -105.533346)
			(xy 272.12701 -105.486749) (xy 272.176263 -105.446004) (xy 272.230234 -105.411753) (xy 272.288073 -105.384536)
			(xy 272.348866 -105.364783) (xy 272.411656 -105.352805) (xy 272.475452 -105.348792) (xy 272.539248 -105.352805)
			(xy 272.602038 -105.364783) (xy 272.662831 -105.384536) (xy 272.72067 -105.411753) (xy 272.774641 -105.446004)
			(xy 272.823894 -105.486749) (xy 272.867651 -105.533346) (xy 272.905224 -105.585061) (xy 272.936018 -105.641076)
			(xy 272.95955 -105.700509) (xy 272.975447 -105.762423) (xy 272.983458 -105.825841) (xy 272.98396 -105.857802)
			(xy 273.282154 -105.857802) (xy 273.286225 -105.80218) (xy 273.298351 -105.747743) (xy 273.318274 -105.695652)
			(xy 273.34557 -105.647017) (xy 273.379656 -105.602874) (xy 273.419805 -105.564165) (xy 273.465163 -105.531714)
			(xy 273.514763 -105.506213) (xy 273.567547 -105.488206) (xy 273.62239 -105.478076) (xy 273.678124 -105.476039)
			(xy 273.733561 -105.482139) (xy 273.787518 -105.496245) (xy 273.838847 -105.518057) (xy 273.886453 -105.547111)
			(xy 273.929321 -105.582786) (xy 273.966538 -105.624323) (xy 273.997311 -105.670836) (xy 274.020983 -105.721333)
			(xy 274.037051 -105.77474) (xy 274.045171 -105.829916) (xy 274.04568 -105.857802) (xy 274.045171 -105.885688)
			(xy 274.037051 -105.940864) (xy 274.020983 -105.994271) (xy 273.997311 -106.044768) (xy 273.966538 -106.091281)
			(xy 273.929321 -106.132818) (xy 273.886453 -106.168493) (xy 273.838847 -106.197547) (xy 273.787518 -106.219359)
			(xy 273.733561 -106.233465) (xy 273.678124 -106.239565) (xy 273.62239 -106.237528) (xy 273.567547 -106.227398)
			(xy 273.514763 -106.209391) (xy 273.465163 -106.18389) (xy 273.419805 -106.151439) (xy 273.379656 -106.11273)
			(xy 273.34557 -106.068587) (xy 273.318274 -106.019952) (xy 273.298351 -105.967861) (xy 273.286225 -105.913424)
			(xy 273.282154 -105.857802) (xy 272.98396 -105.857802) (xy 272.983458 -105.889763) (xy 272.975447 -105.953181)
			(xy 272.95955 -106.015095) (xy 272.936018 -106.074528) (xy 272.905224 -106.130543) (xy 272.867651 -106.182258)
			(xy 272.823894 -106.228855) (xy 272.774641 -106.2696) (xy 272.72067 -106.303851) (xy 272.662831 -106.331068)
			(xy 272.602038 -106.350821) (xy 272.539248 -106.362799) (xy 272.475452 -106.366813) (xy 272.411656 -106.362799)
			(xy 272.348866 -106.350821) (xy 272.288073 -106.331068) (xy 272.230234 -106.303851) (xy 272.176263 -106.2696)
			(xy 272.12701 -106.228855) (xy 272.083253 -106.182258) (xy 272.04568 -106.130543) (xy 272.014886 -106.074528)
			(xy 271.991354 -106.015095) (xy 271.975457 -105.953181) (xy 271.967446 -105.889763) (xy 217.856357 -105.889763)
			(xy 217.853383 -105.913303) (xy 217.837486 -105.975217) (xy 217.813954 -106.03465) (xy 217.78316 -106.090665)
			(xy 217.745587 -106.14238) (xy 217.70183 -106.188977) (xy 217.652577 -106.229722) (xy 217.598606 -106.263973)
			(xy 217.540767 -106.29119) (xy 217.479974 -106.310943) (xy 217.417184 -106.322921) (xy 217.353388 -106.326935)
			(xy 217.289592 -106.322921) (xy 217.226802 -106.310943) (xy 217.166009 -106.29119) (xy 217.10817 -106.263973)
			(xy 217.054199 -106.229722) (xy 217.004946 -106.188977) (xy 216.961189 -106.14238) (xy 216.923616 -106.090665)
			(xy 216.892822 -106.03465) (xy 216.86929 -105.975217) (xy 216.853393 -105.913303) (xy 216.845382 -105.849885)
			(xy 216.84488 -105.817924) (xy 216.84488 -105.817416) (xy 216.845343 -105.78718) (xy 216.852547 -105.727138)
			(xy 216.866821 -105.668374) (xy 216.887961 -105.611718) (xy 216.915671 -105.557968) (xy 216.932256 -105.532682)
			(xy 216.939368 -105.522014) (xy 216.942162 -105.497122) (xy 216.901268 -105.395268) (xy 216.881964 -105.379012)
			(xy 216.869518 -105.376472) (xy 216.837869 -105.369149) (xy 216.776621 -105.347494) (xy 216.718632 -105.318212)
			(xy 216.664846 -105.28178) (xy 216.616141 -105.238791) (xy 216.573311 -105.189947) (xy 216.537053 -105.136043)
			(xy 216.522046 -105.107232) (xy 216.517801 -105.099311) (xy 216.504766 -105.086955) (xy 216.496646 -105.083102)
			(xy 216.46896 -105.071418) (xy 216.460634 -105.068171) (xy 216.442807 -105.067123) (xy 216.434162 -105.069386)
			(xy 216.397836 -105.07981) (xy 216.323103 -105.09103) (xy 216.285318 -105.091738) (xy 216.253357 -105.091198)
			(xy 216.189938 -105.083189) (xy 216.128024 -105.067294) (xy 216.068589 -105.043764) (xy 216.012573 -105.01297)
			(xy 215.960858 -104.975399) (xy 215.91426 -104.931642) (xy 215.873513 -104.882389) (xy 215.839261 -104.828418)
			(xy 215.812044 -104.77058) (xy 215.79229 -104.709786) (xy 215.780312 -104.646996) (xy 215.776298 -104.5832)
			(xy 195.959947 -104.5832) (xy 195.935444 -104.605046) (xy 195.884733 -104.640246) (xy 195.830133 -104.669047)
			(xy 195.772449 -104.691027) (xy 195.712528 -104.705862) (xy 195.651251 -104.713333) (xy 195.620386 -104.713786)
			(xy 195.588424 -104.713327) (xy 195.525005 -104.705314) (xy 195.46309 -104.689415) (xy 195.403655 -104.665882)
			(xy 195.347639 -104.635086) (xy 195.295924 -104.597511) (xy 195.249327 -104.553752) (xy 195.208581 -104.504497)
			(xy 195.174329 -104.450524) (xy 195.147112 -104.392684) (xy 195.127359 -104.331889) (xy 195.115381 -104.269098)
			(xy 195.111367 -104.2053) (xy 192.681766 -104.2053) (xy 192.642721 -104.2376) (xy 192.58875 -104.271851)
			(xy 192.530911 -104.299068) (xy 192.470118 -104.318821) (xy 192.407328 -104.330799) (xy 192.343532 -104.334813)
			(xy 192.279736 -104.330799) (xy 192.216946 -104.318821) (xy 192.156153 -104.299068) (xy 192.098314 -104.271851)
			(xy 192.044343 -104.2376) (xy 191.99509 -104.196855) (xy 191.951333 -104.150258) (xy 191.91376 -104.098543)
			(xy 191.882966 -104.042528) (xy 191.859434 -103.983095) (xy 191.843537 -103.921181) (xy 191.835526 -103.857763)
			(xy 184.838848 -103.857763) (xy 184.838848 -105.293117) (xy 194.049644 -105.293117) (xy 194.049644 -105.229195)
			(xy 194.057655 -105.165777) (xy 194.073552 -105.103863) (xy 194.097084 -105.04443) (xy 194.127878 -104.988415)
			(xy 194.165451 -104.9367) (xy 194.209208 -104.890103) (xy 194.258461 -104.849358) (xy 194.312432 -104.815107)
			(xy 194.370271 -104.78789) (xy 194.431064 -104.768137) (xy 194.493854 -104.756159) (xy 194.55765 -104.752146)
			(xy 194.621446 -104.756159) (xy 194.684236 -104.768137) (xy 194.745029 -104.78789) (xy 194.802868 -104.815107)
			(xy 194.856839 -104.849358) (xy 194.906092 -104.890103) (xy 194.949849 -104.9367) (xy 194.987422 -104.988415)
			(xy 195.018216 -105.04443) (xy 195.041748 -105.103863) (xy 195.057645 -105.165777) (xy 195.065656 -105.229195)
			(xy 195.066158 -105.261156) (xy 195.065656 -105.293117) (xy 195.057645 -105.356535) (xy 195.041748 -105.418449)
			(xy 195.018216 -105.477882) (xy 194.998307 -105.514097) (xy 198.297794 -105.514097) (xy 198.297794 -105.450175)
			(xy 198.305805 -105.386757) (xy 198.321702 -105.324843) (xy 198.345234 -105.26541) (xy 198.376028 -105.209395)
			(xy 198.413601 -105.15768) (xy 198.457358 -105.111083) (xy 198.506611 -105.070338) (xy 198.560582 -105.036087)
			(xy 198.618421 -105.00887) (xy 198.679214 -104.989117) (xy 198.742004 -104.977139) (xy 198.8058 -104.973126)
			(xy 198.869596 -104.977139) (xy 198.932386 -104.989117) (xy 198.993179 -105.00887) (xy 199.051018 -105.036087)
			(xy 199.104989 -105.070338) (xy 199.154242 -105.111083) (xy 199.197999 -105.15768) (xy 199.235572 -105.209395)
			(xy 199.266366 -105.26541) (xy 199.289898 -105.324843) (xy 199.305795 -105.386757) (xy 199.313806 -105.450175)
			(xy 199.314308 -105.482136) (xy 199.313806 -105.514097) (xy 199.305795 -105.577515) (xy 199.289898 -105.639429)
			(xy 199.266366 -105.698862) (xy 199.235572 -105.754877) (xy 199.197999 -105.806592) (xy 199.154242 -105.853189)
			(xy 199.104989 -105.893934) (xy 199.051018 -105.928185) (xy 198.993179 -105.955402) (xy 198.932386 -105.975155)
			(xy 198.869596 -105.987133) (xy 198.8058 -105.991147) (xy 198.742004 -105.987133) (xy 198.679214 -105.975155)
			(xy 198.618421 -105.955402) (xy 198.560582 -105.928185) (xy 198.506611 -105.893934) (xy 198.457358 -105.853189)
			(xy 198.413601 -105.806592) (xy 198.376028 -105.754877) (xy 198.345234 -105.698862) (xy 198.321702 -105.639429)
			(xy 198.305805 -105.577515) (xy 198.297794 -105.514097) (xy 194.998307 -105.514097) (xy 194.987422 -105.533897)
			(xy 194.949849 -105.585612) (xy 194.906092 -105.632209) (xy 194.856839 -105.672954) (xy 194.802868 -105.707205)
			(xy 194.745029 -105.734422) (xy 194.684236 -105.754175) (xy 194.621446 -105.766153) (xy 194.55765 -105.770167)
			(xy 194.493854 -105.766153) (xy 194.431064 -105.754175) (xy 194.370271 -105.734422) (xy 194.312432 -105.707205)
			(xy 194.258461 -105.672954) (xy 194.209208 -105.632209) (xy 194.165451 -105.585612) (xy 194.127878 -105.533897)
			(xy 194.097084 -105.477882) (xy 194.073552 -105.418449) (xy 194.057655 -105.356535) (xy 194.049644 -105.293117)
			(xy 184.838848 -105.293117) (xy 184.838848 -105.915714) (xy 184.839075 -105.922315) (xy 184.842559 -105.935052)
			(xy 184.845706 -105.94086) (xy 184.850024 -105.947972) (xy 184.851294 -105.94975) (xy 184.860946 -105.958386)
			(xy 184.868566 -105.961688) (xy 184.891387 -105.972545) (xy 184.933716 -106.00015) (xy 184.971352 -106.033874)
			(xy 185.003417 -106.072933) (xy 185.029166 -106.116416) (xy 185.047998 -106.163311) (xy 185.059475 -106.212525)
			(xy 185.063329 -106.262913) (xy 185.061338 -106.288919) (xy 185.98185 -106.288919) (xy 185.98185 -106.236945)
			(xy 185.98998 -106.18561) (xy 186.006041 -106.13618) (xy 186.029637 -106.08987) (xy 186.060187 -106.047822)
			(xy 186.096938 -106.011071) (xy 186.138986 -105.980521) (xy 186.185296 -105.956925) (xy 186.234726 -105.940864)
			(xy 186.286061 -105.932734) (xy 186.338035 -105.932734) (xy 186.38937 -105.940864) (xy 186.4388 -105.956925)
			(xy 186.48511 -105.980521) (xy 186.527158 -106.011071) (xy 186.563909 -106.047822) (xy 186.594459 -106.08987)
			(xy 186.618055 -106.13618) (xy 186.634116 -106.18561) (xy 186.642246 -106.236945) (xy 186.642756 -106.262932)
			(xy 186.642246 -106.288919) (xy 191.581788 -106.288919) (xy 191.581788 -106.236945) (xy 191.589918 -106.18561)
			(xy 191.605979 -106.13618) (xy 191.629575 -106.08987) (xy 191.660125 -106.047822) (xy 191.696876 -106.011071)
			(xy 191.738924 -105.980521) (xy 191.785234 -105.956925) (xy 191.834664 -105.940864) (xy 191.885999 -105.932734)
			(xy 191.937973 -105.932734) (xy 191.989308 -105.940864) (xy 192.038738 -105.956925) (xy 192.085048 -105.980521)
			(xy 192.127096 -106.011071) (xy 192.163847 -106.047822) (xy 192.194397 -106.08987) (xy 192.217993 -106.13618)
			(xy 192.234054 -106.18561) (xy 192.242184 -106.236945) (xy 192.242694 -106.262932) (xy 192.242184 -106.288919)
			(xy 192.381888 -106.288919) (xy 192.381888 -106.236945) (xy 192.390018 -106.18561) (xy 192.406079 -106.13618)
			(xy 192.429675 -106.08987) (xy 192.460225 -106.047822) (xy 192.496976 -106.011071) (xy 192.539024 -105.980521)
			(xy 192.585334 -105.956925) (xy 192.634764 -105.940864) (xy 192.686099 -105.932734) (xy 192.738073 -105.932734)
			(xy 192.789408 -105.940864) (xy 192.838838 -105.956925) (xy 192.885148 -105.980521) (xy 192.927196 -106.011071)
			(xy 192.963947 -106.047822) (xy 192.994497 -106.08987) (xy 193.018093 -106.13618) (xy 193.034154 -106.18561)
			(xy 193.042284 -106.236945) (xy 193.042794 -106.262932) (xy 193.042284 -106.288919) (xy 193.181734 -106.288919)
			(xy 193.181734 -106.236945) (xy 193.189864 -106.18561) (xy 193.205925 -106.13618) (xy 193.229521 -106.08987)
			(xy 193.260071 -106.047822) (xy 193.296822 -106.011071) (xy 193.33887 -105.980521) (xy 193.38518 -105.956925)
			(xy 193.43461 -105.940864) (xy 193.485945 -105.932734) (xy 193.537919 -105.932734) (xy 193.589254 -105.940864)
			(xy 193.638684 -105.956925) (xy 193.684994 -105.980521) (xy 193.727042 -106.011071) (xy 193.763793 -106.047822)
			(xy 193.794343 -106.08987) (xy 193.817939 -106.13618) (xy 193.834 -106.18561) (xy 193.84213 -106.236945)
			(xy 193.84264 -106.262932) (xy 193.84213 -106.288919) (xy 193.981834 -106.288919) (xy 193.981834 -106.236945)
			(xy 193.989964 -106.18561) (xy 194.006025 -106.13618) (xy 194.029621 -106.08987) (xy 194.060171 -106.047822)
			(xy 194.096922 -106.011071) (xy 194.13897 -105.980521) (xy 194.18528 -105.956925) (xy 194.23471 -105.940864)
			(xy 194.286045 -105.932734) (xy 194.338019 -105.932734) (xy 194.389354 -105.940864) (xy 194.438784 -105.956925)
			(xy 194.485094 -105.980521) (xy 194.527142 -106.011071) (xy 194.563893 -106.047822) (xy 194.594443 -106.08987)
			(xy 194.618039 -106.13618) (xy 194.6341 -106.18561) (xy 194.64223 -106.236945) (xy 194.64274 -106.262932)
			(xy 194.64223 -106.288919) (xy 194.6341 -106.340254) (xy 194.618039 -106.389684) (xy 194.594443 -106.435994)
			(xy 194.563893 -106.478042) (xy 194.527142 -106.514793) (xy 194.485094 -106.545343) (xy 194.438784 -106.568939)
			(xy 194.389354 -106.585) (xy 194.338019 -106.59313) (xy 194.286045 -106.59313) (xy 194.23471 -106.585)
			(xy 194.18528 -106.568939) (xy 194.13897 -106.545343) (xy 194.096922 -106.514793) (xy 194.060171 -106.478042)
			(xy 194.029621 -106.435994) (xy 194.006025 -106.389684) (xy 193.989964 -106.340254) (xy 193.981834 -106.288919)
			(xy 193.84213 -106.288919) (xy 193.834 -106.340254) (xy 193.817939 -106.389684) (xy 193.794343 -106.435994)
			(xy 193.763793 -106.478042) (xy 193.727042 -106.514793) (xy 193.684994 -106.545343) (xy 193.638684 -106.568939)
			(xy 193.589254 -106.585) (xy 193.537919 -106.59313) (xy 193.485945 -106.59313) (xy 193.43461 -106.585)
			(xy 193.38518 -106.568939) (xy 193.33887 -106.545343) (xy 193.296822 -106.514793) (xy 193.260071 -106.478042)
			(xy 193.229521 -106.435994) (xy 193.205925 -106.389684) (xy 193.189864 -106.340254) (xy 193.181734 -106.288919)
			(xy 193.042284 -106.288919) (xy 193.034154 -106.340254) (xy 193.018093 -106.389684) (xy 192.994497 -106.435994)
			(xy 192.963947 -106.478042) (xy 192.927196 -106.514793) (xy 192.885148 -106.545343) (xy 192.838838 -106.568939)
			(xy 192.789408 -106.585) (xy 192.738073 -106.59313) (xy 192.686099 -106.59313) (xy 192.634764 -106.585)
			(xy 192.585334 -106.568939) (xy 192.539024 -106.545343) (xy 192.496976 -106.514793) (xy 192.460225 -106.478042)
			(xy 192.429675 -106.435994) (xy 192.406079 -106.389684) (xy 192.390018 -106.340254) (xy 192.381888 -106.288919)
			(xy 192.242184 -106.288919) (xy 192.234054 -106.340254) (xy 192.217993 -106.389684) (xy 192.194397 -106.435994)
			(xy 192.163847 -106.478042) (xy 192.127096 -106.514793) (xy 192.085048 -106.545343) (xy 192.038738 -106.568939)
			(xy 191.989308 -106.585) (xy 191.937973 -106.59313) (xy 191.885999 -106.59313) (xy 191.834664 -106.585)
			(xy 191.785234 -106.568939) (xy 191.738924 -106.545343) (xy 191.696876 -106.514793) (xy 191.660125 -106.478042)
			(xy 191.629575 -106.435994) (xy 191.605979 -106.389684) (xy 191.589918 -106.340254) (xy 191.581788 -106.288919)
			(xy 186.642246 -106.288919) (xy 186.634116 -106.340254) (xy 186.618055 -106.389684) (xy 186.594459 -106.435994)
			(xy 186.563909 -106.478042) (xy 186.527158 -106.514793) (xy 186.48511 -106.545343) (xy 186.4388 -106.568939)
			(xy 186.38937 -106.585) (xy 186.338035 -106.59313) (xy 186.286061 -106.59313) (xy 186.234726 -106.585)
			(xy 186.185296 -106.568939) (xy 186.138986 -106.545343) (xy 186.096938 -106.514793) (xy 186.060187 -106.478042)
			(xy 186.029637 -106.435994) (xy 186.006041 -106.389684) (xy 185.98998 -106.340254) (xy 185.98185 -106.288919)
			(xy 185.061338 -106.288919) (xy 185.059471 -106.313301) (xy 185.04799 -106.362514) (xy 185.029154 -106.409408)
			(xy 185.003402 -106.452889) (xy 184.971333 -106.491945) (xy 184.933695 -106.525666) (xy 184.891364 -106.553267)
			(xy 184.868566 -106.564176) (xy 184.860946 -106.567478) (xy 184.851294 -106.576114) (xy 184.850024 -106.577892)
			(xy 184.845706 -106.585004) (xy 184.842585 -106.590822) (xy 184.839107 -106.603553) (xy 184.838848 -106.61015)
			(xy 184.838848 -106.672359) (xy 197.969622 -106.672359) (xy 197.969622 -106.619061) (xy 197.977565 -106.566357)
			(xy 197.993275 -106.515427) (xy 198.016401 -106.467406) (xy 198.046425 -106.423369) (xy 198.082677 -106.384298)
			(xy 198.124348 -106.351067) (xy 198.170506 -106.324418) (xy 198.22012 -106.304946) (xy 198.272082 -106.293086)
			(xy 198.325232 -106.289103) (xy 198.378382 -106.293086) (xy 198.430344 -106.304946) (xy 198.479958 -106.324418)
			(xy 198.526116 -106.351067) (xy 198.567787 -106.384298) (xy 198.604039 -106.423369) (xy 198.634063 -106.467406)
			(xy 198.650687 -106.501925) (xy 199.268832 -106.501925) (xy 199.268832 -106.448627) (xy 199.276775 -106.395923)
			(xy 199.292485 -106.344993) (xy 199.315611 -106.296972) (xy 199.345635 -106.252935) (xy 199.381887 -106.213864)
			(xy 199.423558 -106.180633) (xy 199.469716 -106.153984) (xy 199.51933 -106.134512) (xy 199.571292 -106.122652)
			(xy 199.624442 -106.118669) (xy 199.677592 -106.122652) (xy 199.729554 -106.134512) (xy 199.779168 -106.153984)
			(xy 199.825326 -106.180633) (xy 199.866997 -106.213864) (xy 199.903249 -106.252935) (xy 199.933273 -106.296972)
			(xy 199.956399 -106.344993) (xy 199.972109 -106.395923) (xy 199.980052 -106.448627) (xy 199.98055 -106.475276)
			(xy 199.980052 -106.501925) (xy 199.972109 -106.554629) (xy 199.956399 -106.605559) (xy 199.933273 -106.65358)
			(xy 199.903249 -106.697617) (xy 199.866997 -106.736688) (xy 199.825326 -106.769919) (xy 199.779168 -106.796568)
			(xy 199.729554 -106.81604) (xy 199.677592 -106.8279) (xy 199.624442 -106.831884) (xy 199.571292 -106.8279)
			(xy 199.51933 -106.81604) (xy 199.469716 -106.796568) (xy 199.423558 -106.769919) (xy 199.381887 -106.736688)
			(xy 199.345635 -106.697617) (xy 199.315611 -106.65358) (xy 199.292485 -106.605559) (xy 199.276775 -106.554629)
			(xy 199.268832 -106.501925) (xy 198.650687 -106.501925) (xy 198.657189 -106.515427) (xy 198.672899 -106.566357)
			(xy 198.680842 -106.619061) (xy 198.68134 -106.64571) (xy 198.680842 -106.672359) (xy 198.672899 -106.725063)
			(xy 198.657189 -106.775993) (xy 198.634063 -106.824014) (xy 198.604039 -106.868051) (xy 198.567787 -106.907122)
			(xy 198.526116 -106.940353) (xy 198.479958 -106.967002) (xy 198.430344 -106.986474) (xy 198.378382 -106.998334)
			(xy 198.325232 -107.002318) (xy 198.272082 -106.998334) (xy 198.22012 -106.986474) (xy 198.170506 -106.967002)
			(xy 198.124348 -106.940353) (xy 198.082677 -106.907122) (xy 198.046425 -106.868051) (xy 198.016401 -106.824014)
			(xy 197.993275 -106.775993) (xy 197.977565 -106.725063) (xy 197.969622 -106.672359) (xy 184.838848 -106.672359)
			(xy 184.838848 -106.715814) (xy 184.839075 -106.722415) (xy 184.842559 -106.735152) (xy 184.845706 -106.74096)
			(xy 184.850024 -106.748072) (xy 184.851294 -106.74985) (xy 184.860946 -106.758486) (xy 184.868566 -106.761788)
			(xy 184.891311 -106.772611) (xy 184.93351 -106.800111) (xy 184.971054 -106.833689) (xy 185.003075 -106.872569)
			(xy 185.028834 -106.915852) (xy 185.047737 -106.96254) (xy 185.059345 -107.011553) (xy 185.06186 -107.036616)
			(xy 185.062622 -107.046268) (xy 185.067702 -107.056682) (xy 185.069812 -107.060346) (xy 185.075043 -107.066987)
			(xy 185.078116 -107.06989) (xy 185.128662 -107.116372) (xy 185.135113 -107.121932) (xy 185.150688 -107.128799)
			(xy 185.159142 -107.129834) (xy 185.162698 -107.130088) (xy 185.881518 -107.130088) (xy 185.885074 -107.129834)
			(xy 185.893538 -107.128836) (xy 185.909125 -107.121966) (xy 185.915554 -107.116372) (xy 185.9661 -107.06989)
			(xy 185.969178 -107.066991) (xy 185.974414 -107.060352) (xy 185.976514 -107.056682) (xy 185.981594 -107.046268)
			(xy 185.982356 -107.036616) (xy 185.984936 -107.010774) (xy 185.997123 -106.960292) (xy 186.01705 -106.912336)
			(xy 186.044227 -106.868083) (xy 186.077986 -106.828622) (xy 186.117498 -106.794921) (xy 186.161791 -106.76781)
			(xy 186.209777 -106.747955) (xy 186.260276 -106.735843) (xy 186.312048 -106.731772) (xy 186.36382 -106.735843)
			(xy 186.414319 -106.747955) (xy 186.462305 -106.76781) (xy 186.506598 -106.794921) (xy 186.54611 -106.828622)
			(xy 186.579869 -106.868083) (xy 186.607046 -106.912336) (xy 186.626973 -106.960292) (xy 186.63916 -107.010774)
			(xy 186.64174 -107.036616) (xy 186.642502 -107.046268) (xy 186.647582 -107.056682) (xy 186.649691 -107.060346)
			(xy 186.654921 -107.066989) (xy 186.657996 -107.06989) (xy 186.678797 -107.089019) (xy 190.781688 -107.089019)
			(xy 190.781688 -107.037045) (xy 190.789818 -106.98571) (xy 190.805879 -106.93628) (xy 190.829475 -106.88997)
			(xy 190.860025 -106.847922) (xy 190.896776 -106.811171) (xy 190.938824 -106.780621) (xy 190.985134 -106.757025)
			(xy 191.034564 -106.740964) (xy 191.085899 -106.732834) (xy 191.137873 -106.732834) (xy 191.189208 -106.740964)
			(xy 191.238638 -106.757025) (xy 191.284948 -106.780621) (xy 191.326996 -106.811171) (xy 191.363747 -106.847922)
			(xy 191.394297 -106.88997) (xy 191.417893 -106.93628) (xy 191.433954 -106.98571) (xy 191.442084 -107.037045)
			(xy 191.442594 -107.063032) (xy 191.442084 -107.089019) (xy 191.581788 -107.089019) (xy 191.581788 -107.037045)
			(xy 191.589918 -106.98571) (xy 191.605979 -106.93628) (xy 191.629575 -106.88997) (xy 191.660125 -106.847922)
			(xy 191.696876 -106.811171) (xy 191.738924 -106.780621) (xy 191.785234 -106.757025) (xy 191.834664 -106.740964)
			(xy 191.885999 -106.732834) (xy 191.937973 -106.732834) (xy 191.989308 -106.740964) (xy 192.038738 -106.757025)
			(xy 192.085048 -106.780621) (xy 192.127096 -106.811171) (xy 192.163847 -106.847922) (xy 192.194397 -106.88997)
			(xy 192.217993 -106.93628) (xy 192.234054 -106.98571) (xy 192.242184 -107.037045) (xy 192.242694 -107.063032)
			(xy 192.242184 -107.089019) (xy 192.381888 -107.089019) (xy 192.381888 -107.037045) (xy 192.390018 -106.98571)
			(xy 192.406079 -106.93628) (xy 192.429675 -106.88997) (xy 192.460225 -106.847922) (xy 192.496976 -106.811171)
			(xy 192.539024 -106.780621) (xy 192.585334 -106.757025) (xy 192.634764 -106.740964) (xy 192.686099 -106.732834)
			(xy 192.738073 -106.732834) (xy 192.789408 -106.740964) (xy 192.838838 -106.757025) (xy 192.885148 -106.780621)
			(xy 192.927196 -106.811171) (xy 192.963947 -106.847922) (xy 192.994497 -106.88997) (xy 193.018093 -106.93628)
			(xy 193.034154 -106.98571) (xy 193.042284 -107.037045) (xy 193.042794 -107.063032) (xy 193.042284 -107.089019)
			(xy 193.034154 -107.140354) (xy 193.018093 -107.189784) (xy 192.994497 -107.236094) (xy 192.963947 -107.278142)
			(xy 192.927196 -107.314893) (xy 192.885148 -107.345443) (xy 192.838838 -107.369039) (xy 192.789408 -107.3851)
			(xy 192.738073 -107.39323) (xy 192.686099 -107.39323) (xy 192.634764 -107.3851) (xy 192.585334 -107.369039)
			(xy 192.539024 -107.345443) (xy 192.496976 -107.314893) (xy 192.460225 -107.278142) (xy 192.429675 -107.236094)
			(xy 192.406079 -107.189784) (xy 192.390018 -107.140354) (xy 192.381888 -107.089019) (xy 192.242184 -107.089019)
			(xy 192.234054 -107.140354) (xy 192.217993 -107.189784) (xy 192.194397 -107.236094) (xy 192.163847 -107.278142)
			(xy 192.127096 -107.314893) (xy 192.085048 -107.345443) (xy 192.038738 -107.369039) (xy 191.989308 -107.3851)
			(xy 191.937973 -107.39323) (xy 191.885999 -107.39323) (xy 191.834664 -107.3851) (xy 191.785234 -107.369039)
			(xy 191.738924 -107.345443) (xy 191.696876 -107.314893) (xy 191.660125 -107.278142) (xy 191.629575 -107.236094)
			(xy 191.605979 -107.189784) (xy 191.589918 -107.140354) (xy 191.581788 -107.089019) (xy 191.442084 -107.089019)
			(xy 191.433954 -107.140354) (xy 191.417893 -107.189784) (xy 191.394297 -107.236094) (xy 191.363747 -107.278142)
			(xy 191.326996 -107.314893) (xy 191.284948 -107.345443) (xy 191.238638 -107.369039) (xy 191.189208 -107.3851)
			(xy 191.137873 -107.39323) (xy 191.085899 -107.39323) (xy 191.034564 -107.3851) (xy 190.985134 -107.369039)
			(xy 190.938824 -107.345443) (xy 190.896776 -107.314893) (xy 190.860025 -107.278142) (xy 190.829475 -107.236094)
			(xy 190.805879 -107.189784) (xy 190.789818 -107.140354) (xy 190.781688 -107.089019) (xy 186.678797 -107.089019)
			(xy 186.708542 -107.116372) (xy 186.714992 -107.121935) (xy 186.730566 -107.128808) (xy 186.739022 -107.129834)
			(xy 186.742578 -107.130088) (xy 190.053214 -107.130088) (xy 190.058105 -107.130221) (xy 190.067701 -107.132132)
			(xy 190.072264 -107.133898) (xy 190.116714 -107.151932) (xy 190.128142 -107.156665) (xy 190.150269 -107.167725)
			(xy 190.16091 -107.17403) (xy 190.17655 -107.183834) (xy 190.205587 -107.206628) (xy 190.218822 -107.219496)
			(xy 190.282576 -107.28325) (xy 190.300031 -107.301476) (xy 190.329319 -107.342568) (xy 190.35145 -107.387918)
			(xy 190.365821 -107.43629) (xy 190.372043 -107.486367) (xy 190.371476 -107.511596) (xy 190.37046 -107.53725)
			(xy 190.395131 -107.542155) (xy 190.442723 -107.558434) (xy 190.487303 -107.58173) (xy 190.527843 -107.611504)
			(xy 190.563409 -107.647073) (xy 190.593181 -107.687615) (xy 190.616474 -107.732196) (xy 190.63275 -107.779789)
			(xy 190.637668 -107.804458) (xy 190.663322 -107.803442) (xy 190.68855 -107.802913) (xy 190.738623 -107.809133)
			(xy 190.786992 -107.823498) (xy 190.832343 -107.845619) (xy 190.87344 -107.874892) (xy 190.888036 -107.888865)
			(xy 191.581788 -107.888865) (xy 191.581788 -107.836891) (xy 191.589918 -107.785556) (xy 191.605979 -107.736126)
			(xy 191.629575 -107.689816) (xy 191.660125 -107.647768) (xy 191.696876 -107.611017) (xy 191.738924 -107.580467)
			(xy 191.785234 -107.556871) (xy 191.834664 -107.54081) (xy 191.885999 -107.53268) (xy 191.937973 -107.53268)
			(xy 191.989308 -107.54081) (xy 192.038738 -107.556871) (xy 192.085048 -107.580467) (xy 192.127096 -107.611017)
			(xy 192.163847 -107.647768) (xy 192.194397 -107.689816) (xy 192.217993 -107.736126) (xy 192.234054 -107.785556)
			(xy 192.242184 -107.836891) (xy 192.242694 -107.862878) (xy 192.242184 -107.888865) (xy 192.381888 -107.888865)
			(xy 192.381888 -107.836891) (xy 192.390018 -107.785556) (xy 192.406079 -107.736126) (xy 192.429675 -107.689816)
			(xy 192.460225 -107.647768) (xy 192.496976 -107.611017) (xy 192.539024 -107.580467) (xy 192.585334 -107.556871)
			(xy 192.634764 -107.54081) (xy 192.686099 -107.53268) (xy 192.738073 -107.53268) (xy 192.789408 -107.54081)
			(xy 192.838838 -107.556871) (xy 192.885148 -107.580467) (xy 192.927196 -107.611017) (xy 192.963947 -107.647768)
			(xy 192.994497 -107.689816) (xy 193.018093 -107.736126) (xy 193.034154 -107.785556) (xy 193.042284 -107.836891)
			(xy 193.042794 -107.862878) (xy 193.042284 -107.888865) (xy 193.181734 -107.888865) (xy 193.181734 -107.836891)
			(xy 193.189864 -107.785556) (xy 193.205925 -107.736126) (xy 193.229521 -107.689816) (xy 193.260071 -107.647768)
			(xy 193.296822 -107.611017) (xy 193.33887 -107.580467) (xy 193.38518 -107.556871) (xy 193.43461 -107.54081)
			(xy 193.485945 -107.53268) (xy 193.537919 -107.53268) (xy 193.589254 -107.54081) (xy 193.638684 -107.556871)
			(xy 193.684994 -107.580467) (xy 193.727042 -107.611017) (xy 193.763793 -107.647768) (xy 193.794343 -107.689816)
			(xy 193.817939 -107.736126) (xy 193.834 -107.785556) (xy 193.84213 -107.836891) (xy 193.84264 -107.862878)
			(xy 193.84213 -107.888865) (xy 193.981834 -107.888865) (xy 193.981834 -107.836891) (xy 193.989964 -107.785556)
			(xy 194.006025 -107.736126) (xy 194.029621 -107.689816) (xy 194.060171 -107.647768) (xy 194.096922 -107.611017)
			(xy 194.13897 -107.580467) (xy 194.18528 -107.556871) (xy 194.23471 -107.54081) (xy 194.286045 -107.53268)
			(xy 194.338019 -107.53268) (xy 194.389354 -107.54081) (xy 194.438784 -107.556871) (xy 194.485094 -107.580467)
			(xy 194.492006 -107.585489) (xy 195.35901 -107.585489) (xy 195.35901 -107.532191) (xy 195.366953 -107.479487)
			(xy 195.382663 -107.428557) (xy 195.405789 -107.380536) (xy 195.435813 -107.336499) (xy 195.472065 -107.297428)
			(xy 195.513736 -107.264197) (xy 195.559894 -107.237548) (xy 195.609508 -107.218076) (xy 195.66147 -107.206216)
			(xy 195.71462 -107.202233) (xy 195.76777 -107.206216) (xy 195.819732 -107.218076) (xy 195.869346 -107.237548)
			(xy 195.915504 -107.264197) (xy 195.957175 -107.297428) (xy 195.993427 -107.336499) (xy 196.023451 -107.380536)
			(xy 196.046577 -107.428557) (xy 196.062287 -107.479487) (xy 196.069809 -107.5294) (xy 197.986168 -107.5294)
			(xy 197.990151 -107.476251) (xy 198.00201 -107.424289) (xy 198.021481 -107.374674) (xy 198.048128 -107.328516)
			(xy 198.081357 -107.286844) (xy 198.120425 -107.250589) (xy 198.16446 -107.220562) (xy 198.212478 -107.197433)
			(xy 198.263407 -107.181718) (xy 198.316109 -107.173769) (xy 198.342758 -107.173268) (xy 198.343012 -107.173268)
			(xy 198.367877 -107.173718) (xy 198.417123 -107.180649) (xy 198.464926 -107.194361) (xy 198.510358 -107.214587)
			(xy 198.552536 -107.240933) (xy 198.571866 -107.25658) (xy 198.583304 -107.265496) (xy 198.609823 -107.277194)
			(xy 198.638561 -107.280958) (xy 198.667198 -107.276484) (xy 198.693419 -107.264134) (xy 198.715105 -107.244904)
			(xy 198.730505 -107.22035) (xy 198.734934 -107.206542) (xy 198.74228 -107.18197) (xy 198.763146 -107.135119)
			(xy 198.79052 -107.091748) (xy 198.823835 -107.052753) (xy 198.862401 -107.018944) (xy 198.905419 -106.991018)
			(xy 198.951999 -106.969555) (xy 199.001178 -106.954998) (xy 199.051936 -106.94765) (xy 199.07758 -106.947208)
			(xy 199.104233 -106.947648) (xy 199.156945 -106.95559) (xy 199.207884 -106.9713) (xy 199.255912 -106.994427)
			(xy 199.299957 -107.024454) (xy 199.339035 -107.060711) (xy 199.372272 -107.102387) (xy 199.398926 -107.148551)
			(xy 199.418402 -107.198173) (xy 199.430264 -107.250142) (xy 199.434248 -107.3033) (xy 199.430264 -107.356458)
			(xy 199.418402 -107.408427) (xy 199.398926 -107.458049) (xy 199.372272 -107.504213) (xy 199.339035 -107.545889)
			(xy 199.299957 -107.582146) (xy 199.255912 -107.612173) (xy 199.207884 -107.6353) (xy 199.156945 -107.65101)
			(xy 199.104233 -107.658952) (xy 199.07758 -107.659424) (xy 199.077326 -107.659424) (xy 199.052461 -107.658954)
			(xy 199.003217 -107.652028) (xy 198.955414 -107.638321) (xy 198.909982 -107.6181) (xy 198.867803 -107.591757)
			(xy 198.848472 -107.576112) (xy 198.837086 -107.567125) (xy 198.810552 -107.555434) (xy 198.781801 -107.55168)
			(xy 198.753154 -107.556165) (xy 198.726926 -107.568528) (xy 198.705235 -107.587769) (xy 198.689833 -107.612336)
			(xy 198.685404 -107.62615) (xy 198.678019 -107.65071) (xy 198.657157 -107.697558) (xy 198.629787 -107.740929)
			(xy 198.596477 -107.779923) (xy 198.557917 -107.813733) (xy 198.514904 -107.84166) (xy 198.468328 -107.863126)
			(xy 198.419154 -107.877686) (xy 198.3684 -107.88504) (xy 198.342758 -107.885484) (xy 198.316109 -107.885031)
			(xy 198.263407 -107.877082) (xy 198.212478 -107.861367) (xy 198.16446 -107.838238) (xy 198.120425 -107.808211)
			(xy 198.081357 -107.771956) (xy 198.048128 -107.730284) (xy 198.021481 -107.684126) (xy 198.00201 -107.634511)
			(xy 197.990151 -107.582549) (xy 197.986168 -107.5294) (xy 196.069809 -107.5294) (xy 196.07023 -107.532191)
			(xy 196.070728 -107.55884) (xy 196.07023 -107.585489) (xy 196.062287 -107.638193) (xy 196.046577 -107.689123)
			(xy 196.023451 -107.737144) (xy 195.993427 -107.781181) (xy 195.957175 -107.820252) (xy 195.915504 -107.853483)
			(xy 195.869346 -107.880132) (xy 195.819732 -107.899604) (xy 195.76777 -107.911464) (xy 195.71462 -107.915448)
			(xy 195.66147 -107.911464) (xy 195.609508 -107.899604) (xy 195.559894 -107.880132) (xy 195.513736 -107.853483)
			(xy 195.472065 -107.820252) (xy 195.435813 -107.781181) (xy 195.405789 -107.737144) (xy 195.382663 -107.689123)
			(xy 195.366953 -107.638193) (xy 195.35901 -107.585489) (xy 194.492006 -107.585489) (xy 194.527142 -107.611017)
			(xy 194.563893 -107.647768) (xy 194.594443 -107.689816) (xy 194.618039 -107.736126) (xy 194.6341 -107.785556)
			(xy 194.64223 -107.836891) (xy 194.64274 -107.862878) (xy 194.64223 -107.888865) (xy 194.6341 -107.9402)
			(xy 194.618039 -107.98963) (xy 194.594443 -108.03594) (xy 194.563893 -108.077988) (xy 194.527142 -108.114739)
			(xy 194.485094 -108.145289) (xy 194.438784 -108.168885) (xy 194.389354 -108.184946) (xy 194.338019 -108.193076)
			(xy 194.286045 -108.193076) (xy 194.23471 -108.184946) (xy 194.18528 -108.168885) (xy 194.13897 -108.145289)
			(xy 194.096922 -108.114739) (xy 194.060171 -108.077988) (xy 194.029621 -108.03594) (xy 194.006025 -107.98963)
			(xy 193.989964 -107.9402) (xy 193.981834 -107.888865) (xy 193.84213 -107.888865) (xy 193.834 -107.9402)
			(xy 193.817939 -107.98963) (xy 193.794343 -108.03594) (xy 193.763793 -108.077988) (xy 193.727042 -108.114739)
			(xy 193.684994 -108.145289) (xy 193.638684 -108.168885) (xy 193.589254 -108.184946) (xy 193.537919 -108.193076)
			(xy 193.485945 -108.193076) (xy 193.43461 -108.184946) (xy 193.38518 -108.168885) (xy 193.33887 -108.145289)
			(xy 193.296822 -108.114739) (xy 193.260071 -108.077988) (xy 193.229521 -108.03594) (xy 193.205925 -107.98963)
			(xy 193.189864 -107.9402) (xy 193.181734 -107.888865) (xy 193.042284 -107.888865) (xy 193.034154 -107.9402)
			(xy 193.018093 -107.98963) (xy 192.994497 -108.03594) (xy 192.963947 -108.077988) (xy 192.927196 -108.114739)
			(xy 192.885148 -108.145289) (xy 192.838838 -108.168885) (xy 192.789408 -108.184946) (xy 192.738073 -108.193076)
			(xy 192.686099 -108.193076) (xy 192.634764 -108.184946) (xy 192.585334 -108.168885) (xy 192.539024 -108.145289)
			(xy 192.496976 -108.114739) (xy 192.460225 -108.077988) (xy 192.429675 -108.03594) (xy 192.406079 -107.98963)
			(xy 192.390018 -107.9402) (xy 192.381888 -107.888865) (xy 192.242184 -107.888865) (xy 192.234054 -107.9402)
			(xy 192.217993 -107.98963) (xy 192.194397 -108.03594) (xy 192.163847 -108.077988) (xy 192.127096 -108.114739)
			(xy 192.085048 -108.145289) (xy 192.038738 -108.168885) (xy 191.989308 -108.184946) (xy 191.937973 -108.193076)
			(xy 191.885999 -108.193076) (xy 191.834664 -108.184946) (xy 191.785234 -108.168885) (xy 191.738924 -108.145289)
			(xy 191.696876 -108.114739) (xy 191.660125 -108.077988) (xy 191.629575 -108.03594) (xy 191.605979 -107.98963)
			(xy 191.589918 -107.9402) (xy 191.581788 -107.888865) (xy 190.888036 -107.888865) (xy 190.891668 -107.892342)
			(xy 191.082422 -108.083096) (xy 191.099793 -108.101223) (xy 191.128957 -108.142085) (xy 191.151035 -108.187172)
			(xy 191.165428 -108.235266) (xy 191.17175 -108.285069) (xy 191.171322 -108.310172) (xy 191.170306 -108.33735)
			(xy 191.194962 -108.342253) (xy 191.242527 -108.35852) (xy 191.287085 -108.381793) (xy 191.327611 -108.411537)
			(xy 191.363173 -108.447067) (xy 191.392952 -108.487567) (xy 191.416265 -108.532104) (xy 191.432573 -108.579655)
			(xy 191.437514 -108.604304) (xy 191.438022 -108.604304) (xy 191.456056 -108.603796) (xy 191.464692 -108.603542)
			(xy 191.471296 -108.603288) (xy 191.474852 -108.603288) (xy 191.491616 -108.603796) (xy 191.501268 -108.603796)
			(xy 191.520572 -108.60659) (xy 191.525323 -108.60686) (xy 191.534782 -108.60583) (xy 191.539368 -108.604558)
			(xy 191.551306 -108.599224) (xy 191.569594 -108.587794) (xy 191.570102 -108.58754) (xy 191.573683 -108.585167)
			(xy 191.580068 -108.579423) (xy 191.582802 -108.57611) (xy 191.598804 -108.556298) (xy 191.601598 -108.548678)
			(xy 191.610744 -108.525201) (xy 191.635119 -108.481108) (xy 191.665902 -108.441223) (xy 191.702379 -108.406469)
			(xy 191.743706 -108.377652) (xy 191.788926 -108.355437) (xy 191.836994 -108.34034) (xy 191.886795 -108.33271)
			(xy 191.911986 -108.33227) (xy 191.937975 -108.332778) (xy 191.989312 -108.340907) (xy 192.038746 -108.356967)
			(xy 192.085059 -108.380561) (xy 192.127111 -108.411111) (xy 192.163866 -108.447862) (xy 192.19442 -108.48991)
			(xy 192.21802 -108.536221) (xy 192.234084 -108.585653) (xy 192.242219 -108.63699) (xy 192.242694 -108.662978)
			(xy 192.242216 -108.688165) (xy 192.242093 -108.688965) (xy 192.381888 -108.688965) (xy 192.381888 -108.636991)
			(xy 192.390018 -108.585656) (xy 192.406079 -108.536226) (xy 192.429675 -108.489916) (xy 192.460225 -108.447868)
			(xy 192.496976 -108.411117) (xy 192.539024 -108.380567) (xy 192.585334 -108.356971) (xy 192.634764 -108.34091)
			(xy 192.686099 -108.33278) (xy 192.738073 -108.33278) (xy 192.789408 -108.34091) (xy 192.838838 -108.356971)
			(xy 192.885148 -108.380567) (xy 192.927196 -108.411117) (xy 192.963947 -108.447868) (xy 192.994497 -108.489916)
			(xy 193.018093 -108.536226) (xy 193.034154 -108.585656) (xy 193.042284 -108.636991) (xy 193.042794 -108.662978)
			(xy 193.042284 -108.688965) (xy 193.181734 -108.688965) (xy 193.181734 -108.636991) (xy 193.189864 -108.585656)
			(xy 193.205925 -108.536226) (xy 193.229521 -108.489916) (xy 193.260071 -108.447868) (xy 193.296822 -108.411117)
			(xy 193.33887 -108.380567) (xy 193.38518 -108.356971) (xy 193.43461 -108.34091) (xy 193.485945 -108.33278)
			(xy 193.537919 -108.33278) (xy 193.589254 -108.34091) (xy 193.638684 -108.356971) (xy 193.684994 -108.380567)
			(xy 193.727042 -108.411117) (xy 193.763793 -108.447868) (xy 193.794343 -108.489916) (xy 193.817939 -108.536226)
			(xy 193.834 -108.585656) (xy 193.84213 -108.636991) (xy 193.84264 -108.662978) (xy 193.84213 -108.688965)
			(xy 193.981834 -108.688965) (xy 193.981834 -108.636991) (xy 193.989964 -108.585656) (xy 194.006025 -108.536226)
			(xy 194.029621 -108.489916) (xy 194.060171 -108.447868) (xy 194.096922 -108.411117) (xy 194.13897 -108.380567)
			(xy 194.18528 -108.356971) (xy 194.23471 -108.34091) (xy 194.286045 -108.33278) (xy 194.338019 -108.33278)
			(xy 194.389354 -108.34091) (xy 194.438784 -108.356971) (xy 194.485094 -108.380567) (xy 194.527142 -108.411117)
			(xy 194.55089 -108.434865) (xy 195.660762 -108.434865) (xy 195.660762 -108.381567) (xy 195.668705 -108.328863)
			(xy 195.684415 -108.277933) (xy 195.707541 -108.229912) (xy 195.737565 -108.185875) (xy 195.773817 -108.146804)
			(xy 195.815488 -108.113573) (xy 195.861646 -108.086924) (xy 195.91126 -108.067452) (xy 195.963222 -108.055592)
			(xy 196.016372 -108.051609) (xy 196.069522 -108.055592) (xy 196.121484 -108.067452) (xy 196.171098 -108.086924)
			(xy 196.217256 -108.113573) (xy 196.258927 -108.146804) (xy 196.295179 -108.185875) (xy 196.325203 -108.229912)
			(xy 196.348329 -108.277933) (xy 196.364039 -108.328863) (xy 196.371982 -108.381567) (xy 196.37248 -108.408216)
			(xy 196.371982 -108.434865) (xy 196.364039 -108.487569) (xy 196.348329 -108.538499) (xy 196.345006 -108.5454)
			(xy 197.986168 -108.5454) (xy 197.990151 -108.492251) (xy 198.00201 -108.440289) (xy 198.021481 -108.390674)
			(xy 198.048128 -108.344516) (xy 198.081357 -108.302844) (xy 198.120425 -108.266589) (xy 198.16446 -108.236562)
			(xy 198.212478 -108.213433) (xy 198.263407 -108.197718) (xy 198.316109 -108.189769) (xy 198.342758 -108.189268)
			(xy 198.367782 -108.189734) (xy 198.417337 -108.196735) (xy 198.465423 -108.210607) (xy 198.511093 -108.231075)
			(xy 198.553447 -108.257737) (xy 198.591651 -108.290066) (xy 198.624952 -108.327426) (xy 198.639176 -108.348018)
			(xy 198.646741 -108.358132) (xy 198.668982 -108.370014) (xy 198.681594 -108.370624) (xy 198.765922 -108.370624)
			(xy 198.778533 -108.370018) (xy 198.800781 -108.358134) (xy 198.80834 -108.348018) (xy 198.822583 -108.327438)
			(xy 198.855878 -108.290072) (xy 198.894078 -108.257736) (xy 198.936428 -108.231067) (xy 198.982095 -108.21059)
			(xy 199.03018 -108.196708) (xy 199.079734 -108.189695) (xy 199.104758 -108.189268) (xy 199.105012 -108.189268)
			(xy 199.133586 -108.189858) (xy 199.189997 -108.199008) (xy 199.244226 -108.217039) (xy 199.294885 -108.24349)
			(xy 199.318118 -108.260134) (xy 199.326246 -108.26623) (xy 199.345804 -108.27131) (xy 199.436736 -108.258356)
			(xy 199.454008 -108.247942) (xy 199.460104 -108.239814) (xy 199.480736 -108.213225) (xy 199.527913 -108.165225)
			(xy 199.581013 -108.123873) (xy 199.639106 -108.089891) (xy 199.701176 -108.063873) (xy 199.766137 -108.046276)
			(xy 199.832853 -108.037407) (xy 199.866504 -108.036868) (xy 199.866758 -108.036868) (xy 199.898721 -108.037394)
			(xy 199.962142 -108.045401) (xy 200.02406 -108.061295) (xy 200.083497 -108.084823) (xy 200.139517 -108.115616)
			(xy 200.191235 -108.153188) (xy 200.237837 -108.196946) (xy 200.278586 -108.246199) (xy 200.31284 -108.300172)
			(xy 200.340059 -108.358012) (xy 200.359814 -108.418808) (xy 200.371793 -108.481601) (xy 200.375808 -108.5454)
			(xy 200.371793 -108.609199) (xy 200.359814 -108.671992) (xy 200.340059 -108.732788) (xy 200.31284 -108.790628)
			(xy 200.278586 -108.844601) (xy 200.237837 -108.893854) (xy 200.191235 -108.937612) (xy 200.139517 -108.975184)
			(xy 200.083497 -109.005977) (xy 200.02406 -109.029505) (xy 199.962142 -109.045399) (xy 199.898721 -109.053406)
			(xy 199.866758 -109.053884) (xy 199.866504 -109.053884) (xy 199.832855 -109.053364) (xy 199.766148 -109.044464)
			(xy 199.701196 -109.026847) (xy 199.639134 -109.00082) (xy 199.581046 -108.966837) (xy 199.527946 -108.925492)
			(xy 199.480761 -108.877506) (xy 199.460104 -108.850938) (xy 199.454008 -108.84281) (xy 199.436736 -108.832396)
			(xy 199.345804 -108.819442) (xy 199.326246 -108.824522) (xy 199.318118 -108.830618) (xy 199.294894 -108.84728)
			(xy 199.244243 -108.873758) (xy 199.19001 -108.891793) (xy 199.133589 -108.900921) (xy 199.105012 -108.901484)
			(xy 199.104758 -108.901484) (xy 199.079731 -108.901104) (xy 199.030172 -108.894089) (xy 198.982082 -108.880204)
			(xy 198.936411 -108.859723) (xy 198.894058 -108.833048) (xy 198.855857 -108.800705) (xy 198.822561 -108.763332)
			(xy 198.80834 -108.742734) (xy 198.800828 -108.732573) (xy 198.778546 -108.720718) (xy 198.765922 -108.720128)
			(xy 198.681594 -108.720128) (xy 198.668987 -108.720763) (xy 198.64674 -108.732628) (xy 198.639176 -108.742734)
			(xy 198.624972 -108.763343) (xy 198.591671 -108.80071) (xy 198.553466 -108.833045) (xy 198.511109 -108.859712)
			(xy 198.465435 -108.880185) (xy 198.417344 -108.894059) (xy 198.367784 -108.901063) (xy 198.342758 -108.901484)
			(xy 198.316109 -108.901031) (xy 198.263407 -108.893082) (xy 198.212478 -108.877367) (xy 198.16446 -108.854238)
			(xy 198.120425 -108.824211) (xy 198.081357 -108.787956) (xy 198.048128 -108.746284) (xy 198.021481 -108.700126)
			(xy 198.00201 -108.650511) (xy 197.990151 -108.598549) (xy 197.986168 -108.5454) (xy 196.345006 -108.5454)
			(xy 196.325203 -108.58652) (xy 196.295179 -108.630557) (xy 196.258927 -108.669628) (xy 196.217256 -108.702859)
			(xy 196.171098 -108.729508) (xy 196.121484 -108.74898) (xy 196.069522 -108.76084) (xy 196.016372 -108.764824)
			(xy 195.963222 -108.76084) (xy 195.91126 -108.74898) (xy 195.861646 -108.729508) (xy 195.815488 -108.702859)
			(xy 195.773817 -108.669628) (xy 195.737565 -108.630557) (xy 195.707541 -108.58652) (xy 195.684415 -108.538499)
			(xy 195.668705 -108.487569) (xy 195.660762 -108.434865) (xy 194.55089 -108.434865) (xy 194.563893 -108.447868)
			(xy 194.594443 -108.489916) (xy 194.618039 -108.536226) (xy 194.6341 -108.585656) (xy 194.64223 -108.636991)
			(xy 194.64274 -108.662978) (xy 194.64223 -108.688965) (xy 194.6341 -108.7403) (xy 194.618039 -108.78973)
			(xy 194.594443 -108.83604) (xy 194.563893 -108.878088) (xy 194.527142 -108.914839) (xy 194.485094 -108.945389)
			(xy 194.438784 -108.968985) (xy 194.389354 -108.985046) (xy 194.338019 -108.993176) (xy 194.286045 -108.993176)
			(xy 194.23471 -108.985046) (xy 194.18528 -108.968985) (xy 194.13897 -108.945389) (xy 194.096922 -108.914839)
			(xy 194.060171 -108.878088) (xy 194.029621 -108.83604) (xy 194.006025 -108.78973) (xy 193.989964 -108.7403)
			(xy 193.981834 -108.688965) (xy 193.84213 -108.688965) (xy 193.834 -108.7403) (xy 193.817939 -108.78973)
			(xy 193.794343 -108.83604) (xy 193.763793 -108.878088) (xy 193.727042 -108.914839) (xy 193.684994 -108.945389)
			(xy 193.638684 -108.968985) (xy 193.589254 -108.985046) (xy 193.537919 -108.993176) (xy 193.485945 -108.993176)
			(xy 193.43461 -108.985046) (xy 193.38518 -108.968985) (xy 193.33887 -108.945389) (xy 193.296822 -108.914839)
			(xy 193.260071 -108.878088) (xy 193.229521 -108.83604) (xy 193.205925 -108.78973) (xy 193.189864 -108.7403)
			(xy 193.181734 -108.688965) (xy 193.042284 -108.688965) (xy 193.034154 -108.7403) (xy 193.018093 -108.78973)
			(xy 192.994497 -108.83604) (xy 192.963947 -108.878088) (xy 192.927196 -108.914839) (xy 192.885148 -108.945389)
			(xy 192.838838 -108.968985) (xy 192.789408 -108.985046) (xy 192.738073 -108.993176) (xy 192.686099 -108.993176)
			(xy 192.634764 -108.985046) (xy 192.585334 -108.968985) (xy 192.539024 -108.945389) (xy 192.496976 -108.914839)
			(xy 192.460225 -108.878088) (xy 192.429675 -108.83604) (xy 192.406079 -108.78973) (xy 192.390018 -108.7403)
			(xy 192.381888 -108.688965) (xy 192.242093 -108.688965) (xy 192.234569 -108.737955) (xy 192.219464 -108.786011)
			(xy 192.197249 -108.831222) (xy 192.168438 -108.872544) (xy 192.133696 -108.909021) (xy 192.093827 -108.939811)
			(xy 192.049752 -108.964202) (xy 192.026286 -108.973366) (xy 192.018666 -108.97616) (xy 191.998854 -108.992162)
			(xy 191.995534 -108.994889) (xy 191.989785 -109.001273) (xy 191.987424 -109.004862) (xy 191.98717 -109.00537)
			(xy 191.97574 -109.023404) (xy 191.9732 -109.027976) (xy 191.970742 -109.03343) (xy 191.968163 -109.045109)
			(xy 191.96812 -109.05109) (xy 191.968628 -109.056932) (xy 191.968628 -109.057186) (xy 191.96939 -109.06252)
			(xy 191.96939 -109.062774) (xy 191.969644 -109.064552) (xy 191.97066 -109.07395) (xy 191.97066 -109.074458)
			(xy 191.971311 -109.083396) (xy 191.971695 -109.101315) (xy 191.971422 -109.110272) (xy 191.971168 -109.118908)
			(xy 191.97066 -109.136942) (xy 191.97066 -109.13745) (xy 191.995303 -109.142363) (xy 192.04284 -109.158646)
			(xy 192.087368 -109.181928) (xy 192.127864 -109.211676) (xy 192.163397 -109.247204) (xy 192.193149 -109.287696)
			(xy 192.216438 -109.332222) (xy 192.232726 -109.379756) (xy 192.237614 -109.404404) (xy 192.238122 -109.404404)
			(xy 192.256156 -109.403896) (xy 192.264792 -109.403642) (xy 192.271396 -109.403388) (xy 192.274952 -109.403388)
			(xy 192.291716 -109.403896) (xy 192.301368 -109.403896) (xy 192.320672 -109.40669) (xy 192.325423 -109.40696)
			(xy 192.334882 -109.40593) (xy 192.339468 -109.404658) (xy 192.351406 -109.399324) (xy 192.369694 -109.387894)
			(xy 192.370202 -109.38764) (xy 192.373783 -109.385267) (xy 192.380168 -109.379523) (xy 192.382902 -109.37621)
			(xy 192.398904 -109.356398) (xy 192.401698 -109.348778) (xy 192.410844 -109.325301) (xy 192.435219 -109.281208)
			(xy 192.466002 -109.241323) (xy 192.502479 -109.206569) (xy 192.543806 -109.177752) (xy 192.589026 -109.155537)
			(xy 192.637094 -109.14044) (xy 192.686895 -109.13281) (xy 192.712086 -109.13237) (xy 192.737521 -109.132836)
			(xy 192.78779 -109.140628) (xy 192.836273 -109.15603) (xy 192.881823 -109.178678) (xy 192.923365 -109.208037)
			(xy 192.959919 -109.243414) (xy 192.990621 -109.283975) (xy 193.014746 -109.32876) (xy 193.031725 -109.376713)
			(xy 193.036952 -109.40161) (xy 193.037714 -109.405166) (xy 193.039752 -109.412074) (xy 193.047107 -109.424449)
			(xy 193.052192 -109.42955) (xy 193.052446 -109.429804) (xy 193.056256 -109.432852) (xy 193.059308 -109.435059)
			(xy 193.065942 -109.438627) (xy 193.069464 -109.439964) (xy 193.077846 -109.443012) (xy 193.137282 -109.443012)
			(xy 193.146047 -109.442594) (xy 193.162531 -109.43661) (xy 193.16954 -109.431328) (xy 193.176398 -109.42574)
			(xy 193.185288 -109.411008) (xy 193.187066 -109.40161) (xy 193.192253 -109.376708) (xy 193.209252 -109.328768)
			(xy 193.233392 -109.283997) (xy 193.264104 -109.243451) (xy 193.300664 -109.208087) (xy 193.342208 -109.17874)
			(xy 193.387757 -109.156101) (xy 193.436235 -109.140705) (xy 193.4865 -109.132915) (xy 193.537364 -109.132915)
			(xy 193.587629 -109.140705) (xy 193.636107 -109.156101) (xy 193.681656 -109.17874) (xy 193.7232 -109.208087)
			(xy 193.75976 -109.243451) (xy 193.790472 -109.283997) (xy 193.814612 -109.328768) (xy 193.831611 -109.376708)
			(xy 193.836798 -109.40161) (xy 193.83756 -109.405166) (xy 193.839595 -109.412076) (xy 193.846945 -109.424456)
			(xy 193.852038 -109.42955) (xy 193.852292 -109.429804) (xy 193.856102 -109.432852) (xy 193.859153 -109.435062)
			(xy 193.865784 -109.438636) (xy 193.86931 -109.439964) (xy 193.877692 -109.443012) (xy 193.937382 -109.443012)
			(xy 193.946147 -109.442594) (xy 193.962631 -109.43661) (xy 193.96964 -109.431328) (xy 193.976498 -109.42574)
			(xy 193.985388 -109.411008) (xy 193.987166 -109.40161) (xy 193.992353 -109.376708) (xy 194.009352 -109.328768)
			(xy 194.033492 -109.283997) (xy 194.064204 -109.243451) (xy 194.100764 -109.208087) (xy 194.142308 -109.17874)
			(xy 194.187857 -109.156101) (xy 194.236335 -109.140705) (xy 194.2866 -109.132915) (xy 194.337464 -109.132915)
			(xy 194.387729 -109.140705) (xy 194.436207 -109.156101) (xy 194.481756 -109.17874) (xy 194.5233 -109.208087)
			(xy 194.55986 -109.243451) (xy 194.590572 -109.283997) (xy 194.614712 -109.328768) (xy 194.631617 -109.376443)
			(xy 195.134982 -109.376443) (xy 195.134982 -109.323145) (xy 195.142925 -109.270441) (xy 195.158635 -109.219511)
			(xy 195.181761 -109.17149) (xy 195.211785 -109.127453) (xy 195.248037 -109.088382) (xy 195.289708 -109.055151)
			(xy 195.335866 -109.028502) (xy 195.38548 -109.00903) (xy 195.437442 -108.99717) (xy 195.490592 -108.993187)
			(xy 195.543742 -108.99717) (xy 195.595704 -109.00903) (xy 195.645318 -109.028502) (xy 195.691476 -109.055151)
			(xy 195.733147 -109.088382) (xy 195.769399 -109.127453) (xy 195.799423 -109.17149) (xy 195.822549 -109.219511)
			(xy 195.838259 -109.270441) (xy 195.846202 -109.323145) (xy 195.8467 -109.349794) (xy 195.846202 -109.376443)
			(xy 195.838259 -109.429147) (xy 195.822549 -109.480077) (xy 195.799423 -109.528098) (xy 195.772559 -109.5675)
			(xy 197.986164 -109.5675) (xy 197.990147 -109.51435) (xy 198.002006 -109.462387) (xy 198.021477 -109.412772)
			(xy 198.048125 -109.366613) (xy 198.081354 -109.324941) (xy 198.120423 -109.288686) (xy 198.164458 -109.258659)
			(xy 198.212477 -109.235529) (xy 198.263406 -109.219814) (xy 198.316109 -109.211865) (xy 198.342758 -109.211364)
			(xy 198.368587 -109.211811) (xy 198.419705 -109.219258) (xy 198.469209 -109.234016) (xy 198.51606 -109.255775)
			(xy 198.559274 -109.284078) (xy 198.597943 -109.318331) (xy 198.631253 -109.357814) (xy 198.645272 -109.379512)
			(xy 198.65298 -109.391109) (xy 198.673544 -109.409871) (xy 198.698409 -109.422389) (xy 198.725729 -109.427731)
			(xy 198.753478 -109.425503) (xy 198.779595 -109.415869) (xy 198.802144 -109.399545) (xy 198.811134 -109.38891)
			(xy 198.828127 -109.368198) (xy 198.867245 -109.331596) (xy 198.911407 -109.301271) (xy 198.959615 -109.277908)
			(xy 199.010781 -109.262035) (xy 199.063748 -109.25401) (xy 199.090534 -109.253528) (xy 199.117184 -109.253956)
			(xy 199.169889 -109.261905) (xy 199.220821 -109.277619) (xy 199.268841 -109.300749) (xy 199.312879 -109.330777)
			(xy 199.351949 -109.367033) (xy 199.38518 -109.408706) (xy 199.411829 -109.454867) (xy 199.431301 -109.504484)
			(xy 199.443161 -109.556448) (xy 199.44353 -109.561376) (xy 201.747374 -109.561376) (xy 201.747879 -109.530089)
			(xy 201.755552 -109.467989) (xy 201.770792 -109.4073) (xy 201.793368 -109.348941) (xy 201.822938 -109.293796)
			(xy 201.859055 -109.242698) (xy 201.901172 -109.196422) (xy 201.948653 -109.155667) (xy 201.97445 -109.137958)
			(xy 201.9846 -109.130433) (xy 201.996462 -109.108162) (xy 201.997056 -109.09554) (xy 201.997056 -109.011212)
			(xy 201.996417 -108.998606) (xy 201.984555 -108.976358) (xy 201.97445 -108.968794) (xy 201.94864 -108.951109)
			(xy 201.901178 -108.91034) (xy 201.859078 -108.864054) (xy 201.822975 -108.812953) (xy 201.793416 -108.757807)
			(xy 201.770846 -108.699451) (xy 201.755609 -108.638767) (xy 201.747933 -108.576671) (xy 201.747934 -108.514103)
			(xy 201.755614 -108.452007) (xy 201.770855 -108.391324) (xy 201.793427 -108.332969) (xy 201.822989 -108.277825)
			(xy 201.859094 -108.226725) (xy 201.901197 -108.180442) (xy 201.948661 -108.139675) (xy 201.97445 -108.121958)
			(xy 201.9846 -108.114433) (xy 201.996462 -108.092162) (xy 201.997056 -108.07954) (xy 201.997056 -107.995212)
			(xy 201.996417 -107.982606) (xy 201.984555 -107.960358) (xy 201.97445 -107.952794) (xy 201.94864 -107.935109)
			(xy 201.901178 -107.89434) (xy 201.859078 -107.848054) (xy 201.822975 -107.796953) (xy 201.793416 -107.741807)
			(xy 201.770846 -107.683451) (xy 201.755609 -107.622767) (xy 201.747933 -107.560671) (xy 201.747934 -107.498103)
			(xy 201.755614 -107.436007) (xy 201.770855 -107.375324) (xy 201.793427 -107.316969) (xy 201.822989 -107.261825)
			(xy 201.859094 -107.210725) (xy 201.901197 -107.164442) (xy 201.948661 -107.123675) (xy 201.97445 -107.105958)
			(xy 201.9846 -107.098433) (xy 201.996462 -107.076162) (xy 201.997056 -107.06354) (xy 201.997056 -106.979212)
			(xy 201.996417 -106.966606) (xy 201.984555 -106.944358) (xy 201.97445 -106.936794) (xy 201.94864 -106.919109)
			(xy 201.901178 -106.87834) (xy 201.859078 -106.832054) (xy 201.822975 -106.780953) (xy 201.793416 -106.725807)
			(xy 201.770846 -106.667451) (xy 201.755609 -106.606767) (xy 201.747933 -106.544671) (xy 201.747934 -106.482103)
			(xy 201.755614 -106.420007) (xy 201.770855 -106.359324) (xy 201.793427 -106.300969) (xy 201.822989 -106.245825)
			(xy 201.859094 -106.194725) (xy 201.901197 -106.148442) (xy 201.948661 -106.107675) (xy 201.97445 -106.089958)
			(xy 201.9846 -106.082433) (xy 201.996462 -106.060162) (xy 201.997056 -106.04754) (xy 201.997056 -105.963212)
			(xy 201.996417 -105.950606) (xy 201.984555 -105.928358) (xy 201.97445 -105.920794) (xy 201.948637 -105.903108)
			(xy 201.901157 -105.862347) (xy 201.859041 -105.816066) (xy 201.822924 -105.764965) (xy 201.793352 -105.709818)
			(xy 201.770774 -105.651457) (xy 201.755531 -105.590767) (xy 201.747852 -105.528664) (xy 201.747374 -105.497376)
			(xy 201.747876 -105.465415) (xy 201.755887 -105.401997) (xy 201.771784 -105.340083) (xy 201.795316 -105.28065)
			(xy 201.82611 -105.224635) (xy 201.863683 -105.17292) (xy 201.90744 -105.126323) (xy 201.956693 -105.085578)
			(xy 202.010664 -105.051327) (xy 202.068503 -105.02411) (xy 202.129296 -105.004357) (xy 202.192086 -104.992379)
			(xy 202.255882 -104.988366) (xy 202.319678 -104.992379) (xy 202.382468 -105.004357) (xy 202.443261 -105.02411)
			(xy 202.5011 -105.051327) (xy 202.555071 -105.085578) (xy 202.604324 -105.126323) (xy 202.648081 -105.17292)
			(xy 202.685654 -105.224635) (xy 202.716448 -105.28065) (xy 202.73998 -105.340083) (xy 202.755877 -105.401997)
			(xy 202.763888 -105.465415) (xy 202.76439 -105.497376) (xy 202.763941 -105.528664) (xy 202.756261 -105.590768)
			(xy 202.741014 -105.651459) (xy 202.718431 -105.709819) (xy 202.688853 -105.764964) (xy 202.652728 -105.816061)
			(xy 202.610603 -105.862335) (xy 202.563115 -105.903087) (xy 202.537314 -105.920794) (xy 202.52718 -105.928335)
			(xy 202.515312 -105.950595) (xy 202.514708 -105.963212) (xy 202.514708 -106.04754) (xy 202.51539 -106.06014)
			(xy 202.527222 -106.082387) (xy 202.537314 -106.089958) (xy 202.56308 -106.107705) (xy 202.610543 -106.148468)
			(xy 202.652646 -106.194746) (xy 202.688751 -106.245842) (xy 202.718313 -106.300982) (xy 202.740886 -106.359333)
			(xy 202.756126 -106.420013) (xy 202.763806 -106.482104) (xy 202.763806 -106.513376) (xy 207.13573 -106.513376)
			(xy 207.13621 -106.482088) (xy 207.143884 -106.419986) (xy 207.159126 -106.359295) (xy 207.181704 -106.300935)
			(xy 207.211278 -106.24579) (xy 207.247399 -106.194693) (xy 207.289521 -106.148418) (xy 207.337007 -106.107665)
			(xy 207.362806 -106.089958) (xy 207.372966 -106.082445) (xy 207.38482 -106.060164) (xy 207.385412 -106.04754)
			(xy 207.385412 -105.963212) (xy 207.38479 -105.950603) (xy 207.372918 -105.928354) (xy 207.362806 -105.920794)
			(xy 207.336983 -105.903122) (xy 207.289505 -105.862358) (xy 207.247391 -105.816074) (xy 207.211275 -105.764971)
			(xy 207.181706 -105.709822) (xy 207.159129 -105.65146) (xy 207.143886 -105.590768) (xy 207.136208 -105.528664)
			(xy 207.13573 -105.497376) (xy 207.136232 -105.465415) (xy 207.144243 -105.401997) (xy 207.16014 -105.340083)
			(xy 207.183672 -105.28065) (xy 207.214466 -105.224635) (xy 207.252039 -105.17292) (xy 207.295796 -105.126323)
			(xy 207.345049 -105.085578) (xy 207.39902 -105.051327) (xy 207.456859 -105.02411) (xy 207.517652 -105.004357)
			(xy 207.580442 -104.992379) (xy 207.644238 -104.988366) (xy 207.708034 -104.992379) (xy 207.770824 -105.004357)
			(xy 207.831617 -105.02411) (xy 207.889456 -105.051327) (xy 207.943427 -105.085578) (xy 207.99268 -105.126323)
			(xy 208.036437 -105.17292) (xy 208.07401 -105.224635) (xy 208.104804 -105.28065) (xy 208.128336 -105.340083)
			(xy 208.144233 -105.401997) (xy 208.152244 -105.465415) (xy 208.152746 -105.497376) (xy 208.152317 -105.528665)
			(xy 208.144636 -105.59077) (xy 208.129387 -105.651463) (xy 208.106802 -105.709823) (xy 208.077221 -105.764969)
			(xy 208.041093 -105.816065) (xy 207.998964 -105.862338) (xy 207.951472 -105.903089) (xy 207.92567 -105.920794)
			(xy 207.915546 -105.928347) (xy 207.90367 -105.950597) (xy 207.903064 -105.963212) (xy 207.903064 -106.04754)
			(xy 207.903724 -106.060144) (xy 207.91557 -106.082392) (xy 207.92567 -106.089958) (xy 207.951466 -106.107669)
			(xy 207.998944 -106.148427) (xy 208.041061 -106.194704) (xy 208.077179 -106.245801) (xy 208.106753 -106.300945)
			(xy 208.129334 -106.359302) (xy 208.144581 -106.419989) (xy 208.152265 -106.482089) (xy 208.152746 -106.513376)
			(xy 209.636106 -106.513376) (xy 209.636597 -106.482089) (xy 209.64427 -106.419987) (xy 209.659511 -106.359297)
			(xy 209.682089 -106.300938) (xy 209.711661 -106.245792) (xy 209.74778 -106.194695) (xy 209.7899 -106.148419)
			(xy 209.837384 -106.107666) (xy 209.863182 -106.089958) (xy 209.873337 -106.08244) (xy 209.885195 -106.060163)
			(xy 209.885788 -106.04754) (xy 209.885788 -105.963212) (xy 209.885136 -105.950608) (xy 209.873282 -105.928361)
			(xy 209.863182 -105.920794) (xy 209.837353 -105.90313) (xy 209.789877 -105.862364) (xy 209.747763 -105.816078)
			(xy 209.711649 -105.764974) (xy 209.68208 -105.709824) (xy 209.659504 -105.651461) (xy 209.644262 -105.590769)
			(xy 209.636584 -105.528665) (xy 209.636106 -105.497376) (xy 209.636608 -105.465415) (xy 209.644619 -105.401997)
			(xy 209.660516 -105.340083) (xy 209.684048 -105.28065) (xy 209.714842 -105.224635) (xy 209.752415 -105.17292)
			(xy 209.796172 -105.126323) (xy 209.845425 -105.085578) (xy 209.899396 -105.051327) (xy 209.957235 -105.02411)
			(xy 210.018028 -105.004357) (xy 210.080818 -104.992379) (xy 210.144614 -104.988366) (xy 210.20841 -104.992379)
			(xy 210.2712 -105.004357) (xy 210.331993 -105.02411) (xy 210.389832 -105.051327) (xy 210.443803 -105.085578)
			(xy 210.493056 -105.126323) (xy 210.536813 -105.17292) (xy 210.574386 -105.224635) (xy 210.60518 -105.28065)
			(xy 210.628712 -105.340083) (xy 210.644609 -105.401997) (xy 210.65262 -105.465415) (xy 210.653122 -105.497376)
			(xy 210.652659 -105.528664) (xy 210.644979 -105.590766) (xy 210.629733 -105.651456) (xy 210.607151 -105.709815)
			(xy 210.577576 -105.764961) (xy 210.541453 -105.816057) (xy 210.49933 -105.862333) (xy 210.451845 -105.903086)
			(xy 210.426046 -105.920794) (xy 210.415918 -105.928342) (xy 210.404045 -105.950596) (xy 210.40344 -105.963212)
			(xy 210.40344 -106.04754) (xy 210.40411 -106.060142) (xy 210.415949 -106.08239) (xy 210.426046 -106.089958)
			(xy 210.451836 -106.107677) (xy 210.499316 -106.148433) (xy 210.541434 -106.194709) (xy 210.577553 -106.245804)
			(xy 210.607127 -106.300947) (xy 210.629709 -106.359303) (xy 210.644957 -106.41999) (xy 210.645318 -106.422909)
			(xy 214.375994 -106.422909) (xy 214.375994 -106.358987) (xy 214.384005 -106.295569) (xy 214.399902 -106.233655)
			(xy 214.423434 -106.174222) (xy 214.454228 -106.118207) (xy 214.491801 -106.066492) (xy 214.535558 -106.019895)
			(xy 214.584811 -105.97915) (xy 214.638782 -105.944899) (xy 214.696621 -105.917682) (xy 214.757414 -105.897929)
			(xy 214.820204 -105.885951) (xy 214.884 -105.881938) (xy 214.947796 -105.885951) (xy 215.010586 -105.897929)
			(xy 215.071379 -105.917682) (xy 215.129218 -105.944899) (xy 215.183189 -105.97915) (xy 215.232442 -106.019895)
			(xy 215.276199 -106.066492) (xy 215.313772 -106.118207) (xy 215.344566 -106.174222) (xy 215.368098 -106.233655)
			(xy 215.383995 -106.295569) (xy 215.392006 -106.358987) (xy 215.392508 -106.390948) (xy 215.392006 -106.422909)
			(xy 215.383995 -106.486327) (xy 215.368098 -106.548241) (xy 215.344566 -106.607674) (xy 215.313772 -106.663689)
			(xy 215.276199 -106.715404) (xy 215.232442 -106.762001) (xy 215.207783 -106.7824) (xy 238.699051 -106.7824)
			(xy 238.703065 -106.718603) (xy 238.715042 -106.655812) (xy 238.734795 -106.595017) (xy 238.762011 -106.537176)
			(xy 238.796261 -106.483203) (xy 238.837005 -106.433948) (xy 238.883601 -106.390187) (xy 238.935314 -106.352611)
			(xy 238.991329 -106.321813) (xy 239.050762 -106.298277) (xy 239.112676 -106.282375) (xy 239.176094 -106.274359)
			(xy 239.208056 -106.273854) (xy 239.238778 -106.274288) (xy 239.299773 -106.281695) (xy 239.359432 -106.296393)
			(xy 239.416887 -106.318171) (xy 239.471301 -106.346709) (xy 239.496854 -106.36377) (xy 239.505539 -106.369163)
			(xy 239.525556 -106.373224) (xy 239.545573 -106.369163) (xy 239.554258 -106.36377) (xy 239.579824 -106.346731)
			(xy 239.634236 -106.318196) (xy 239.691688 -106.296421) (xy 239.751344 -106.281724) (xy 239.812336 -106.274319)
			(xy 239.843056 -106.273854) (xy 239.875018 -106.274408) (xy 239.938438 -106.282415) (xy 240.000354 -106.298308)
			(xy 240.05979 -106.321835) (xy 240.115809 -106.352627) (xy 240.167526 -106.390198) (xy 240.214126 -106.433955)
			(xy 240.254874 -106.483207) (xy 240.289128 -106.537178) (xy 240.316346 -106.595017) (xy 240.336101 -106.655812)
			(xy 240.348079 -106.718603) (xy 240.352094 -106.7824) (xy 240.348079 -106.846197) (xy 240.336101 -106.908988)
			(xy 240.325676 -106.941069) (xy 258.761986 -106.941069) (xy 258.761986 -106.877147) (xy 258.769997 -106.813729)
			(xy 258.785894 -106.751815) (xy 258.809426 -106.692382) (xy 258.84022 -106.636367) (xy 258.877793 -106.584652)
			(xy 258.92155 -106.538055) (xy 258.970803 -106.49731) (xy 259.024774 -106.463059) (xy 259.082613 -106.435842)
			(xy 259.143406 -106.416089) (xy 259.206196 -106.404111) (xy 259.269992 -106.400098) (xy 259.333788 -106.404111)
			(xy 259.396578 -106.416089) (xy 259.457371 -106.435842) (xy 259.51521 -106.463059) (xy 259.569181 -106.49731)
			(xy 259.618434 -106.538055) (xy 259.662191 -106.584652) (xy 259.699764 -106.636367) (xy 259.730558 -106.692382)
			(xy 259.75409 -106.751815) (xy 259.769987 -106.813729) (xy 259.777998 -106.877147) (xy 259.7785 -106.909108)
			(xy 259.777998 -106.941069) (xy 259.769987 -107.004487) (xy 259.75409 -107.066401) (xy 259.730558 -107.125834)
			(xy 259.699764 -107.181849) (xy 259.662191 -107.233564) (xy 259.618434 -107.280161) (xy 259.569181 -107.320906)
			(xy 259.51521 -107.355157) (xy 259.457371 -107.382374) (xy 259.396578 -107.402127) (xy 259.333788 -107.414105)
			(xy 259.269992 -107.418119) (xy 259.206196 -107.414105) (xy 259.143406 -107.402127) (xy 259.082613 -107.382374)
			(xy 259.024774 -107.355157) (xy 258.970803 -107.320906) (xy 258.92155 -107.280161) (xy 258.877793 -107.233564)
			(xy 258.84022 -107.181849) (xy 258.809426 -107.125834) (xy 258.785894 -107.066401) (xy 258.769997 -107.004487)
			(xy 258.761986 -106.941069) (xy 240.325676 -106.941069) (xy 240.316346 -106.969783) (xy 240.289128 -107.027622)
			(xy 240.254874 -107.081593) (xy 240.214126 -107.130845) (xy 240.167526 -107.174602) (xy 240.115809 -107.212173)
			(xy 240.05979 -107.242965) (xy 240.000354 -107.266492) (xy 239.938438 -107.282385) (xy 239.875018 -107.290392)
			(xy 239.843056 -107.29087) (xy 239.812335 -107.290426) (xy 239.75134 -107.283021) (xy 239.691681 -107.268324)
			(xy 239.634226 -107.246549) (xy 239.579811 -107.218014) (xy 239.554258 -107.200954) (xy 239.545573 -107.195561)
			(xy 239.525556 -107.1915) (xy 239.505539 -107.195561) (xy 239.496854 -107.200954) (xy 239.471314 -107.218034)
			(xy 239.416895 -107.246562) (xy 239.359436 -107.268328) (xy 239.299774 -107.283015) (xy 239.238778 -107.29041)
			(xy 239.208056 -107.29087) (xy 239.176094 -107.290441) (xy 239.112676 -107.282425) (xy 239.050762 -107.266523)
			(xy 238.991329 -107.242987) (xy 238.935314 -107.212189) (xy 238.883601 -107.174613) (xy 238.837005 -107.130852)
			(xy 238.796261 -107.081597) (xy 238.762011 -107.027624) (xy 238.734795 -106.969783) (xy 238.715042 -106.908988)
			(xy 238.703065 -106.846197) (xy 238.699051 -106.7824) (xy 215.207783 -106.7824) (xy 215.183189 -106.802746)
			(xy 215.129218 -106.836997) (xy 215.071379 -106.864214) (xy 215.010586 -106.883967) (xy 214.947796 -106.895945)
			(xy 214.884 -106.899959) (xy 214.820204 -106.895945) (xy 214.757414 -106.883967) (xy 214.696621 -106.864214)
			(xy 214.638782 -106.836997) (xy 214.584811 -106.802746) (xy 214.535558 -106.762001) (xy 214.491801 -106.715404)
			(xy 214.454228 -106.663689) (xy 214.423434 -106.607674) (xy 214.399902 -106.548241) (xy 214.384005 -106.486327)
			(xy 214.375994 -106.422909) (xy 210.645318 -106.422909) (xy 210.652641 -106.48209) (xy 210.653122 -106.513376)
			(xy 210.65262 -106.545337) (xy 210.644609 -106.608755) (xy 210.628712 -106.670669) (xy 210.60518 -106.730102)
			(xy 210.574386 -106.786117) (xy 210.536813 -106.837832) (xy 210.493056 -106.884429) (xy 210.443803 -106.925174)
			(xy 210.389832 -106.959425) (xy 210.331993 -106.986642) (xy 210.2712 -107.006395) (xy 210.20841 -107.018373)
			(xy 210.144614 -107.022387) (xy 210.080818 -107.018373) (xy 210.018028 -107.006395) (xy 209.957235 -106.986642)
			(xy 209.899396 -106.959425) (xy 209.845425 -106.925174) (xy 209.796172 -106.884429) (xy 209.752415 -106.837832)
			(xy 209.714842 -106.786117) (xy 209.684048 -106.730102) (xy 209.660516 -106.670669) (xy 209.644619 -106.608755)
			(xy 209.636608 -106.545337) (xy 209.636106 -106.513376) (xy 208.152746 -106.513376) (xy 208.152244 -106.545337)
			(xy 208.144233 -106.608755) (xy 208.128336 -106.670669) (xy 208.104804 -106.730102) (xy 208.07401 -106.786117)
			(xy 208.036437 -106.837832) (xy 207.99268 -106.884429) (xy 207.943427 -106.925174) (xy 207.889456 -106.959425)
			(xy 207.831617 -106.986642) (xy 207.770824 -107.006395) (xy 207.708034 -107.018373) (xy 207.644238 -107.022387)
			(xy 207.580442 -107.018373) (xy 207.517652 -107.006395) (xy 207.456859 -106.986642) (xy 207.39902 -106.959425)
			(xy 207.345049 -106.925174) (xy 207.295796 -106.884429) (xy 207.252039 -106.837832) (xy 207.214466 -106.786117)
			(xy 207.183672 -106.730102) (xy 207.16014 -106.670669) (xy 207.144243 -106.608755) (xy 207.136232 -106.545337)
			(xy 207.13573 -106.513376) (xy 202.763806 -106.513376) (xy 202.763807 -106.544669) (xy 202.756131 -106.606761)
			(xy 202.740894 -106.667442) (xy 202.718325 -106.725794) (xy 202.688765 -106.780936) (xy 202.652663 -106.832033)
			(xy 202.610563 -106.878314) (xy 202.563101 -106.919079) (xy 202.537314 -106.936794) (xy 202.52718 -106.944335)
			(xy 202.515312 -106.966595) (xy 202.514708 -106.979212) (xy 202.514708 -107.06354) (xy 202.51539 -107.07614)
			(xy 202.527222 -107.098387) (xy 202.537314 -107.105958) (xy 202.56308 -107.123705) (xy 202.610543 -107.164468)
			(xy 202.652646 -107.210746) (xy 202.688751 -107.261842) (xy 202.718313 -107.316982) (xy 202.735921 -107.362498)
			(xy 206.164432 -107.362498) (xy 206.168503 -107.306876) (xy 206.180629 -107.252439) (xy 206.200552 -107.200348)
			(xy 206.227848 -107.151713) (xy 206.261934 -107.10757) (xy 206.302083 -107.068861) (xy 206.347441 -107.03641)
			(xy 206.397041 -107.010909) (xy 206.449825 -106.992902) (xy 206.504668 -106.982772) (xy 206.560402 -106.980735)
			(xy 206.615839 -106.986835) (xy 206.669796 -107.000941) (xy 206.721125 -107.022753) (xy 206.768731 -107.051807)
			(xy 206.811599 -107.087482) (xy 206.848816 -107.129019) (xy 206.879589 -107.175532) (xy 206.903261 -107.226029)
			(xy 206.919329 -107.279436) (xy 206.927449 -107.334612) (xy 206.927958 -107.362498) (xy 206.927449 -107.390384)
			(xy 206.919329 -107.44556) (xy 206.903261 -107.498967) (xy 206.879589 -107.549464) (xy 206.879267 -107.54995)
			(xy 209.590892 -107.54995) (xy 209.594963 -107.494328) (xy 209.607089 -107.439891) (xy 209.627012 -107.3878)
			(xy 209.654308 -107.339165) (xy 209.688394 -107.295022) (xy 209.728543 -107.256313) (xy 209.773901 -107.223862)
			(xy 209.823501 -107.198361) (xy 209.876285 -107.180354) (xy 209.931128 -107.170224) (xy 209.986862 -107.168187)
			(xy 210.042299 -107.174287) (xy 210.096256 -107.188393) (xy 210.147585 -107.210205) (xy 210.195191 -107.239259)
			(xy 210.238059 -107.274934) (xy 210.275276 -107.316471) (xy 210.306049 -107.362984) (xy 210.329721 -107.413481)
			(xy 210.345789 -107.466888) (xy 210.351736 -107.5073) (xy 211.277967 -107.5073) (xy 211.281981 -107.443503)
			(xy 211.293959 -107.380712) (xy 211.313712 -107.319918) (xy 211.340928 -107.262078) (xy 211.375179 -107.208105)
			(xy 211.415924 -107.158851) (xy 211.462521 -107.115092) (xy 211.514235 -107.077517) (xy 211.57025 -107.04672)
			(xy 211.629684 -107.023187) (xy 211.691598 -107.007287) (xy 211.755016 -106.999273) (xy 211.786978 -106.99877)
			(xy 211.817685 -106.999253) (xy 211.878655 -107.006637) (xy 211.93829 -107.021312) (xy 211.995723 -107.043065)
			(xy 212.050118 -107.071578) (xy 212.100681 -107.106436) (xy 212.146677 -107.147132) (xy 212.187436 -107.193072)
			(xy 212.222363 -107.243588) (xy 212.237066 -107.27055) (xy 212.243416 -107.282742) (xy 212.266784 -107.297474)
			(xy 212.369146 -107.300014) (xy 212.378232 -107.299895) (xy 212.395419 -107.294032) (xy 212.409467 -107.282526)
			(xy 212.414358 -107.274868) (xy 212.431564 -107.246762) (xy 212.472189 -107.194871) (xy 212.519178 -107.148664)
			(xy 212.571741 -107.108913) (xy 212.628999 -107.076284) (xy 212.689992 -107.051326) (xy 212.753698 -107.034456)
			(xy 212.819049 -107.025955) (xy 212.852 -107.02544) (xy 212.883944 -107.025927) (xy 212.947331 -107.03392)
			(xy 213.009216 -107.049792) (xy 213.068624 -107.073294) (xy 213.12462 -107.104054) (xy 213.17632 -107.141588)
			(xy 213.22291 -107.185305) (xy 213.243668 -107.20959) (xy 213.251288 -107.218734) (xy 213.272878 -107.228386)
			(xy 213.377272 -107.224322) (xy 213.397846 -107.213146) (xy 213.404704 -107.203494) (xy 213.422635 -107.179031)
			(xy 213.463348 -107.134071) (xy 213.509122 -107.094275) (xy 213.559306 -107.060209) (xy 213.613187 -107.032355)
			(xy 213.669999 -107.011111) (xy 213.728936 -106.996778) (xy 213.789159 -106.989559) (xy 213.819486 -106.989118)
			(xy 213.850434 -106.989543) (xy 213.911871 -106.997072) (xy 213.971942 -107.011997) (xy 214.029759 -107.034098)
			(xy 214.084468 -107.063047) (xy 214.135263 -107.098418) (xy 214.181393 -107.139689) (xy 214.222177 -107.186249)
			(xy 214.257013 -107.237412) (xy 214.271606 -107.264708) (xy 214.271606 -107.264962) (xy 214.276096 -107.272772)
			(xy 214.289395 -107.284904) (xy 214.306058 -107.291715) (xy 214.31504 -107.292394) (xy 214.403686 -107.295442)
			(xy 214.412725 -107.295364) (xy 214.429869 -107.289677) (xy 214.443953 -107.278369) (xy 214.448898 -107.270804)
			(xy 214.466223 -107.243128) (xy 214.506883 -107.192038) (xy 214.55375 -107.146574) (xy 214.606051 -107.107483)
			(xy 214.662926 -107.07541) (xy 214.723439 -107.050882) (xy 214.786594 -107.034301) (xy 214.851352 -107.025943)
			(xy 214.884 -107.02544) (xy 214.915964 -107.025846) (xy 214.979388 -107.033858) (xy 215.041308 -107.049756)
			(xy 215.100747 -107.07329) (xy 215.156767 -107.104087) (xy 215.208486 -107.141663) (xy 215.255088 -107.185425)
			(xy 215.295837 -107.234683) (xy 215.330092 -107.288659) (xy 215.357311 -107.346503) (xy 215.377066 -107.407302)
			(xy 215.389045 -107.470098) (xy 215.393059 -107.5339) (xy 215.389045 -107.597702) (xy 215.377066 -107.660498)
			(xy 215.357311 -107.721297) (xy 215.330092 -107.779141) (xy 215.295837 -107.833117) (xy 215.255088 -107.882375)
			(xy 215.208486 -107.926137) (xy 215.156767 -107.963713) (xy 215.100747 -107.99451) (xy 215.041308 -108.018044)
			(xy 215.016467 -108.024422) (xy 217.796618 -108.024422) (xy 217.79712 -107.992461) (xy 217.805131 -107.929043)
			(xy 217.821028 -107.867129) (xy 217.84456 -107.807696) (xy 217.875354 -107.751681) (xy 217.912927 -107.699966)
			(xy 217.956684 -107.653369) (xy 218.005937 -107.612624) (xy 218.059908 -107.578373) (xy 218.117747 -107.551156)
			(xy 218.17854 -107.531403) (xy 218.24133 -107.519425) (xy 218.305126 -107.515412) (xy 218.368922 -107.519425)
			(xy 218.431712 -107.531403) (xy 218.492505 -107.551156) (xy 218.550344 -107.578373) (xy 218.604315 -107.612624)
			(xy 218.653568 -107.653369) (xy 218.697325 -107.699966) (xy 218.734898 -107.751681) (xy 218.765692 -107.807696)
			(xy 218.789224 -107.867129) (xy 218.805121 -107.929043) (xy 218.813132 -107.992461) (xy 218.813634 -108.024422)
			(xy 218.813163 -108.056308) (xy 218.80518 -108.119577) (xy 218.789353 -108.181354) (xy 218.765932 -108.240668)
			(xy 218.735282 -108.296591) (xy 218.697885 -108.348247) (xy 218.654327 -108.394824) (xy 218.60529 -108.435594)
			(xy 218.578684 -108.453174) (xy 218.567762 -108.460032) (xy 218.555062 -108.483146) (xy 218.556078 -108.595414)
			(xy 218.568778 -108.618274) (xy 218.579954 -108.625132) (xy 218.608621 -108.643519) (xy 218.661249 -108.686747)
			(xy 218.707648 -108.736602) (xy 218.727782 -108.76407) (xy 218.735446 -108.773619) (xy 218.75721 -108.784758)
			(xy 218.769438 -108.785406) (xy 218.852242 -108.785406) (xy 218.864477 -108.784806) (xy 218.886239 -108.773633)
			(xy 218.893898 -108.76407) (xy 218.911778 -108.739557) (xy 218.952475 -108.694553) (xy 218.998242 -108.654717)
			(xy 219.048428 -108.620614) (xy 219.102317 -108.592729) (xy 219.159143 -108.57146) (xy 219.218098 -108.55711)
			(xy 219.278342 -108.549882) (xy 219.30868 -108.54944) (xy 219.340646 -108.549824) (xy 219.404075 -108.557834)
			(xy 219.465999 -108.573732) (xy 219.525442 -108.597265) (xy 219.581468 -108.628063) (xy 219.593166 -108.636562)
			(xy 220.487748 -108.636562) (xy 220.488293 -108.603306) (xy 220.496969 -108.537364) (xy 220.514167 -108.473114)
			(xy 220.539595 -108.411656) (xy 220.572817 -108.354036) (xy 220.613268 -108.30124) (xy 220.660257 -108.254168)
			(xy 220.712981 -108.213623) (xy 220.770541 -108.180297) (xy 220.831954 -108.15476) (xy 220.863922 -108.14558)
			(xy 220.878146 -108.14177) (xy 220.897958 -108.12018) (xy 220.916754 -108.01477) (xy 220.918062 -108.005283)
			(xy 220.914293 -107.986519) (xy 220.903951 -107.970414) (xy 220.896434 -107.964478) (xy 220.895926 -107.964478)
			(xy 220.871409 -107.946581) (xy 220.826406 -107.905844) (xy 220.78657 -107.86004) (xy 220.752469 -107.809822)
			(xy 220.724586 -107.755901) (xy 220.703318 -107.699046) (xy 220.688968 -107.640064) (xy 220.681739 -107.579793)
			(xy 220.681296 -107.549442) (xy 220.681798 -107.517481) (xy 220.689809 -107.454063) (xy 220.705706 -107.392149)
			(xy 220.729238 -107.332716) (xy 220.760032 -107.276701) (xy 220.797605 -107.224986) (xy 220.841362 -107.178389)
			(xy 220.890615 -107.137644) (xy 220.944586 -107.103393) (xy 221.002425 -107.076176) (xy 221.063218 -107.056423)
			(xy 221.126008 -107.044445) (xy 221.189804 -107.040432) (xy 221.2536 -107.044445) (xy 221.31639 -107.056423)
			(xy 221.377183 -107.076176) (xy 221.435022 -107.103393) (xy 221.488993 -107.137644) (xy 221.538246 -107.178389)
			(xy 221.582003 -107.224986) (xy 221.619576 -107.276701) (xy 221.65037 -107.332716) (xy 221.673902 -107.392149)
			(xy 221.689799 -107.454063) (xy 221.69781 -107.517481) (xy 221.698312 -107.549442) (xy 221.6978 -107.582699)
			(xy 221.689123 -107.648644) (xy 221.671923 -107.712896) (xy 221.646492 -107.774356) (xy 221.613266 -107.831977)
			(xy 221.572811 -107.884773) (xy 221.570623 -107.886965) (xy 250.492254 -107.886965) (xy 250.492254 -107.823043)
			(xy 250.500265 -107.759625) (xy 250.516162 -107.697711) (xy 250.539694 -107.638278) (xy 250.570488 -107.582263)
			(xy 250.608061 -107.530548) (xy 250.651818 -107.483951) (xy 250.701071 -107.443206) (xy 250.755042 -107.408955)
			(xy 250.812881 -107.381738) (xy 250.873674 -107.361985) (xy 250.936464 -107.350007) (xy 251.00026 -107.345994)
			(xy 251.064056 -107.350007) (xy 251.126846 -107.361985) (xy 251.187639 -107.381738) (xy 251.245478 -107.408955)
			(xy 251.299449 -107.443206) (xy 251.348702 -107.483951) (xy 251.392459 -107.530548) (xy 251.430032 -107.582263)
			(xy 251.460826 -107.638278) (xy 251.484358 -107.697711) (xy 251.500255 -107.759625) (xy 251.506335 -107.80776)
			(xy 252.66091 -107.80776) (xy 252.664981 -107.752138) (xy 252.677107 -107.697701) (xy 252.69703 -107.64561)
			(xy 252.724326 -107.596975) (xy 252.758412 -107.552832) (xy 252.798561 -107.514123) (xy 252.843919 -107.481672)
			(xy 252.893519 -107.456171) (xy 252.946303 -107.438164) (xy 253.001146 -107.428034) (xy 253.05688 -107.425997)
			(xy 253.112317 -107.432097) (xy 253.166274 -107.446203) (xy 253.217603 -107.468015) (xy 253.265209 -107.497069)
			(xy 253.308077 -107.532744) (xy 253.345294 -107.574281) (xy 253.376067 -107.620794) (xy 253.399739 -107.671291)
			(xy 253.415807 -107.724698) (xy 253.418194 -107.740915) (xy 259.700516 -107.740915) (xy 259.700516 -107.676993)
			(xy 259.708527 -107.613575) (xy 259.724424 -107.551661) (xy 259.747956 -107.492228) (xy 259.77875 -107.436213)
			(xy 259.816323 -107.384498) (xy 259.86008 -107.337901) (xy 259.909333 -107.297156) (xy 259.963304 -107.262905)
			(xy 260.021143 -107.235688) (xy 260.081936 -107.215935) (xy 260.144726 -107.203957) (xy 260.208522 -107.199944)
			(xy 260.211781 -107.200149) (xy 271.967446 -107.200149) (xy 271.967446 -107.136227) (xy 271.975457 -107.072809)
			(xy 271.991354 -107.010895) (xy 272.014886 -106.951462) (xy 272.04568 -106.895447) (xy 272.083253 -106.843732)
			(xy 272.12701 -106.797135) (xy 272.176263 -106.75639) (xy 272.230234 -106.722139) (xy 272.288073 -106.694922)
			(xy 272.348866 -106.675169) (xy 272.411656 -106.663191) (xy 272.475452 -106.659178) (xy 272.539248 -106.663191)
			(xy 272.602038 -106.675169) (xy 272.662831 -106.694922) (xy 272.72067 -106.722139) (xy 272.774641 -106.75639)
			(xy 272.823894 -106.797135) (xy 272.867651 -106.843732) (xy 272.905224 -106.895447) (xy 272.936018 -106.951462)
			(xy 272.95955 -107.010895) (xy 272.975447 -107.072809) (xy 272.983458 -107.136227) (xy 272.98396 -107.168188)
			(xy 273.282154 -107.168188) (xy 273.286225 -107.112566) (xy 273.298351 -107.058129) (xy 273.318274 -107.006038)
			(xy 273.34557 -106.957403) (xy 273.379656 -106.91326) (xy 273.419805 -106.874551) (xy 273.465163 -106.8421)
			(xy 273.514763 -106.816599) (xy 273.567547 -106.798592) (xy 273.62239 -106.788462) (xy 273.678124 -106.786425)
			(xy 273.733561 -106.792525) (xy 273.787518 -106.806631) (xy 273.838847 -106.828443) (xy 273.886453 -106.857497)
			(xy 273.929321 -106.893172) (xy 273.966538 -106.934709) (xy 273.987145 -106.965856) (xy 308.192327 -106.965856)
			(xy 308.192327 -106.911344) (xy 308.200085 -106.857387) (xy 308.215444 -106.805083) (xy 308.238089 -106.755498)
			(xy 308.267562 -106.70964) (xy 308.303261 -106.668444) (xy 308.344459 -106.632748) (xy 308.390319 -106.603278)
			(xy 308.439906 -106.580635) (xy 308.49221 -106.56528) (xy 308.546168 -106.557525) (xy 308.573424 -106.557064)
			(xy 308.601889 -106.557559) (xy 308.658189 -106.566017) (xy 308.712607 -106.582741) (xy 308.763939 -106.607362)
			(xy 308.811046 -106.639332) (xy 308.852882 -106.677943) (xy 308.871112 -106.699812) (xy 308.880375 -106.710555)
			(xy 308.903504 -106.726954) (xy 308.930252 -106.736357) (xy 308.958554 -106.738039) (xy 308.986228 -106.731871)
			(xy 309.011136 -106.718327) (xy 309.031358 -106.698454) (xy 309.038752 -106.68635) (xy 309.055798 -106.657445)
			(xy 309.096277 -106.603926) (xy 309.143442 -106.556193) (xy 309.196474 -106.515077) (xy 309.254451 -106.48129)
			(xy 309.316368 -106.45542) (xy 309.381148 -106.437917) (xy 309.447668 -106.429083) (xy 309.48122 -106.42854)
			(xy 309.513183 -106.428947) (xy 309.576605 -106.436961) (xy 309.638523 -106.452861) (xy 309.69796 -106.476396)
			(xy 309.753978 -106.507194) (xy 309.805695 -106.54477) (xy 309.852295 -106.588532) (xy 309.893042 -106.637789)
			(xy 309.898525 -106.646429) (xy 312.792866 -106.646429) (xy 312.792866 -106.582507) (xy 312.800877 -106.519089)
			(xy 312.816774 -106.457175) (xy 312.840306 -106.397742) (xy 312.8711 -106.341727) (xy 312.908673 -106.290012)
			(xy 312.95243 -106.243415) (xy 313.001683 -106.20267) (xy 313.055654 -106.168419) (xy 313.113493 -106.141202)
			(xy 313.174286 -106.121449) (xy 313.237076 -106.109471) (xy 313.300872 -106.105458) (xy 313.364668 -106.109471)
			(xy 313.427458 -106.121449) (xy 313.488251 -106.141202) (xy 313.54609 -106.168419) (xy 313.600061 -106.20267)
			(xy 313.649314 -106.243415) (xy 313.693071 -106.290012) (xy 313.730644 -106.341727) (xy 313.761438 -106.397742)
			(xy 313.78497 -106.457175) (xy 313.800867 -106.519089) (xy 313.808878 -106.582507) (xy 313.80938 -106.614468)
			(xy 313.808878 -106.646429) (xy 313.800867 -106.709847) (xy 313.78497 -106.771761) (xy 313.761438 -106.831194)
			(xy 313.730644 -106.887209) (xy 313.693071 -106.938924) (xy 313.649314 -106.985521) (xy 313.600061 -107.026266)
			(xy 313.54609 -107.060517) (xy 313.488251 -107.087734) (xy 313.427458 -107.107487) (xy 313.364668 -107.119465)
			(xy 313.300872 -107.123479) (xy 313.237076 -107.119465) (xy 313.174286 -107.107487) (xy 313.113493 -107.087734)
			(xy 313.055654 -107.060517) (xy 313.001683 -107.026266) (xy 312.95243 -106.985521) (xy 312.908673 -106.938924)
			(xy 312.8711 -106.887209) (xy 312.840306 -106.831194) (xy 312.816774 -106.771761) (xy 312.800877 -106.709847)
			(xy 312.792866 -106.646429) (xy 309.898525 -106.646429) (xy 309.927295 -106.691765) (xy 309.954513 -106.749607)
			(xy 309.974267 -106.810405) (xy 309.986245 -106.8732) (xy 309.990259 -106.937) (xy 309.986245 -107.0008)
			(xy 309.974267 -107.063595) (xy 309.954513 -107.124393) (xy 309.930558 -107.1753) (xy 326.9869 -107.1753)
			(xy 326.987415 -107.14196) (xy 326.996124 -107.075851) (xy 327.013406 -107.011449) (xy 327.038963 -106.949861)
			(xy 327.072357 -106.892146) (xy 327.113013 -106.839294) (xy 327.136252 -106.815382) (xy 327.136506 -106.815128)
			(xy 327.143057 -106.807725) (xy 327.150515 -106.789441) (xy 327.150984 -106.779568) (xy 327.150984 -106.697272)
			(xy 327.143618 -106.678984) (xy 327.136506 -106.671872) (xy 327.135998 -106.671364) (xy 327.112792 -106.647463)
			(xy 327.072215 -106.594628) (xy 327.038886 -106.536945) (xy 327.013376 -106.475404) (xy 326.996123 -106.411058)
			(xy 326.987422 -106.345009) (xy 326.9869 -106.3117) (xy 326.987402 -106.279739) (xy 326.995413 -106.216321)
			(xy 327.01131 -106.154407) (xy 327.034842 -106.094974) (xy 327.065636 -106.038959) (xy 327.103209 -105.987244)
			(xy 327.146966 -105.940647) (xy 327.196219 -105.899902) (xy 327.25019 -105.865651) (xy 327.308029 -105.838434)
			(xy 327.368822 -105.818681) (xy 327.431612 -105.806703) (xy 327.495408 -105.80269) (xy 327.559204 -105.806703)
			(xy 327.621994 -105.818681) (xy 327.682787 -105.838434) (xy 327.740626 -105.865651) (xy 327.794597 -105.899902)
			(xy 327.84385 -105.940647) (xy 327.887607 -105.987244) (xy 327.92518 -106.038959) (xy 327.955974 -106.094974)
			(xy 327.979506 -106.154407) (xy 327.995403 -106.216321) (xy 328.003414 -106.279739) (xy 328.003916 -106.3117)
			(xy 328.00341 -106.344169) (xy 408.97657 -106.344169) (xy 408.97657 -106.280247) (xy 408.984581 -106.216829)
			(xy 409.000478 -106.154915) (xy 409.02401 -106.095482) (xy 409.054804 -106.039467) (xy 409.092377 -105.987752)
			(xy 409.136134 -105.941155) (xy 409.185387 -105.90041) (xy 409.239358 -105.866159) (xy 409.297197 -105.838942)
			(xy 409.35799 -105.819189) (xy 409.42078 -105.807211) (xy 409.484576 -105.803198) (xy 409.548372 -105.807211)
			(xy 409.611162 -105.819189) (xy 409.671955 -105.838942) (xy 409.715182 -105.859283) (xy 429.780694 -105.859283)
			(xy 429.780694 -105.795361) (xy 429.788705 -105.731943) (xy 429.804602 -105.670029) (xy 429.828134 -105.610596)
			(xy 429.858928 -105.554581) (xy 429.896501 -105.502866) (xy 429.940258 -105.456269) (xy 429.989511 -105.415524)
			(xy 430.043482 -105.381273) (xy 430.101321 -105.354056) (xy 430.162114 -105.334303) (xy 430.224904 -105.322325)
			(xy 430.2887 -105.318312) (xy 430.352496 -105.322325) (xy 430.415286 -105.334303) (xy 430.476079 -105.354056)
			(xy 430.533918 -105.381273) (xy 430.587889 -105.415524) (xy 430.637142 -105.456269) (xy 430.680899 -105.502866)
			(xy 430.718472 -105.554581) (xy 430.749266 -105.610596) (xy 430.772798 -105.670029) (xy 430.788695 -105.731943)
			(xy 430.796706 -105.795361) (xy 430.797208 -105.827322) (xy 430.796706 -105.859283) (xy 430.788695 -105.922701)
			(xy 430.772798 -105.984615) (xy 430.749266 -106.044048) (xy 430.718472 -106.100063) (xy 430.680899 -106.151778)
			(xy 430.637142 -106.198375) (xy 430.587889 -106.23912) (xy 430.533918 -106.273371) (xy 430.476079 -106.300588)
			(xy 430.415286 -106.320341) (xy 430.352496 -106.332319) (xy 430.2887 -106.336333) (xy 430.224904 -106.332319)
			(xy 430.162114 -106.320341) (xy 430.101321 -106.300588) (xy 430.043482 -106.273371) (xy 429.989511 -106.23912)
			(xy 429.940258 -106.198375) (xy 429.896501 -106.151778) (xy 429.858928 -106.100063) (xy 429.828134 -106.044048)
			(xy 429.804602 -105.984615) (xy 429.788705 -105.922701) (xy 429.780694 -105.859283) (xy 409.715182 -105.859283)
			(xy 409.729794 -105.866159) (xy 409.783765 -105.90041) (xy 409.833018 -105.941155) (xy 409.876775 -105.987752)
			(xy 409.914348 -106.039467) (xy 409.945142 -106.095482) (xy 409.968674 -106.154915) (xy 409.984571 -106.216829)
			(xy 409.992582 -106.280247) (xy 409.993084 -106.312208) (xy 409.992582 -106.344169) (xy 409.984571 -106.407587)
			(xy 409.968674 -106.469501) (xy 409.945142 -106.528934) (xy 409.914348 -106.584949) (xy 409.876775 -106.636664)
			(xy 409.833018 -106.683261) (xy 409.783765 -106.724006) (xy 409.729794 -106.758257) (xy 409.671955 -106.785474)
			(xy 409.611162 -106.805227) (xy 409.548372 -106.817205) (xy 409.484576 -106.821219) (xy 409.42078 -106.817205)
			(xy 409.35799 -106.805227) (xy 409.297197 -106.785474) (xy 409.239358 -106.758257) (xy 409.185387 -106.724006)
			(xy 409.136134 -106.683261) (xy 409.092377 -106.636664) (xy 409.054804 -106.584949) (xy 409.02401 -106.528934)
			(xy 409.000478 -106.469501) (xy 408.984581 -106.407587) (xy 408.97657 -106.344169) (xy 328.00341 -106.344169)
			(xy 328.003396 -106.34504) (xy 327.994687 -106.411148) (xy 327.977406 -106.47555) (xy 327.95185 -106.537138)
			(xy 327.918457 -106.594854) (xy 327.877803 -106.647706) (xy 327.854564 -106.671618) (xy 327.85431 -106.671872)
			(xy 327.847761 -106.679277) (xy 327.840302 -106.69756) (xy 327.839832 -106.707432) (xy 327.839832 -106.789728)
			(xy 327.847198 -106.808016) (xy 327.85431 -106.815128) (xy 327.854818 -106.815636) (xy 327.878027 -106.839534)
			(xy 327.918603 -106.89237) (xy 327.951932 -106.950054) (xy 327.97744 -107.011595) (xy 327.994693 -107.075942)
			(xy 328.003394 -107.14199) (xy 328.003916 -107.1753) (xy 328.003414 -107.207261) (xy 327.995403 -107.270679)
			(xy 327.979506 -107.332593) (xy 327.965068 -107.369059) (xy 409.626048 -107.369059) (xy 409.626048 -107.305137)
			(xy 409.634059 -107.241719) (xy 409.649956 -107.179805) (xy 409.673488 -107.120372) (xy 409.704282 -107.064357)
			(xy 409.741855 -107.012642) (xy 409.785612 -106.966045) (xy 409.834865 -106.9253) (xy 409.888836 -106.891049)
			(xy 409.946675 -106.863832) (xy 410.007468 -106.844079) (xy 410.070258 -106.832101) (xy 410.134054 -106.828088)
			(xy 410.19785 -106.832101) (xy 410.26064 -106.844079) (xy 410.321433 -106.863832) (xy 410.379272 -106.891049)
			(xy 410.433243 -106.9253) (xy 410.482496 -106.966045) (xy 410.526253 -107.012642) (xy 410.563826 -107.064357)
			(xy 410.59462 -107.120372) (xy 410.618152 -107.179805) (xy 410.619006 -107.183131) (xy 428.804826 -107.183131)
			(xy 428.804826 -107.119209) (xy 428.812837 -107.055791) (xy 428.828734 -106.993877) (xy 428.852266 -106.934444)
			(xy 428.88306 -106.878429) (xy 428.920633 -106.826714) (xy 428.96439 -106.780117) (xy 429.013643 -106.739372)
			(xy 429.067614 -106.705121) (xy 429.125453 -106.677904) (xy 429.186246 -106.658151) (xy 429.249036 -106.646173)
			(xy 429.312832 -106.64216) (xy 429.376628 -106.646173) (xy 429.439418 -106.658151) (xy 429.500211 -106.677904)
			(xy 429.55805 -106.705121) (xy 429.612021 -106.739372) (xy 429.661274 -106.780117) (xy 429.705031 -106.826714)
			(xy 429.742604 -106.878429) (xy 429.773398 -106.934444) (xy 429.79693 -106.993877) (xy 429.812827 -107.055791)
			(xy 429.820838 -107.119209) (xy 429.82134 -107.15117) (xy 429.820838 -107.183131) (xy 429.812827 -107.246549)
			(xy 429.809142 -107.2609) (xy 430.136587 -107.2609) (xy 430.140601 -107.197106) (xy 430.152578 -107.134318)
			(xy 430.172329 -107.073527) (xy 430.199544 -107.01569) (xy 430.233793 -106.96172) (xy 430.274536 -106.912467)
			(xy 430.32113 -106.86871) (xy 430.372841 -106.831137) (xy 430.428853 -106.800341) (xy 430.488284 -106.776808)
			(xy 430.550195 -106.760908) (xy 430.61361 -106.752894) (xy 430.64557 -106.75239) (xy 430.677739 -106.752869)
			(xy 430.741563 -106.760993) (xy 430.803853 -106.777103) (xy 430.863613 -106.800942) (xy 430.872634 -106.805941)
			(xy 433.214266 -106.805941) (xy 433.214266 -106.742019) (xy 433.222277 -106.678601) (xy 433.238174 -106.616687)
			(xy 433.261706 -106.557254) (xy 433.2925 -106.501239) (xy 433.330073 -106.449524) (xy 433.37383 -106.402927)
			(xy 433.423083 -106.362182) (xy 433.477054 -106.327931) (xy 433.534893 -106.300714) (xy 433.595686 -106.280961)
			(xy 433.658476 -106.268983) (xy 433.722272 -106.26497) (xy 433.786068 -106.268983) (xy 433.848858 -106.280961)
			(xy 433.909651 -106.300714) (xy 433.96749 -106.327931) (xy 434.021461 -106.362182) (xy 434.068156 -106.400811)
			(xy 454.745084 -106.400811) (xy 454.745084 -106.336889) (xy 454.753095 -106.273471) (xy 454.768992 -106.211557)
			(xy 454.792524 -106.152124) (xy 454.823318 -106.096109) (xy 454.860891 -106.044394) (xy 454.904648 -105.997797)
			(xy 454.953901 -105.957052) (xy 455.007872 -105.922801) (xy 455.065711 -105.895584) (xy 455.126504 -105.875831)
			(xy 455.189294 -105.863853) (xy 455.25309 -105.85984) (xy 455.316886 -105.863853) (xy 455.379676 -105.875831)
			(xy 455.440469 -105.895584) (xy 455.498308 -105.922801) (xy 455.552279 -105.957052) (xy 455.601532 -105.997797)
			(xy 455.645289 -106.044394) (xy 455.682862 -106.096109) (xy 455.713656 -106.152124) (xy 455.737188 -106.211557)
			(xy 455.753085 -106.273471) (xy 455.761096 -106.336889) (xy 455.761598 -106.36885) (xy 455.761096 -106.400811)
			(xy 455.753085 -106.464229) (xy 455.737188 -106.526143) (xy 455.713656 -106.585576) (xy 455.682862 -106.641591)
			(xy 455.645289 -106.693306) (xy 455.601532 -106.739903) (xy 455.552279 -106.780648) (xy 455.498308 -106.814899)
			(xy 455.440469 -106.842116) (xy 455.379676 -106.861869) (xy 455.316886 -106.873847) (xy 455.25309 -106.877861)
			(xy 455.189294 -106.873847) (xy 455.126504 -106.861869) (xy 455.065711 -106.842116) (xy 455.007872 -106.814899)
			(xy 454.953901 -106.780648) (xy 454.904648 -106.739903) (xy 454.860891 -106.693306) (xy 454.823318 -106.641591)
			(xy 454.792524 -106.585576) (xy 454.768992 -106.526143) (xy 454.753095 -106.464229) (xy 454.745084 -106.400811)
			(xy 434.068156 -106.400811) (xy 434.070714 -106.402927) (xy 434.114471 -106.449524) (xy 434.152044 -106.501239)
			(xy 434.182838 -106.557254) (xy 434.20637 -106.616687) (xy 434.222267 -106.678601) (xy 434.230278 -106.742019)
			(xy 434.23078 -106.77398) (xy 434.230278 -106.805941) (xy 434.222267 -106.869359) (xy 434.20637 -106.931273)
			(xy 434.182838 -106.990706) (xy 434.167374 -107.018836) (xy 455.666854 -107.018836) (xy 455.670925 -106.963214)
			(xy 455.683051 -106.908777) (xy 455.702974 -106.856686) (xy 455.73027 -106.808051) (xy 455.764356 -106.763908)
			(xy 455.804505 -106.725199) (xy 455.849863 -106.692748) (xy 455.899463 -106.667247) (xy 455.952247 -106.64924)
			(xy 456.00709 -106.63911) (xy 456.062824 -106.637073) (xy 456.118261 -106.643173) (xy 456.172218 -106.657279)
			(xy 456.223547 -106.679091) (xy 456.271153 -106.708145) (xy 456.314021 -106.74382) (xy 456.351238 -106.785357)
			(xy 456.382011 -106.83187) (xy 456.405683 -106.882367) (xy 456.421751 -106.935774) (xy 456.429871 -106.99095)
			(xy 456.43038 -107.018836) (xy 456.429871 -107.046722) (xy 456.421751 -107.101898) (xy 456.405683 -107.155305)
			(xy 456.382011 -107.205802) (xy 456.351238 -107.252315) (xy 456.314021 -107.293852) (xy 456.271153 -107.329527)
			(xy 456.223547 -107.358581) (xy 456.172218 -107.380393) (xy 456.118261 -107.394499) (xy 456.062824 -107.400599)
			(xy 456.00709 -107.398562) (xy 455.952247 -107.388432) (xy 455.899463 -107.370425) (xy 455.849863 -107.344924)
			(xy 455.804505 -107.312473) (xy 455.764356 -107.273764) (xy 455.73027 -107.229621) (xy 455.702974 -107.180986)
			(xy 455.683051 -107.128895) (xy 455.670925 -107.074458) (xy 455.666854 -107.018836) (xy 434.167374 -107.018836)
			(xy 434.152044 -107.046721) (xy 434.114471 -107.098436) (xy 434.070714 -107.145033) (xy 434.021461 -107.185778)
			(xy 433.96749 -107.220029) (xy 433.909651 -107.247246) (xy 433.848858 -107.266999) (xy 433.786068 -107.278977)
			(xy 433.722272 -107.282991) (xy 433.658476 -107.278977) (xy 433.595686 -107.266999) (xy 433.534893 -107.247246)
			(xy 433.477054 -107.220029) (xy 433.423083 -107.185778) (xy 433.37383 -107.145033) (xy 433.330073 -107.098436)
			(xy 433.2925 -107.046721) (xy 433.261706 -106.990706) (xy 433.238174 -106.931273) (xy 433.222277 -106.869359)
			(xy 433.214266 -106.805941) (xy 430.872634 -106.805941) (xy 430.919888 -106.832127) (xy 430.971781 -106.870163)
			(xy 431.018461 -106.914439) (xy 431.059183 -106.964251) (xy 431.093298 -107.018801) (xy 431.120259 -107.077218)
			(xy 431.139636 -107.13857) (xy 431.151119 -107.201876) (xy 431.153316 -107.233974) (xy 431.153316 -107.234228)
			(xy 431.15441 -107.244343) (xy 431.16344 -107.262555) (xy 431.170842 -107.269534) (xy 431.233834 -107.324398)
			(xy 431.252884 -107.330494) (xy 431.263298 -107.329732) (xy 431.295556 -107.328462) (xy 431.324762 -107.32902)
			(xy 431.382485 -107.337963) (xy 431.438175 -107.355585) (xy 431.490535 -107.381478) (xy 431.514758 -107.397804)
			(xy 431.515012 -107.398058) (xy 431.523631 -107.403304) (xy 431.543376 -107.407353) (xy 431.553366 -107.405932)
			(xy 431.625502 -107.391962) (xy 431.635408 -107.38953) (xy 431.652309 -107.378142) (xy 431.658268 -107.369864)
			(xy 431.658522 -107.36961) (xy 431.676108 -107.343242) (xy 431.716863 -107.2947) (xy 431.763338 -107.251602)
			(xy 431.81481 -107.214616) (xy 431.870481 -107.184317) (xy 431.929487 -107.161175) (xy 431.990913 -107.145548)
			(xy 432.053805 -107.137679) (xy 432.085496 -107.1372) (xy 432.117459 -107.137665) (xy 432.180881 -107.145676)
			(xy 432.242799 -107.161574) (xy 432.302236 -107.185106) (xy 432.358255 -107.215902) (xy 432.409972 -107.253477)
			(xy 432.456573 -107.297237) (xy 432.497321 -107.346493) (xy 432.531574 -107.400467) (xy 432.558793 -107.458309)
			(xy 432.578547 -107.519106) (xy 432.590526 -107.5819) (xy 432.59454 -107.6457) (xy 432.590526 -107.7095)
			(xy 432.578547 -107.772294) (xy 432.558793 -107.833091) (xy 432.531574 -107.890933) (xy 432.497321 -107.944907)
			(xy 432.456573 -107.994163) (xy 432.409972 -108.037923) (xy 432.358255 -108.075498) (xy 432.302236 -108.106294)
			(xy 432.242799 -108.129826) (xy 432.180881 -108.145724) (xy 432.117459 -108.153735) (xy 432.085496 -108.154216)
			(xy 432.05516 -108.15381) (xy 431.994917 -108.1466) (xy 431.935961 -108.13227) (xy 431.87913 -108.111024)
			(xy 431.825232 -108.083164) (xy 431.775033 -108.049087) (xy 431.729247 -108.009277) (xy 431.70856 -107.987084)
			(xy 431.701702 -107.979464) (xy 431.682906 -107.970828) (xy 431.59934 -107.968288) (xy 431.589057 -107.968426)
			(xy 431.569921 -107.975908) (xy 431.562256 -107.982766) (xy 431.549247 -107.995209) (xy 431.521259 -108.017851)
			(xy 431.506376 -108.027978) (xy 431.496624 -108.035258) (xy 431.484815 -108.056493) (xy 431.48377 -108.068618)
			(xy 431.480468 -108.163868) (xy 431.491136 -108.18622) (xy 431.49626 -108.19003) (xy 434.248558 -108.19003)
			(xy 434.252629 -108.134408) (xy 434.264755 -108.079971) (xy 434.284678 -108.02788) (xy 434.311974 -107.979245)
			(xy 434.34606 -107.935102) (xy 434.386209 -107.896393) (xy 434.431567 -107.863942) (xy 434.481167 -107.838441)
			(xy 434.533951 -107.820434) (xy 434.588794 -107.810304) (xy 434.644528 -107.808267) (xy 434.699965 -107.814367)
			(xy 434.753922 -107.828473) (xy 434.805251 -107.850285) (xy 434.852857 -107.879339) (xy 434.895725 -107.915014)
			(xy 434.932942 -107.956551) (xy 434.963715 -108.003064) (xy 434.987387 -108.053561) (xy 434.998858 -108.091689)
			(xy 454.715874 -108.091689) (xy 454.715874 -108.027767) (xy 454.723885 -107.964349) (xy 454.739782 -107.902435)
			(xy 454.763314 -107.843002) (xy 454.794108 -107.786987) (xy 454.831681 -107.735272) (xy 454.875438 -107.688675)
			(xy 454.924691 -107.64793) (xy 454.978662 -107.613679) (xy 455.036501 -107.586462) (xy 455.097294 -107.566709)
			(xy 455.160084 -107.554731) (xy 455.22388 -107.550718) (xy 455.287676 -107.554731) (xy 455.350466 -107.566709)
			(xy 455.411259 -107.586462) (xy 455.469098 -107.613679) (xy 455.523069 -107.64793) (xy 455.560298 -107.678728)
			(xy 461.611978 -107.678728) (xy 461.616049 -107.623106) (xy 461.628175 -107.568669) (xy 461.648098 -107.516578)
			(xy 461.675394 -107.467943) (xy 461.70948 -107.4238) (xy 461.749629 -107.385091) (xy 461.794987 -107.35264)
			(xy 461.844587 -107.327139) (xy 461.897371 -107.309132) (xy 461.952214 -107.299002) (xy 462.007948 -107.296965)
			(xy 462.063385 -107.303065) (xy 462.117342 -107.317171) (xy 462.168671 -107.338983) (xy 462.216277 -107.368037)
			(xy 462.259145 -107.403712) (xy 462.296362 -107.445249) (xy 462.327135 -107.491762) (xy 462.350807 -107.542259)
			(xy 462.366875 -107.595666) (xy 462.374995 -107.650842) (xy 462.375504 -107.678728) (xy 462.374995 -107.706614)
			(xy 462.366875 -107.76179) (xy 462.350807 -107.815197) (xy 462.327135 -107.865694) (xy 462.296362 -107.912207)
			(xy 462.259145 -107.953744) (xy 462.24111 -107.968753) (xy 462.46389 -107.968753) (xy 462.46389 -107.904831)
			(xy 462.471901 -107.841413) (xy 462.487798 -107.779499) (xy 462.51133 -107.720066) (xy 462.542124 -107.664051)
			(xy 462.579697 -107.612336) (xy 462.623454 -107.565739) (xy 462.672707 -107.524994) (xy 462.726678 -107.490743)
			(xy 462.784517 -107.463526) (xy 462.84531 -107.443773) (xy 462.9081 -107.431795) (xy 462.971896 -107.427782)
			(xy 463.035692 -107.431795) (xy 463.098482 -107.443773) (xy 463.159275 -107.463526) (xy 463.217114 -107.490743)
			(xy 463.271085 -107.524994) (xy 463.320338 -107.565739) (xy 463.364095 -107.612336) (xy 463.401668 -107.664051)
			(xy 463.432462 -107.720066) (xy 463.455994 -107.779499) (xy 463.471891 -107.841413) (xy 463.479902 -107.904831)
			(xy 463.480404 -107.936792) (xy 463.479902 -107.968753) (xy 463.471891 -108.032171) (xy 463.455994 -108.094085)
			(xy 463.432462 -108.153518) (xy 463.401668 -108.209533) (xy 463.364095 -108.261248) (xy 463.320338 -108.307845)
			(xy 463.271085 -108.34859) (xy 463.217114 -108.382841) (xy 463.159275 -108.410058) (xy 463.098482 -108.429811)
			(xy 463.035692 -108.441789) (xy 462.971896 -108.445803) (xy 462.9081 -108.441789) (xy 462.84531 -108.429811)
			(xy 462.784517 -108.410058) (xy 462.726678 -108.382841) (xy 462.672707 -108.34859) (xy 462.623454 -108.307845)
			(xy 462.579697 -108.261248) (xy 462.542124 -108.209533) (xy 462.51133 -108.153518) (xy 462.487798 -108.094085)
			(xy 462.471901 -108.032171) (xy 462.46389 -107.968753) (xy 462.24111 -107.968753) (xy 462.216277 -107.989419)
			(xy 462.168671 -108.018473) (xy 462.117342 -108.040285) (xy 462.063385 -108.054391) (xy 462.007948 -108.060491)
			(xy 461.952214 -108.058454) (xy 461.897371 -108.048324) (xy 461.844587 -108.030317) (xy 461.794987 -108.004816)
			(xy 461.749629 -107.972365) (xy 461.70948 -107.933656) (xy 461.675394 -107.889513) (xy 461.648098 -107.840878)
			(xy 461.628175 -107.788787) (xy 461.616049 -107.73435) (xy 461.611978 -107.678728) (xy 455.560298 -107.678728)
			(xy 455.572322 -107.688675) (xy 455.616079 -107.735272) (xy 455.653652 -107.786987) (xy 455.684446 -107.843002)
			(xy 455.707978 -107.902435) (xy 455.723875 -107.964349) (xy 455.731886 -108.027767) (xy 455.732388 -108.059728)
			(xy 455.731886 -108.091689) (xy 455.723875 -108.155107) (xy 455.707978 -108.217021) (xy 455.684446 -108.276454)
			(xy 455.653652 -108.332469) (xy 455.616079 -108.384184) (xy 455.572322 -108.430781) (xy 455.523069 -108.471526)
			(xy 455.469098 -108.505777) (xy 455.411259 -108.532994) (xy 455.350466 -108.552747) (xy 455.287676 -108.564725)
			(xy 455.22388 -108.568739) (xy 455.160084 -108.564725) (xy 455.097294 -108.552747) (xy 455.036501 -108.532994)
			(xy 454.978662 -108.505777) (xy 454.924691 -108.471526) (xy 454.875438 -108.430781) (xy 454.831681 -108.384184)
			(xy 454.794108 -108.332469) (xy 454.763314 -108.276454) (xy 454.739782 -108.217021) (xy 454.723885 -108.155107)
			(xy 454.715874 -108.091689) (xy 434.998858 -108.091689) (xy 435.003455 -108.106968) (xy 435.011575 -108.162144)
			(xy 435.012084 -108.19003) (xy 435.011575 -108.217916) (xy 435.003455 -108.273092) (xy 434.987387 -108.326499)
			(xy 434.963715 -108.376996) (xy 434.932942 -108.423509) (xy 434.895725 -108.465046) (xy 434.852857 -108.500721)
			(xy 434.805251 -108.529775) (xy 434.753922 -108.551587) (xy 434.699965 -108.565693) (xy 434.644528 -108.571793)
			(xy 434.588794 -108.569756) (xy 434.533951 -108.559626) (xy 434.481167 -108.541619) (xy 434.431567 -108.516118)
			(xy 434.386209 -108.483667) (xy 434.34606 -108.444958) (xy 434.311974 -108.400815) (xy 434.284678 -108.35218)
			(xy 434.264755 -108.300089) (xy 434.252629 -108.245652) (xy 434.248558 -108.19003) (xy 431.49626 -108.19003)
			(xy 431.501042 -108.193586) (xy 431.524051 -108.211729) (xy 431.564722 -108.253909) (xy 431.598468 -108.30181)
			(xy 431.624493 -108.354307) (xy 431.642188 -108.410166) (xy 431.651135 -108.468073) (xy 431.651664 -108.49737)
			(xy 431.651178 -108.524621) (xy 431.643422 -108.578569) (xy 431.628067 -108.630864) (xy 431.605425 -108.680441)
			(xy 431.575959 -108.726291) (xy 431.540268 -108.767482) (xy 431.499077 -108.803173) (xy 431.453227 -108.832639)
			(xy 431.40365 -108.855281) (xy 431.351355 -108.870636) (xy 431.297407 -108.878392) (xy 431.242905 -108.878392)
			(xy 431.188957 -108.870636) (xy 431.136662 -108.855281) (xy 431.087085 -108.832639) (xy 431.041235 -108.803173)
			(xy 431.000044 -108.767482) (xy 430.964353 -108.726291) (xy 430.934887 -108.680441) (xy 430.912245 -108.630864)
			(xy 430.89689 -108.578569) (xy 430.889134 -108.524621) (xy 430.888648 -108.49737) (xy 430.889057 -108.470502)
			(xy 430.89659 -108.417297) (xy 430.911516 -108.365675) (xy 430.933541 -108.31666) (xy 430.962227 -108.271222)
			(xy 430.997007 -108.23026) (xy 431.037192 -108.194585) (xy 431.059336 -108.179362) (xy 431.069073 -108.172065)
			(xy 431.080889 -108.150842) (xy 431.081942 -108.138722) (xy 431.085244 -108.043472) (xy 431.074576 -108.02112)
			(xy 431.06467 -108.013754) (xy 431.040559 -107.9947) (xy 430.998224 -107.950157) (xy 430.963578 -107.899403)
			(xy 430.937519 -107.843751) (xy 430.928526 -107.814364) (xy 430.925732 -107.804458) (xy 430.912778 -107.788456)
			(xy 430.839372 -107.749086) (xy 430.830248 -107.744652) (xy 430.810069 -107.7427) (xy 430.800256 -107.745276)
			(xy 430.799748 -107.745276) (xy 430.762201 -107.756533) (xy 430.684761 -107.768647) (xy 430.64557 -107.769406)
			(xy 430.61361 -107.768906) (xy 430.550195 -107.760892) (xy 430.488284 -107.744992) (xy 430.428853 -107.721459)
			(xy 430.372841 -107.690663) (xy 430.32113 -107.65309) (xy 430.274536 -107.609333) (xy 430.233793 -107.56008)
			(xy 430.199544 -107.50611) (xy 430.172329 -107.448273) (xy 430.152578 -107.387482) (xy 430.140601 -107.324694)
			(xy 430.136587 -107.2609) (xy 429.809142 -107.2609) (xy 429.79693 -107.308463) (xy 429.773398 -107.367896)
			(xy 429.742604 -107.423911) (xy 429.705031 -107.475626) (xy 429.661274 -107.522223) (xy 429.612021 -107.562968)
			(xy 429.55805 -107.597219) (xy 429.500211 -107.624436) (xy 429.439418 -107.644189) (xy 429.376628 -107.656167)
			(xy 429.312832 -107.660181) (xy 429.249036 -107.656167) (xy 429.186246 -107.644189) (xy 429.125453 -107.624436)
			(xy 429.067614 -107.597219) (xy 429.013643 -107.562968) (xy 428.96439 -107.522223) (xy 428.920633 -107.475626)
			(xy 428.88306 -107.423911) (xy 428.852266 -107.367896) (xy 428.828734 -107.308463) (xy 428.812837 -107.246549)
			(xy 428.804826 -107.183131) (xy 410.619006 -107.183131) (xy 410.634049 -107.241719) (xy 410.64206 -107.305137)
			(xy 410.642562 -107.337098) (xy 410.64206 -107.369059) (xy 410.634049 -107.432477) (xy 410.618152 -107.494391)
			(xy 410.59462 -107.553824) (xy 410.563826 -107.609839) (xy 410.526253 -107.661554) (xy 410.482496 -107.708151)
			(xy 410.433243 -107.748896) (xy 410.379272 -107.783147) (xy 410.321433 -107.810364) (xy 410.26064 -107.830117)
			(xy 410.19785 -107.842095) (xy 410.134054 -107.846109) (xy 410.070258 -107.842095) (xy 410.007468 -107.830117)
			(xy 409.946675 -107.810364) (xy 409.888836 -107.783147) (xy 409.834865 -107.748896) (xy 409.785612 -107.708151)
			(xy 409.741855 -107.661554) (xy 409.704282 -107.609839) (xy 409.673488 -107.553824) (xy 409.649956 -107.494391)
			(xy 409.634059 -107.432477) (xy 409.626048 -107.369059) (xy 327.965068 -107.369059) (xy 327.955974 -107.392026)
			(xy 327.92518 -107.448041) (xy 327.887607 -107.499756) (xy 327.84385 -107.546353) (xy 327.794597 -107.587098)
			(xy 327.740626 -107.621349) (xy 327.682787 -107.648566) (xy 327.621994 -107.668319) (xy 327.559204 -107.680297)
			(xy 327.495408 -107.684311) (xy 327.431612 -107.680297) (xy 327.368822 -107.668319) (xy 327.308029 -107.648566)
			(xy 327.25019 -107.621349) (xy 327.196219 -107.587098) (xy 327.146966 -107.546353) (xy 327.103209 -107.499756)
			(xy 327.065636 -107.448041) (xy 327.034842 -107.392026) (xy 327.01131 -107.332593) (xy 326.995413 -107.270679)
			(xy 326.987402 -107.207261) (xy 326.9869 -107.1753) (xy 309.930558 -107.1753) (xy 309.927295 -107.182235)
			(xy 309.893042 -107.236211) (xy 309.852295 -107.285468) (xy 309.805695 -107.32923) (xy 309.753978 -107.366806)
			(xy 309.69796 -107.397604) (xy 309.638523 -107.421139) (xy 309.576605 -107.437039) (xy 309.513183 -107.445053)
			(xy 309.48122 -107.445556) (xy 309.447758 -107.445046) (xy 309.381413 -107.436269) (xy 309.316793 -107.418865)
			(xy 309.255014 -107.393134) (xy 309.197144 -107.359521) (xy 309.144185 -107.318607) (xy 309.09705 -107.271099)
			(xy 309.056554 -107.217819) (xy 309.039514 -107.189016) (xy 309.032083 -107.176942) (xy 309.011763 -107.157186)
			(xy 308.986797 -107.143773) (xy 308.959106 -107.137736) (xy 308.930822 -107.139539) (xy 308.904123 -107.149043)
			(xy 308.881062 -107.165517) (xy 308.871874 -107.176316) (xy 308.853688 -107.198359) (xy 308.811806 -107.237235)
			(xy 308.764594 -107.269431) (xy 308.71311 -107.294226) (xy 308.658504 -107.311067) (xy 308.601996 -107.319578)
			(xy 308.573424 -107.32008) (xy 308.546168 -107.319675) (xy 308.49221 -107.31192) (xy 308.439906 -107.296565)
			(xy 308.390319 -107.273922) (xy 308.344459 -107.244452) (xy 308.303261 -107.208756) (xy 308.267562 -107.16756)
			(xy 308.238089 -107.121702) (xy 308.215444 -107.072117) (xy 308.200085 -107.019813) (xy 308.192327 -106.965856)
			(xy 273.987145 -106.965856) (xy 273.997311 -106.981222) (xy 274.020983 -107.031719) (xy 274.037051 -107.085126)
			(xy 274.045171 -107.140302) (xy 274.04568 -107.168188) (xy 274.045171 -107.196074) (xy 274.037051 -107.25125)
			(xy 274.020983 -107.304657) (xy 273.997311 -107.355154) (xy 273.966538 -107.401667) (xy 273.929321 -107.443204)
			(xy 273.886453 -107.478879) (xy 273.838847 -107.507933) (xy 273.787518 -107.529745) (xy 273.733561 -107.543851)
			(xy 273.678124 -107.549951) (xy 273.62239 -107.547914) (xy 273.567547 -107.537784) (xy 273.514763 -107.519777)
			(xy 273.465163 -107.494276) (xy 273.419805 -107.461825) (xy 273.379656 -107.423116) (xy 273.34557 -107.378973)
			(xy 273.318274 -107.330338) (xy 273.298351 -107.278247) (xy 273.286225 -107.22381) (xy 273.282154 -107.168188)
			(xy 272.98396 -107.168188) (xy 272.983458 -107.200149) (xy 272.975447 -107.263567) (xy 272.95955 -107.325481)
			(xy 272.936018 -107.384914) (xy 272.905224 -107.440929) (xy 272.867651 -107.492644) (xy 272.823894 -107.539241)
			(xy 272.774641 -107.579986) (xy 272.72067 -107.614237) (xy 272.662831 -107.641454) (xy 272.602038 -107.661207)
			(xy 272.539248 -107.673185) (xy 272.475452 -107.677199) (xy 272.411656 -107.673185) (xy 272.348866 -107.661207)
			(xy 272.288073 -107.641454) (xy 272.230234 -107.614237) (xy 272.176263 -107.579986) (xy 272.12701 -107.539241)
			(xy 272.083253 -107.492644) (xy 272.04568 -107.440929) (xy 272.014886 -107.384914) (xy 271.991354 -107.325481)
			(xy 271.975457 -107.263567) (xy 271.967446 -107.200149) (xy 260.211781 -107.200149) (xy 260.272318 -107.203957)
			(xy 260.335108 -107.215935) (xy 260.395901 -107.235688) (xy 260.45374 -107.262905) (xy 260.507711 -107.297156)
			(xy 260.556964 -107.337901) (xy 260.600721 -107.384498) (xy 260.638294 -107.436213) (xy 260.669088 -107.492228)
			(xy 260.69262 -107.551661) (xy 260.708517 -107.613575) (xy 260.716528 -107.676993) (xy 260.71703 -107.708954)
			(xy 260.716528 -107.740915) (xy 260.708517 -107.804333) (xy 260.69262 -107.866247) (xy 260.669088 -107.92568)
			(xy 260.638294 -107.981695) (xy 260.600721 -108.03341) (xy 260.556964 -108.080007) (xy 260.507711 -108.120752)
			(xy 260.45374 -108.155003) (xy 260.395901 -108.18222) (xy 260.335108 -108.201973) (xy 260.272318 -108.213951)
			(xy 260.208522 -108.217965) (xy 260.144726 -108.213951) (xy 260.081936 -108.201973) (xy 260.021143 -108.18222)
			(xy 259.963304 -108.155003) (xy 259.909333 -108.120752) (xy 259.86008 -108.080007) (xy 259.816323 -108.03341)
			(xy 259.77875 -107.981695) (xy 259.747956 -107.92568) (xy 259.724424 -107.866247) (xy 259.708527 -107.804333)
			(xy 259.700516 -107.740915) (xy 253.418194 -107.740915) (xy 253.423927 -107.779874) (xy 253.424436 -107.80776)
			(xy 253.423927 -107.835646) (xy 253.415807 -107.890822) (xy 253.399739 -107.944229) (xy 253.376067 -107.994726)
			(xy 253.345294 -108.041239) (xy 253.308077 -108.082776) (xy 253.265209 -108.118451) (xy 253.217603 -108.147505)
			(xy 253.166274 -108.169317) (xy 253.112317 -108.183423) (xy 253.05688 -108.189523) (xy 253.001146 -108.187486)
			(xy 252.946303 -108.177356) (xy 252.893519 -108.159349) (xy 252.843919 -108.133848) (xy 252.798561 -108.101397)
			(xy 252.758412 -108.062688) (xy 252.724326 -108.018545) (xy 252.69703 -107.96991) (xy 252.677107 -107.917819)
			(xy 252.664981 -107.863382) (xy 252.66091 -107.80776) (xy 251.506335 -107.80776) (xy 251.508266 -107.823043)
			(xy 251.508768 -107.855004) (xy 251.508266 -107.886965) (xy 251.500255 -107.950383) (xy 251.484358 -108.012297)
			(xy 251.460826 -108.07173) (xy 251.430032 -108.127745) (xy 251.392459 -108.17946) (xy 251.348702 -108.226057)
			(xy 251.299449 -108.266802) (xy 251.245478 -108.301053) (xy 251.187639 -108.32827) (xy 251.126846 -108.348023)
			(xy 251.064056 -108.360001) (xy 251.00026 -108.364015) (xy 250.936464 -108.360001) (xy 250.873674 -108.348023)
			(xy 250.812881 -108.32827) (xy 250.755042 -108.301053) (xy 250.701071 -108.266802) (xy 250.651818 -108.226057)
			(xy 250.608061 -108.17946) (xy 250.570488 -108.127745) (xy 250.539694 -108.07173) (xy 250.516162 -108.012297)
			(xy 250.500265 -107.950383) (xy 250.492254 -107.886965) (xy 221.570623 -107.886965) (xy 221.525819 -107.931845)
			(xy 221.47309 -107.972389) (xy 221.415526 -108.005712) (xy 221.354108 -108.031246) (xy 221.322138 -108.040424)
			(xy 221.307914 -108.044234) (xy 221.288102 -108.065824) (xy 221.269306 -108.171234) (xy 221.268051 -108.180726)
			(xy 221.271792 -108.199486) (xy 221.282115 -108.21559) (xy 221.289626 -108.221526) (xy 221.290134 -108.221526)
			(xy 221.314644 -108.239433) (xy 221.359649 -108.280167) (xy 221.399486 -108.325969) (xy 221.433589 -108.376186)
			(xy 221.461473 -108.430105) (xy 221.477514 -108.472986) (xy 265.073382 -108.472986) (xy 265.077453 -108.417364)
			(xy 265.089579 -108.362927) (xy 265.109502 -108.310836) (xy 265.136798 -108.262201) (xy 265.170884 -108.218058)
			(xy 265.211033 -108.179349) (xy 265.256391 -108.146898) (xy 265.305991 -108.121397) (xy 265.358775 -108.10339)
			(xy 265.413618 -108.09326) (xy 265.469352 -108.091223) (xy 265.524789 -108.097323) (xy 265.578746 -108.111429)
			(xy 265.630075 -108.133241) (xy 265.677681 -108.162295) (xy 265.720549 -108.19797) (xy 265.757766 -108.239507)
			(xy 265.788539 -108.28602) (xy 265.812211 -108.336517) (xy 265.828279 -108.389924) (xy 265.836399 -108.4451)
			(xy 265.836908 -108.472986) (xy 265.836399 -108.500872) (xy 265.828279 -108.556048) (xy 265.812211 -108.609455)
			(xy 265.788539 -108.659952) (xy 265.757766 -108.706465) (xy 265.748506 -108.7168) (xy 276.366515 -108.7168)
			(xy 276.370529 -108.653008) (xy 276.382506 -108.590222) (xy 276.402258 -108.529432) (xy 276.429473 -108.471597)
			(xy 276.463721 -108.417628) (xy 276.504464 -108.368378) (xy 276.551058 -108.324623) (xy 276.602769 -108.287052)
			(xy 276.658781 -108.256259) (xy 276.718211 -108.232728) (xy 276.780121 -108.216832) (xy 276.843535 -108.20882)
			(xy 276.875494 -108.208318) (xy 276.905723 -108.208793) (xy 276.965755 -108.21594) (xy 277.024517 -108.230157)
			(xy 277.081177 -108.251243) (xy 277.134936 -108.278902) (xy 277.185035 -108.312741) (xy 277.230766 -108.352285)
			(xy 277.271484 -108.396973) (xy 277.306614 -108.446176) (xy 277.321518 -108.472478) (xy 277.329019 -108.48515)
			(xy 277.349963 -108.505836) (xy 277.375937 -108.519688) (xy 277.404783 -108.525555) (xy 277.434105 -108.52295)
			(xy 277.461465 -108.512088) (xy 277.484589 -108.493873) (xy 277.493476 -108.48213) (xy 277.508855 -108.461045)
			(xy 277.544447 -108.422877) (xy 277.584909 -108.389917) (xy 277.629485 -108.362778) (xy 277.677344 -108.341967)
			(xy 277.727593 -108.327873) (xy 277.779294 -108.320759) (xy 277.805388 -108.320332) (xy 277.832644 -108.320714)
			(xy 277.886602 -108.328471) (xy 277.938907 -108.343827) (xy 277.988494 -108.366471) (xy 278.034353 -108.395942)
			(xy 278.075552 -108.43164) (xy 278.111251 -108.472837) (xy 278.140723 -108.518695) (xy 278.15718 -108.554731)
			(xy 315.06896 -108.554731) (xy 315.06896 -108.490809) (xy 315.076971 -108.427391) (xy 315.092868 -108.365477)
			(xy 315.1164 -108.306044) (xy 315.147194 -108.250029) (xy 315.184767 -108.198314) (xy 315.228524 -108.151717)
			(xy 315.277777 -108.110972) (xy 315.331748 -108.076721) (xy 315.389587 -108.049504) (xy 315.45038 -108.029751)
			(xy 315.51317 -108.017773) (xy 315.576966 -108.01376) (xy 315.640762 -108.017773) (xy 315.703552 -108.029751)
			(xy 315.764345 -108.049504) (xy 315.822184 -108.076721) (xy 315.876155 -108.110972) (xy 315.925408 -108.151717)
			(xy 315.969165 -108.198314) (xy 316.006738 -108.250029) (xy 316.037532 -108.306044) (xy 316.061064 -108.365477)
			(xy 316.076961 -108.427391) (xy 316.084972 -108.490809) (xy 316.085474 -108.52277) (xy 316.084972 -108.554731)
			(xy 316.076961 -108.618149) (xy 316.061064 -108.680063) (xy 316.037532 -108.739496) (xy 316.006738 -108.795511)
			(xy 315.969165 -108.847226) (xy 315.925408 -108.893823) (xy 315.876155 -108.934568) (xy 315.822184 -108.968819)
			(xy 315.764345 -108.996036) (xy 315.703552 -109.015789) (xy 315.640762 -109.027767) (xy 315.576966 -109.031781)
			(xy 315.51317 -109.027767) (xy 315.45038 -109.015789) (xy 315.389587 -108.996036) (xy 315.331748 -108.968819)
			(xy 315.277777 -108.934568) (xy 315.228524 -108.893823) (xy 315.184767 -108.847226) (xy 315.147194 -108.795511)
			(xy 315.1164 -108.739496) (xy 315.092868 -108.680063) (xy 315.076971 -108.618149) (xy 315.06896 -108.554731)
			(xy 278.15718 -108.554731) (xy 278.163369 -108.568282) (xy 278.178727 -108.620586) (xy 278.186485 -108.674544)
			(xy 278.186485 -108.729056) (xy 278.178727 -108.783014) (xy 278.163369 -108.835318) (xy 278.140723 -108.884905)
			(xy 278.111251 -108.930763) (xy 278.075552 -108.97196) (xy 278.034353 -109.007658) (xy 277.988494 -109.037129)
			(xy 277.938907 -109.059773) (xy 277.886602 -109.075129) (xy 277.832644 -109.082886) (xy 277.805388 -109.083348)
			(xy 277.775973 -109.082815) (xy 277.717843 -109.073776) (xy 277.66179 -109.055916) (xy 277.609147 -109.029658)
			(xy 277.561161 -108.995625) (xy 277.518972 -108.954625) (xy 277.500842 -108.931456) (xy 277.491528 -108.920031)
			(xy 277.46782 -108.902545) (xy 277.440106 -108.892555) (xy 277.410694 -108.890893) (xy 277.382032 -108.897697)
			(xy 277.356505 -108.912401) (xy 277.336239 -108.933781) (xy 277.329138 -108.946696) (xy 277.314583 -108.974224)
			(xy 277.27986 -109.025914) (xy 277.239086 -109.072977) (xy 277.192871 -109.114711) (xy 277.141907 -109.150491)
			(xy 277.086957 -109.179781) (xy 277.028842 -109.202144) (xy 276.968431 -109.217246) (xy 276.906629 -109.224859)
			(xy 276.875494 -109.225334) (xy 276.843535 -109.22478) (xy 276.780121 -109.216768) (xy 276.718211 -109.200872)
			(xy 276.658781 -109.177341) (xy 276.602769 -109.146548) (xy 276.551058 -109.108977) (xy 276.504464 -109.065222)
			(xy 276.463721 -109.015972) (xy 276.429473 -108.962003) (xy 276.402258 -108.904168) (xy 276.382506 -108.843378)
			(xy 276.370529 -108.780592) (xy 276.366515 -108.7168) (xy 265.748506 -108.7168) (xy 265.720549 -108.748002)
			(xy 265.677681 -108.783677) (xy 265.630075 -108.812731) (xy 265.578746 -108.834543) (xy 265.524789 -108.848649)
			(xy 265.469352 -108.854749) (xy 265.413618 -108.852712) (xy 265.358775 -108.842582) (xy 265.305991 -108.824575)
			(xy 265.256391 -108.799074) (xy 265.211033 -108.766623) (xy 265.170884 -108.727914) (xy 265.136798 -108.683771)
			(xy 265.109502 -108.635136) (xy 265.089579 -108.583045) (xy 265.077453 -108.528608) (xy 265.073382 -108.472986)
			(xy 221.477514 -108.472986) (xy 221.482741 -108.486959) (xy 221.497092 -108.545941) (xy 221.504321 -108.606211)
			(xy 221.504764 -108.636562) (xy 221.504282 -108.667592) (xy 221.496728 -108.729192) (xy 221.48174 -108.789415)
			(xy 221.45954 -108.84737) (xy 221.430457 -108.902194) (xy 221.41307 -108.9279) (xy 221.407063 -108.937601)
			(xy 221.403261 -108.96006) (xy 221.409534 -108.981958) (xy 221.416626 -108.990892) (xy 221.43665 -109.014161)
			(xy 221.471509 -109.064693) (xy 221.50003 -109.119056) (xy 221.513636 -109.154933) (xy 262.23188 -109.154933)
			(xy 262.23188 -109.091011) (xy 262.239891 -109.027593) (xy 262.255788 -108.965679) (xy 262.27932 -108.906246)
			(xy 262.310114 -108.850231) (xy 262.347687 -108.798516) (xy 262.391444 -108.751919) (xy 262.440697 -108.711174)
			(xy 262.494668 -108.676923) (xy 262.552507 -108.649706) (xy 262.6133 -108.629953) (xy 262.67609 -108.617975)
			(xy 262.739886 -108.613962) (xy 262.803682 -108.617975) (xy 262.866472 -108.629953) (xy 262.927265 -108.649706)
			(xy 262.985104 -108.676923) (xy 263.039075 -108.711174) (xy 263.088328 -108.751919) (xy 263.132085 -108.798516)
			(xy 263.169658 -108.850231) (xy 263.200452 -108.906246) (xy 263.223984 -108.965679) (xy 263.239881 -109.027593)
			(xy 263.247892 -109.091011) (xy 263.248394 -109.122972) (xy 263.247892 -109.154933) (xy 263.239881 -109.218351)
			(xy 263.223984 -109.280265) (xy 263.200452 -109.339698) (xy 263.169658 -109.395713) (xy 263.132085 -109.447428)
			(xy 263.088328 -109.494025) (xy 263.039075 -109.53477) (xy 262.985104 -109.569021) (xy 262.927265 -109.596238)
			(xy 262.866472 -109.615991) (xy 262.803682 -109.627969) (xy 262.739886 -109.631983) (xy 262.67609 -109.627969)
			(xy 262.6133 -109.615991) (xy 262.552507 -109.596238) (xy 262.494668 -109.569021) (xy 262.440697 -109.53477)
			(xy 262.391444 -109.494025) (xy 262.347687 -109.447428) (xy 262.310114 -109.395713) (xy 262.27932 -109.339698)
			(xy 262.255788 -109.280265) (xy 262.239891 -109.218351) (xy 262.23188 -109.154933) (xy 221.513636 -109.154933)
			(xy 221.521799 -109.176457) (xy 221.536498 -109.236061) (xy 221.543914 -109.297001) (xy 221.544388 -109.327696)
			(xy 221.543886 -109.359657) (xy 221.535875 -109.423075) (xy 221.519978 -109.484989) (xy 221.496446 -109.544422)
			(xy 221.465652 -109.600437) (xy 221.428079 -109.652152) (xy 221.384322 -109.698749) (xy 221.335069 -109.739494)
			(xy 221.281098 -109.773745) (xy 221.223259 -109.800962) (xy 221.162466 -109.820715) (xy 221.099676 -109.832693)
			(xy 221.03588 -109.836707) (xy 220.972084 -109.832693) (xy 220.909294 -109.820715) (xy 220.848501 -109.800962)
			(xy 220.790662 -109.773745) (xy 220.736691 -109.739494) (xy 220.687438 -109.698749) (xy 220.643681 -109.652152)
			(xy 220.606108 -109.600437) (xy 220.575314 -109.544422) (xy 220.551782 -109.484989) (xy 220.535885 -109.423075)
			(xy 220.527874 -109.359657) (xy 220.527372 -109.327696) (xy 220.527826 -109.296665) (xy 220.535386 -109.235064)
			(xy 220.55038 -109.17484) (xy 220.572586 -109.116886) (xy 220.601675 -109.062063) (xy 220.619066 -109.036358)
			(xy 220.625106 -109.026676) (xy 220.628893 -109.004205) (xy 220.622607 -108.982302) (xy 220.61551 -108.973366)
			(xy 220.59552 -108.95007) (xy 220.560656 -108.899544) (xy 220.532129 -108.845187) (xy 220.510354 -108.787792)
			(xy 220.495648 -108.728192) (xy 220.488226 -108.667255) (xy 220.487748 -108.636562) (xy 219.593166 -108.636562)
			(xy 219.633191 -108.66564) (xy 219.679796 -108.709404) (xy 219.720549 -108.758664) (xy 219.754807 -108.812643)
			(xy 219.782028 -108.870491) (xy 219.801785 -108.931294) (xy 219.813765 -108.994094) (xy 219.81778 -109.0579)
			(xy 219.813765 -109.121706) (xy 219.801785 -109.184506) (xy 219.782028 -109.245309) (xy 219.754807 -109.303157)
			(xy 219.720549 -109.357136) (xy 219.679796 -109.406396) (xy 219.633191 -109.45016) (xy 219.581468 -109.487737)
			(xy 219.525442 -109.518535) (xy 219.465999 -109.542068) (xy 219.404075 -109.557966) (xy 219.340646 -109.565976)
			(xy 219.30868 -109.566456) (xy 219.278342 -109.565984) (xy 219.218095 -109.558775) (xy 219.159137 -109.544438)
			(xy 219.102307 -109.523177) (xy 219.048415 -109.495296) (xy 218.99823 -109.461192) (xy 218.952467 -109.421351)
			(xy 218.911777 -109.37634) (xy 218.893898 -109.351826) (xy 218.886244 -109.342267) (xy 218.864472 -109.331133)
			(xy 218.852242 -109.33049) (xy 218.769438 -109.33049) (xy 218.75721 -109.331139) (xy 218.735447 -109.342277)
			(xy 218.727782 -109.351826) (xy 218.709914 -109.376348) (xy 218.669214 -109.421351) (xy 218.623446 -109.461187)
			(xy 218.573259 -109.49529) (xy 218.519368 -109.523173) (xy 218.46254 -109.544441) (xy 218.403584 -109.558789)
			(xy 218.343339 -109.566015) (xy 218.313 -109.566456) (xy 218.282271 -109.565944) (xy 218.221261 -109.558536)
			(xy 218.161588 -109.543829) (xy 218.104123 -109.522037) (xy 218.049704 -109.493478) (xy 217.999123 -109.458567)
			(xy 217.953119 -109.417815) (xy 217.912362 -109.371815) (xy 217.877447 -109.321238) (xy 217.848882 -109.266821)
			(xy 217.827085 -109.209358) (xy 217.812372 -109.149687) (xy 217.804959 -109.088677) (xy 217.804492 -109.057948)
			(xy 217.804974 -109.026063) (xy 217.812959 -108.962795) (xy 217.828787 -108.90102) (xy 217.852208 -108.841707)
			(xy 217.882856 -108.785785) (xy 217.92025 -108.734129) (xy 217.963805 -108.68755) (xy 218.012838 -108.646778)
			(xy 218.039442 -108.629196) (xy 218.050364 -108.622338) (xy 218.063064 -108.599224) (xy 218.062048 -108.486956)
			(xy 218.049348 -108.464096) (xy 218.038172 -108.457238) (xy 218.010888 -108.439814) (xy 217.960549 -108.399106)
			(xy 217.915784 -108.352338) (xy 217.877315 -108.300268) (xy 217.845766 -108.243737) (xy 217.821646 -108.183659)
			(xy 217.805344 -108.121007) (xy 217.797126 -108.056791) (xy 217.796618 -108.024422) (xy 215.016467 -108.024422)
			(xy 214.979388 -108.033942) (xy 214.915964 -108.041954) (xy 214.884 -108.042456) (xy 214.853053 -108.041974)
			(xy 214.791618 -108.034455) (xy 214.731548 -108.019538) (xy 214.673732 -107.997446) (xy 214.619021 -107.968504)
			(xy 214.568226 -107.933139) (xy 214.522095 -107.891875) (xy 214.48131 -107.845319) (xy 214.446474 -107.79416)
			(xy 214.43188 -107.766866) (xy 214.43188 -107.766612) (xy 214.427407 -107.758791) (xy 214.4141 -107.746662)
			(xy 214.39743 -107.739856) (xy 214.388446 -107.73918) (xy 214.2998 -107.736132) (xy 214.290761 -107.736212)
			(xy 214.273619 -107.7419) (xy 214.259534 -107.753206) (xy 214.254588 -107.76077) (xy 214.237264 -107.788447)
			(xy 214.196604 -107.839538) (xy 214.149738 -107.885003) (xy 214.097436 -107.924094) (xy 214.040561 -107.956167)
			(xy 213.980048 -107.980695) (xy 213.916892 -107.997275) (xy 213.852134 -108.005632) (xy 213.819486 -108.006134)
			(xy 213.787541 -108.005666) (xy 213.724154 -107.997671) (xy 213.662268 -107.981796) (xy 213.602859 -107.958292)
			(xy 213.546863 -107.927528) (xy 213.495164 -107.889991) (xy 213.448575 -107.846271) (xy 213.427818 -107.821984)
			(xy 213.420198 -107.81284) (xy 213.398608 -107.803188) (xy 213.294214 -107.807252) (xy 213.27364 -107.818428)
			(xy 213.266782 -107.82808) (xy 213.248852 -107.852544) (xy 213.208139 -107.897505) (xy 213.162366 -107.937301)
			(xy 213.112182 -107.971368) (xy 213.058301 -107.999222) (xy 213.001488 -108.020466) (xy 212.942551 -108.034798)
			(xy 212.882327 -108.042016) (xy 212.852 -108.042456) (xy 212.821293 -108.041977) (xy 212.760324 -108.034591)
			(xy 212.700689 -108.019914) (xy 212.643256 -107.99816) (xy 212.588862 -107.969647) (xy 212.538299 -107.934788)
			(xy 212.492303 -107.894093) (xy 212.451544 -107.848153) (xy 212.416616 -107.797638) (xy 212.401912 -107.770676)
			(xy 212.395562 -107.758484) (xy 212.372194 -107.743752) (xy 212.269832 -107.741212) (xy 212.260743 -107.741303)
			(xy 212.243554 -107.747176) (xy 212.229508 -107.758694) (xy 212.22462 -107.766358) (xy 212.20737 -107.794435)
			(xy 212.166749 -107.846324) (xy 212.119767 -107.892532) (xy 212.06721 -107.932285) (xy 212.009959 -107.964916)
			(xy 211.948973 -107.98988) (xy 211.885273 -108.006757) (xy 211.819927 -108.015266) (xy 211.786978 -108.015786)
			(xy 211.755016 -108.015327) (xy 211.691598 -108.007313) (xy 211.629684 -107.991413) (xy 211.57025 -107.96788)
			(xy 211.514235 -107.937083) (xy 211.462521 -107.899508) (xy 211.415924 -107.855749) (xy 211.375179 -107.806495)
			(xy 211.340928 -107.752522) (xy 211.313712 -107.694682) (xy 211.293959 -107.633888) (xy 211.281981 -107.571097)
			(xy 211.277967 -107.5073) (xy 210.351736 -107.5073) (xy 210.353909 -107.522064) (xy 210.354418 -107.54995)
			(xy 210.353909 -107.577836) (xy 210.345789 -107.633012) (xy 210.329721 -107.686419) (xy 210.306049 -107.736916)
			(xy 210.275276 -107.783429) (xy 210.238059 -107.824966) (xy 210.195191 -107.860641) (xy 210.147585 -107.889695)
			(xy 210.096256 -107.911507) (xy 210.042299 -107.925613) (xy 209.986862 -107.931713) (xy 209.931128 -107.929676)
			(xy 209.876285 -107.919546) (xy 209.823501 -107.901539) (xy 209.773901 -107.876038) (xy 209.728543 -107.843587)
			(xy 209.688394 -107.804878) (xy 209.654308 -107.760735) (xy 209.627012 -107.7121) (xy 209.607089 -107.660009)
			(xy 209.594963 -107.605572) (xy 209.590892 -107.54995) (xy 206.879267 -107.54995) (xy 206.848816 -107.595977)
			(xy 206.811599 -107.637514) (xy 206.768731 -107.673189) (xy 206.721125 -107.702243) (xy 206.669796 -107.724055)
			(xy 206.615839 -107.738161) (xy 206.560402 -107.744261) (xy 206.504668 -107.742224) (xy 206.449825 -107.732094)
			(xy 206.397041 -107.714087) (xy 206.347441 -107.688586) (xy 206.302083 -107.656135) (xy 206.261934 -107.617426)
			(xy 206.227848 -107.573283) (xy 206.200552 -107.524648) (xy 206.180629 -107.472557) (xy 206.168503 -107.41812)
			(xy 206.164432 -107.362498) (xy 202.735921 -107.362498) (xy 202.740886 -107.375333) (xy 202.756126 -107.436013)
			(xy 202.763806 -107.498104) (xy 202.763807 -107.560669) (xy 202.756131 -107.622761) (xy 202.740894 -107.683442)
			(xy 202.718325 -107.741794) (xy 202.688765 -107.796936) (xy 202.652663 -107.848033) (xy 202.610563 -107.894314)
			(xy 202.563101 -107.935079) (xy 202.537314 -107.952794) (xy 202.52718 -107.960335) (xy 202.515312 -107.982595)
			(xy 202.514708 -107.995212) (xy 202.514708 -108.07954) (xy 202.51539 -108.09214) (xy 202.527222 -108.114387)
			(xy 202.537314 -108.121958) (xy 202.56308 -108.139705) (xy 202.610543 -108.180468) (xy 202.652646 -108.226746)
			(xy 202.688751 -108.277842) (xy 202.718313 -108.332982) (xy 202.740886 -108.391333) (xy 202.756126 -108.452013)
			(xy 202.758747 -108.4732) (xy 206.057008 -108.4732) (xy 206.061022 -108.409406) (xy 206.073 -108.346618)
			(xy 206.092752 -108.285826) (xy 206.119969 -108.227989) (xy 206.154219 -108.17402) (xy 206.194964 -108.124769)
			(xy 206.24156 -108.081012) (xy 206.293273 -108.043442) (xy 206.349287 -108.012648) (xy 206.408719 -107.989118)
			(xy 206.470631 -107.973223) (xy 206.534048 -107.965212) (xy 206.566008 -107.964732) (xy 206.596631 -107.965175)
			(xy 206.657432 -107.972543) (xy 206.716908 -107.98716) (xy 206.774198 -108.008814) (xy 206.828473 -108.037191)
			(xy 206.878947 -108.071881) (xy 206.92489 -108.112382) (xy 206.965636 -108.158107) (xy 207.000596 -108.208395)
			(xy 207.015334 -108.235242) (xy 207.020007 -108.243126) (xy 207.033769 -108.255209) (xy 207.050884 -108.261725)
			(xy 207.060038 -108.262166) (xy 207.150208 -108.262166) (xy 207.159377 -108.261784) (xy 207.176529 -108.255297)
			(xy 207.190279 -108.243164) (xy 207.194912 -108.235242) (xy 207.209643 -108.20839) (xy 207.244596 -108.158096)
			(xy 207.285339 -108.112365) (xy 207.331281 -108.071861) (xy 207.381757 -108.037171) (xy 207.436035 -108.008796)
			(xy 207.49333 -107.987149) (xy 207.55281 -107.972542) (xy 207.613614 -107.965188) (xy 207.644238 -107.964732)
			(xy 207.674972 -107.965102) (xy 207.735993 -107.972516) (xy 207.795674 -107.987231) (xy 207.853147 -108.009032)
			(xy 207.907573 -108.037603) (xy 207.958158 -108.072525) (xy 208.004165 -108.11329) (xy 208.044923 -108.159303)
			(xy 208.079838 -108.209894) (xy 208.1084 -108.264324) (xy 208.130192 -108.3218) (xy 208.144898 -108.381484)
			(xy 208.152303 -108.442505) (xy 208.152746 -108.47324) (xy 208.152289 -108.504528) (xy 208.144613 -108.566632)
			(xy 208.129368 -108.627324) (xy 208.106787 -108.685684) (xy 208.07721 -108.74083) (xy 208.041085 -108.791927)
			(xy 207.99896 -108.838201) (xy 207.951471 -108.878952) (xy 207.92567 -108.896658) (xy 207.915517 -108.904179)
			(xy 207.903656 -108.926453) (xy 207.903064 -108.939076) (xy 207.903064 -109.023404) (xy 207.903686 -109.036013)
			(xy 207.915559 -109.058261) (xy 207.92567 -109.065822) (xy 207.951449 -109.083556) (xy 207.998928 -109.124311)
			(xy 208.041045 -109.170585) (xy 208.077165 -109.221678) (xy 208.106741 -109.276819) (xy 208.129324 -109.335173)
			(xy 208.144575 -109.395857) (xy 208.152263 -109.457954) (xy 208.152746 -109.48924) (xy 208.152244 -109.521201)
			(xy 208.144233 -109.584619) (xy 208.128336 -109.646533) (xy 208.104804 -109.705966) (xy 208.07401 -109.761981)
			(xy 208.036437 -109.813696) (xy 207.99268 -109.860293) (xy 207.943427 -109.901038) (xy 207.889456 -109.935289)
			(xy 207.831617 -109.962506) (xy 207.770824 -109.982259) (xy 207.708034 -109.994237) (xy 207.644238 -109.998251)
			(xy 207.580442 -109.994237) (xy 207.517652 -109.982259) (xy 207.456859 -109.962506) (xy 207.39902 -109.935289)
			(xy 207.345049 -109.901038) (xy 207.295796 -109.860293) (xy 207.252039 -109.813696) (xy 207.214466 -109.761981)
			(xy 207.183672 -109.705966) (xy 207.16014 -109.646533) (xy 207.144243 -109.584619) (xy 207.136232 -109.521201)
			(xy 207.13573 -109.48924) (xy 207.136182 -109.457952) (xy 207.143861 -109.395848) (xy 207.159107 -109.335157)
			(xy 207.181689 -109.276797) (xy 207.211267 -109.221651) (xy 207.247392 -109.170554) (xy 207.289517 -109.12428)
			(xy 207.337005 -109.083528) (xy 207.362806 -109.065822) (xy 207.372936 -109.058277) (xy 207.384806 -109.03602)
			(xy 207.385412 -109.023404) (xy 207.385412 -108.939076) (xy 207.384812 -108.926464) (xy 207.372925 -108.904216)
			(xy 207.362806 -108.896658) (xy 207.336739 -108.878782) (xy 207.288827 -108.837557) (xy 207.246404 -108.790702)
			(xy 207.210124 -108.738944) (xy 207.194912 -108.711238) (xy 207.190275 -108.703317) (xy 207.176534 -108.691172)
			(xy 207.159378 -108.684695) (xy 207.150208 -108.684314) (xy 207.060038 -108.684314) (xy 207.050873 -108.684739)
			(xy 207.033724 -108.691208) (xy 207.019971 -108.703324) (xy 207.015334 -108.711238) (xy 207.00056 -108.738065)
			(xy 206.965613 -108.78836) (xy 206.924876 -108.834091) (xy 206.878939 -108.874597) (xy 206.828469 -108.90929)
			(xy 206.774196 -108.937668) (xy 206.716907 -108.959319) (xy 206.657431 -108.97393) (xy 206.59663 -108.98129)
			(xy 206.566008 -108.981748) (xy 206.534048 -108.981188) (xy 206.470631 -108.973177) (xy 206.408719 -108.957282)
			(xy 206.349287 -108.933752) (xy 206.293273 -108.902958) (xy 206.24156 -108.865388) (xy 206.194964 -108.821631)
			(xy 206.154219 -108.77238) (xy 206.119969 -108.718411) (xy 206.092752 -108.660574) (xy 206.073 -108.599782)
			(xy 206.061022 -108.536994) (xy 206.057008 -108.4732) (xy 202.758747 -108.4732) (xy 202.763806 -108.514104)
			(xy 202.763807 -108.576669) (xy 202.756131 -108.638761) (xy 202.740894 -108.699442) (xy 202.718325 -108.757794)
			(xy 202.688765 -108.812936) (xy 202.652663 -108.864033) (xy 202.610563 -108.910314) (xy 202.563101 -108.951079)
			(xy 202.537314 -108.968794) (xy 202.52718 -108.976335) (xy 202.515312 -108.998595) (xy 202.514708 -109.011212)
			(xy 202.514708 -109.09554) (xy 202.51539 -109.10814) (xy 202.527222 -109.130387) (xy 202.537314 -109.137958)
			(xy 202.56312 -109.155655) (xy 202.610596 -109.196416) (xy 202.652711 -109.242696) (xy 202.688828 -109.293796)
			(xy 202.718399 -109.348942) (xy 202.740979 -109.4073) (xy 202.756226 -109.467988) (xy 202.763909 -109.530089)
			(xy 202.76439 -109.561376) (xy 202.763961 -109.592265) (xy 202.756486 -109.65359) (xy 202.74163 -109.713556)
			(xy 202.719613 -109.771278) (xy 202.690761 -109.825905) (xy 202.655498 -109.876631) (xy 202.614344 -109.922707)
			(xy 202.567908 -109.963454) (xy 202.542648 -109.981238) (xy 202.542394 -109.981238) (xy 202.532633 -109.989028)
			(xy 202.521208 -110.011186) (xy 202.52055 -110.023656) (xy 202.52182 -110.121192) (xy 202.534266 -110.143544)
			(xy 202.544934 -110.150402) (xy 202.571243 -110.168055) (xy 202.619733 -110.208832) (xy 202.662784 -110.255315)
			(xy 202.699729 -110.306784) (xy 202.729996 -110.362443) (xy 202.753117 -110.42143) (xy 202.768734 -110.482832)
			(xy 202.776605 -110.545698) (xy 202.77709 -110.577376) (xy 202.776588 -110.609337) (xy 202.77569 -110.616449)
			(xy 203.268574 -110.616449) (xy 203.268574 -110.552527) (xy 203.276585 -110.489109) (xy 203.292482 -110.427195)
			(xy 203.316014 -110.367762) (xy 203.346808 -110.311747) (xy 203.384381 -110.260032) (xy 203.428138 -110.213435)
			(xy 203.477391 -110.17269) (xy 203.531362 -110.138439) (xy 203.589201 -110.111222) (xy 203.649994 -110.091469)
			(xy 203.712784 -110.079491) (xy 203.77658 -110.075478) (xy 203.840376 -110.079491) (xy 203.903166 -110.091469)
			(xy 203.963959 -110.111222) (xy 204.021798 -110.138439) (xy 204.075769 -110.17269) (xy 204.125022 -110.213435)
			(xy 204.168779 -110.260032) (xy 204.206352 -110.311747) (xy 204.237146 -110.367762) (xy 204.260678 -110.427195)
			(xy 204.276575 -110.489109) (xy 204.284586 -110.552527) (xy 204.285088 -110.584488) (xy 204.284586 -110.616449)
			(xy 204.276575 -110.679867) (xy 204.260678 -110.741781) (xy 204.237146 -110.801214) (xy 204.206352 -110.857229)
			(xy 204.168779 -110.908944) (xy 204.125022 -110.955541) (xy 204.075769 -110.996286) (xy 204.021798 -111.030537)
			(xy 203.963959 -111.057754) (xy 203.903166 -111.077507) (xy 203.840376 -111.089485) (xy 203.77658 -111.093499)
			(xy 203.712784 -111.089485) (xy 203.649994 -111.077507) (xy 203.589201 -111.057754) (xy 203.531362 -111.030537)
			(xy 203.477391 -110.996286) (xy 203.428138 -110.955541) (xy 203.384381 -110.908944) (xy 203.346808 -110.857229)
			(xy 203.316014 -110.801214) (xy 203.292482 -110.741781) (xy 203.276585 -110.679867) (xy 203.268574 -110.616449)
			(xy 202.77569 -110.616449) (xy 202.768577 -110.672755) (xy 202.75268 -110.734669) (xy 202.729148 -110.794102)
			(xy 202.698354 -110.850117) (xy 202.660781 -110.901832) (xy 202.617024 -110.948429) (xy 202.567771 -110.989174)
			(xy 202.5138 -111.023425) (xy 202.455961 -111.050642) (xy 202.395168 -111.070395) (xy 202.332378 -111.082373)
			(xy 202.268582 -111.086387) (xy 202.204786 -111.082373) (xy 202.141996 -111.070395) (xy 202.081203 -111.050642)
			(xy 202.023364 -111.023425) (xy 201.969393 -110.989174) (xy 201.92014 -110.948429) (xy 201.876383 -110.901832)
			(xy 201.83881 -110.850117) (xy 201.808016 -110.794102) (xy 201.784484 -110.734669) (xy 201.768587 -110.672755)
			(xy 201.760576 -110.609337) (xy 201.760074 -110.577376) (xy 201.760558 -110.546488) (xy 201.768027 -110.485167)
			(xy 201.782875 -110.425203) (xy 201.804884 -110.367481) (xy 201.83373 -110.312854) (xy 201.868985 -110.262128)
			(xy 201.910131 -110.21605) (xy 201.956559 -110.1753) (xy 201.981816 -110.157514) (xy 201.98207 -110.157514)
			(xy 201.991864 -110.14976) (xy 202.003269 -110.127574) (xy 202.003914 -110.115096) (xy 202.002644 -110.01756)
			(xy 201.990198 -109.995208) (xy 201.97953 -109.98835) (xy 201.953213 -109.970708) (xy 201.904721 -109.929931)
			(xy 201.861668 -109.883448) (xy 201.824722 -109.831977) (xy 201.794455 -109.776316) (xy 201.771336 -109.717327)
			(xy 201.755722 -109.655923) (xy 201.747856 -109.593055) (xy 201.747374 -109.561376) (xy 199.44353 -109.561376)
			(xy 199.447144 -109.6096) (xy 199.443161 -109.662752) (xy 199.431301 -109.714716) (xy 199.411829 -109.764333)
			(xy 199.38518 -109.810494) (xy 199.351949 -109.852167) (xy 199.312879 -109.888423) (xy 199.268841 -109.918451)
			(xy 199.220821 -109.941581) (xy 199.169889 -109.957295) (xy 199.117184 -109.965244) (xy 199.090534 -109.965744)
			(xy 199.064705 -109.965299) (xy 199.013587 -109.957852) (xy 198.964083 -109.943093) (xy 198.917232 -109.921333)
			(xy 198.874018 -109.89303) (xy 198.83535 -109.858777) (xy 198.802039 -109.819294) (xy 198.78802 -109.797596)
			(xy 198.780322 -109.785992) (xy 198.759756 -109.767227) (xy 198.734889 -109.754709) (xy 198.707566 -109.749367)
			(xy 198.679816 -109.751597) (xy 198.653697 -109.761233) (xy 198.631147 -109.777561) (xy 198.622158 -109.788198)
			(xy 198.605171 -109.808915) (xy 198.566052 -109.845516) (xy 198.521889 -109.875841) (xy 198.473679 -109.899203)
			(xy 198.422512 -109.915075) (xy 198.369544 -109.923099) (xy 198.342758 -109.92358) (xy 198.316109 -109.923135)
			(xy 198.263406 -109.915186) (xy 198.212477 -109.899471) (xy 198.164458 -109.876341) (xy 198.120423 -109.846314)
			(xy 198.081354 -109.810059) (xy 198.048125 -109.768387) (xy 198.021477 -109.722228) (xy 198.002006 -109.672613)
			(xy 197.990147 -109.62065) (xy 197.986164 -109.5675) (xy 195.772559 -109.5675) (xy 195.769399 -109.572135)
			(xy 195.733147 -109.611206) (xy 195.691476 -109.644437) (xy 195.645318 -109.671086) (xy 195.595704 -109.690558)
			(xy 195.543742 -109.702418) (xy 195.490592 -109.706402) (xy 195.437442 -109.702418) (xy 195.38548 -109.690558)
			(xy 195.335866 -109.671086) (xy 195.289708 -109.644437) (xy 195.248037 -109.611206) (xy 195.211785 -109.572135)
			(xy 195.181761 -109.528098) (xy 195.158635 -109.480077) (xy 195.142925 -109.429147) (xy 195.134982 -109.376443)
			(xy 194.631617 -109.376443) (xy 194.631711 -109.376708) (xy 194.636898 -109.40161) (xy 194.63766 -109.405166)
			(xy 194.639695 -109.412076) (xy 194.647045 -109.424456) (xy 194.652138 -109.42955) (xy 194.652392 -109.429804)
			(xy 194.656202 -109.432852) (xy 194.659253 -109.435062) (xy 194.665884 -109.438636) (xy 194.66941 -109.439964)
			(xy 194.677792 -109.443012) (xy 194.70624 -109.443012) (xy 194.716307 -109.443443) (xy 194.734899 -109.451169)
			(xy 194.742308 -109.457998) (xy 195.716398 -110.432088) (xy 195.718684 -110.43412) (xy 195.719446 -110.434882)
			(xy 195.729627 -110.442547) (xy 195.754545 -110.447735) (xy 195.766944 -110.444788) (xy 195.768976 -110.444026)
			(xy 195.855336 -110.4138) (xy 195.862076 -110.411213) (xy 195.873819 -110.402828) (xy 195.87845 -110.39729)
			(xy 195.88212 -110.392428) (xy 195.887257 -110.381386) (xy 195.88861 -110.375446) (xy 195.889118 -110.371382)
			(xy 195.892498 -110.34562) (xy 195.905763 -110.295384) (xy 195.926186 -110.247609) (xy 195.953336 -110.203309)
			(xy 195.986634 -110.163425) (xy 196.025375 -110.128802) (xy 196.068736 -110.100177) (xy 196.115796 -110.078156)
			(xy 196.165557 -110.063208) (xy 196.216961 -110.055649) (xy 196.24294 -110.055152) (xy 196.270922 -110.055704)
			(xy 196.326197 -110.064464) (xy 196.379421 -110.081761) (xy 196.429285 -110.107171) (xy 196.47456 -110.140067)
			(xy 196.514133 -110.17964) (xy 196.547029 -110.224915) (xy 196.572439 -110.274779) (xy 196.589736 -110.328003)
			(xy 196.598496 -110.383278) (xy 196.599048 -110.41126) (xy 196.59858 -110.43723) (xy 196.591039 -110.488619)
			(xy 196.576112 -110.538367) (xy 196.554114 -110.585419) (xy 196.525514 -110.628775) (xy 196.497714 -110.659905)
			(xy 197.910948 -110.659905) (xy 197.910948 -110.606607) (xy 197.918891 -110.553903) (xy 197.934601 -110.502973)
			(xy 197.957727 -110.454952) (xy 197.987751 -110.410915) (xy 198.024003 -110.371844) (xy 198.065674 -110.338613)
			(xy 198.111832 -110.311964) (xy 198.161446 -110.292492) (xy 198.213408 -110.280632) (xy 198.266558 -110.276649)
			(xy 198.319708 -110.280632) (xy 198.37167 -110.292492) (xy 198.421284 -110.311964) (xy 198.467442 -110.338613)
			(xy 198.509113 -110.371844) (xy 198.545365 -110.410915) (xy 198.575389 -110.454952) (xy 198.598515 -110.502973)
			(xy 198.614225 -110.553903) (xy 198.621594 -110.6028) (xy 198.748168 -110.6028) (xy 198.752151 -110.549651)
			(xy 198.76401 -110.497689) (xy 198.783481 -110.448074) (xy 198.810128 -110.401916) (xy 198.843357 -110.360244)
			(xy 198.882425 -110.323989) (xy 198.92646 -110.293962) (xy 198.974478 -110.270833) (xy 199.025407 -110.255118)
			(xy 199.078109 -110.247169) (xy 199.104758 -110.246668) (xy 199.129965 -110.24708) (xy 199.179872 -110.254218)
			(xy 199.228272 -110.268327) (xy 199.274196 -110.289125) (xy 199.316725 -110.316197) (xy 199.336152 -110.332266)
			(xy 199.344526 -110.338704) (xy 199.364737 -110.344746) (xy 199.375268 -110.34395) (xy 199.460358 -110.333536)
			(xy 199.478392 -110.322868) (xy 199.484742 -110.314232) (xy 199.502724 -110.290048) (xy 199.543419 -110.245598)
			(xy 199.589083 -110.20627) (xy 199.639076 -110.172615) (xy 199.692696 -110.145106) (xy 199.749192 -110.124128)
			(xy 199.807772 -110.109974) (xy 199.867613 -110.102844) (xy 199.897746 -110.102396) (xy 199.929705 -110.102893)
			(xy 199.99312 -110.110909) (xy 200.055029 -110.12681) (xy 200.114458 -110.150344) (xy 200.170468 -110.181141)
			(xy 200.222178 -110.218714) (xy 200.268771 -110.262472) (xy 200.309512 -110.311724) (xy 200.34376 -110.365693)
			(xy 200.370974 -110.42353) (xy 200.390725 -110.48432) (xy 200.402701 -110.547107) (xy 200.406715 -110.6109)
			(xy 200.402701 -110.674693) (xy 200.390725 -110.73748) (xy 200.370974 -110.79827) (xy 200.34376 -110.856107)
			(xy 200.309512 -110.910076) (xy 200.268771 -110.959328) (xy 200.222178 -111.003086) (xy 200.170468 -111.040659)
			(xy 200.114458 -111.071456) (xy 200.055029 -111.09499) (xy 199.99312 -111.110891) (xy 199.929705 -111.118907)
			(xy 199.897746 -111.119412) (xy 199.866947 -111.118997) (xy 199.805801 -111.111561) (xy 199.746 -111.096792)
			(xy 199.688422 -111.074907) (xy 199.63391 -111.046226) (xy 199.583262 -111.011169) (xy 199.53722 -110.970251)
			(xy 199.496458 -110.924069) (xy 199.478646 -110.89894) (xy 199.472804 -110.890304) (xy 199.454516 -110.879128)
			(xy 199.369934 -110.866936) (xy 199.35938 -110.865887) (xy 199.338996 -110.871678) (xy 199.330564 -110.878112)
			(xy 199.311387 -110.893318) (xy 199.269656 -110.918888) (xy 199.224815 -110.938499) (xy 199.17771 -110.951779)
			(xy 199.129229 -110.95848) (xy 199.104758 -110.958884) (xy 199.078109 -110.958431) (xy 199.025407 -110.950482)
			(xy 198.974478 -110.934767) (xy 198.92646 -110.911638) (xy 198.882425 -110.881611) (xy 198.843357 -110.845356)
			(xy 198.810128 -110.803684) (xy 198.783481 -110.757526) (xy 198.76401 -110.707911) (xy 198.752151 -110.655949)
			(xy 198.748168 -110.6028) (xy 198.621594 -110.6028) (xy 198.622168 -110.606607) (xy 198.622666 -110.633256)
			(xy 198.622168 -110.659905) (xy 198.614225 -110.712609) (xy 198.598515 -110.763539) (xy 198.575389 -110.81156)
			(xy 198.545365 -110.855597) (xy 198.509113 -110.894668) (xy 198.467442 -110.927899) (xy 198.421284 -110.954548)
			(xy 198.37167 -110.97402) (xy 198.319708 -110.98588) (xy 198.266558 -110.989864) (xy 198.213408 -110.98588)
			(xy 198.161446 -110.97402) (xy 198.111832 -110.954548) (xy 198.065674 -110.927899) (xy 198.024003 -110.894668)
			(xy 197.987751 -110.855597) (xy 197.957727 -110.81156) (xy 197.934601 -110.763539) (xy 197.918891 -110.712609)
			(xy 197.910948 -110.659905) (xy 196.497714 -110.659905) (xy 196.490918 -110.667515) (xy 196.45106 -110.700818)
			(xy 196.406786 -110.727976) (xy 196.359037 -110.748413) (xy 196.308824 -110.761695) (xy 196.283072 -110.765082)
			(xy 196.282818 -110.765082) (xy 196.278754 -110.76559) (xy 196.272816 -110.766951) (xy 196.261772 -110.772081)
			(xy 196.25691 -110.77575) (xy 196.25141 -110.780416) (xy 196.243032 -110.792149) (xy 196.2404 -110.798864)
			(xy 196.229224 -110.830868) (xy 196.209412 -110.888018) (xy 196.206582 -110.900413) (xy 196.212043 -110.92521)
			(xy 196.219826 -110.935262) (xy 196.220842 -110.936532) (xy 196.222112 -110.937802) (xy 196.513958 -111.229648)
			(xy 196.520801 -111.237047) (xy 196.528525 -111.255646) (xy 196.528944 -111.265716) (xy 196.528944 -111.593376)
			(xy 201.886564 -111.593376) (xy 201.890635 -111.537754) (xy 201.902761 -111.483317) (xy 201.922684 -111.431226)
			(xy 201.94998 -111.382591) (xy 201.984066 -111.338448) (xy 202.024215 -111.299739) (xy 202.069573 -111.267288)
			(xy 202.119173 -111.241787) (xy 202.171957 -111.22378) (xy 202.2268 -111.21365) (xy 202.282534 -111.211613)
			(xy 202.337971 -111.217713) (xy 202.391928 -111.231819) (xy 202.443257 -111.253631) (xy 202.490863 -111.282685)
			(xy 202.533731 -111.31836) (xy 202.570948 -111.359897) (xy 202.601721 -111.40641) (xy 202.625393 -111.456907)
			(xy 202.641461 -111.510314) (xy 202.649581 -111.56549) (xy 202.65009 -111.593376) (xy 202.649581 -111.621262)
			(xy 202.641461 -111.676438) (xy 202.625393 -111.729845) (xy 202.601721 -111.780342) (xy 202.570948 -111.826855)
			(xy 202.533731 -111.868392) (xy 202.490863 -111.904067) (xy 202.443257 -111.933121) (xy 202.391928 -111.954933)
			(xy 202.337971 -111.969039) (xy 202.282534 -111.975139) (xy 202.2268 -111.973102) (xy 202.171957 -111.962972)
			(xy 202.119173 -111.944965) (xy 202.069573 -111.919464) (xy 202.024215 -111.887013) (xy 201.984066 -111.848304)
			(xy 201.94998 -111.804161) (xy 201.922684 -111.755526) (xy 201.902761 -111.703435) (xy 201.890635 -111.648998)
			(xy 201.886564 -111.593376) (xy 196.528944 -111.593376) (xy 196.528944 -112.636025) (xy 197.987148 -112.636025)
			(xy 197.987148 -112.582727) (xy 197.995091 -112.530023) (xy 198.010801 -112.479093) (xy 198.033927 -112.431072)
			(xy 198.063951 -112.387035) (xy 198.100203 -112.347964) (xy 198.141874 -112.314733) (xy 198.188032 -112.288084)
			(xy 198.237646 -112.268612) (xy 198.289608 -112.256752) (xy 198.342758 -112.252769) (xy 198.395908 -112.256752)
			(xy 198.44787 -112.268612) (xy 198.497484 -112.288084) (xy 198.543642 -112.314733) (xy 198.585313 -112.347964)
			(xy 198.621565 -112.387035) (xy 198.651589 -112.431072) (xy 198.674715 -112.479093) (xy 198.690425 -112.530023)
			(xy 198.698368 -112.582727) (xy 198.698866 -112.609376) (xy 198.698368 -112.636025) (xy 198.697567 -112.641337)
			(xy 199.358752 -112.641337) (xy 199.358752 -112.577415) (xy 199.366763 -112.513997) (xy 199.38266 -112.452083)
			(xy 199.406192 -112.39265) (xy 199.436986 -112.336635) (xy 199.474559 -112.28492) (xy 199.518316 -112.238323)
			(xy 199.567569 -112.197578) (xy 199.62154 -112.163327) (xy 199.679379 -112.13611) (xy 199.740172 -112.116357)
			(xy 199.802962 -112.104379) (xy 199.866758 -112.100366) (xy 199.930554 -112.104379) (xy 199.993344 -112.116357)
			(xy 200.054137 -112.13611) (xy 200.111976 -112.163327) (xy 200.165947 -112.197578) (xy 200.2152 -112.238323)
			(xy 200.258957 -112.28492) (xy 200.29653 -112.336635) (xy 200.327324 -112.39265) (xy 200.350856 -112.452083)
			(xy 200.366753 -112.513997) (xy 200.374764 -112.577415) (xy 200.375266 -112.609376) (xy 200.374764 -112.641337)
			(xy 200.366753 -112.704755) (xy 200.350856 -112.766669) (xy 200.327324 -112.826102) (xy 200.29653 -112.882117)
			(xy 200.258957 -112.933832) (xy 200.2152 -112.980429) (xy 200.165947 -113.021174) (xy 200.111976 -113.055425)
			(xy 200.054137 -113.082642) (xy 199.993344 -113.102395) (xy 199.930554 -113.114373) (xy 199.866758 -113.118387)
			(xy 199.802962 -113.114373) (xy 199.740172 -113.102395) (xy 199.679379 -113.082642) (xy 199.62154 -113.055425)
			(xy 199.567569 -113.021174) (xy 199.518316 -112.980429) (xy 199.474559 -112.933832) (xy 199.436986 -112.882117)
			(xy 199.406192 -112.826102) (xy 199.38266 -112.766669) (xy 199.366763 -112.704755) (xy 199.358752 -112.641337)
			(xy 198.697567 -112.641337) (xy 198.690425 -112.688729) (xy 198.674715 -112.739659) (xy 198.651589 -112.78768)
			(xy 198.621565 -112.831717) (xy 198.585313 -112.870788) (xy 198.543642 -112.904019) (xy 198.497484 -112.930668)
			(xy 198.44787 -112.95014) (xy 198.395908 -112.962) (xy 198.342758 -112.965984) (xy 198.289608 -112.962)
			(xy 198.237646 -112.95014) (xy 198.188032 -112.930668) (xy 198.141874 -112.904019) (xy 198.100203 -112.870788)
			(xy 198.063951 -112.831717) (xy 198.033927 -112.78768) (xy 198.010801 -112.739659) (xy 197.995091 -112.688729)
			(xy 197.987148 -112.636025) (xy 196.528944 -112.636025) (xy 196.528944 -113.652025) (xy 197.987148 -113.652025)
			(xy 197.987148 -113.598727) (xy 197.995091 -113.546023) (xy 198.010801 -113.495093) (xy 198.033927 -113.447072)
			(xy 198.063951 -113.403035) (xy 198.100203 -113.363964) (xy 198.141874 -113.330733) (xy 198.188032 -113.304084)
			(xy 198.237646 -113.284612) (xy 198.289608 -113.272752) (xy 198.342758 -113.268769) (xy 198.395908 -113.272752)
			(xy 198.44787 -113.284612) (xy 198.497484 -113.304084) (xy 198.543642 -113.330733) (xy 198.585313 -113.363964)
			(xy 198.621565 -113.403035) (xy 198.651589 -113.447072) (xy 198.674715 -113.495093) (xy 198.690425 -113.546023)
			(xy 198.698368 -113.598727) (xy 198.698866 -113.625376) (xy 198.698368 -113.652025) (xy 198.697601 -113.657112)
			(xy 201.979993 -113.657112) (xy 201.979994 -113.593662) (xy 201.987893 -113.530706) (xy 202.003566 -113.469222)
			(xy 202.026769 -113.410168) (xy 202.057143 -113.35446) (xy 202.094213 -113.302966) (xy 202.137405 -113.256486)
			(xy 202.186045 -113.215744) (xy 202.212448 -113.198148) (xy 202.223116 -113.19129) (xy 202.235562 -113.168938)
			(xy 202.236832 -113.058702) (xy 202.225148 -113.036096) (xy 202.214734 -113.028984) (xy 202.189509 -113.011211)
			(xy 202.143188 -112.970437) (xy 202.102141 -112.924358) (xy 202.066972 -112.873651) (xy 202.038195 -112.819062)
			(xy 202.016236 -112.761391) (xy 202.001415 -112.701488) (xy 201.993951 -112.640231) (xy 201.9935 -112.609376)
			(xy 201.994002 -112.577415) (xy 202.002013 -112.513997) (xy 202.01791 -112.452083) (xy 202.041442 -112.39265)
			(xy 202.072236 -112.336635) (xy 202.109809 -112.28492) (xy 202.153566 -112.238323) (xy 202.202819 -112.197578)
			(xy 202.25679 -112.163327) (xy 202.314629 -112.13611) (xy 202.375422 -112.116357) (xy 202.438212 -112.104379)
			(xy 202.502008 -112.100366) (xy 202.565804 -112.104379) (xy 202.628594 -112.116357) (xy 202.689387 -112.13611)
			(xy 202.747226 -112.163327) (xy 202.801197 -112.197578) (xy 202.85045 -112.238323) (xy 202.894207 -112.28492)
			(xy 202.93178 -112.336635) (xy 202.962574 -112.39265) (xy 202.986106 -112.452083) (xy 203.002003 -112.513997)
			(xy 203.010014 -112.577415) (xy 203.010515 -112.609333) (xy 203.31658 -112.609333) (xy 203.31658 -112.545411)
			(xy 203.324591 -112.481993) (xy 203.340488 -112.420079) (xy 203.36402 -112.360646) (xy 203.394814 -112.304631)
			(xy 203.432387 -112.252916) (xy 203.476144 -112.206319) (xy 203.525397 -112.165574) (xy 203.579368 -112.131323)
			(xy 203.637207 -112.104106) (xy 203.698 -112.084353) (xy 203.76079 -112.072375) (xy 203.824586 -112.068362)
			(xy 203.888382 -112.072375) (xy 203.951172 -112.084353) (xy 204.011965 -112.104106) (xy 204.069804 -112.131323)
			(xy 204.123775 -112.165574) (xy 204.173028 -112.206319) (xy 204.216785 -112.252916) (xy 204.254358 -112.304631)
			(xy 204.260255 -112.315357) (xy 205.450321 -112.315357) (xy 205.450321 -112.260843) (xy 205.45808 -112.206884)
			(xy 205.473439 -112.154578) (xy 205.496087 -112.104991) (xy 205.525561 -112.059131) (xy 205.561262 -112.017934)
			(xy 205.602463 -111.982237) (xy 205.648326 -111.952767) (xy 205.697915 -111.930125) (xy 205.750223 -111.914771)
			(xy 205.804183 -111.907018) (xy 205.83144 -111.906558) (xy 205.85736 -111.906945) (xy 205.908722 -111.913963)
			(xy 205.95866 -111.927876) (xy 206.006251 -111.948429) (xy 206.050618 -111.975242) (xy 206.090942 -112.00782)
			(xy 206.126479 -112.045563) (xy 206.156572 -112.087773) (xy 206.169006 -112.11052) (xy 206.173578 -112.11941)
			(xy 206.188818 -112.13211) (xy 206.275686 -112.16005) (xy 206.295498 -112.158526) (xy 206.304388 -112.154208)
			(xy 206.33086 -112.141497) (xy 206.386097 -112.121554) (xy 206.443261 -112.108096) (xy 206.501593 -112.101303)
			(xy 206.530956 -112.100868) (xy 206.564235 -112.101417) (xy 206.630225 -112.110089) (xy 206.694519 -112.127303)
			(xy 206.756014 -112.152764) (xy 206.813658 -112.186036) (xy 206.866465 -112.22655) (xy 206.890366 -112.249712)
			(xy 206.897112 -112.255903) (xy 206.913775 -112.263458) (xy 206.922878 -112.264444) (xy 206.953104 -112.26673)
			(xy 206.962274 -112.266979) (xy 206.97985 -112.261787) (xy 206.987394 -112.25657) (xy 207.007904 -112.241415)
			(xy 207.05142 -112.214822) (xy 207.074262 -112.203484) (xy 207.074516 -112.203484) (xy 207.08273 -112.199089)
			(xy 207.095499 -112.185544) (xy 207.102578 -112.168328) (xy 207.103218 -112.159034) (xy 207.105758 -112.06861)
			(xy 207.105629 -112.059271) (xy 207.099443 -112.041665) (xy 207.087341 -112.027459) (xy 207.079342 -112.022636)
			(xy 207.053068 -112.007725) (xy 207.003913 -111.972601) (xy 206.959268 -111.931897) (xy 206.919762 -111.88619)
			(xy 206.885952 -111.836122) (xy 206.858315 -111.7824) (xy 206.83724 -111.72578) (xy 206.823023 -111.667062)
			(xy 206.815867 -111.607073) (xy 206.815436 -111.576866) (xy 206.815847 -111.546319) (xy 206.823161 -111.485664)
			(xy 206.837691 -111.426323) (xy 206.859228 -111.36915) (xy 206.887462 -111.314971) (xy 206.921985 -111.264566)
			(xy 206.9623 -111.218662) (xy 207.007825 -111.17792) (xy 207.032606 -111.160052) (xy 207.042766 -111.15294)
			(xy 207.054196 -111.131096) (xy 207.05445 -111.035592) (xy 207.0537 -111.023248) (xy 207.042308 -111.001347)
			(xy 207.032606 -110.993682) (xy 207.021206 -110.985519) (xy 206.999222 -110.96811) (xy 206.988664 -110.958884)
			(xy 206.981464 -110.953054) (xy 206.964139 -110.946538) (xy 206.954882 -110.946184) (xy 206.924656 -110.946184)
			(xy 206.915404 -110.946564) (xy 206.898086 -110.953077) (xy 206.890874 -110.958884) (xy 206.867616 -110.978786)
			(xy 206.817168 -111.01346) (xy 206.76292 -111.041822) (xy 206.705658 -111.063463) (xy 206.646211 -111.078067)
			(xy 206.585439 -111.085425) (xy 206.554832 -111.085884) (xy 206.522867 -111.085453) (xy 206.45944 -111.077444)
			(xy 206.397518 -111.061548) (xy 206.338076 -111.038017) (xy 206.282052 -111.007221) (xy 206.23033 -110.969645)
			(xy 206.183725 -110.925884) (xy 206.142973 -110.876626) (xy 206.108716 -110.822648) (xy 206.081495 -110.764803)
			(xy 206.061739 -110.704002) (xy 206.049759 -110.641204) (xy 206.045744 -110.5774) (xy 206.049759 -110.513596)
			(xy 206.061739 -110.450798) (xy 206.081495 -110.389997) (xy 206.108716 -110.332152) (xy 206.142973 -110.278174)
			(xy 206.183725 -110.228916) (xy 206.23033 -110.185155) (xy 206.282052 -110.147579) (xy 206.338076 -110.116783)
			(xy 206.397518 -110.093252) (xy 206.45944 -110.077356) (xy 206.522867 -110.069347) (xy 206.554832 -110.068868)
			(xy 206.585441 -110.069304) (xy 206.646215 -110.076655) (xy 206.705666 -110.091259) (xy 206.762929 -110.112904)
			(xy 206.817175 -110.141275) (xy 206.867617 -110.175962) (xy 206.890874 -110.195868) (xy 206.898057 -110.201721)
			(xy 206.915395 -110.208221) (xy 206.924656 -110.208568) (xy 206.954882 -110.208568) (xy 206.964134 -110.208195)
			(xy 206.981452 -110.201676) (xy 206.988664 -110.195868) (xy 207.011915 -110.175957) (xy 207.062363 -110.141282)
			(xy 207.116613 -110.11292) (xy 207.173876 -110.091281) (xy 207.233325 -110.076679) (xy 207.294098 -110.069325)
			(xy 207.324706 -110.068868) (xy 207.355436 -110.06935) (xy 207.416448 -110.076759) (xy 207.476123 -110.091468)
			(xy 207.533589 -110.113262) (xy 207.58801 -110.141823) (xy 207.638591 -110.176736) (xy 207.684596 -110.217491)
			(xy 207.725352 -110.263494) (xy 207.760267 -110.314075) (xy 207.788831 -110.368494) (xy 207.810627 -110.42596)
			(xy 207.825338 -110.485634) (xy 207.832749 -110.546646) (xy 207.833214 -110.577376) (xy 209.415888 -110.577376)
			(xy 209.416387 -110.546089) (xy 209.42406 -110.483988) (xy 209.4393 -110.423299) (xy 209.461877 -110.36494)
			(xy 209.491448 -110.309794) (xy 209.527566 -110.258697) (xy 209.569685 -110.212421) (xy 209.617166 -110.171666)
			(xy 209.642964 -110.153958) (xy 209.653116 -110.146436) (xy 209.664976 -110.124162) (xy 209.66557 -110.11154)
			(xy 209.66557 -110.027212) (xy 209.664925 -110.014607) (xy 209.653067 -109.992359) (xy 209.642964 -109.984794)
			(xy 209.617154 -109.967103) (xy 209.569674 -109.926343) (xy 209.527557 -109.880064) (xy 209.491439 -109.828964)
			(xy 209.461867 -109.773817) (xy 209.439289 -109.715457) (xy 209.424045 -109.654766) (xy 209.416366 -109.592664)
			(xy 209.415888 -109.561376) (xy 209.41639 -109.529415) (xy 209.424401 -109.465997) (xy 209.440298 -109.404083)
			(xy 209.46383 -109.34465) (xy 209.494624 -109.288635) (xy 209.532197 -109.23692) (xy 209.575954 -109.190323)
			(xy 209.625207 -109.149578) (xy 209.679178 -109.115327) (xy 209.737017 -109.08811) (xy 209.79781 -109.068357)
			(xy 209.8606 -109.056379) (xy 209.924396 -109.052366) (xy 209.988192 -109.056379) (xy 210.050982 -109.068357)
			(xy 210.111775 -109.08811) (xy 210.143127 -109.102863) (xy 214.372438 -109.102863) (xy 214.372438 -109.038941)
			(xy 214.380449 -108.975523) (xy 214.396346 -108.913609) (xy 214.419878 -108.854176) (xy 214.450672 -108.798161)
			(xy 214.488245 -108.746446) (xy 214.532002 -108.699849) (xy 214.581255 -108.659104) (xy 214.635226 -108.624853)
			(xy 214.693065 -108.597636) (xy 214.753858 -108.577883) (xy 214.816648 -108.565905) (xy 214.880444 -108.561892)
			(xy 214.94424 -108.565905) (xy 215.00703 -108.577883) (xy 215.067823 -108.597636) (xy 215.125662 -108.624853)
			(xy 215.179633 -108.659104) (xy 215.228886 -108.699849) (xy 215.272643 -108.746446) (xy 215.310216 -108.798161)
			(xy 215.34101 -108.854176) (xy 215.364542 -108.913609) (xy 215.380439 -108.975523) (xy 215.38845 -109.038941)
			(xy 215.388952 -109.070902) (xy 215.38845 -109.102863) (xy 215.380439 -109.166281) (xy 215.364542 -109.228195)
			(xy 215.34101 -109.287628) (xy 215.310216 -109.343643) (xy 215.272643 -109.395358) (xy 215.228886 -109.441955)
			(xy 215.179633 -109.4827) (xy 215.125662 -109.516951) (xy 215.067823 -109.544168) (xy 215.00703 -109.563921)
			(xy 214.94424 -109.575899) (xy 214.880444 -109.579913) (xy 214.816648 -109.575899) (xy 214.753858 -109.563921)
			(xy 214.693065 -109.544168) (xy 214.635226 -109.516951) (xy 214.581255 -109.4827) (xy 214.532002 -109.441955)
			(xy 214.488245 -109.395358) (xy 214.450672 -109.343643) (xy 214.419878 -109.287628) (xy 214.396346 -109.228195)
			(xy 214.380449 -109.166281) (xy 214.372438 -109.102863) (xy 210.143127 -109.102863) (xy 210.169614 -109.115327)
			(xy 210.223585 -109.149578) (xy 210.272838 -109.190323) (xy 210.316595 -109.23692) (xy 210.354168 -109.288635)
			(xy 210.384962 -109.34465) (xy 210.408494 -109.404083) (xy 210.424391 -109.465997) (xy 210.432402 -109.529415)
			(xy 210.432904 -109.561376) (xy 210.432449 -109.592664) (xy 210.424769 -109.654767) (xy 210.409522 -109.715458)
			(xy 210.38694 -109.773817) (xy 210.357363 -109.828962) (xy 210.321239 -109.880059) (xy 210.279115 -109.926334)
			(xy 210.231628 -109.967087) (xy 210.205828 -109.984794) (xy 210.195696 -109.992338) (xy 210.183826 -110.014595)
			(xy 210.183222 -110.027212) (xy 210.183222 -110.11154) (xy 210.183899 -110.124141) (xy 210.195734 -110.146388)
			(xy 210.205828 -110.153958) (xy 210.231614 -110.171683) (xy 210.279095 -110.212437) (xy 210.321213 -110.258712)
			(xy 210.357333 -110.309807) (xy 210.386908 -110.364949) (xy 210.399325 -110.397036) (xy 211.563202 -110.397036)
			(xy 211.567273 -110.341414) (xy 211.579399 -110.286977) (xy 211.599322 -110.234886) (xy 211.626618 -110.186251)
			(xy 211.660704 -110.142108) (xy 211.700853 -110.103399) (xy 211.746211 -110.070948) (xy 211.795811 -110.045447)
			(xy 211.848595 -110.02744) (xy 211.903438 -110.01731) (xy 211.959172 -110.015273) (xy 212.014609 -110.021373)
			(xy 212.068566 -110.035479) (xy 212.119895 -110.057291) (xy 212.167501 -110.086345) (xy 212.172138 -110.090204)
			(xy 257.012692 -110.090204) (xy 257.016763 -110.034582) (xy 257.028889 -109.980145) (xy 257.048812 -109.928054)
			(xy 257.076108 -109.879419) (xy 257.110194 -109.835276) (xy 257.150343 -109.796567) (xy 257.195701 -109.764116)
			(xy 257.245301 -109.738615) (xy 257.298085 -109.720608) (xy 257.352928 -109.710478) (xy 257.408662 -109.708441)
			(xy 257.464099 -109.714541) (xy 257.518056 -109.728647) (xy 257.569385 -109.750459) (xy 257.616655 -109.779308)
			(xy 300.84979 -109.779308) (xy 300.853861 -109.723686) (xy 300.865987 -109.669249) (xy 300.88591 -109.617158)
			(xy 300.913206 -109.568523) (xy 300.947292 -109.52438) (xy 300.987441 -109.485671) (xy 301.032799 -109.45322)
			(xy 301.082399 -109.427719) (xy 301.135183 -109.409712) (xy 301.190026 -109.399582) (xy 301.24576 -109.397545)
			(xy 301.301197 -109.403645) (xy 301.355154 -109.417751) (xy 301.406483 -109.439563) (xy 301.454089 -109.468617)
			(xy 301.496957 -109.504292) (xy 301.534174 -109.545829) (xy 301.564947 -109.592342) (xy 301.588619 -109.642839)
			(xy 301.604687 -109.696246) (xy 301.604688 -109.69625) (xy 304.71186 -109.69625) (xy 304.715931 -109.640628)
			(xy 304.728057 -109.586191) (xy 304.74798 -109.5341) (xy 304.775276 -109.485465) (xy 304.809362 -109.441322)
			(xy 304.849511 -109.402613) (xy 304.894869 -109.370162) (xy 304.944469 -109.344661) (xy 304.997253 -109.326654)
			(xy 305.052096 -109.316524) (xy 305.10783 -109.314487) (xy 305.163267 -109.320587) (xy 305.217224 -109.334693)
			(xy 305.268553 -109.356505) (xy 305.316159 -109.385559) (xy 305.359027 -109.421234) (xy 305.396244 -109.462771)
			(xy 305.427017 -109.509284) (xy 305.450689 -109.559781) (xy 305.466757 -109.613188) (xy 305.474877 -109.668364)
			(xy 305.475386 -109.69625) (xy 305.474877 -109.724136) (xy 305.466757 -109.779312) (xy 305.450689 -109.832719)
			(xy 305.427017 -109.883216) (xy 305.396244 -109.929729) (xy 305.359027 -109.971266) (xy 305.316159 -110.006941)
			(xy 305.268553 -110.035995) (xy 305.217224 -110.057807) (xy 305.163267 -110.071913) (xy 305.10783 -110.078013)
			(xy 305.052096 -110.075976) (xy 304.997253 -110.065846) (xy 304.944469 -110.047839) (xy 304.894869 -110.022338)
			(xy 304.849511 -109.989887) (xy 304.809362 -109.951178) (xy 304.775276 -109.907035) (xy 304.74798 -109.8584)
			(xy 304.728057 -109.806309) (xy 304.715931 -109.751872) (xy 304.71186 -109.69625) (xy 301.604688 -109.69625)
			(xy 301.612807 -109.751422) (xy 301.613316 -109.779308) (xy 301.612807 -109.807194) (xy 301.604687 -109.86237)
			(xy 301.588619 -109.915777) (xy 301.564947 -109.966274) (xy 301.534174 -110.012787) (xy 301.496957 -110.054324)
			(xy 301.454089 -110.089999) (xy 301.406483 -110.119053) (xy 301.355154 -110.140865) (xy 301.301197 -110.154971)
			(xy 301.24576 -110.161071) (xy 301.190026 -110.159034) (xy 301.135183 -110.148904) (xy 301.082399 -110.130897)
			(xy 301.032799 -110.105396) (xy 300.987441 -110.072945) (xy 300.947292 -110.034236) (xy 300.913206 -109.990093)
			(xy 300.88591 -109.941458) (xy 300.865987 -109.889367) (xy 300.853861 -109.83493) (xy 300.84979 -109.779308)
			(xy 257.616655 -109.779308) (xy 257.616991 -109.779513) (xy 257.659859 -109.815188) (xy 257.697076 -109.856725)
			(xy 257.727849 -109.903238) (xy 257.751521 -109.953735) (xy 257.767589 -110.007142) (xy 257.775709 -110.062318)
			(xy 257.776218 -110.090204) (xy 257.775709 -110.11809) (xy 257.767589 -110.173266) (xy 257.751521 -110.226673)
			(xy 257.727849 -110.27717) (xy 257.697076 -110.323683) (xy 257.659859 -110.36522) (xy 257.616991 -110.400895)
			(xy 257.569385 -110.429949) (xy 257.518056 -110.451761) (xy 257.464099 -110.465867) (xy 257.408662 -110.471967)
			(xy 257.352928 -110.46993) (xy 257.298085 -110.4598) (xy 257.245301 -110.441793) (xy 257.195701 -110.416292)
			(xy 257.150343 -110.383841) (xy 257.110194 -110.345132) (xy 257.076108 -110.300989) (xy 257.048812 -110.252354)
			(xy 257.028889 -110.200263) (xy 257.016763 -110.145826) (xy 257.012692 -110.090204) (xy 212.172138 -110.090204)
			(xy 212.210369 -110.12202) (xy 212.247586 -110.163557) (xy 212.278359 -110.21007) (xy 212.302031 -110.260567)
			(xy 212.318099 -110.313974) (xy 212.326219 -110.36915) (xy 212.326728 -110.397036) (xy 212.326219 -110.424922)
			(xy 212.318099 -110.480098) (xy 212.302031 -110.533505) (xy 212.278359 -110.584002) (xy 212.247586 -110.630515)
			(xy 212.210369 -110.672052) (xy 212.167501 -110.707727) (xy 212.119895 -110.736781) (xy 212.068566 -110.758593)
			(xy 212.014609 -110.772699) (xy 211.959172 -110.778799) (xy 211.903438 -110.776762) (xy 211.848595 -110.766632)
			(xy 211.795811 -110.748625) (xy 211.746211 -110.723124) (xy 211.700853 -110.690673) (xy 211.660704 -110.651964)
			(xy 211.626618 -110.607821) (xy 211.599322 -110.559186) (xy 211.579399 -110.507095) (xy 211.567273 -110.452658)
			(xy 211.563202 -110.397036) (xy 210.399325 -110.397036) (xy 210.40949 -110.423304) (xy 210.424739 -110.483991)
			(xy 210.432423 -110.54609) (xy 210.432904 -110.577376) (xy 210.432402 -110.609337) (xy 210.424391 -110.672755)
			(xy 210.408494 -110.734669) (xy 210.384962 -110.794102) (xy 210.354168 -110.850117) (xy 210.316595 -110.901832)
			(xy 210.272838 -110.948429) (xy 210.223585 -110.989174) (xy 210.169614 -111.023425) (xy 210.111775 -111.050642)
			(xy 210.065201 -111.065775) (xy 253.20218 -111.065775) (xy 253.20218 -111.001853) (xy 253.210191 -110.938435)
			(xy 253.226088 -110.876521) (xy 253.24962 -110.817088) (xy 253.280414 -110.761073) (xy 253.317987 -110.709358)
			(xy 253.361744 -110.662761) (xy 253.410997 -110.622016) (xy 253.464968 -110.587765) (xy 253.522807 -110.560548)
			(xy 253.5836 -110.540795) (xy 253.64639 -110.528817) (xy 253.710186 -110.524804) (xy 253.773982 -110.528817)
			(xy 253.836772 -110.540795) (xy 253.897565 -110.560548) (xy 253.955404 -110.587765) (xy 254.009375 -110.622016)
			(xy 254.058628 -110.662761) (xy 254.102385 -110.709358) (xy 254.139958 -110.761073) (xy 254.170752 -110.817088)
			(xy 254.194284 -110.876521) (xy 254.210181 -110.938435) (xy 254.218192 -111.001853) (xy 254.218694 -111.033814)
			(xy 254.218192 -111.065775) (xy 254.210181 -111.129193) (xy 254.194284 -111.191107) (xy 254.170752 -111.25054)
			(xy 254.139958 -111.306555) (xy 254.113191 -111.343397) (xy 275.041354 -111.343397) (xy 275.041354 -111.279475)
			(xy 275.049365 -111.216057) (xy 275.065262 -111.154143) (xy 275.088794 -111.09471) (xy 275.119588 -111.038695)
			(xy 275.157161 -110.98698) (xy 275.200918 -110.940383) (xy 275.250171 -110.899638) (xy 275.304142 -110.865387)
			(xy 275.361981 -110.83817) (xy 275.422774 -110.818417) (xy 275.485564 -110.806439) (xy 275.54936 -110.802426)
			(xy 275.613156 -110.806439) (xy 275.675946 -110.818417) (xy 275.736739 -110.83817) (xy 275.794578 -110.865387)
			(xy 275.803423 -110.871) (xy 298.19499 -110.871) (xy 298.199003 -110.807204) (xy 298.210981 -110.744414)
			(xy 298.230734 -110.683621) (xy 298.257951 -110.625782) (xy 298.292202 -110.571811) (xy 298.332947 -110.522558)
			(xy 298.379544 -110.478801) (xy 298.431259 -110.441228) (xy 298.487274 -110.410434) (xy 298.546707 -110.386902)
			(xy 298.608621 -110.371005) (xy 298.672039 -110.362994) (xy 298.704 -110.362492) (xy 298.735662 -110.36294)
			(xy 298.798497 -110.370793) (xy 298.85987 -110.38639) (xy 298.918831 -110.409489) (xy 298.974466 -110.439732)
			(xy 299.025914 -110.476651) (xy 299.072378 -110.519674) (xy 299.093128 -110.543594) (xy 299.102824 -110.554362)
			(xy 299.126918 -110.570433) (xy 299.154557 -110.579085) (xy 299.183514 -110.57962) (xy 299.211454 -110.571995)
			(xy 299.236125 -110.556824) (xy 299.255537 -110.535331) (xy 299.262292 -110.522512) (xy 299.276536 -110.49424)
			(xy 299.310964 -110.441114) (xy 299.351721 -110.392673) (xy 299.398177 -110.349667) (xy 299.449613 -110.312761)
			(xy 299.505233 -110.282527) (xy 299.564176 -110.259432) (xy 299.625531 -110.243835) (xy 299.688347 -110.235975)
			(xy 299.72 -110.235492) (xy 299.751961 -110.235994) (xy 299.815379 -110.244005) (xy 299.877293 -110.259902)
			(xy 299.936726 -110.283434) (xy 299.992741 -110.314228) (xy 300.044456 -110.351801) (xy 300.091053 -110.395558)
			(xy 300.131798 -110.444811) (xy 300.166049 -110.498782) (xy 300.193266 -110.556621) (xy 300.213019 -110.617414)
			(xy 300.220111 -110.654592) (xy 322.194174 -110.654592) (xy 322.194646 -110.623872) (xy 322.202046 -110.562878)
			(xy 322.216737 -110.50322) (xy 322.238505 -110.445764) (xy 322.267034 -110.391349) (xy 322.28409 -110.365794)
			(xy 322.289491 -110.357113) (xy 322.293552 -110.337093) (xy 322.289486 -110.317074) (xy 322.28409 -110.30839)
			(xy 322.267031 -110.282837) (xy 322.238498 -110.228422) (xy 322.216728 -110.170967) (xy 322.202036 -110.111307)
			(xy 322.194636 -110.050313) (xy 322.194174 -110.019592) (xy 322.194676 -109.987631) (xy 322.202687 -109.924213)
			(xy 322.218584 -109.862299) (xy 322.242116 -109.802866) (xy 322.27291 -109.746851) (xy 322.310483 -109.695136)
			(xy 322.35424 -109.648539) (xy 322.403493 -109.607794) (xy 322.457464 -109.573543) (xy 322.515303 -109.546326)
			(xy 322.576096 -109.526573) (xy 322.638886 -109.514595) (xy 322.702682 -109.510582) (xy 322.766478 -109.514595)
			(xy 322.829268 -109.526573) (xy 322.890061 -109.546326) (xy 322.9479 -109.573543) (xy 323.001871 -109.607794)
			(xy 323.051124 -109.648539) (xy 323.094881 -109.695136) (xy 323.132454 -109.746851) (xy 323.163248 -109.802866)
			(xy 323.18678 -109.862299) (xy 323.202677 -109.924213) (xy 323.210688 -109.987631) (xy 323.21119 -110.019592)
			(xy 323.210716 -110.050312) (xy 323.203318 -110.111306) (xy 323.188628 -110.170965) (xy 323.16686 -110.22842)
			(xy 323.138331 -110.282836) (xy 323.121274 -110.30839) (xy 323.11589 -110.317079) (xy 323.111828 -110.337093)
			(xy 323.115884 -110.357109) (xy 323.121274 -110.365794) (xy 323.138322 -110.391355) (xy 323.166857 -110.445767)
			(xy 323.188631 -110.50322) (xy 323.203325 -110.562878) (xy 323.210727 -110.623872) (xy 323.21119 -110.654592)
			(xy 323.210688 -110.686553) (xy 323.202677 -110.749971) (xy 323.18678 -110.811885) (xy 323.163248 -110.871318)
			(xy 323.132454 -110.927333) (xy 323.094881 -110.979048) (xy 323.051124 -111.025645) (xy 323.001871 -111.06639)
			(xy 322.9479 -111.100641) (xy 322.902703 -111.121909) (xy 369.565422 -111.121909) (xy 369.565422 -111.057987)
			(xy 369.573433 -110.994569) (xy 369.58933 -110.932655) (xy 369.612862 -110.873222) (xy 369.643656 -110.817207)
			(xy 369.681229 -110.765492) (xy 369.724986 -110.718895) (xy 369.774239 -110.67815) (xy 369.82821 -110.643899)
			(xy 369.886049 -110.616682) (xy 369.946842 -110.596929) (xy 370.009632 -110.584951) (xy 370.073428 -110.580938)
			(xy 370.137224 -110.584951) (xy 370.200014 -110.596929) (xy 370.260807 -110.616682) (xy 370.318646 -110.643899)
			(xy 370.372617 -110.67815) (xy 370.42187 -110.718895) (xy 370.441141 -110.739417) (xy 415.365214 -110.739417)
			(xy 415.368942 -110.686169) (xy 415.380055 -110.63396) (xy 415.398338 -110.58381) (xy 415.423433 -110.536698)
			(xy 415.454851 -110.493544) (xy 415.491977 -110.455192) (xy 415.512758 -110.438438) (xy 415.521548 -110.430815)
			(xy 415.531739 -110.409926) (xy 415.532316 -110.398306) (xy 415.532316 -110.31855) (xy 415.531786 -110.306917)
			(xy 415.52159 -110.286008) (xy 415.512758 -110.278418) (xy 415.492003 -110.261631) (xy 415.454873 -110.223282)
			(xy 415.423452 -110.180131) (xy 415.398352 -110.133022) (xy 415.380065 -110.082873) (xy 415.368946 -110.030665)
			(xy 415.365214 -109.977417) (xy 415.368942 -109.924169) (xy 415.380055 -109.87196) (xy 415.398338 -109.82181)
			(xy 415.423433 -109.774698) (xy 415.454851 -109.731544) (xy 415.491977 -109.693192) (xy 415.512758 -109.676438)
			(xy 415.521548 -109.668815) (xy 415.531739 -109.647926) (xy 415.532316 -109.636306) (xy 415.532316 -109.55655)
			(xy 415.531786 -109.544917) (xy 415.52159 -109.524008) (xy 415.512758 -109.516418) (xy 415.492003 -109.499631)
			(xy 415.454873 -109.461282) (xy 415.423452 -109.418131) (xy 415.398352 -109.371022) (xy 415.380065 -109.320873)
			(xy 415.368946 -109.268665) (xy 415.365214 -109.215417) (xy 415.368942 -109.162169) (xy 415.380055 -109.10996)
			(xy 415.398338 -109.05981) (xy 415.423433 -109.012698) (xy 415.454851 -108.969544) (xy 415.491977 -108.931192)
			(xy 415.512758 -108.914438) (xy 415.521548 -108.906815) (xy 415.531739 -108.885926) (xy 415.532316 -108.874306)
			(xy 415.532316 -108.79455) (xy 415.531786 -108.782917) (xy 415.52159 -108.762008) (xy 415.512758 -108.754418)
			(xy 415.490274 -108.736227) (xy 415.450541 -108.694206) (xy 415.417603 -108.646671) (xy 415.392215 -108.59471)
			(xy 415.374959 -108.539513) (xy 415.366228 -108.482344) (xy 415.365692 -108.453428) (xy 415.366181 -108.426176)
			(xy 415.373935 -108.372226) (xy 415.389287 -108.319928) (xy 415.411926 -108.270348) (xy 415.441391 -108.224495)
			(xy 415.477082 -108.183302) (xy 415.518273 -108.147608) (xy 415.564124 -108.11814) (xy 415.613702 -108.095497)
			(xy 415.665998 -108.08014) (xy 415.719948 -108.072383) (xy 415.7472 -108.07192) (xy 415.776117 -108.072431)
			(xy 415.833289 -108.08116) (xy 415.888488 -108.098419) (xy 415.94045 -108.123812) (xy 415.987984 -108.156758)
			(xy 416.03 -108.1965) (xy 416.04819 -108.218986) (xy 416.055796 -108.227793) (xy 416.076698 -108.237973)
			(xy 416.088322 -108.238544) (xy 416.168078 -108.238544) (xy 416.179709 -108.237997) (xy 416.20062 -108.227816)
			(xy 416.20821 -108.218986) (xy 416.226392 -108.196495) (xy 416.268414 -108.156761) (xy 416.315951 -108.123823)
			(xy 416.367914 -108.098436) (xy 416.423113 -108.081181) (xy 416.480284 -108.072454) (xy 416.5092 -108.07192)
			(xy 416.536454 -108.072355) (xy 416.590408 -108.080113) (xy 416.642708 -108.095471) (xy 416.69229 -108.118115)
			(xy 416.738144 -108.147586) (xy 416.779337 -108.183282) (xy 416.815031 -108.224478) (xy 416.844498 -108.270335)
			(xy 416.867139 -108.319919) (xy 416.882493 -108.37222) (xy 416.890247 -108.426174) (xy 416.890708 -108.453428)
			(xy 416.890173 -108.482345) (xy 416.881452 -108.539517) (xy 416.8642 -108.594717) (xy 416.838812 -108.646679)
			(xy 416.805869 -108.694213) (xy 416.766128 -108.736229) (xy 416.743642 -108.754418) (xy 416.734827 -108.762017)
			(xy 416.72465 -108.782924) (xy 416.724084 -108.79455) (xy 416.724084 -108.874306) (xy 416.72464 -108.885936)
			(xy 416.734817 -108.906845) (xy 416.743642 -108.914438) (xy 416.764453 -108.931158) (xy 416.801583 -108.969516)
			(xy 416.833005 -109.012674) (xy 416.858103 -109.059791) (xy 416.876388 -109.109947) (xy 416.887503 -109.162163)
			(xy 416.89123 -109.215417) (xy 416.887498 -109.268672) (xy 416.876378 -109.320886) (xy 416.858089 -109.37104)
			(xy 416.832986 -109.418155) (xy 416.801561 -109.461311) (xy 416.764427 -109.499665) (xy 416.743642 -109.516418)
			(xy 416.734827 -109.524017) (xy 416.72465 -109.544924) (xy 416.724084 -109.55655) (xy 416.724084 -109.636306)
			(xy 416.72464 -109.647936) (xy 416.734817 -109.668845) (xy 416.743642 -109.676438) (xy 416.764453 -109.693158)
			(xy 416.801583 -109.731516) (xy 416.833005 -109.774674) (xy 416.858103 -109.821791) (xy 416.876388 -109.871947)
			(xy 416.887503 -109.924163) (xy 416.89123 -109.977417) (xy 416.887498 -110.030672) (xy 416.876378 -110.082886)
			(xy 416.858089 -110.13304) (xy 416.832986 -110.180155) (xy 416.801561 -110.223311) (xy 416.764427 -110.261665)
			(xy 416.743642 -110.278418) (xy 416.734827 -110.286017) (xy 416.72465 -110.306924) (xy 416.724585 -110.308258)
			(xy 417.984813 -110.308258) (xy 417.984813 -110.253742) (xy 417.992572 -110.199782) (xy 418.007932 -110.147475)
			(xy 418.03058 -110.097887) (xy 418.060055 -110.052027) (xy 418.095757 -110.010828) (xy 418.136959 -109.975131)
			(xy 418.182822 -109.94566) (xy 418.232413 -109.923018) (xy 418.284721 -109.907663) (xy 418.338682 -109.89991)
			(xy 418.36594 -109.89945) (xy 418.366194 -109.89945) (xy 418.39255 -109.899905) (xy 418.44476 -109.907173)
			(xy 418.495473 -109.921556) (xy 418.543724 -109.942782) (xy 418.588594 -109.970447) (xy 418.62923 -110.004023)
			(xy 418.647372 -110.023148) (xy 418.653976 -110.03026) (xy 418.671248 -110.038896) (xy 418.75075 -110.044484)
			(xy 418.760316 -110.044877) (xy 418.778601 -110.039242) (xy 418.78631 -110.033562) (xy 418.786818 -110.033308)
			(xy 418.814156 -110.011595) (xy 418.873678 -109.975109) (xy 418.937638 -109.947121) (xy 419.004828 -109.928158)
			(xy 419.073983 -109.918579) (xy 419.10889 -109.917992) (xy 419.14118 -109.918494) (xy 419.20524 -109.926681)
			(xy 419.267748 -109.942911) (xy 419.327699 -109.966923) (xy 419.384128 -109.998331) (xy 419.436127 -110.03663)
			(xy 419.48286 -110.081203) (xy 419.503606 -110.105952) (xy 419.50386 -110.106206) (xy 419.509597 -110.112719)
			(xy 419.524451 -110.121678) (xy 419.541452 -110.125123) (xy 419.550088 -110.12424) (xy 419.64991 -110.11027)
			(xy 419.670738 -110.094268) (xy 419.676072 -110.081822) (xy 419.689462 -110.051634) (xy 419.722971 -109.994726)
			(xy 419.763567 -109.942635) (xy 419.810565 -109.896239) (xy 419.863174 -109.856319) (xy 419.92051 -109.823546)
			(xy 419.981606 -109.798472) (xy 420.045434 -109.78152) (xy 420.110919 -109.772974) (xy 420.14394 -109.77245)
			(xy 420.176525 -109.773004) (xy 420.241159 -109.781338) (xy 420.304197 -109.797865) (xy 420.364607 -109.822314)
			(xy 420.421396 -109.854282) (xy 420.473634 -109.893247) (xy 420.520463 -109.938569) (xy 420.541196 -109.963712)
			(xy 420.54793 -109.971389) (xy 420.565882 -109.981086) (xy 420.575994 -109.982508) (xy 420.659052 -109.990382)
			(xy 420.67861 -109.984032) (xy 420.686484 -109.977428) (xy 420.709518 -109.958352) (xy 420.759277 -109.92517)
			(xy 420.812588 -109.898058) (xy 420.868713 -109.877392) (xy 420.926875 -109.863456) (xy 420.986272 -109.856444)
			(xy 421.016176 -109.856016) (xy 421.01643 -109.856016) (xy 421.04708 -109.856465) (xy 421.107935 -109.863823)
			(xy 421.167466 -109.878441) (xy 421.224808 -109.900108) (xy 421.279131 -109.928508) (xy 421.329647 -109.963231)
			(xy 421.375624 -110.003773) (xy 421.416396 -110.049547) (xy 421.43426 -110.074456) (xy 421.441372 -110.08487)
			(xy 421.463978 -110.096554) (xy 421.573706 -110.09503) (xy 421.595804 -110.082838) (xy 421.602662 -110.07217)
			(xy 421.617826 -110.049783) (xy 421.653511 -110.009159) (xy 421.694575 -109.973981) (xy 421.740195 -109.944955)
			(xy 421.789457 -109.922662) (xy 421.841374 -109.907548) (xy 421.894904 -109.899918) (xy 421.92194 -109.89945)
			(xy 421.949186 -109.900023) (xy 422.003124 -109.907783) (xy 422.055408 -109.92314) (xy 422.104975 -109.945781)
			(xy 422.150815 -109.975245) (xy 422.191996 -110.010933) (xy 422.227679 -110.052117) (xy 422.257138 -110.097961)
			(xy 422.279774 -110.14753) (xy 422.295125 -110.199815) (xy 422.30288 -110.253754) (xy 422.30288 -110.27664)
			(xy 427.901098 -110.27664) (xy 427.905169 -110.221018) (xy 427.917295 -110.166581) (xy 427.937218 -110.11449)
			(xy 427.964514 -110.065855) (xy 427.9986 -110.021712) (xy 428.038749 -109.983003) (xy 428.084107 -109.950552)
			(xy 428.133707 -109.925051) (xy 428.186491 -109.907044) (xy 428.241334 -109.896914) (xy 428.297068 -109.894877)
			(xy 428.352505 -109.900977) (xy 428.406462 -109.915083) (xy 428.457791 -109.936895) (xy 428.505397 -109.965949)
			(xy 428.548265 -110.001624) (xy 428.585482 -110.043161) (xy 428.616255 -110.089674) (xy 428.639927 -110.140171)
			(xy 428.642394 -110.14837) (xy 430.710338 -110.14837) (xy 430.714409 -110.092748) (xy 430.726535 -110.038311)
			(xy 430.746458 -109.98622) (xy 430.773754 -109.937585) (xy 430.80784 -109.893442) (xy 430.847989 -109.854733)
			(xy 430.893347 -109.822282) (xy 430.942947 -109.796781) (xy 430.995731 -109.778774) (xy 431.050574 -109.768644)
			(xy 431.106308 -109.766607) (xy 431.161745 -109.772707) (xy 431.215702 -109.786813) (xy 431.267031 -109.808625)
			(xy 431.314637 -109.837679) (xy 431.357505 -109.873354) (xy 431.394722 -109.914891) (xy 431.425495 -109.961404)
			(xy 431.449167 -110.011901) (xy 431.465235 -110.065308) (xy 431.473355 -110.120484) (xy 431.473841 -110.1471)
			(xy 431.703478 -110.1471) (xy 431.707549 -110.091478) (xy 431.719675 -110.037041) (xy 431.739598 -109.98495)
			(xy 431.766894 -109.936315) (xy 431.80098 -109.892172) (xy 431.841129 -109.853463) (xy 431.886487 -109.821012)
			(xy 431.936087 -109.795511) (xy 431.988871 -109.777504) (xy 432.043714 -109.767374) (xy 432.099448 -109.765337)
			(xy 432.154885 -109.771437) (xy 432.208842 -109.785543) (xy 432.260171 -109.807355) (xy 432.307777 -109.836409)
			(xy 432.350645 -109.872084) (xy 432.387862 -109.913621) (xy 432.418635 -109.960134) (xy 432.442307 -110.010631)
			(xy 432.458375 -110.064038) (xy 432.466495 -110.119214) (xy 432.467004 -110.1471) (xy 432.466507 -110.174351)
			(xy 432.593478 -110.174351) (xy 432.593478 -110.119849) (xy 432.601234 -110.065902) (xy 432.616589 -110.013607)
			(xy 432.63923 -109.96403) (xy 432.668696 -109.91818) (xy 432.704387 -109.87699) (xy 432.745577 -109.841298)
			(xy 432.791427 -109.811832) (xy 432.841003 -109.789191) (xy 432.893298 -109.773835) (xy 432.947245 -109.766078)
			(xy 432.974496 -109.765592) (xy 433.000876 -109.766036) (xy 433.053135 -109.773302) (xy 433.078636 -109.78007)
			(xy 433.090386 -109.782681) (xy 433.113972 -109.778057) (xy 433.123848 -109.77118) (xy 433.198016 -109.713268)
			(xy 433.208176 -109.691424) (xy 433.207922 -109.679232) (xy 433.207668 -109.66323) (xy 433.208136 -109.631686)
			(xy 433.215936 -109.569083) (xy 433.23142 -109.507926) (xy 433.254349 -109.449153) (xy 433.284373 -109.393668)
			(xy 433.321029 -109.342323) (xy 433.363755 -109.295906) (xy 433.411894 -109.255131) (xy 433.464707 -109.220624)
			(xy 433.521383 -109.192914) (xy 433.581052 -109.172428) (xy 433.642796 -109.15948) (xy 433.705667 -109.154268)
			(xy 433.768701 -109.156874) (xy 433.830928 -109.167257) (xy 433.891393 -109.185257) (xy 433.949167 -109.210598)
			(xy 434.003362 -109.242891) (xy 434.053147 -109.281639) (xy 434.097757 -109.326248) (xy 434.136506 -109.376033)
			(xy 434.168799 -109.430228) (xy 434.194141 -109.488002) (xy 434.212142 -109.548466) (xy 434.222525 -109.610693)
			(xy 434.225132 -109.673727) (xy 434.219921 -109.736598) (xy 434.206974 -109.798342) (xy 434.186488 -109.858011)
			(xy 434.158779 -109.914687) (xy 434.124272 -109.967501) (xy 434.083498 -110.015641) (xy 434.037082 -110.058367)
			(xy 433.985737 -110.095024) (xy 433.930252 -110.125048) (xy 433.87148 -110.147979) (xy 433.810323 -110.163463)
			(xy 433.74772 -110.171264) (xy 433.716176 -110.171738) (xy 433.687805 -110.171343) (xy 433.631414 -110.165032)
			(xy 433.576077 -110.152481) (xy 433.522482 -110.133845) (xy 433.49672 -110.121954) (xy 433.485798 -110.11662)
			(xy 433.461668 -110.117128) (xy 433.37861 -110.161832) (xy 433.368376 -110.168135) (xy 433.354724 -110.187877)
			(xy 433.352448 -110.199678) (xy 433.348197 -110.22669) (xy 433.332987 -110.279212) (xy 433.310437 -110.329027)
			(xy 433.28101 -110.375114) (xy 433.245307 -110.41653) (xy 433.20406 -110.452428) (xy 433.158113 -110.482073)
			(xy 433.108405 -110.504858) (xy 433.055955 -110.520316) (xy 433.001836 -110.528133) (xy 432.974496 -110.528608)
			(xy 432.947245 -110.528122) (xy 432.893298 -110.520365) (xy 432.841003 -110.505009) (xy 432.791427 -110.482368)
			(xy 432.745577 -110.452902) (xy 432.704387 -110.41721) (xy 432.668696 -110.37602) (xy 432.63923 -110.33017)
			(xy 432.616589 -110.280593) (xy 432.601234 -110.228298) (xy 432.593478 -110.174351) (xy 432.466507 -110.174351)
			(xy 432.466495 -110.174986) (xy 432.458375 -110.230162) (xy 432.442307 -110.283569) (xy 432.418635 -110.334066)
			(xy 432.387862 -110.380579) (xy 432.350645 -110.422116) (xy 432.307777 -110.457791) (xy 432.260171 -110.486845)
			(xy 432.208842 -110.508657) (xy 432.154885 -110.522763) (xy 432.099448 -110.528863) (xy 432.043714 -110.526826)
			(xy 431.988871 -110.516696) (xy 431.936087 -110.498689) (xy 431.886487 -110.473188) (xy 431.841129 -110.440737)
			(xy 431.80098 -110.402028) (xy 431.766894 -110.357885) (xy 431.739598 -110.30925) (xy 431.719675 -110.257159)
			(xy 431.707549 -110.202722) (xy 431.703478 -110.1471) (xy 431.473841 -110.1471) (xy 431.473864 -110.14837)
			(xy 431.473355 -110.176256) (xy 431.465235 -110.231432) (xy 431.449167 -110.284839) (xy 431.425495 -110.335336)
			(xy 431.394722 -110.381849) (xy 431.357505 -110.423386) (xy 431.314637 -110.459061) (xy 431.267031 -110.488115)
			(xy 431.215702 -110.509927) (xy 431.161745 -110.524033) (xy 431.106308 -110.530133) (xy 431.050574 -110.528096)
			(xy 430.995731 -110.517966) (xy 430.942947 -110.499959) (xy 430.893347 -110.474458) (xy 430.847989 -110.442007)
			(xy 430.80784 -110.403298) (xy 430.773754 -110.359155) (xy 430.746458 -110.31052) (xy 430.726535 -110.258429)
			(xy 430.714409 -110.203992) (xy 430.710338 -110.14837) (xy 428.642394 -110.14837) (xy 428.655995 -110.193578)
			(xy 428.664115 -110.248754) (xy 428.664624 -110.27664) (xy 428.664115 -110.304526) (xy 428.655995 -110.359702)
			(xy 428.639927 -110.413109) (xy 428.616255 -110.463606) (xy 428.585482 -110.510119) (xy 428.548265 -110.551656)
			(xy 428.505397 -110.587331) (xy 428.457791 -110.616385) (xy 428.406462 -110.638197) (xy 428.352505 -110.652303)
			(xy 428.297068 -110.658403) (xy 428.241334 -110.656366) (xy 428.186491 -110.646236) (xy 428.133707 -110.628229)
			(xy 428.084107 -110.602728) (xy 428.038749 -110.570277) (xy 427.9986 -110.531568) (xy 427.964514 -110.487425)
			(xy 427.937218 -110.43879) (xy 427.917295 -110.386699) (xy 427.905169 -110.332262) (xy 427.901098 -110.27664)
			(xy 422.30288 -110.27664) (xy 422.30288 -110.308246) (xy 422.295125 -110.362185) (xy 422.279774 -110.41447)
			(xy 422.257138 -110.464039) (xy 422.227679 -110.509883) (xy 422.191996 -110.551067) (xy 422.150815 -110.586755)
			(xy 422.104975 -110.616219) (xy 422.055408 -110.63886) (xy 422.003124 -110.654217) (xy 421.949186 -110.661977)
			(xy 421.92194 -110.662466) (xy 421.89626 -110.662013) (xy 421.845364 -110.655121) (xy 421.795855 -110.641456)
			(xy 421.74863 -110.621266) (xy 421.704543 -110.594917) (xy 421.664395 -110.562886) (xy 421.64635 -110.54461)
			(xy 421.646096 -110.544356) (xy 421.636965 -110.535853) (xy 421.61327 -110.528129) (xy 421.600884 -110.529624)
			(xy 421.505126 -110.546134) (xy 421.485314 -110.561374) (xy 421.480234 -110.573058) (xy 421.46643 -110.60243)
			(xy 421.432501 -110.657754) (xy 421.391808 -110.708311) (xy 421.345014 -110.75328) (xy 421.292879 -110.79193)
			(xy 421.23625 -110.823633) (xy 421.176048 -110.847874) (xy 421.113251 -110.864257) (xy 421.04888 -110.872518)
			(xy 421.01643 -110.873032) (xy 420.983844 -110.872507) (xy 420.919209 -110.864168) (xy 420.856169 -110.847637)
			(xy 420.795759 -110.823184) (xy 420.73897 -110.79121) (xy 420.686734 -110.752241) (xy 420.639906 -110.706915)
			(xy 420.619174 -110.68177) (xy 420.612455 -110.674078) (xy 420.594492 -110.66439) (xy 420.584376 -110.662974)
			(xy 420.501318 -110.6551) (xy 420.48176 -110.66145) (xy 420.473886 -110.668054) (xy 420.450861 -110.687141)
			(xy 420.4011 -110.720323) (xy 420.347787 -110.747433) (xy 420.291661 -110.768098) (xy 420.233497 -110.782031)
			(xy 420.174099 -110.789039) (xy 420.144194 -110.789466) (xy 420.14394 -110.789466) (xy 420.111651 -110.788921)
			(xy 420.047594 -110.780739) (xy 419.985087 -110.764515) (xy 419.925137 -110.740509) (xy 419.868708 -110.709108)
			(xy 419.816708 -110.670817) (xy 419.769972 -110.626251) (xy 419.749224 -110.601506) (xy 419.74897 -110.601252)
			(xy 419.743205 -110.594766) (xy 419.728366 -110.585795) (xy 419.711375 -110.58234) (xy 419.702742 -110.583218)
			(xy 419.60292 -110.597188) (xy 419.582092 -110.61319) (xy 419.576758 -110.625636) (xy 419.563322 -110.655803)
			(xy 419.52982 -110.712712) (xy 419.489232 -110.764803) (xy 419.44224 -110.811201) (xy 419.389636 -110.851124)
			(xy 419.332306 -110.8839) (xy 419.271215 -110.908977) (xy 419.207391 -110.925933) (xy 419.141909 -110.934482)
			(xy 419.10889 -110.935008) (xy 419.078557 -110.934612) (xy 419.018323 -110.927389) (xy 418.959376 -110.913047)
			(xy 418.902556 -110.89179) (xy 418.848671 -110.863921) (xy 418.798486 -110.829835) (xy 418.752716 -110.790017)
			(xy 418.712011 -110.745034) (xy 418.67695 -110.695525) (xy 418.662104 -110.66907) (xy 418.657113 -110.660755)
			(xy 418.642226 -110.648351) (xy 418.633148 -110.64494) (xy 418.557456 -110.620302) (xy 418.538152 -110.621572)
			(xy 418.529262 -110.625636) (xy 418.50361 -110.637229) (xy 418.449759 -110.653626) (xy 418.394085 -110.661939)
			(xy 418.36594 -110.662466) (xy 418.338682 -110.66209) (xy 418.284721 -110.654337) (xy 418.232413 -110.638982)
			(xy 418.182822 -110.61634) (xy 418.136959 -110.586869) (xy 418.095757 -110.551172) (xy 418.060055 -110.509973)
			(xy 418.03058 -110.464113) (xy 418.007932 -110.414525) (xy 417.992572 -110.362218) (xy 417.984813 -110.308258)
			(xy 416.724585 -110.308258) (xy 416.724084 -110.31855) (xy 416.724084 -110.398306) (xy 416.72464 -110.409936)
			(xy 416.734817 -110.430845) (xy 416.743642 -110.438438) (xy 416.764453 -110.455158) (xy 416.801583 -110.493516)
			(xy 416.833005 -110.536674) (xy 416.858103 -110.583791) (xy 416.876388 -110.633947) (xy 416.887503 -110.686163)
			(xy 416.89123 -110.739417) (xy 416.887498 -110.792672) (xy 416.876378 -110.844886) (xy 416.858089 -110.89504)
			(xy 416.832986 -110.942155) (xy 416.811218 -110.972049) (xy 429.374294 -110.972049) (xy 429.374294 -110.908127)
			(xy 429.382305 -110.844709) (xy 429.398202 -110.782795) (xy 429.421734 -110.723362) (xy 429.452528 -110.667347)
			(xy 429.490101 -110.615632) (xy 429.533858 -110.569035) (xy 429.583111 -110.52829) (xy 429.637082 -110.494039)
			(xy 429.694921 -110.466822) (xy 429.755714 -110.447069) (xy 429.818504 -110.435091) (xy 429.8823 -110.431078)
			(xy 429.946096 -110.435091) (xy 430.008886 -110.447069) (xy 430.069679 -110.466822) (xy 430.127518 -110.494039)
			(xy 430.181489 -110.52829) (xy 430.230742 -110.569035) (xy 430.274499 -110.615632) (xy 430.312072 -110.667347)
			(xy 430.342866 -110.723362) (xy 430.366398 -110.782795) (xy 430.379317 -110.833111) (xy 462.38007 -110.833111)
			(xy 462.38007 -110.769189) (xy 462.388081 -110.705771) (xy 462.403978 -110.643857) (xy 462.42751 -110.584424)
			(xy 462.458304 -110.528409) (xy 462.495877 -110.476694) (xy 462.539634 -110.430097) (xy 462.588887 -110.389352)
			(xy 462.642858 -110.355101) (xy 462.700697 -110.327884) (xy 462.76149 -110.308131) (xy 462.82428 -110.296153)
			(xy 462.888076 -110.29214) (xy 462.951872 -110.296153) (xy 463.014662 -110.308131) (xy 463.075455 -110.327884)
			(xy 463.133294 -110.355101) (xy 463.187265 -110.389352) (xy 463.236518 -110.430097) (xy 463.280275 -110.476694)
			(xy 463.317848 -110.528409) (xy 463.348642 -110.584424) (xy 463.372174 -110.643857) (xy 463.388071 -110.705771)
			(xy 463.396082 -110.769189) (xy 463.396584 -110.80115) (xy 463.396082 -110.833111) (xy 463.388071 -110.896529)
			(xy 463.372174 -110.958443) (xy 463.348642 -111.017876) (xy 463.317848 -111.073891) (xy 463.280275 -111.125606)
			(xy 463.236518 -111.172203) (xy 463.187265 -111.212948) (xy 463.133294 -111.247199) (xy 463.075455 -111.274416)
			(xy 463.014662 -111.294169) (xy 462.951872 -111.306147) (xy 462.888076 -111.310161) (xy 462.82428 -111.306147)
			(xy 462.76149 -111.294169) (xy 462.700697 -111.274416) (xy 462.642858 -111.247199) (xy 462.588887 -111.212948)
			(xy 462.539634 -111.172203) (xy 462.495877 -111.125606) (xy 462.458304 -111.073891) (xy 462.42751 -111.017876)
			(xy 462.403978 -110.958443) (xy 462.388081 -110.896529) (xy 462.38007 -110.833111) (xy 430.379317 -110.833111)
			(xy 430.382295 -110.844709) (xy 430.390306 -110.908127) (xy 430.390808 -110.940088) (xy 430.390306 -110.972049)
			(xy 430.382295 -111.035467) (xy 430.366398 -111.097381) (xy 430.342866 -111.156814) (xy 430.312072 -111.212829)
			(xy 430.274499 -111.264544) (xy 430.230742 -111.311141) (xy 430.181489 -111.351886) (xy 430.127518 -111.386137)
			(xy 430.069679 -111.413354) (xy 430.008886 -111.433107) (xy 429.946096 -111.445085) (xy 429.8823 -111.449099)
			(xy 429.818504 -111.445085) (xy 429.755714 -111.433107) (xy 429.694921 -111.413354) (xy 429.637082 -111.386137)
			(xy 429.583111 -111.351886) (xy 429.533858 -111.311141) (xy 429.490101 -111.264544) (xy 429.452528 -111.212829)
			(xy 429.421734 -111.156814) (xy 429.398202 -111.097381) (xy 429.382305 -111.035467) (xy 429.374294 -110.972049)
			(xy 416.811218 -110.972049) (xy 416.801561 -110.985311) (xy 416.764427 -111.023665) (xy 416.743642 -111.040418)
			(xy 416.734827 -111.048017) (xy 416.72465 -111.068924) (xy 416.724084 -111.08055) (xy 416.724084 -111.160306)
			(xy 416.72464 -111.171936) (xy 416.734817 -111.192845) (xy 416.743642 -111.200438) (xy 416.766152 -111.218597)
			(xy 416.805884 -111.260625) (xy 416.838819 -111.308167) (xy 416.864202 -111.360134) (xy 416.881453 -111.415337)
			(xy 416.890176 -111.47251) (xy 416.890708 -111.501428) (xy 416.890248 -111.52868) (xy 416.882488 -111.582629)
			(xy 416.867129 -111.634924) (xy 416.844485 -111.684501) (xy 416.815016 -111.730351) (xy 416.779321 -111.771541)
			(xy 416.738129 -111.807232) (xy 416.692277 -111.836698) (xy 416.642698 -111.859339) (xy 416.590401 -111.874694)
			(xy 416.536452 -111.88245) (xy 416.5092 -111.882936) (xy 416.480282 -111.882442) (xy 416.423108 -111.873711)
			(xy 416.367908 -111.85645) (xy 416.315946 -111.831054) (xy 416.268413 -111.798105) (xy 416.226398 -111.758358)
			(xy 416.20821 -111.73587) (xy 416.200594 -111.727072) (xy 416.1797 -111.716885) (xy 416.168078 -111.716312)
			(xy 416.088322 -111.716312) (xy 416.076693 -111.716874) (xy 416.055783 -111.727046) (xy 416.04819 -111.73587)
			(xy 416.029997 -111.758352) (xy 415.987979 -111.798089) (xy 415.940444 -111.831029) (xy 415.888483 -111.856418)
			(xy 415.833286 -111.873674) (xy 415.776116 -111.882402) (xy 415.7472 -111.882936) (xy 415.71995 -111.882422)
			(xy 415.666005 -111.874667) (xy 415.613712 -111.859313) (xy 415.564137 -111.836674) (xy 415.518288 -111.80721)
			(xy 415.477098 -111.771522) (xy 415.441407 -111.730335) (xy 415.41194 -111.684488) (xy 415.389297 -111.634914)
			(xy 415.373939 -111.582623) (xy 415.36618 -111.528678) (xy 415.365692 -111.501428) (xy 415.366195 -111.47251)
			(xy 415.374923 -111.415337) (xy 415.392181 -111.360136) (xy 415.417575 -111.308173) (xy 415.450523 -111.26064)
			(xy 415.49027 -111.218626) (xy 415.512758 -111.200438) (xy 415.521548 -111.192815) (xy 415.531739 -111.171926)
			(xy 415.532316 -111.160306) (xy 415.532316 -111.08055) (xy 415.531786 -111.068917) (xy 415.52159 -111.048008)
			(xy 415.512758 -111.040418) (xy 415.492003 -111.023631) (xy 415.454873 -110.985282) (xy 415.423452 -110.942131)
			(xy 415.398352 -110.895022) (xy 415.380065 -110.844873) (xy 415.368946 -110.792665) (xy 415.365214 -110.739417)
			(xy 370.441141 -110.739417) (xy 370.465627 -110.765492) (xy 370.5032 -110.817207) (xy 370.533994 -110.873222)
			(xy 370.557526 -110.932655) (xy 370.573423 -110.994569) (xy 370.581434 -111.057987) (xy 370.581936 -111.089948)
			(xy 370.581434 -111.121909) (xy 370.573423 -111.185327) (xy 370.557526 -111.247241) (xy 370.533994 -111.306674)
			(xy 370.5032 -111.362689) (xy 370.465627 -111.414404) (xy 370.42187 -111.461001) (xy 370.372617 -111.501746)
			(xy 370.318646 -111.535997) (xy 370.260807 -111.563214) (xy 370.200014 -111.582967) (xy 370.137224 -111.594945)
			(xy 370.073428 -111.598959) (xy 370.009632 -111.594945) (xy 369.946842 -111.582967) (xy 369.886049 -111.563214)
			(xy 369.82821 -111.535997) (xy 369.774239 -111.501746) (xy 369.724986 -111.461001) (xy 369.681229 -111.414404)
			(xy 369.643656 -111.362689) (xy 369.612862 -111.306674) (xy 369.58933 -111.247241) (xy 369.573433 -111.185327)
			(xy 369.565422 -111.121909) (xy 322.902703 -111.121909) (xy 322.890061 -111.127858) (xy 322.829268 -111.147611)
			(xy 322.766478 -111.159589) (xy 322.702682 -111.163603) (xy 322.638886 -111.159589) (xy 322.576096 -111.147611)
			(xy 322.515303 -111.127858) (xy 322.457464 -111.100641) (xy 322.403493 -111.06639) (xy 322.35424 -111.025645)
			(xy 322.310483 -110.979048) (xy 322.27291 -110.927333) (xy 322.242116 -110.871318) (xy 322.218584 -110.811885)
			(xy 322.202687 -110.749971) (xy 322.194676 -110.686553) (xy 322.194174 -110.654592) (xy 300.220111 -110.654592)
			(xy 300.224997 -110.680204) (xy 300.229011 -110.744) (xy 300.224997 -110.807796) (xy 300.213019 -110.870586)
			(xy 300.193266 -110.931379) (xy 300.166049 -110.989218) (xy 300.131798 -111.043189) (xy 300.091053 -111.092442)
			(xy 300.044456 -111.136199) (xy 299.992741 -111.173772) (xy 299.936726 -111.204566) (xy 299.877293 -111.228098)
			(xy 299.815379 -111.243995) (xy 299.751961 -111.252006) (xy 299.72 -111.252508) (xy 299.688338 -111.25206)
			(xy 299.625503 -111.244207) (xy 299.56413 -111.22861) (xy 299.505169 -111.205511) (xy 299.449534 -111.175268)
			(xy 299.398086 -111.138349) (xy 299.351622 -111.095326) (xy 299.330872 -111.071406) (xy 299.321176 -111.060638)
			(xy 299.297082 -111.044567) (xy 299.269443 -111.035915) (xy 299.240486 -111.03538) (xy 299.212546 -111.043005)
			(xy 299.187875 -111.058176) (xy 299.168463 -111.079669) (xy 299.161708 -111.092488) (xy 299.147464 -111.12076)
			(xy 299.113036 -111.173886) (xy 299.072279 -111.222327) (xy 299.025823 -111.265333) (xy 298.974387 -111.302239)
			(xy 298.937454 -111.322315) (xy 309.200544 -111.322315) (xy 309.200544 -111.258393) (xy 309.208555 -111.194975)
			(xy 309.224452 -111.133061) (xy 309.247984 -111.073628) (xy 309.278778 -111.017613) (xy 309.316351 -110.965898)
			(xy 309.360108 -110.919301) (xy 309.409361 -110.878556) (xy 309.463332 -110.844305) (xy 309.521171 -110.817088)
			(xy 309.581964 -110.797335) (xy 309.644754 -110.785357) (xy 309.70855 -110.781344) (xy 309.772346 -110.785357)
			(xy 309.835136 -110.797335) (xy 309.895929 -110.817088) (xy 309.953768 -110.844305) (xy 310.007739 -110.878556)
			(xy 310.056992 -110.919301) (xy 310.100749 -110.965898) (xy 310.138322 -111.017613) (xy 310.169116 -111.073628)
			(xy 310.192648 -111.133061) (xy 310.208545 -111.194975) (xy 310.216556 -111.258393) (xy 310.217058 -111.290354)
			(xy 310.216556 -111.322315) (xy 310.208545 -111.385733) (xy 310.192648 -111.447647) (xy 310.169116 -111.50708)
			(xy 310.138322 -111.563095) (xy 310.109525 -111.602731) (xy 315.06896 -111.602731) (xy 315.06896 -111.538809)
			(xy 315.076971 -111.475391) (xy 315.092868 -111.413477) (xy 315.1164 -111.354044) (xy 315.147194 -111.298029)
			(xy 315.184767 -111.246314) (xy 315.228524 -111.199717) (xy 315.277777 -111.158972) (xy 315.331748 -111.124721)
			(xy 315.389587 -111.097504) (xy 315.45038 -111.077751) (xy 315.51317 -111.065773) (xy 315.576966 -111.06176)
			(xy 315.640762 -111.065773) (xy 315.703552 -111.077751) (xy 315.764345 -111.097504) (xy 315.822184 -111.124721)
			(xy 315.876155 -111.158972) (xy 315.925408 -111.199717) (xy 315.969165 -111.246314) (xy 316.006738 -111.298029)
			(xy 316.037532 -111.354044) (xy 316.061064 -111.413477) (xy 316.076961 -111.475391) (xy 316.084972 -111.538809)
			(xy 316.085474 -111.57077) (xy 316.084972 -111.602731) (xy 316.076961 -111.666149) (xy 316.061064 -111.728063)
			(xy 316.037532 -111.787496) (xy 316.006738 -111.843511) (xy 315.969165 -111.895226) (xy 315.925408 -111.941823)
			(xy 315.876155 -111.982568) (xy 315.822184 -112.016819) (xy 315.764345 -112.044036) (xy 315.703552 -112.063789)
			(xy 315.640762 -112.075767) (xy 315.576966 -112.079781) (xy 315.51317 -112.075767) (xy 315.45038 -112.063789)
			(xy 315.389587 -112.044036) (xy 315.331748 -112.016819) (xy 315.277777 -111.982568) (xy 315.228524 -111.941823)
			(xy 315.184767 -111.895226) (xy 315.147194 -111.843511) (xy 315.1164 -111.787496) (xy 315.092868 -111.728063)
			(xy 315.076971 -111.666149) (xy 315.06896 -111.602731) (xy 310.109525 -111.602731) (xy 310.100749 -111.61481)
			(xy 310.056992 -111.661407) (xy 310.007739 -111.702152) (xy 309.953768 -111.736403) (xy 309.895929 -111.76362)
			(xy 309.835136 -111.783373) (xy 309.772346 -111.795351) (xy 309.70855 -111.799365) (xy 309.644754 -111.795351)
			(xy 309.581964 -111.783373) (xy 309.521171 -111.76362) (xy 309.463332 -111.736403) (xy 309.409361 -111.702152)
			(xy 309.360108 -111.661407) (xy 309.316351 -111.61481) (xy 309.278778 -111.563095) (xy 309.247984 -111.50708)
			(xy 309.224452 -111.447647) (xy 309.208555 -111.385733) (xy 309.200544 -111.322315) (xy 298.937454 -111.322315)
			(xy 298.918767 -111.332473) (xy 298.859824 -111.355568) (xy 298.798469 -111.371165) (xy 298.735653 -111.379025)
			(xy 298.704 -111.379508) (xy 298.672039 -111.379006) (xy 298.608621 -111.370995) (xy 298.546707 -111.355098)
			(xy 298.487274 -111.331566) (xy 298.431259 -111.300772) (xy 298.379544 -111.263199) (xy 298.332947 -111.219442)
			(xy 298.292202 -111.170189) (xy 298.257951 -111.116218) (xy 298.230734 -111.058379) (xy 298.210981 -110.997586)
			(xy 298.199003 -110.934796) (xy 298.19499 -110.871) (xy 275.803423 -110.871) (xy 275.848549 -110.899638)
			(xy 275.897802 -110.940383) (xy 275.941559 -110.98698) (xy 275.979132 -111.038695) (xy 276.009926 -111.09471)
			(xy 276.033458 -111.154143) (xy 276.049355 -111.216057) (xy 276.057366 -111.279475) (xy 276.057868 -111.311436)
			(xy 276.057366 -111.343397) (xy 276.049355 -111.406815) (xy 276.033458 -111.468729) (xy 276.009926 -111.528162)
			(xy 275.979132 -111.584177) (xy 275.941559 -111.635892) (xy 275.897802 -111.682489) (xy 275.848549 -111.723234)
			(xy 275.794578 -111.757485) (xy 275.736739 -111.784702) (xy 275.675946 -111.804455) (xy 275.640022 -111.811308)
			(xy 300.84979 -111.811308) (xy 300.853861 -111.755686) (xy 300.865987 -111.701249) (xy 300.88591 -111.649158)
			(xy 300.913206 -111.600523) (xy 300.947292 -111.55638) (xy 300.987441 -111.517671) (xy 301.032799 -111.48522)
			(xy 301.082399 -111.459719) (xy 301.135183 -111.441712) (xy 301.190026 -111.431582) (xy 301.24576 -111.429545)
			(xy 301.301197 -111.435645) (xy 301.355154 -111.449751) (xy 301.406483 -111.471563) (xy 301.454089 -111.500617)
			(xy 301.496957 -111.536292) (xy 301.534174 -111.577829) (xy 301.564947 -111.624342) (xy 301.588619 -111.674839)
			(xy 301.604687 -111.728246) (xy 301.612807 -111.783422) (xy 301.613316 -111.811308) (xy 301.612807 -111.839194)
			(xy 301.604687 -111.89437) (xy 301.588619 -111.947777) (xy 301.564947 -111.998274) (xy 301.534174 -112.044787)
			(xy 301.496957 -112.086324) (xy 301.454089 -112.121999) (xy 301.406483 -112.151053) (xy 301.355154 -112.172865)
			(xy 301.301197 -112.186971) (xy 301.24576 -112.193071) (xy 301.190026 -112.191034) (xy 301.135183 -112.180904)
			(xy 301.082399 -112.162897) (xy 301.032799 -112.137396) (xy 300.987441 -112.104945) (xy 300.947292 -112.066236)
			(xy 300.913206 -112.022093) (xy 300.88591 -111.973458) (xy 300.865987 -111.921367) (xy 300.853861 -111.86693)
			(xy 300.84979 -111.811308) (xy 275.640022 -111.811308) (xy 275.613156 -111.816433) (xy 275.54936 -111.820447)
			(xy 275.485564 -111.816433) (xy 275.422774 -111.804455) (xy 275.361981 -111.784702) (xy 275.304142 -111.757485)
			(xy 275.250171 -111.723234) (xy 275.200918 -111.682489) (xy 275.157161 -111.635892) (xy 275.119588 -111.584177)
			(xy 275.088794 -111.528162) (xy 275.065262 -111.468729) (xy 275.049365 -111.406815) (xy 275.041354 -111.343397)
			(xy 254.113191 -111.343397) (xy 254.102385 -111.35827) (xy 254.058628 -111.404867) (xy 254.009375 -111.445612)
			(xy 253.955404 -111.479863) (xy 253.897565 -111.50708) (xy 253.836772 -111.526833) (xy 253.773982 -111.538811)
			(xy 253.710186 -111.542825) (xy 253.64639 -111.538811) (xy 253.5836 -111.526833) (xy 253.522807 -111.50708)
			(xy 253.464968 -111.479863) (xy 253.410997 -111.445612) (xy 253.361744 -111.404867) (xy 253.317987 -111.35827)
			(xy 253.280414 -111.306555) (xy 253.24962 -111.25054) (xy 253.226088 -111.191107) (xy 253.210191 -111.129193)
			(xy 253.20218 -111.065775) (xy 210.065201 -111.065775) (xy 210.050982 -111.070395) (xy 209.988192 -111.082373)
			(xy 209.924396 -111.086387) (xy 209.8606 -111.082373) (xy 209.79781 -111.070395) (xy 209.737017 -111.050642)
			(xy 209.679178 -111.023425) (xy 209.625207 -110.989174) (xy 209.575954 -110.948429) (xy 209.532197 -110.901832)
			(xy 209.494624 -110.850117) (xy 209.46383 -110.794102) (xy 209.440298 -110.734669) (xy 209.424401 -110.672755)
			(xy 209.41639 -110.609337) (xy 209.415888 -110.577376) (xy 207.833214 -110.577376) (xy 207.832738 -110.607921)
			(xy 207.825432 -110.668573) (xy 207.81091 -110.727911) (xy 207.789381 -110.785082) (xy 207.761157 -110.839261)
			(xy 207.726643 -110.889667) (xy 207.686337 -110.935574) (xy 207.64082 -110.97632) (xy 207.616044 -110.99419)
			(xy 207.605884 -111.001302) (xy 207.594454 -111.023146) (xy 207.5942 -111.11865) (xy 207.594906 -111.131001)
			(xy 207.606328 -111.152902) (xy 207.616044 -111.16056) (xy 207.640752 -111.178428) (xy 207.686109 -111.219182)
			(xy 207.726269 -111.265066) (xy 207.760657 -111.315422) (xy 207.788779 -111.369526) (xy 207.810232 -111.426605)
			(xy 207.824709 -111.485838) (xy 207.832001 -111.546378) (xy 207.832452 -111.576866) (xy 207.831973 -111.608647)
			(xy 207.824054 -111.671715) (xy 207.808337 -111.733304) (xy 207.785065 -111.792453) (xy 207.754602 -111.848241)
			(xy 207.717424 -111.899796) (xy 207.674109 -111.946316) (xy 207.625334 -111.987073) (xy 207.571859 -112.021434)
			(xy 207.5434 -112.03559) (xy 207.543146 -112.03559) (xy 207.534956 -112.040025) (xy 207.522179 -112.053549)
			(xy 207.51509 -112.070751) (xy 207.514444 -112.08004) (xy 207.511904 -112.170464) (xy 207.512021 -112.179805)
			(xy 207.518206 -112.197415) (xy 207.530317 -112.211619) (xy 207.53832 -112.216438) (xy 207.564574 -112.231383)
			(xy 207.61373 -112.266502) (xy 207.658376 -112.3072) (xy 207.697884 -112.352903) (xy 207.731697 -112.402967)
			(xy 207.759337 -112.456685) (xy 207.780415 -112.513301) (xy 207.794634 -112.572016) (xy 207.801794 -112.632002)
			(xy 207.802226 -112.662208) (xy 209.984848 -112.662208) (xy 209.985325 -112.631792) (xy 209.992581 -112.571394)
			(xy 210.006991 -112.512294) (xy 210.02835 -112.455334) (xy 210.056351 -112.40133) (xy 210.090595 -112.351052)
			(xy 210.130592 -112.305218) (xy 210.175773 -112.264484) (xy 210.22549 -112.22943) (xy 210.279034 -112.200559)
			(xy 210.307174 -112.189006) (xy 210.320031 -112.18337) (xy 210.342327 -112.166338) (xy 210.359145 -112.14388)
			(xy 210.369214 -112.117692) (xy 210.371772 -112.089752) (xy 210.366628 -112.062171) (xy 210.35417 -112.037032)
			(xy 210.335338 -112.016233) (xy 210.323684 -112.008412) (xy 210.29664 -111.990912) (xy 210.24675 -111.950163)
			(xy 210.202402 -111.903443) (xy 210.164305 -111.8515) (xy 210.133068 -111.795164) (xy 210.10919 -111.735337)
			(xy 210.093053 -111.672974) (xy 210.084915 -111.609074) (xy 210.084416 -111.576866) (xy 210.084918 -111.544905)
			(xy 210.092929 -111.481487) (xy 210.108826 -111.419573) (xy 210.132358 -111.36014) (xy 210.163152 -111.304125)
			(xy 210.200725 -111.25241) (xy 210.244482 -111.205813) (xy 210.293735 -111.165068) (xy 210.347706 -111.130817)
			(xy 210.405545 -111.1036) (xy 210.466338 -111.083847) (xy 210.529128 -111.071869) (xy 210.592924 -111.067856)
			(xy 210.65672 -111.071869) (xy 210.71951 -111.083847) (xy 210.780303 -111.1036) (xy 210.838142 -111.130817)
			(xy 210.892113 -111.165068) (xy 210.941366 -111.205813) (xy 210.985123 -111.25241) (xy 211.022696 -111.304125)
			(xy 211.05349 -111.36014) (xy 211.077022 -111.419573) (xy 211.092919 -111.481487) (xy 211.10093 -111.544905)
			(xy 211.101432 -111.576866) (xy 211.100945 -111.607282) (xy 211.093692 -111.66768) (xy 211.079284 -111.726781)
			(xy 211.057927 -111.78374) (xy 211.040496 -111.817361) (xy 214.147394 -111.817361) (xy 214.147394 -111.753439)
			(xy 214.155405 -111.690021) (xy 214.171302 -111.628107) (xy 214.194834 -111.568674) (xy 214.225628 -111.512659)
			(xy 214.263201 -111.460944) (xy 214.306958 -111.414347) (xy 214.356211 -111.373602) (xy 214.410182 -111.339351)
			(xy 214.468021 -111.312134) (xy 214.528814 -111.292381) (xy 214.591604 -111.280403) (xy 214.6554 -111.27639)
			(xy 214.719196 -111.280403) (xy 214.781986 -111.292381) (xy 214.842779 -111.312134) (xy 214.900618 -111.339351)
			(xy 214.954589 -111.373602) (xy 215.003842 -111.414347) (xy 215.047599 -111.460944) (xy 215.085172 -111.512659)
			(xy 215.115966 -111.568674) (xy 215.139498 -111.628107) (xy 215.155395 -111.690021) (xy 215.163406 -111.753439)
			(xy 215.163908 -111.7854) (xy 215.163406 -111.817361) (xy 215.155395 -111.880779) (xy 215.139498 -111.942693)
			(xy 215.115966 -112.002126) (xy 215.085172 -112.058141) (xy 215.047599 -112.109856) (xy 215.003842 -112.156453)
			(xy 214.954589 -112.197198) (xy 214.900618 -112.231449) (xy 214.842779 -112.258666) (xy 214.781986 -112.278419)
			(xy 214.719196 -112.290397) (xy 214.6554 -112.294411) (xy 214.591604 -112.290397) (xy 214.528814 -112.278419)
			(xy 214.468021 -112.258666) (xy 214.410182 -112.231449) (xy 214.356211 -112.197198) (xy 214.306958 -112.156453)
			(xy 214.263201 -112.109856) (xy 214.225628 -112.058141) (xy 214.194834 -112.002126) (xy 214.171302 -111.942693)
			(xy 214.155405 -111.880779) (xy 214.147394 -111.817361) (xy 211.040496 -111.817361) (xy 211.029927 -111.837745)
			(xy 210.995684 -111.888024) (xy 210.955687 -111.933857) (xy 210.910507 -111.974592) (xy 210.86079 -112.009645)
			(xy 210.807246 -112.038516) (xy 210.779106 -112.050068) (xy 210.766194 -112.055588) (xy 210.743891 -112.072639)
			(xy 210.727072 -112.095118) (xy 210.717006 -112.121326) (xy 210.714455 -112.149284) (xy 210.719611 -112.176881)
			(xy 210.732084 -112.202032) (xy 210.750933 -112.222839) (xy 210.762596 -112.230662) (xy 210.789669 -112.248119)
			(xy 210.83956 -112.288874) (xy 210.883907 -112.335599) (xy 210.922002 -112.387549) (xy 210.953236 -112.443891)
			(xy 210.977109 -112.503724) (xy 210.993239 -112.566092) (xy 211.001369 -112.629998) (xy 211.001864 -112.662208)
			(xy 211.001362 -112.694169) (xy 210.993351 -112.757587) (xy 210.977454 -112.819501) (xy 210.953922 -112.878934)
			(xy 210.923128 -112.934949) (xy 210.886211 -112.985761) (xy 211.277194 -112.985761) (xy 211.277194 -112.921839)
			(xy 211.285205 -112.858421) (xy 211.301102 -112.796507) (xy 211.324634 -112.737074) (xy 211.355428 -112.681059)
			(xy 211.393001 -112.629344) (xy 211.436758 -112.582747) (xy 211.486011 -112.542002) (xy 211.539982 -112.507751)
			(xy 211.597821 -112.480534) (xy 211.658614 -112.460781) (xy 211.721404 -112.448803) (xy 211.7852 -112.44479)
			(xy 211.848996 -112.448803) (xy 211.911786 -112.460781) (xy 211.972579 -112.480534) (xy 212.030418 -112.507751)
			(xy 212.084389 -112.542002) (xy 212.133642 -112.582747) (xy 212.177399 -112.629344) (xy 212.214972 -112.681059)
			(xy 212.245766 -112.737074) (xy 212.269298 -112.796507) (xy 212.285195 -112.858421) (xy 212.293206 -112.921839)
			(xy 212.293708 -112.9538) (xy 212.293206 -112.985761) (xy 212.285195 -113.049179) (xy 212.269298 -113.111093)
			(xy 212.245766 -113.170526) (xy 212.214972 -113.226541) (xy 212.177399 -113.278256) (xy 212.133642 -113.324853)
			(xy 212.084389 -113.365598) (xy 212.030418 -113.399849) (xy 211.972579 -113.427066) (xy 211.911786 -113.446819)
			(xy 211.848996 -113.458797) (xy 211.7852 -113.462811) (xy 211.721404 -113.458797) (xy 211.658614 -113.446819)
			(xy 211.597821 -113.427066) (xy 211.539982 -113.399849) (xy 211.486011 -113.365598) (xy 211.436758 -113.324853)
			(xy 211.393001 -113.278256) (xy 211.355428 -113.226541) (xy 211.324634 -113.170526) (xy 211.301102 -113.111093)
			(xy 211.285205 -113.049179) (xy 211.277194 -112.985761) (xy 210.886211 -112.985761) (xy 210.885555 -112.986664)
			(xy 210.841798 -113.033261) (xy 210.792545 -113.074006) (xy 210.738574 -113.108257) (xy 210.680735 -113.135474)
			(xy 210.619942 -113.155227) (xy 210.557152 -113.167205) (xy 210.493356 -113.171219) (xy 210.42956 -113.167205)
			(xy 210.36677 -113.155227) (xy 210.305977 -113.135474) (xy 210.248138 -113.108257) (xy 210.194167 -113.074006)
			(xy 210.144914 -113.033261) (xy 210.101157 -112.986664) (xy 210.063584 -112.934949) (xy 210.03279 -112.878934)
			(xy 210.009258 -112.819501) (xy 209.993361 -112.757587) (xy 209.98535 -112.694169) (xy 209.984848 -112.662208)
			(xy 207.802226 -112.662208) (xy 207.801751 -112.692938) (xy 207.794342 -112.753951) (xy 207.779633 -112.813626)
			(xy 207.757839 -112.871093) (xy 207.729276 -112.925514) (xy 207.694363 -112.976096) (xy 207.653607 -113.0221)
			(xy 207.607603 -113.062857) (xy 207.557023 -113.097771) (xy 207.502602 -113.126335) (xy 207.445136 -113.14813)
			(xy 207.385461 -113.162841) (xy 207.324448 -113.170251) (xy 207.293718 -113.170716) (xy 207.260438 -113.170188)
			(xy 207.194447 -113.161513) (xy 207.130153 -113.144295) (xy 207.068658 -113.11883) (xy 207.011014 -113.085554)
			(xy 206.958208 -113.045036) (xy 206.934308 -113.021872) (xy 206.92756 -113.015683) (xy 206.910899 -113.008124)
			(xy 206.901796 -113.00714) (xy 206.87157 -113.004854) (xy 206.862399 -113.004576) (xy 206.84482 -113.009786)
			(xy 206.83728 -113.015014) (xy 206.810741 -113.034461) (xy 206.753581 -113.067044) (xy 206.692692 -113.091977)
			(xy 206.629095 -113.108841) (xy 206.563853 -113.117354) (xy 206.530956 -113.117884) (xy 206.500364 -113.117431)
			(xy 206.439623 -113.110096) (xy 206.3802 -113.095525) (xy 206.322955 -113.073929) (xy 206.268716 -113.045619)
			(xy 206.218265 -113.011006) (xy 206.172332 -112.970588) (xy 206.131582 -112.924951) (xy 206.096602 -112.874754)
			(xy 206.067898 -112.820722) (xy 206.045885 -112.763636) (xy 206.037942 -112.73409) (xy 206.035402 -112.724438)
			(xy 206.023718 -112.708436) (xy 205.945994 -112.660938) (xy 205.926436 -112.657636) (xy 205.916784 -112.659922)
			(xy 205.8958 -112.664424) (xy 205.853153 -112.669257) (xy 205.831694 -112.669574) (xy 205.83144 -112.669574)
			(xy 205.804183 -112.669182) (xy 205.750223 -112.661429) (xy 205.697915 -112.646075) (xy 205.648326 -112.623433)
			(xy 205.602463 -112.593963) (xy 205.561262 -112.558266) (xy 205.525561 -112.517069) (xy 205.496087 -112.471209)
			(xy 205.473439 -112.421622) (xy 205.45808 -112.369316) (xy 205.450321 -112.315357) (xy 204.260255 -112.315357)
			(xy 204.285152 -112.360646) (xy 204.308684 -112.420079) (xy 204.324581 -112.481993) (xy 204.332592 -112.545411)
			(xy 204.333094 -112.577372) (xy 204.332592 -112.609333) (xy 204.324581 -112.672751) (xy 204.308684 -112.734665)
			(xy 204.285152 -112.794098) (xy 204.254358 -112.850113) (xy 204.216785 -112.901828) (xy 204.173028 -112.948425)
			(xy 204.123775 -112.98917) (xy 204.069804 -113.023421) (xy 204.011965 -113.050638) (xy 203.951172 -113.070391)
			(xy 203.888382 -113.082369) (xy 203.824586 -113.086383) (xy 203.76079 -113.082369) (xy 203.698 -113.070391)
			(xy 203.637207 -113.050638) (xy 203.579368 -113.023421) (xy 203.525397 -112.98917) (xy 203.476144 -112.948425)
			(xy 203.432387 -112.901828) (xy 203.394814 -112.850113) (xy 203.36402 -112.794098) (xy 203.340488 -112.734665)
			(xy 203.324591 -112.672751) (xy 203.31658 -112.609333) (xy 203.010515 -112.609333) (xy 203.010516 -112.609376)
			(xy 203.010038 -112.6411) (xy 203.002144 -112.704055) (xy 202.986474 -112.765538) (xy 202.963273 -112.824592)
			(xy 202.932901 -112.880298) (xy 202.895832 -112.931791) (xy 202.852641 -112.978269) (xy 202.804001 -113.01901)
			(xy 202.777598 -113.036604) (xy 202.76693 -113.043462) (xy 202.754484 -113.065814) (xy 202.753214 -113.17605)
			(xy 202.764898 -113.198656) (xy 202.775312 -113.205768) (xy 202.802152 -113.224822) (xy 202.851211 -113.268704)
			(xy 202.894198 -113.318549) (xy 202.930394 -113.373525) (xy 202.954913 -113.423911) (xy 208.503006 -113.423911)
			(xy 208.503006 -113.359989) (xy 208.511017 -113.296571) (xy 208.526914 -113.234657) (xy 208.550446 -113.175224)
			(xy 208.58124 -113.119209) (xy 208.618813 -113.067494) (xy 208.66257 -113.020897) (xy 208.711823 -112.980152)
			(xy 208.765794 -112.945901) (xy 208.823633 -112.918684) (xy 208.884426 -112.898931) (xy 208.947216 -112.886953)
			(xy 209.011012 -112.88294) (xy 209.074808 -112.886953) (xy 209.137598 -112.898931) (xy 209.198391 -112.918684)
			(xy 209.25623 -112.945901) (xy 209.310201 -112.980152) (xy 209.359454 -113.020897) (xy 209.403211 -113.067494)
			(xy 209.440784 -113.119209) (xy 209.471578 -113.175224) (xy 209.49511 -113.234657) (xy 209.511007 -113.296571)
			(xy 209.519018 -113.359989) (xy 209.51952 -113.39195) (xy 209.519018 -113.423911) (xy 209.511007 -113.487329)
			(xy 209.49511 -113.549243) (xy 209.471578 -113.608676) (xy 209.440784 -113.664691) (xy 209.403211 -113.716406)
			(xy 209.359454 -113.763003) (xy 209.310201 -113.803748) (xy 209.25623 -113.837999) (xy 209.198391 -113.865216)
			(xy 209.137598 -113.884969) (xy 209.074808 -113.896947) (xy 209.011012 -113.900961) (xy 208.947216 -113.896947)
			(xy 208.884426 -113.884969) (xy 208.823633 -113.865216) (xy 208.765794 -113.837999) (xy 208.711823 -113.803748)
			(xy 208.66257 -113.763003) (xy 208.618813 -113.716406) (xy 208.58124 -113.664691) (xy 208.550446 -113.608676)
			(xy 208.526914 -113.549243) (xy 208.511017 -113.487329) (xy 208.503006 -113.423911) (xy 202.954913 -113.423911)
			(xy 202.959195 -113.43271) (xy 202.980118 -113.495118) (xy 202.992815 -113.559703) (xy 202.997072 -113.625386)
			(xy 202.992818 -113.69107) (xy 202.980125 -113.755656) (xy 202.959205 -113.818064) (xy 202.930408 -113.877252)
			(xy 202.894214 -113.932229) (xy 202.85123 -113.982076) (xy 202.802173 -114.025961) (xy 202.775312 -114.044984)
			(xy 202.764898 -114.052096) (xy 202.753214 -114.074702) (xy 202.754484 -114.184938) (xy 202.76693 -114.20729)
			(xy 202.777598 -114.214148) (xy 202.803996 -114.231747) (xy 202.852631 -114.272491) (xy 202.861159 -114.281669)
			(xy 203.335376 -114.281669) (xy 203.335376 -114.217747) (xy 203.343387 -114.154329) (xy 203.359284 -114.092415)
			(xy 203.382816 -114.032982) (xy 203.41361 -113.976967) (xy 203.451183 -113.925252) (xy 203.49494 -113.878655)
			(xy 203.544193 -113.83791) (xy 203.598164 -113.803659) (xy 203.656003 -113.776442) (xy 203.716796 -113.756689)
			(xy 203.779586 -113.744711) (xy 203.843382 -113.740698) (xy 203.907178 -113.744711) (xy 203.969968 -113.756689)
			(xy 204.030761 -113.776442) (xy 204.0886 -113.803659) (xy 204.142571 -113.83791) (xy 204.191824 -113.878655)
			(xy 204.235581 -113.925252) (xy 204.273154 -113.976967) (xy 204.303948 -114.032982) (xy 204.32748 -114.092415)
			(xy 204.343377 -114.154329) (xy 204.351388 -114.217747) (xy 204.35189 -114.2497) (xy 205.966276 -114.2497)
			(xy 205.970291 -114.1859) (xy 205.98227 -114.123106) (xy 206.002025 -114.062309) (xy 206.029244 -114.004468)
			(xy 206.063498 -113.950494) (xy 206.104248 -113.901239) (xy 206.150849 -113.85748) (xy 206.202568 -113.819907)
			(xy 206.258588 -113.789113) (xy 206.318026 -113.765582) (xy 206.379944 -113.749688) (xy 206.443367 -113.741679)
			(xy 206.47533 -113.7412) (xy 206.506389 -113.741689) (xy 206.568044 -113.749252) (xy 206.628318 -113.764275)
			(xy 206.686311 -113.786532) (xy 206.741159 -113.815692) (xy 206.792043 -113.85132) (xy 206.815436 -113.871756)
			(xy 206.822597 -113.877675) (xy 206.839935 -113.884311) (xy 206.849218 -113.88471) (xy 206.927196 -113.88471)
			(xy 206.944468 -113.878106) (xy 206.95158 -113.871756) (xy 206.974975 -113.851322) (xy 207.02586 -113.815692)
			(xy 207.080707 -113.786529) (xy 207.138699 -113.764267) (xy 207.198972 -113.749238) (xy 207.260627 -113.741667)
			(xy 207.291686 -113.7412) (xy 207.323649 -113.741664) (xy 207.387072 -113.749675) (xy 207.448991 -113.765571)
			(xy 207.508429 -113.789103) (xy 207.564449 -113.819899) (xy 207.616168 -113.857473) (xy 207.662769 -113.901234)
			(xy 207.703518 -113.95049) (xy 207.737773 -114.004464) (xy 207.764992 -114.062307) (xy 207.784747 -114.123105)
			(xy 207.796725 -114.185899) (xy 207.80074 -114.2497) (xy 210.051697 -114.2497) (xy 210.055711 -114.185908)
			(xy 210.067687 -114.123122) (xy 210.087438 -114.062331) (xy 210.114652 -114.004496) (xy 210.1489 -113.950527)
			(xy 210.189642 -113.901276) (xy 210.236235 -113.857519) (xy 210.287944 -113.819947) (xy 210.343955 -113.789151)
			(xy 210.403384 -113.765618) (xy 210.465293 -113.749719) (xy 210.528707 -113.741704) (xy 210.560666 -113.7412)
			(xy 210.593891 -113.741714) (xy 210.659776 -113.750355) (xy 210.723973 -113.767508) (xy 210.785388 -113.79288)
			(xy 210.842973 -113.826038) (xy 210.895746 -113.866417) (xy 210.942808 -113.913328) (xy 210.96351 -113.93932)
			(xy 210.969352 -113.94694) (xy 210.985862 -113.9571) (xy 211.074 -113.97107) (xy 211.092796 -113.967006)
			(xy 211.10067 -113.961672) (xy 211.125937 -113.945178) (xy 211.179605 -113.917599) (xy 211.236162 -113.896567)
			(xy 211.29481 -113.882379) (xy 211.354726 -113.875235) (xy 211.384896 -113.874804) (xy 211.416859 -113.875261)
			(xy 211.480282 -113.883272) (xy 211.5422 -113.89917) (xy 211.601638 -113.922702) (xy 211.657657 -113.953499)
			(xy 211.709375 -113.991074) (xy 211.755975 -114.034834) (xy 211.796724 -114.08409) (xy 211.830978 -114.138065)
			(xy 211.858196 -114.195908) (xy 211.877951 -114.256705) (xy 211.889929 -114.3195) (xy 211.893944 -114.3833)
			(xy 211.889929 -114.4471) (xy 211.877951 -114.509895) (xy 211.858196 -114.570692) (xy 211.830978 -114.628535)
			(xy 211.796724 -114.68251) (xy 211.755975 -114.731766) (xy 211.709375 -114.775526) (xy 211.657657 -114.813101)
			(xy 211.601638 -114.843898) (xy 211.5422 -114.86743) (xy 211.480282 -114.883328) (xy 211.416859 -114.891339)
			(xy 211.384896 -114.89182) (xy 211.351671 -114.891326) (xy 211.285785 -114.88268) (xy 211.221588 -114.865524)
			(xy 211.160173 -114.840148) (xy 211.102589 -114.806987) (xy 211.049816 -114.766606) (xy 211.002754 -114.719693)
			(xy 210.982052 -114.6937) (xy 210.97621 -114.68608) (xy 210.9597 -114.67592) (xy 210.871562 -114.66195)
			(xy 210.852766 -114.666014) (xy 210.844892 -114.671348) (xy 210.819637 -114.68786) (xy 210.765965 -114.715436)
			(xy 210.709406 -114.736464) (xy 210.650755 -114.750647) (xy 210.590837 -114.757787) (xy 210.560666 -114.758216)
			(xy 210.528707 -114.757696) (xy 210.465293 -114.749681) (xy 210.403384 -114.733782) (xy 210.343955 -114.710249)
			(xy 210.287944 -114.679453) (xy 210.236235 -114.641881) (xy 210.189642 -114.598124) (xy 210.1489 -114.548873)
			(xy 210.114652 -114.494904) (xy 210.087438 -114.437069) (xy 210.067687 -114.376279) (xy 210.055711 -114.313492)
			(xy 210.051697 -114.2497) (xy 207.80074 -114.2497) (xy 207.796725 -114.313501) (xy 207.784747 -114.376295)
			(xy 207.764992 -114.437093) (xy 207.737773 -114.494936) (xy 207.703518 -114.54891) (xy 207.662769 -114.598166)
			(xy 207.616168 -114.641927) (xy 207.564449 -114.679501) (xy 207.508429 -114.710297) (xy 207.448991 -114.733829)
			(xy 207.387072 -114.749725) (xy 207.323649 -114.757736) (xy 207.291686 -114.758216) (xy 207.260626 -114.757774)
			(xy 207.198969 -114.750201) (xy 207.138694 -114.735169) (xy 207.080701 -114.712903) (xy 207.025855 -114.683735)
			(xy 206.974972 -114.648099) (xy 206.95158 -114.62766) (xy 206.944412 -114.62175) (xy 206.92708 -114.615108)
			(xy 206.917798 -114.614706) (xy 206.83982 -114.614706) (xy 206.822548 -114.62131) (xy 206.815436 -114.62766)
			(xy 206.792036 -114.648089) (xy 206.741153 -114.683719) (xy 206.686307 -114.712882) (xy 206.628315 -114.735145)
			(xy 206.568043 -114.750175) (xy 206.506389 -114.757748) (xy 206.47533 -114.758216) (xy 206.443367 -114.757721)
			(xy 206.379944 -114.749712) (xy 206.318026 -114.733818) (xy 206.258588 -114.710287) (xy 206.202568 -114.679493)
			(xy 206.150849 -114.64192) (xy 206.104248 -114.598161) (xy 206.063498 -114.548906) (xy 206.029244 -114.494932)
			(xy 206.002025 -114.437091) (xy 205.98227 -114.376294) (xy 205.970291 -114.3135) (xy 205.966276 -114.2497)
			(xy 204.35189 -114.2497) (xy 204.35189 -114.249708) (xy 204.351388 -114.281669) (xy 204.343377 -114.345087)
			(xy 204.32748 -114.407001) (xy 204.303948 -114.466434) (xy 204.273154 -114.522449) (xy 204.235581 -114.574164)
			(xy 204.191824 -114.620761) (xy 204.142571 -114.661506) (xy 204.0886 -114.695757) (xy 204.030761 -114.722974)
			(xy 203.969968 -114.742727) (xy 203.907178 -114.754705) (xy 203.843382 -114.758719) (xy 203.779586 -114.754705)
			(xy 203.716796 -114.742727) (xy 203.656003 -114.722974) (xy 203.598164 -114.695757) (xy 203.544193 -114.661506)
			(xy 203.49494 -114.620761) (xy 203.451183 -114.574164) (xy 203.41361 -114.522449) (xy 203.382816 -114.466434)
			(xy 203.359284 -114.407001) (xy 203.343387 -114.345087) (xy 203.335376 -114.281669) (xy 202.861159 -114.281669)
			(xy 202.895818 -114.31897) (xy 202.932885 -114.370463) (xy 202.963255 -114.426168) (xy 202.986456 -114.48522)
			(xy 203.002128 -114.5467) (xy 203.010027 -114.609653) (xy 203.010516 -114.641376) (xy 203.010056 -114.672664)
			(xy 203.002376 -114.734767) (xy 202.98713 -114.795457) (xy 202.964548 -114.853816) (xy 202.934971 -114.908961)
			(xy 202.898848 -114.960058) (xy 202.866398 -114.995706) (xy 213.569042 -114.995706) (xy 213.56954 -114.964419)
			(xy 213.577211 -114.902317) (xy 213.592449 -114.841626) (xy 213.615025 -114.783267) (xy 213.644596 -114.728121)
			(xy 213.680715 -114.677023) (xy 213.722835 -114.630748) (xy 213.770319 -114.589995) (xy 213.796118 -114.572288)
			(xy 213.806248 -114.564741) (xy 213.818122 -114.542486) (xy 213.818724 -114.52987) (xy 213.818724 -114.445542)
			(xy 213.81808 -114.432936) (xy 213.806223 -114.410687) (xy 213.796118 -114.403124) (xy 213.770311 -114.385429)
			(xy 213.722833 -114.344668) (xy 213.680717 -114.298388) (xy 213.6446 -114.247289) (xy 213.615029 -114.192143)
			(xy 213.592449 -114.133784) (xy 213.577203 -114.073095) (xy 213.569522 -114.010993) (xy 213.569042 -113.979706)
			(xy 213.569544 -113.947745) (xy 213.577555 -113.884327) (xy 213.593452 -113.822413) (xy 213.616984 -113.76298)
			(xy 213.647778 -113.706965) (xy 213.685351 -113.65525) (xy 213.729108 -113.608653) (xy 213.778361 -113.567908)
			(xy 213.832332 -113.533657) (xy 213.890171 -113.50644) (xy 213.950964 -113.486687) (xy 214.013754 -113.474709)
			(xy 214.07755 -113.470696) (xy 214.141346 -113.474709) (xy 214.204136 -113.486687) (xy 214.264929 -113.50644)
			(xy 214.322768 -113.533657) (xy 214.376739 -113.567908) (xy 214.425992 -113.608653) (xy 214.469749 -113.65525)
			(xy 214.507322 -113.706965) (xy 214.538116 -113.76298) (xy 214.561648 -113.822413) (xy 214.577545 -113.884327)
			(xy 214.584325 -113.938) (xy 217.408339 -113.938) (xy 217.412352 -113.874213) (xy 217.424328 -113.811432)
			(xy 217.444078 -113.750646) (xy 217.47129 -113.692815) (xy 217.505535 -113.638851) (xy 217.546273 -113.589604)
			(xy 217.592863 -113.545851) (xy 217.644568 -113.508281) (xy 217.700574 -113.477489) (xy 217.759998 -113.453958)
			(xy 217.821903 -113.43806) (xy 217.885311 -113.430046) (xy 217.917268 -113.429542) (xy 217.959432 -113.43132)
			(xy 217.970354 -113.432082) (xy 217.99042 -113.42497) (xy 218.06154 -113.357152) (xy 218.069668 -113.337086)
			(xy 218.06916 -113.326164) (xy 218.068906 -113.30686) (xy 218.068906 -113.306352) (xy 218.069377 -113.275631)
			(xy 218.07681 -113.214639) (xy 218.09154 -113.154987) (xy 218.11335 -113.097545) (xy 218.141923 -113.043149)
			(xy 218.176842 -112.992593) (xy 218.217599 -112.946614) (xy 218.2636 -112.90588) (xy 218.314174 -112.870987)
			(xy 218.368584 -112.842442) (xy 218.426037 -112.820661) (xy 218.485697 -112.805963) (xy 218.546692 -112.798561)
			(xy 218.577414 -112.798098) (xy 218.609375 -112.798589) (xy 218.672792 -112.806602) (xy 218.734705 -112.8225)
			(xy 218.794138 -112.846032) (xy 218.850152 -112.876828) (xy 218.901865 -112.914401) (xy 218.948462 -112.958159)
			(xy 218.989206 -113.007412) (xy 219.023457 -113.061383) (xy 219.050673 -113.119222) (xy 219.070425 -113.180015)
			(xy 219.082403 -113.242804) (xy 219.086417 -113.3066) (xy 219.082403 -113.370396) (xy 219.070425 -113.433185)
			(xy 219.050673 -113.493978) (xy 219.023457 -113.551817) (xy 218.989206 -113.605788) (xy 218.948462 -113.655041)
			(xy 218.901865 -113.698799) (xy 218.850152 -113.736372) (xy 218.794138 -113.767168) (xy 218.734705 -113.7907)
			(xy 218.672792 -113.806598) (xy 218.609375 -113.814611) (xy 218.577414 -113.815114) (xy 218.53525 -113.813336)
			(xy 218.524328 -113.812574) (xy 218.504262 -113.819686) (xy 218.433142 -113.887504) (xy 218.425014 -113.90757)
			(xy 218.425522 -113.918492) (xy 218.425776 -113.937796) (xy 218.425776 -113.938304) (xy 218.425282 -113.969025)
			(xy 218.417853 -114.030017) (xy 218.403128 -114.089669) (xy 218.381322 -114.147112) (xy 218.352752 -114.201509)
			(xy 218.317834 -114.252065) (xy 218.277079 -114.298046) (xy 218.23108 -114.33878) (xy 218.180506 -114.373674)
			(xy 218.126097 -114.402219) (xy 218.068644 -114.423998) (xy 218.065738 -114.424714) (xy 221.458028 -114.424714)
			(xy 221.458502 -114.393994) (xy 221.4659 -114.333) (xy 221.48059 -114.273341) (xy 221.502358 -114.215886)
			(xy 221.530887 -114.16147) (xy 221.547944 -114.135916) (xy 221.553322 -114.127224) (xy 221.557384 -114.107212)
			(xy 221.553331 -114.087198) (xy 221.547944 -114.078512) (xy 221.530889 -114.052956) (xy 221.502357 -113.998542)
			(xy 221.480586 -113.941087) (xy 221.465893 -113.881428) (xy 221.458491 -113.820435) (xy 221.458028 -113.789714)
			(xy 221.45853 -113.757753) (xy 221.466541 -113.694335) (xy 221.482438 -113.632421) (xy 221.50597 -113.572988)
			(xy 221.536764 -113.516973) (xy 221.574337 -113.465258) (xy 221.618094 -113.418661) (xy 221.667347 -113.377916)
			(xy 221.721318 -113.343665) (xy 221.779157 -113.316448) (xy 221.83995 -113.296695) (xy 221.90274 -113.284717)
			(xy 221.966536 -113.280704) (xy 222.030332 -113.284717) (xy 222.093122 -113.296695) (xy 222.153915 -113.316448)
			(xy 222.211754 -113.343665) (xy 222.265725 -113.377916) (xy 222.266431 -113.3785) (xy 251.373677 -113.3785)
			(xy 251.377691 -113.314706) (xy 251.389668 -113.251918) (xy 251.409419 -113.191126) (xy 251.436633 -113.133289)
			(xy 251.470882 -113.079318) (xy 251.511624 -113.030066) (xy 251.558218 -112.986307) (xy 251.609928 -112.948733)
			(xy 251.66594 -112.917936) (xy 251.72537 -112.894402) (xy 251.787281 -112.878501) (xy 251.850696 -112.870485)
			(xy 251.882656 -112.86998) (xy 251.917517 -112.870561) (xy 251.986584 -112.880092) (xy 252.053703 -112.898968)
			(xy 252.117613 -112.926835) (xy 252.177119 -112.963171) (xy 252.204474 -112.984788) (xy 252.21184 -112.990884)
			(xy 252.229874 -112.996726) (xy 252.31725 -112.991646) (xy 252.334522 -112.983772) (xy 252.341126 -112.977168)
			(xy 252.36513 -112.953424) (xy 252.418313 -112.911832) (xy 252.476534 -112.877644) (xy 252.538768 -112.851462)
			(xy 252.603919 -112.833748) (xy 252.670842 -112.824812) (xy 252.7046 -112.82426) (xy 252.736559 -112.824826)
			(xy 252.799973 -112.832837) (xy 252.861883 -112.848733) (xy 252.921313 -112.872262) (xy 252.932842 -112.8786)
			(xy 262.355284 -112.8786) (xy 262.359299 -112.8148) (xy 262.371278 -112.752006) (xy 262.391033 -112.691209)
			(xy 262.418253 -112.633367) (xy 262.452509 -112.579393) (xy 262.493259 -112.530139) (xy 262.539861 -112.48638)
			(xy 262.591581 -112.448808) (xy 262.647602 -112.418015) (xy 262.707041 -112.394486) (xy 262.76896 -112.378593)
			(xy 262.832383 -112.370586) (xy 262.864346 -112.370108) (xy 262.897063 -112.370617) (xy 262.961956 -112.379009)
			(xy 263.025235 -112.395661) (xy 263.085854 -112.420297) (xy 263.142809 -112.45251) (xy 263.195158 -112.491767)
			(xy 263.242035 -112.537418) (xy 263.282665 -112.588709) (xy 263.299956 -112.616488) (xy 263.304769 -112.623831)
			(xy 263.318332 -112.634959) (xy 263.33487 -112.640812) (xy 263.343644 -112.641126) (xy 263.430512 -112.641126)
			(xy 263.439277 -112.640789) (xy 263.455788 -112.634899) (xy 263.469363 -112.623806) (xy 263.4742 -112.616488)
			(xy 263.491481 -112.588703) (xy 263.532116 -112.537416) (xy 263.578996 -112.491768) (xy 263.631347 -112.452513)
			(xy 263.688303 -112.420301) (xy 263.748922 -112.395664) (xy 263.8122 -112.37901) (xy 263.877093 -112.370615)
			(xy 263.90981 -112.370108) (xy 263.910064 -112.370108) (xy 263.940273 -112.370501) (xy 264.000267 -112.377648)
			(xy 264.05899 -112.391858) (xy 264.115615 -112.41293) (xy 264.169341 -112.440567) (xy 264.219412 -112.474379)
			(xy 264.24255 -112.493806) (xy 264.249618 -112.499455) (xy 264.266532 -112.505841) (xy 264.27557 -112.506252)
			(xy 264.30605 -112.506252) (xy 264.315087 -112.505831) (xy 264.332003 -112.499454) (xy 264.33907 -112.493806)
			(xy 264.362204 -112.474378) (xy 264.412287 -112.440592) (xy 264.466019 -112.412973) (xy 264.522642 -112.391911)
			(xy 264.581361 -112.3777) (xy 264.641349 -112.370542) (xy 264.671556 -112.370108) (xy 264.67181 -112.370108)
			(xy 264.703959 -112.370634) (xy 264.767746 -112.378723) (xy 264.830003 -112.394796) (xy 264.889734 -112.418595)
			(xy 264.945985 -112.449741) (xy 264.997856 -112.487736) (xy 265.044519 -112.531972) (xy 265.065256 -112.556544)
			(xy 265.071709 -112.563807) (xy 265.088696 -112.573207) (xy 265.098276 -112.574832) (xy 265.168126 -112.583214)
			(xy 265.177852 -112.583924) (xy 265.196659 -112.578823) (xy 265.204702 -112.573308) (xy 265.204956 -112.573308)
			(xy 265.229885 -112.555391) (xy 265.284276 -112.526931) (xy 265.34252 -112.507541) (xy 265.403116 -112.49772)
			(xy 265.43381 -112.497108) (xy 265.434064 -112.497108) (xy 265.4593 -112.497476) (xy 265.509335 -112.504102)
			(xy 265.558056 -112.517284) (xy 265.604606 -112.536789) (xy 265.626596 -112.549178) (xy 265.636941 -112.554628)
			(xy 265.660235 -112.556361) (xy 265.681888 -112.547602) (xy 265.690096 -112.539272) (xy 265.710801 -112.516836)
			(xy 265.756694 -112.476572) (xy 265.807079 -112.442092) (xy 265.86123 -112.413894) (xy 265.918368 -112.392383)
			(xy 265.97767 -112.377869) (xy 266.038284 -112.370559) (xy 266.06881 -112.370108) (xy 266.100772 -112.370579)
			(xy 266.164191 -112.378591) (xy 266.226105 -112.39449) (xy 266.285539 -112.418022) (xy 266.341555 -112.448818)
			(xy 266.39327 -112.486392) (xy 266.439868 -112.530151) (xy 266.480613 -112.579405) (xy 266.514865 -112.633377)
			(xy 266.539049 -112.684771) (xy 275.041354 -112.684771) (xy 275.041354 -112.620849) (xy 275.049365 -112.557431)
			(xy 275.065262 -112.495517) (xy 275.088794 -112.436084) (xy 275.119588 -112.380069) (xy 275.157161 -112.328354)
			(xy 275.200918 -112.281757) (xy 275.250171 -112.241012) (xy 275.304142 -112.206761) (xy 275.361981 -112.179544)
			(xy 275.422774 -112.159791) (xy 275.485564 -112.147813) (xy 275.54936 -112.1438) (xy 275.613156 -112.147813)
			(xy 275.675946 -112.159791) (xy 275.736739 -112.179544) (xy 275.794578 -112.206761) (xy 275.848549 -112.241012)
			(xy 275.897802 -112.281757) (xy 275.941559 -112.328354) (xy 275.964113 -112.359397) (xy 298.790354 -112.359397)
			(xy 298.790354 -112.295475) (xy 298.798365 -112.232057) (xy 298.814262 -112.170143) (xy 298.837794 -112.11071)
			(xy 298.868588 -112.054695) (xy 298.906161 -112.00298) (xy 298.949918 -111.956383) (xy 298.999171 -111.915638)
			(xy 299.053142 -111.881387) (xy 299.110981 -111.85417) (xy 299.171774 -111.834417) (xy 299.234564 -111.822439)
			(xy 299.29836 -111.818426) (xy 299.362156 -111.822439) (xy 299.424946 -111.834417) (xy 299.485739 -111.85417)
			(xy 299.543578 -111.881387) (xy 299.597549 -111.915638) (xy 299.646802 -111.956383) (xy 299.690559 -112.00298)
			(xy 299.728132 -112.054695) (xy 299.758926 -112.11071) (xy 299.782458 -112.170143) (xy 299.798355 -112.232057)
			(xy 299.806366 -112.295475) (xy 299.806868 -112.327436) (xy 299.806366 -112.359397) (xy 299.798355 -112.422815)
			(xy 299.782458 -112.484729) (xy 299.758926 -112.544162) (xy 299.735502 -112.58677) (xy 315.194948 -112.58677)
			(xy 315.199019 -112.531148) (xy 315.211145 -112.476711) (xy 315.231068 -112.42462) (xy 315.258364 -112.375985)
			(xy 315.29245 -112.331842) (xy 315.332599 -112.293133) (xy 315.377957 -112.260682) (xy 315.427557 -112.235181)
			(xy 315.480341 -112.217174) (xy 315.535184 -112.207044) (xy 315.590918 -112.205007) (xy 315.646355 -112.211107)
			(xy 315.700312 -112.225213) (xy 315.751641 -112.247025) (xy 315.799247 -112.276079) (xy 315.842115 -112.311754)
			(xy 315.879332 -112.353291) (xy 315.910105 -112.399804) (xy 315.933777 -112.450301) (xy 315.949845 -112.503708)
			(xy 315.957965 -112.558884) (xy 315.958474 -112.58677) (xy 315.957965 -112.614656) (xy 315.949845 -112.669832)
			(xy 315.933777 -112.723239) (xy 315.910105 -112.773736) (xy 315.879332 -112.820249) (xy 315.842115 -112.861786)
			(xy 315.799247 -112.897461) (xy 315.751641 -112.926515) (xy 315.700312 -112.948327) (xy 315.646355 -112.962433)
			(xy 315.590918 -112.968533) (xy 315.535184 -112.966496) (xy 315.480341 -112.956366) (xy 315.427557 -112.938359)
			(xy 315.377957 -112.912858) (xy 315.332599 -112.880407) (xy 315.29245 -112.841698) (xy 315.258364 -112.797555)
			(xy 315.231068 -112.74892) (xy 315.211145 -112.696829) (xy 315.199019 -112.642392) (xy 315.194948 -112.58677)
			(xy 299.735502 -112.58677) (xy 299.728132 -112.600177) (xy 299.690559 -112.651892) (xy 299.646802 -112.698489)
			(xy 299.597549 -112.739234) (xy 299.543578 -112.773485) (xy 299.485739 -112.800702) (xy 299.424946 -112.820455)
			(xy 299.362156 -112.832433) (xy 299.29836 -112.836447) (xy 299.234564 -112.832433) (xy 299.171774 -112.820455)
			(xy 299.110981 -112.800702) (xy 299.053142 -112.773485) (xy 298.999171 -112.739234) (xy 298.949918 -112.698489)
			(xy 298.906161 -112.651892) (xy 298.868588 -112.600177) (xy 298.837794 -112.544162) (xy 298.814262 -112.484729)
			(xy 298.798365 -112.422815) (xy 298.790354 -112.359397) (xy 275.964113 -112.359397) (xy 275.979132 -112.380069)
			(xy 276.009926 -112.436084) (xy 276.033458 -112.495517) (xy 276.049355 -112.557431) (xy 276.057366 -112.620849)
			(xy 276.057868 -112.65281) (xy 276.057366 -112.684771) (xy 276.049355 -112.748189) (xy 276.033458 -112.810103)
			(xy 276.009926 -112.869536) (xy 275.979132 -112.925551) (xy 275.941559 -112.977266) (xy 275.897802 -113.023863)
			(xy 275.848549 -113.064608) (xy 275.794578 -113.098859) (xy 275.736739 -113.126076) (xy 275.675946 -113.145829)
			(xy 275.613156 -113.157807) (xy 275.54936 -113.161821) (xy 275.485564 -113.157807) (xy 275.422774 -113.145829)
			(xy 275.361981 -113.126076) (xy 275.304142 -113.098859) (xy 275.250171 -113.064608) (xy 275.200918 -113.023863)
			(xy 275.157161 -112.977266) (xy 275.119588 -112.925551) (xy 275.088794 -112.869536) (xy 275.065262 -112.810103)
			(xy 275.049365 -112.748189) (xy 275.041354 -112.684771) (xy 266.539049 -112.684771) (xy 266.542082 -112.691217)
			(xy 266.561835 -112.752012) (xy 266.573813 -112.814803) (xy 266.577827 -112.8786) (xy 266.573813 -112.942397)
			(xy 266.561835 -113.005188) (xy 266.542082 -113.065983) (xy 266.514865 -113.123823) (xy 266.480613 -113.177795)
			(xy 266.439868 -113.227049) (xy 266.39327 -113.270808) (xy 266.341555 -113.308382) (xy 266.285539 -113.339178)
			(xy 266.226105 -113.36271) (xy 266.164191 -113.378609) (xy 266.100772 -113.386621) (xy 266.06881 -113.387124)
			(xy 266.038284 -113.386658) (xy 265.977672 -113.37935) (xy 265.918371 -113.364836) (xy 265.861234 -113.343327)
			(xy 265.807083 -113.315131) (xy 265.756698 -113.280654) (xy 265.710804 -113.240392) (xy 265.690096 -113.21796)
			(xy 265.681889 -113.209644) (xy 265.660235 -113.200929) (xy 265.636956 -113.202649) (xy 265.626596 -113.208054)
			(xy 265.604586 -113.220398) (xy 265.55803 -113.23987) (xy 265.509318 -113.25305) (xy 265.459296 -113.259709)
			(xy 265.434064 -113.260124) (xy 265.43381 -113.260124) (xy 265.403117 -113.259514) (xy 265.342521 -113.249691)
			(xy 265.284278 -113.230298) (xy 265.22989 -113.201834) (xy 265.204956 -113.183924) (xy 265.204702 -113.183924)
			(xy 265.19669 -113.17835) (xy 265.17786 -113.17327) (xy 265.168126 -113.174018) (xy 265.098276 -113.1824)
			(xy 265.088712 -113.184072) (xy 265.071737 -113.193461) (xy 265.065256 -113.200688) (xy 265.044546 -113.225283)
			(xy 264.997869 -113.269507) (xy 264.945989 -113.307493) (xy 264.889735 -113.338637) (xy 264.830003 -113.36244)
			(xy 264.767747 -113.378524) (xy 264.70396 -113.386631) (xy 264.67181 -113.387124) (xy 264.671556 -113.387124)
			(xy 264.641347 -113.386712) (xy 264.581355 -113.379567) (xy 264.522632 -113.365361) (xy 264.466008 -113.344292)
			(xy 264.412281 -113.316659) (xy 264.362209 -113.282851) (xy 264.33907 -113.263426) (xy 264.332002 -113.257777)
			(xy 264.315088 -113.251393) (xy 264.30605 -113.25098) (xy 264.27557 -113.25098) (xy 264.266536 -113.251426)
			(xy 264.24962 -113.257787) (xy 264.24255 -113.263426) (xy 264.219399 -113.282834) (xy 264.169321 -113.316624)
			(xy 264.115593 -113.344247) (xy 264.058973 -113.365314) (xy 264.000257 -113.379528) (xy 263.94027 -113.386689)
			(xy 263.910064 -113.387124) (xy 263.90981 -113.387124) (xy 263.877093 -113.386635) (xy 263.812199 -113.378238)
			(xy 263.74892 -113.361582) (xy 263.688302 -113.336943) (xy 263.631347 -113.304727) (xy 263.578999 -113.265468)
			(xy 263.532121 -113.219815) (xy 263.491491 -113.168524) (xy 263.4742 -113.140744) (xy 263.469404 -113.133387)
			(xy 263.455835 -113.122259) (xy 263.439289 -113.116414) (xy 263.430512 -113.116106) (xy 263.343644 -113.116106)
			(xy 263.33488 -113.116444) (xy 263.318372 -113.12234) (xy 263.304797 -113.133429) (xy 263.299956 -113.140744)
			(xy 263.282649 -113.168511) (xy 263.242016 -113.219797) (xy 263.195138 -113.265445) (xy 263.142791 -113.3047)
			(xy 263.08584 -113.336914) (xy 263.025226 -113.361554) (xy 262.961951 -113.378212) (xy 262.897061 -113.386614)
			(xy 262.864346 -113.387124) (xy 262.832383 -113.386614) (xy 262.76896 -113.378607) (xy 262.707041 -113.362714)
			(xy 262.647602 -113.339185) (xy 262.591581 -113.308392) (xy 262.539861 -113.27082) (xy 262.493259 -113.227061)
			(xy 262.452509 -113.177807) (xy 262.418253 -113.123833) (xy 262.391033 -113.065991) (xy 262.371278 -113.005194)
			(xy 262.359299 -112.9424) (xy 262.355284 -112.8786) (xy 252.932842 -112.8786) (xy 252.977324 -112.903055)
			(xy 253.029035 -112.940625) (xy 253.075629 -112.98438) (xy 253.116372 -113.03363) (xy 253.150621 -113.087598)
			(xy 253.177836 -113.145433) (xy 253.197588 -113.206222) (xy 253.209565 -113.269008) (xy 253.213579 -113.3328)
			(xy 253.209565 -113.396592) (xy 253.197588 -113.459378) (xy 253.177836 -113.520167) (xy 253.150621 -113.578002)
			(xy 253.116372 -113.63197) (xy 253.075629 -113.68122) (xy 253.029035 -113.724975) (xy 252.977324 -113.762545)
			(xy 252.921313 -113.793338) (xy 252.861883 -113.816867) (xy 252.799973 -113.832763) (xy 252.736559 -113.840774)
			(xy 252.7046 -113.841276) (xy 252.669738 -113.84073) (xy 252.600668 -113.831192) (xy 252.53355 -113.812308)
			(xy 252.469639 -113.784433) (xy 252.410136 -113.748089) (xy 252.382782 -113.726468) (xy 252.375416 -113.720372)
			(xy 252.357382 -113.71453) (xy 252.270006 -113.71961) (xy 252.252734 -113.727484) (xy 252.24613 -113.734088)
			(xy 252.222139 -113.757845) (xy 252.168953 -113.799438) (xy 252.11073 -113.833625) (xy 252.048494 -113.859805)
			(xy 251.98334 -113.877516) (xy 251.916415 -113.886447) (xy 251.882656 -113.886996) (xy 251.850696 -113.886515)
			(xy 251.787281 -113.878499) (xy 251.72537 -113.862598) (xy 251.66594 -113.839064) (xy 251.609928 -113.808267)
			(xy 251.558218 -113.770693) (xy 251.511624 -113.726934) (xy 251.470882 -113.677682) (xy 251.436633 -113.623711)
			(xy 251.409419 -113.565874) (xy 251.389668 -113.505082) (xy 251.377691 -113.442294) (xy 251.373677 -113.3785)
			(xy 222.266431 -113.3785) (xy 222.314978 -113.418661) (xy 222.358735 -113.465258) (xy 222.396308 -113.516973)
			(xy 222.427102 -113.572988) (xy 222.450634 -113.632421) (xy 222.466531 -113.694335) (xy 222.474542 -113.757753)
			(xy 222.475044 -113.789714) (xy 222.474589 -113.820435) (xy 222.467188 -113.88143) (xy 222.452493 -113.941089)
			(xy 222.430721 -113.998544) (xy 222.402187 -114.052958) (xy 222.385128 -114.078512) (xy 222.382306 -114.083041)
			(xy 242.864126 -114.083041) (xy 242.864126 -114.019119) (xy 242.872137 -113.955701) (xy 242.888034 -113.893787)
			(xy 242.911566 -113.834354) (xy 242.94236 -113.778339) (xy 242.979933 -113.726624) (xy 243.02369 -113.680027)
			(xy 243.072943 -113.639282) (xy 243.126914 -113.605031) (xy 243.184753 -113.577814) (xy 243.245546 -113.558061)
			(xy 243.308336 -113.546083) (xy 243.372132 -113.54207) (xy 243.435928 -113.546083) (xy 243.498718 -113.558061)
			(xy 243.559511 -113.577814) (xy 243.61735 -113.605031) (xy 243.671321 -113.639282) (xy 243.720574 -113.680027)
			(xy 243.764331 -113.726624) (xy 243.801904 -113.778339) (xy 243.832698 -113.834354) (xy 243.85623 -113.893787)
			(xy 243.872127 -113.955701) (xy 243.880138 -114.019119) (xy 243.88064 -114.05108) (xy 243.880138 -114.083041)
			(xy 243.879945 -114.084565) (xy 249.264926 -114.084565) (xy 249.264926 -114.020643) (xy 249.272937 -113.957225)
			(xy 249.288834 -113.895311) (xy 249.312366 -113.835878) (xy 249.34316 -113.779863) (xy 249.380733 -113.728148)
			(xy 249.42449 -113.681551) (xy 249.473743 -113.640806) (xy 249.527714 -113.606555) (xy 249.585553 -113.579338)
			(xy 249.646346 -113.559585) (xy 249.709136 -113.547607) (xy 249.772932 -113.543594) (xy 249.836728 -113.547607)
			(xy 249.899518 -113.559585) (xy 249.960311 -113.579338) (xy 250.01815 -113.606555) (xy 250.072121 -113.640806)
			(xy 250.121374 -113.681551) (xy 250.165131 -113.728148) (xy 250.202704 -113.779863) (xy 250.233498 -113.835878)
			(xy 250.25703 -113.895311) (xy 250.272927 -113.957225) (xy 250.280938 -114.020643) (xy 250.28144 -114.052604)
			(xy 250.280938 -114.084565) (xy 250.272927 -114.147983) (xy 250.25703 -114.209897) (xy 250.233498 -114.26933)
			(xy 250.202704 -114.325345) (xy 250.165131 -114.37706) (xy 250.121374 -114.423657) (xy 250.072121 -114.464402)
			(xy 250.01815 -114.498653) (xy 249.960311 -114.52587) (xy 249.899518 -114.545623) (xy 249.836728 -114.557601)
			(xy 249.772932 -114.561615) (xy 249.709136 -114.557601) (xy 249.646346 -114.545623) (xy 249.585553 -114.52587)
			(xy 249.527714 -114.498653) (xy 249.473743 -114.464402) (xy 249.42449 -114.423657) (xy 249.380733 -114.37706)
			(xy 249.34316 -114.325345) (xy 249.312366 -114.26933) (xy 249.288834 -114.209897) (xy 249.272937 -114.147983)
			(xy 249.264926 -114.084565) (xy 243.879945 -114.084565) (xy 243.872127 -114.146459) (xy 243.85623 -114.208373)
			(xy 243.832698 -114.267806) (xy 243.801904 -114.323821) (xy 243.764331 -114.375536) (xy 243.720574 -114.422133)
			(xy 243.671321 -114.462878) (xy 243.61735 -114.497129) (xy 243.559511 -114.524346) (xy 243.498718 -114.544099)
			(xy 243.435928 -114.556077) (xy 243.372132 -114.560091) (xy 243.308336 -114.556077) (xy 243.245546 -114.544099)
			(xy 243.184753 -114.524346) (xy 243.126914 -114.497129) (xy 243.072943 -114.462878) (xy 243.02369 -114.422133)
			(xy 242.979933 -114.375536) (xy 242.94236 -114.323821) (xy 242.911566 -114.267806) (xy 242.888034 -114.208373)
			(xy 242.872137 -114.146459) (xy 242.864126 -114.083041) (xy 222.382306 -114.083041) (xy 222.379721 -114.08719)
			(xy 222.37566 -114.107212) (xy 222.37973 -114.127232) (xy 222.385128 -114.135916) (xy 222.402192 -114.161466)
			(xy 222.430723 -114.215882) (xy 222.452493 -114.273338) (xy 222.467184 -114.332998) (xy 222.474582 -114.393993)
			(xy 222.475044 -114.424714) (xy 222.47455 -114.455906) (xy 222.466904 -114.517819) (xy 222.451739 -114.578331)
			(xy 222.450151 -114.582448) (xy 259.414772 -114.582448) (xy 259.415283 -114.551718) (xy 259.422685 -114.490705)
			(xy 259.437389 -114.431029) (xy 259.459178 -114.37356) (xy 259.487736 -114.319137) (xy 259.522646 -114.268554)
			(xy 259.563399 -114.222547) (xy 259.6094 -114.181788) (xy 259.659979 -114.146871) (xy 259.714398 -114.118306)
			(xy 259.771864 -114.096509) (xy 259.831538 -114.081798) (xy 259.89255 -114.074387) (xy 259.92328 -114.07394)
			(xy 259.950458 -114.074702) (xy 259.959956 -114.074788) (xy 259.977964 -114.068787) (xy 259.98551 -114.063018)
			(xy 260.046216 -114.012726) (xy 260.05536 -113.995962) (xy 260.05663 -113.98631) (xy 260.061356 -113.953298)
			(xy 260.078473 -113.888841) (xy 260.103873 -113.827175) (xy 260.137118 -113.769361) (xy 260.177638 -113.716391)
			(xy 260.224737 -113.669174) (xy 260.277606 -113.628522) (xy 260.335337 -113.595133) (xy 260.396939 -113.56958)
			(xy 260.461354 -113.552303) (xy 260.527474 -113.543597) (xy 260.56082 -113.54308) (xy 260.591551 -113.543537)
			(xy 260.652565 -113.550948) (xy 260.71224 -113.565658) (xy 260.769707 -113.587454) (xy 260.824129 -113.616018)
			(xy 260.87471 -113.650934) (xy 260.920715 -113.691691) (xy 260.961471 -113.737696) (xy 260.996386 -113.788278)
			(xy 261.024949 -113.8427) (xy 261.046744 -113.900168) (xy 261.061454 -113.959843) (xy 261.068863 -114.020857)
			(xy 261.069328 -114.051588) (xy 261.068782 -114.085289) (xy 261.064514 -114.117331) (xy 269.402554 -114.117331)
			(xy 269.402554 -114.053409) (xy 269.410565 -113.989991) (xy 269.426462 -113.928077) (xy 269.449994 -113.868644)
			(xy 269.480788 -113.812629) (xy 269.518361 -113.760914) (xy 269.562118 -113.714317) (xy 269.611371 -113.673572)
			(xy 269.665342 -113.639321) (xy 269.723181 -113.612104) (xy 269.783974 -113.592351) (xy 269.846764 -113.580373)
			(xy 269.91056 -113.57636) (xy 269.974356 -113.580373) (xy 270.037146 -113.592351) (xy 270.097939 -113.612104)
			(xy 270.155778 -113.639321) (xy 270.209749 -113.673572) (xy 270.259002 -113.714317) (xy 270.298517 -113.756397)
			(xy 298.790354 -113.756397) (xy 298.790354 -113.692475) (xy 298.798365 -113.629057) (xy 298.814262 -113.567143)
			(xy 298.837794 -113.50771) (xy 298.868588 -113.451695) (xy 298.906161 -113.39998) (xy 298.949918 -113.353383)
			(xy 298.999171 -113.312638) (xy 299.053142 -113.278387) (xy 299.110981 -113.25117) (xy 299.171774 -113.231417)
			(xy 299.234564 -113.219439) (xy 299.29836 -113.215426) (xy 299.362156 -113.219439) (xy 299.424946 -113.231417)
			(xy 299.485739 -113.25117) (xy 299.543578 -113.278387) (xy 299.597549 -113.312638) (xy 299.646802 -113.353383)
			(xy 299.690559 -113.39998) (xy 299.728132 -113.451695) (xy 299.758926 -113.50771) (xy 299.782458 -113.567143)
			(xy 299.798355 -113.629057) (xy 299.806366 -113.692475) (xy 299.806868 -113.724436) (xy 299.806366 -113.756397)
			(xy 299.798355 -113.819815) (xy 299.792323 -113.843308) (xy 300.84979 -113.843308) (xy 300.853861 -113.787686)
			(xy 300.865987 -113.733249) (xy 300.88591 -113.681158) (xy 300.913206 -113.632523) (xy 300.947292 -113.58838)
			(xy 300.987441 -113.549671) (xy 301.032799 -113.51722) (xy 301.082399 -113.491719) (xy 301.135183 -113.473712)
			(xy 301.190026 -113.463582) (xy 301.24576 -113.461545) (xy 301.301197 -113.467645) (xy 301.355154 -113.481751)
			(xy 301.406483 -113.503563) (xy 301.454089 -113.532617) (xy 301.496957 -113.568292) (xy 301.527849 -113.60277)
			(xy 315.194948 -113.60277) (xy 315.199019 -113.547148) (xy 315.211145 -113.492711) (xy 315.231068 -113.44062)
			(xy 315.258364 -113.391985) (xy 315.29245 -113.347842) (xy 315.332599 -113.309133) (xy 315.377957 -113.276682)
			(xy 315.427557 -113.251181) (xy 315.480341 -113.233174) (xy 315.535184 -113.223044) (xy 315.590918 -113.221007)
			(xy 315.646355 -113.227107) (xy 315.700312 -113.241213) (xy 315.751641 -113.263025) (xy 315.799247 -113.292079)
			(xy 315.842115 -113.327754) (xy 315.879332 -113.369291) (xy 315.910105 -113.415804) (xy 315.933777 -113.466301)
			(xy 315.949845 -113.519708) (xy 315.957965 -113.574884) (xy 315.958474 -113.60277) (xy 315.957965 -113.630656)
			(xy 315.949845 -113.685832) (xy 315.933777 -113.739239) (xy 315.910105 -113.789736) (xy 315.879332 -113.836249)
			(xy 315.842115 -113.877786) (xy 315.799247 -113.913461) (xy 315.751641 -113.942515) (xy 315.700312 -113.964327)
			(xy 315.646355 -113.978433) (xy 315.590918 -113.984533) (xy 315.535184 -113.982496) (xy 315.480341 -113.972366)
			(xy 315.427557 -113.954359) (xy 315.377957 -113.928858) (xy 315.332599 -113.896407) (xy 315.29245 -113.857698)
			(xy 315.258364 -113.813555) (xy 315.231068 -113.76492) (xy 315.211145 -113.712829) (xy 315.199019 -113.658392)
			(xy 315.194948 -113.60277) (xy 301.527849 -113.60277) (xy 301.534174 -113.609829) (xy 301.564947 -113.656342)
			(xy 301.588619 -113.706839) (xy 301.604687 -113.760246) (xy 301.612807 -113.815422) (xy 301.613316 -113.843308)
			(xy 301.612807 -113.871194) (xy 301.604687 -113.92637) (xy 301.588619 -113.979777) (xy 301.564947 -114.030274)
			(xy 301.534174 -114.076787) (xy 301.496957 -114.118324) (xy 301.454089 -114.153999) (xy 301.406483 -114.183053)
			(xy 301.355154 -114.204865) (xy 301.301197 -114.218971) (xy 301.24576 -114.225071) (xy 301.190026 -114.223034)
			(xy 301.135183 -114.212904) (xy 301.082399 -114.194897) (xy 301.032799 -114.169396) (xy 300.987441 -114.136945)
			(xy 300.947292 -114.098236) (xy 300.913206 -114.054093) (xy 300.88591 -114.005458) (xy 300.865987 -113.953367)
			(xy 300.853861 -113.89893) (xy 300.84979 -113.843308) (xy 299.792323 -113.843308) (xy 299.782458 -113.881729)
			(xy 299.758926 -113.941162) (xy 299.728132 -113.997177) (xy 299.690559 -114.048892) (xy 299.646802 -114.095489)
			(xy 299.597549 -114.136234) (xy 299.543578 -114.170485) (xy 299.485739 -114.197702) (xy 299.424946 -114.217455)
			(xy 299.362156 -114.229433) (xy 299.29836 -114.233447) (xy 299.234564 -114.229433) (xy 299.171774 -114.217455)
			(xy 299.110981 -114.197702) (xy 299.053142 -114.170485) (xy 298.999171 -114.136234) (xy 298.949918 -114.095489)
			(xy 298.906161 -114.048892) (xy 298.868588 -113.997177) (xy 298.837794 -113.941162) (xy 298.814262 -113.881729)
			(xy 298.798365 -113.819815) (xy 298.790354 -113.756397) (xy 270.298517 -113.756397) (xy 270.302759 -113.760914)
			(xy 270.340332 -113.812629) (xy 270.371126 -113.868644) (xy 270.394658 -113.928077) (xy 270.410555 -113.989991)
			(xy 270.418566 -114.053409) (xy 270.419068 -114.08537) (xy 270.418566 -114.117331) (xy 270.410555 -114.180749)
			(xy 270.394658 -114.242663) (xy 270.371126 -114.302096) (xy 270.340332 -114.358111) (xy 270.302759 -114.409826)
			(xy 270.291557 -114.421755) (xy 370.378143 -114.421755) (xy 370.378143 -114.367245) (xy 370.385901 -114.31329)
			(xy 370.401259 -114.260988) (xy 370.423904 -114.211404) (xy 370.453376 -114.165548) (xy 370.489074 -114.124354)
			(xy 370.530271 -114.088659) (xy 370.576129 -114.059191) (xy 370.625714 -114.036549) (xy 370.678017 -114.021195)
			(xy 370.731973 -114.013441) (xy 370.759228 -114.01298) (xy 370.789921 -114.01359) (xy 370.850516 -114.023415)
			(xy 370.908758 -114.042809) (xy 370.963147 -114.071272) (xy 370.988082 -114.08918) (xy 370.988336 -114.08918)
			(xy 370.996366 -114.094724) (xy 371.015182 -114.099822) (xy 371.024912 -114.099086) (xy 371.094762 -114.090704)
			(xy 371.10433 -114.089048) (xy 371.121303 -114.079648) (xy 371.127782 -114.072416) (xy 371.148527 -114.047851)
			(xy 371.195198 -114.003626) (xy 371.247071 -113.965637) (xy 371.30332 -113.934489) (xy 371.363046 -113.910681)
			(xy 371.425297 -113.894591) (xy 371.48908 -113.886477) (xy 371.521228 -113.88598) (xy 371.553187 -113.886508)
			(xy 371.616601 -113.894522) (xy 371.678511 -113.910421) (xy 371.737939 -113.933953) (xy 371.79395 -113.964748)
			(xy 371.84566 -114.00232) (xy 371.892253 -114.046076) (xy 371.932995 -114.095327) (xy 371.967243 -114.149296)
			(xy 371.994457 -114.207131) (xy 372.014208 -114.267922) (xy 372.026185 -114.330708) (xy 372.030199 -114.3945)
			(xy 372.026185 -114.458292) (xy 372.014208 -114.521078) (xy 371.994457 -114.581869) (xy 371.967243 -114.639704)
			(xy 371.932995 -114.693673) (xy 371.892253 -114.742924) (xy 371.84566 -114.78668) (xy 371.79395 -114.824252)
			(xy 371.737939 -114.855047) (xy 371.678511 -114.878579) (xy 371.616601 -114.894478) (xy 371.553187 -114.902492)
			(xy 371.521228 -114.902996) (xy 371.489078 -114.902513) (xy 371.425289 -114.894416) (xy 371.363031 -114.878336)
			(xy 371.3033 -114.854529) (xy 371.247049 -114.823377) (xy 371.195179 -114.785376) (xy 371.148518 -114.741135)
			(xy 371.127782 -114.71656) (xy 371.121314 -114.709311) (xy 371.104338 -114.699903) (xy 371.094762 -114.698272)
			(xy 371.024912 -114.68989) (xy 371.015186 -114.6892) (xy 370.996381 -114.694287) (xy 370.988336 -114.699796)
			(xy 370.988082 -114.699796) (xy 370.963142 -114.717697) (xy 370.908755 -114.74616) (xy 370.850514 -114.765555)
			(xy 370.789921 -114.775381) (xy 370.759228 -114.775996) (xy 370.731973 -114.775559) (xy 370.678017 -114.767805)
			(xy 370.625714 -114.752451) (xy 370.576129 -114.729809) (xy 370.530271 -114.700341) (xy 370.489074 -114.664646)
			(xy 370.453376 -114.623452) (xy 370.423904 -114.577596) (xy 370.401259 -114.528012) (xy 370.385901 -114.47571)
			(xy 370.378143 -114.421755) (xy 270.291557 -114.421755) (xy 270.259002 -114.456423) (xy 270.209749 -114.497168)
			(xy 270.155778 -114.531419) (xy 270.097939 -114.558636) (xy 270.037146 -114.578389) (xy 269.974356 -114.590367)
			(xy 269.91056 -114.594381) (xy 269.846764 -114.590367) (xy 269.783974 -114.578389) (xy 269.723181 -114.558636)
			(xy 269.665342 -114.531419) (xy 269.611371 -114.497168) (xy 269.562118 -114.456423) (xy 269.518361 -114.409826)
			(xy 269.480788 -114.358111) (xy 269.449994 -114.302096) (xy 269.426462 -114.242663) (xy 269.410565 -114.180749)
			(xy 269.402554 -114.117331) (xy 261.064514 -114.117331) (xy 261.059883 -114.1521) (xy 261.042239 -114.217151)
			(xy 261.029704 -114.248438) (xy 261.025132 -114.25936) (xy 261.026402 -114.282474) (xy 261.07136 -114.362738)
			(xy 261.077545 -114.372556) (xy 261.096574 -114.385789) (xy 261.107936 -114.388138) (xy 261.10819 -114.388138)
			(xy 261.134919 -114.392676) (xy 261.186833 -114.408297) (xy 261.236013 -114.431112) (xy 261.281466 -114.46066)
			(xy 261.322279 -114.496346) (xy 261.357627 -114.53745) (xy 261.3868 -114.583146) (xy 261.409208 -114.632512)
			(xy 261.424402 -114.684553) (xy 261.432074 -114.738221) (xy 261.432548 -114.765328) (xy 261.432062 -114.792579)
			(xy 261.424306 -114.846527) (xy 261.408951 -114.898822) (xy 261.386309 -114.948399) (xy 261.356843 -114.994249)
			(xy 261.327667 -115.027921) (xy 264.509752 -115.027921) (xy 264.509752 -114.963999) (xy 264.517763 -114.900581)
			(xy 264.53366 -114.838667) (xy 264.557192 -114.779234) (xy 264.587986 -114.723219) (xy 264.625559 -114.671504)
			(xy 264.669316 -114.624907) (xy 264.718569 -114.584162) (xy 264.77254 -114.549911) (xy 264.830379 -114.522694)
			(xy 264.891172 -114.502941) (xy 264.953962 -114.490963) (xy 265.017758 -114.48695) (xy 265.081554 -114.490963)
			(xy 265.144344 -114.502941) (xy 265.205137 -114.522694) (xy 265.262976 -114.549911) (xy 265.316947 -114.584162)
			(xy 265.3662 -114.624907) (xy 265.409957 -114.671504) (xy 265.44753 -114.723219) (xy 265.478324 -114.779234)
			(xy 265.495245 -114.82197) (xy 282.559504 -114.82197) (xy 282.563575 -114.766348) (xy 282.575701 -114.711911)
			(xy 282.595624 -114.65982) (xy 282.62292 -114.611185) (xy 282.657006 -114.567042) (xy 282.697155 -114.528333)
			(xy 282.742513 -114.495882) (xy 282.792113 -114.470381) (xy 282.844897 -114.452374) (xy 282.89974 -114.442244)
			(xy 282.955474 -114.440207) (xy 283.010911 -114.446307) (xy 283.064868 -114.460413) (xy 283.116197 -114.482225)
			(xy 283.163803 -114.511279) (xy 283.206671 -114.546954) (xy 283.243888 -114.588491) (xy 283.274661 -114.635004)
			(xy 283.298333 -114.685501) (xy 283.314401 -114.738908) (xy 283.322521 -114.794084) (xy 283.32303 -114.82197)
			(xy 283.322521 -114.849856) (xy 283.314401 -114.905032) (xy 283.298333 -114.958439) (xy 283.274661 -115.008936)
			(xy 283.243888 -115.055449) (xy 283.206671 -115.096986) (xy 283.166966 -115.130029) (xy 298.76851 -115.130029)
			(xy 298.76851 -115.066107) (xy 298.776521 -115.002689) (xy 298.792418 -114.940775) (xy 298.81595 -114.881342)
			(xy 298.846744 -114.825327) (xy 298.884317 -114.773612) (xy 298.928074 -114.727015) (xy 298.977327 -114.68627)
			(xy 299.031298 -114.652019) (xy 299.089137 -114.624802) (xy 299.14993 -114.605049) (xy 299.21272 -114.593071)
			(xy 299.276516 -114.589058) (xy 299.340312 -114.593071) (xy 299.403102 -114.605049) (xy 299.463895 -114.624802)
			(xy 299.521734 -114.652019) (xy 299.575705 -114.68627) (xy 299.624958 -114.727015) (xy 299.668715 -114.773612)
			(xy 299.706288 -114.825327) (xy 299.737082 -114.881342) (xy 299.760614 -114.940775) (xy 299.776511 -115.002689)
			(xy 299.784522 -115.066107) (xy 299.785024 -115.098068) (xy 299.784522 -115.130029) (xy 299.776511 -115.193447)
			(xy 299.760614 -115.255361) (xy 299.737082 -115.314794) (xy 299.706288 -115.370809) (xy 299.668715 -115.422524)
			(xy 299.624958 -115.469121) (xy 299.575705 -115.509866) (xy 299.521734 -115.544117) (xy 299.463895 -115.571334)
			(xy 299.403102 -115.591087) (xy 299.340312 -115.603065) (xy 299.276516 -115.607079) (xy 299.21272 -115.603065)
			(xy 299.14993 -115.591087) (xy 299.089137 -115.571334) (xy 299.031298 -115.544117) (xy 298.977327 -115.509866)
			(xy 298.928074 -115.469121) (xy 298.884317 -115.422524) (xy 298.846744 -115.370809) (xy 298.81595 -115.314794)
			(xy 298.792418 -115.255361) (xy 298.776521 -115.193447) (xy 298.76851 -115.130029) (xy 283.166966 -115.130029)
			(xy 283.163803 -115.132661) (xy 283.116197 -115.161715) (xy 283.064868 -115.183527) (xy 283.010911 -115.197633)
			(xy 282.955474 -115.203733) (xy 282.89974 -115.201696) (xy 282.844897 -115.191566) (xy 282.792113 -115.173559)
			(xy 282.742513 -115.148058) (xy 282.697155 -115.115607) (xy 282.657006 -115.076898) (xy 282.62292 -115.032755)
			(xy 282.595624 -114.98412) (xy 282.575701 -114.932029) (xy 282.563575 -114.877592) (xy 282.559504 -114.82197)
			(xy 265.495245 -114.82197) (xy 265.501856 -114.838667) (xy 265.517753 -114.900581) (xy 265.525764 -114.963999)
			(xy 265.526266 -114.99596) (xy 265.525764 -115.027921) (xy 265.517753 -115.091339) (xy 265.501856 -115.153253)
			(xy 265.478324 -115.212686) (xy 265.44753 -115.268701) (xy 265.409957 -115.320416) (xy 265.3662 -115.367013)
			(xy 265.316947 -115.407758) (xy 265.262976 -115.442009) (xy 265.205137 -115.469226) (xy 265.144344 -115.488979)
			(xy 265.081554 -115.500957) (xy 265.017758 -115.504971) (xy 264.953962 -115.500957) (xy 264.891172 -115.488979)
			(xy 264.830379 -115.469226) (xy 264.77254 -115.442009) (xy 264.718569 -115.407758) (xy 264.669316 -115.367013)
			(xy 264.625559 -115.320416) (xy 264.587986 -115.268701) (xy 264.557192 -115.212686) (xy 264.53366 -115.153253)
			(xy 264.517763 -115.091339) (xy 264.509752 -115.027921) (xy 261.327667 -115.027921) (xy 261.321152 -115.03544)
			(xy 261.279961 -115.071131) (xy 261.234111 -115.100597) (xy 261.184534 -115.123239) (xy 261.132239 -115.138594)
			(xy 261.078291 -115.14635) (xy 261.023789 -115.14635) (xy 260.969841 -115.138594) (xy 260.917546 -115.123239)
			(xy 260.867969 -115.100597) (xy 260.822119 -115.071131) (xy 260.780928 -115.03544) (xy 260.745237 -114.994249)
			(xy 260.715771 -114.948399) (xy 260.693129 -114.898822) (xy 260.677774 -114.846527) (xy 260.670018 -114.792579)
			(xy 260.669532 -114.765328) (xy 260.669532 -114.765074) (xy 260.669813 -114.744462) (xy 260.674272 -114.703478)
			(xy 260.678422 -114.683286) (xy 260.678422 -114.683032) (xy 260.680387 -114.671619) (xy 260.674944 -114.649129)
			(xy 260.668008 -114.639852) (xy 260.6167 -114.57813) (xy 260.608811 -114.569608) (xy 260.587669 -114.560068)
			(xy 260.57606 -114.559842) (xy 260.56082 -114.560096) (xy 260.533642 -114.559334) (xy 260.524143 -114.55924)
			(xy 260.506135 -114.565246) (xy 260.49859 -114.571018) (xy 260.437884 -114.62131) (xy 260.42874 -114.638074)
			(xy 260.42747 -114.647726) (xy 260.423373 -114.676265) (xy 260.409583 -114.732249) (xy 260.389545 -114.786313)
			(xy 260.363518 -114.837761) (xy 260.331834 -114.885934) (xy 260.313678 -114.90833) (xy 260.307582 -114.915696)
			(xy 260.301232 -114.933984) (xy 260.306058 -115.013232) (xy 260.307057 -115.022763) (xy 260.315148 -115.040121)
			(xy 260.321806 -115.047014) (xy 260.32206 -115.047268) (xy 260.346733 -115.071379) (xy 260.390015 -115.125098)
			(xy 260.425634 -115.184176) (xy 260.452936 -115.247529) (xy 260.47142 -115.313993) (xy 260.480744 -115.382345)
			(xy 260.481318 -115.416838) (xy 260.480816 -115.448799) (xy 260.472805 -115.512217) (xy 260.456908 -115.574131)
			(xy 260.433376 -115.633564) (xy 260.402582 -115.689579) (xy 260.365009 -115.741294) (xy 260.321252 -115.787891)
			(xy 260.271999 -115.828636) (xy 260.218028 -115.862887) (xy 260.160189 -115.890104) (xy 260.099396 -115.909857)
			(xy 260.036606 -115.921835) (xy 259.97281 -115.925849) (xy 259.909014 -115.921835) (xy 259.846224 -115.909857)
			(xy 259.785431 -115.890104) (xy 259.727592 -115.862887) (xy 259.673621 -115.828636) (xy 259.624368 -115.787891)
			(xy 259.580611 -115.741294) (xy 259.543038 -115.689579) (xy 259.512244 -115.633564) (xy 259.488712 -115.574131)
			(xy 259.472815 -115.512217) (xy 259.464804 -115.448799) (xy 259.464302 -115.416838) (xy 259.46473 -115.387353)
			(xy 259.471538 -115.328778) (xy 259.485079 -115.271384) (xy 259.505171 -115.215943) (xy 259.531543 -115.1632)
			(xy 259.563842 -115.113862) (xy 259.582412 -115.090956) (xy 259.588508 -115.08359) (xy 259.594858 -115.065302)
			(xy 259.590032 -114.986054) (xy 259.589015 -114.976526) (xy 259.580934 -114.959169) (xy 259.574284 -114.952272)
			(xy 259.57403 -114.952018) (xy 259.549349 -114.927915) (xy 259.506068 -114.874195) (xy 259.47045 -114.815114)
			(xy 259.443149 -114.75176) (xy 259.424668 -114.685295) (xy 259.415345 -114.616941) (xy 259.414772 -114.582448)
			(xy 222.450151 -114.582448) (xy 222.429285 -114.636534) (xy 222.399878 -114.691552) (xy 222.363961 -114.742558)
			(xy 222.322073 -114.788787) (xy 222.298768 -114.809524) (xy 222.29208 -114.815901) (xy 222.283353 -114.832173)
			(xy 222.28175 -114.841274) (xy 222.273114 -114.908584) (xy 222.272265 -114.917864) (xy 222.27657 -114.935979)
			(xy 222.281496 -114.94389) (xy 222.297222 -114.967809) (xy 222.322091 -115.019367) (xy 222.338987 -115.074059)
			(xy 222.347532 -115.130661) (xy 222.348044 -115.159282) (xy 222.347558 -115.186533) (xy 222.339802 -115.240481)
			(xy 222.324447 -115.292776) (xy 222.324049 -115.293648) (xy 242.835938 -115.293648) (xy 242.83644 -115.261687)
			(xy 242.844451 -115.198269) (xy 242.860348 -115.136355) (xy 242.88388 -115.076922) (xy 242.914674 -115.020907)
			(xy 242.952247 -114.969192) (xy 242.996004 -114.922595) (xy 243.045257 -114.88185) (xy 243.099228 -114.847599)
			(xy 243.157067 -114.820382) (xy 243.21786 -114.800629) (xy 243.28065 -114.788651) (xy 243.344446 -114.784638)
			(xy 243.408242 -114.788651) (xy 243.471032 -114.800629) (xy 243.531825 -114.820382) (xy 243.589664 -114.847599)
			(xy 243.643635 -114.88185) (xy 243.692888 -114.922595) (xy 243.736645 -114.969192) (xy 243.774218 -115.020907)
			(xy 243.805012 -115.076922) (xy 243.828544 -115.136355) (xy 243.844441 -115.198269) (xy 243.852452 -115.261687)
			(xy 243.852954 -115.293648) (xy 243.852543 -115.323736) (xy 243.845431 -115.383491) (xy 243.831314 -115.441989)
			(xy 243.810388 -115.49841) (xy 243.801319 -115.516109) (xy 254.48488 -115.516109) (xy 254.48488 -115.452187)
			(xy 254.492891 -115.388769) (xy 254.508788 -115.326855) (xy 254.53232 -115.267422) (xy 254.563114 -115.211407)
			(xy 254.600687 -115.159692) (xy 254.644444 -115.113095) (xy 254.693697 -115.07235) (xy 254.747668 -115.038099)
			(xy 254.805507 -115.010882) (xy 254.8663 -114.991129) (xy 254.92909 -114.979151) (xy 254.992886 -114.975138)
			(xy 255.056682 -114.979151) (xy 255.119472 -114.991129) (xy 255.180265 -115.010882) (xy 255.238104 -115.038099)
			(xy 255.292075 -115.07235) (xy 255.341328 -115.113095) (xy 255.385085 -115.159692) (xy 255.422658 -115.211407)
			(xy 255.453452 -115.267422) (xy 255.476984 -115.326855) (xy 255.492881 -115.388769) (xy 255.500892 -115.452187)
			(xy 255.501394 -115.484148) (xy 255.500892 -115.516109) (xy 255.492881 -115.579527) (xy 255.476984 -115.641441)
			(xy 255.453452 -115.700874) (xy 255.422658 -115.756889) (xy 255.385085 -115.808604) (xy 255.341328 -115.855201)
			(xy 255.292075 -115.895946) (xy 255.238104 -115.930197) (xy 255.180265 -115.957414) (xy 255.119472 -115.977167)
			(xy 255.056682 -115.989145) (xy 254.992886 -115.993159) (xy 254.92909 -115.989145) (xy 254.8663 -115.977167)
			(xy 254.805507 -115.957414) (xy 254.747668 -115.930197) (xy 254.693697 -115.895946) (xy 254.644444 -115.855201)
			(xy 254.600687 -115.808604) (xy 254.563114 -115.756889) (xy 254.53232 -115.700874) (xy 254.508788 -115.641441)
			(xy 254.492891 -115.579527) (xy 254.48488 -115.516109) (xy 243.801319 -115.516109) (xy 243.782946 -115.551965)
			(xy 243.749372 -115.601906) (xy 243.710136 -115.647533) (xy 243.665788 -115.688207) (xy 243.641626 -115.706144)
			(xy 243.632077 -115.713869) (xy 243.621067 -115.735782) (xy 243.620544 -115.748054) (xy 243.621814 -115.843812)
			(xy 243.633752 -115.865656) (xy 243.643912 -115.872514) (xy 243.669232 -115.890293) (xy 243.715762 -115.931072)
			(xy 243.757001 -115.977196) (xy 243.792339 -116.027982) (xy 243.821255 -116.082679) (xy 243.843322 -116.140481)
			(xy 243.858213 -116.200533) (xy 243.865709 -116.261949) (xy 243.866039 -116.284459) (xy 258.370064 -116.284459)
			(xy 258.370064 -116.220537) (xy 258.378075 -116.157119) (xy 258.393972 -116.095205) (xy 258.417504 -116.035772)
			(xy 258.448298 -115.979757) (xy 258.485871 -115.928042) (xy 258.529628 -115.881445) (xy 258.578881 -115.8407)
			(xy 258.632852 -115.806449) (xy 258.690691 -115.779232) (xy 258.751484 -115.759479) (xy 258.814274 -115.747501)
			(xy 258.87807 -115.743488) (xy 258.941866 -115.747501) (xy 259.004656 -115.759479) (xy 259.065449 -115.779232)
			(xy 259.123288 -115.806449) (xy 259.177259 -115.8407) (xy 259.226512 -115.881445) (xy 259.270269 -115.928042)
			(xy 259.307842 -115.979757) (xy 259.338636 -116.035772) (xy 259.362168 -116.095205) (xy 259.378065 -116.157119)
			(xy 259.386076 -116.220537) (xy 259.386578 -116.252498) (xy 259.386076 -116.284459) (xy 259.378065 -116.347877)
			(xy 259.363827 -116.403331) (xy 268.040098 -116.403331) (xy 268.040098 -116.339409) (xy 268.048109 -116.275991)
			(xy 268.064006 -116.214077) (xy 268.087538 -116.154644) (xy 268.118332 -116.098629) (xy 268.155905 -116.046914)
			(xy 268.199662 -116.000317) (xy 268.248915 -115.959572) (xy 268.302886 -115.925321) (xy 268.360725 -115.898104)
			(xy 268.421518 -115.878351) (xy 268.484308 -115.866373) (xy 268.548104 -115.86236) (xy 268.6119 -115.866373)
			(xy 268.67469 -115.878351) (xy 268.735483 -115.898104) (xy 268.793322 -115.925321) (xy 268.847293 -115.959572)
			(xy 268.896546 -116.000317) (xy 268.940303 -116.046914) (xy 268.977876 -116.098629) (xy 269.00867 -116.154644)
			(xy 269.032202 -116.214077) (xy 269.048099 -116.275991) (xy 269.05611 -116.339409) (xy 269.056612 -116.37137)
			(xy 269.05611 -116.403331) (xy 269.048099 -116.466749) (xy 269.032202 -116.528663) (xy 269.00867 -116.588096)
			(xy 268.977876 -116.644111) (xy 268.940303 -116.695826) (xy 268.896546 -116.742423) (xy 268.847293 -116.783168)
			(xy 268.793322 -116.817419) (xy 268.735483 -116.844636) (xy 268.67469 -116.864389) (xy 268.6119 -116.876367)
			(xy 268.548104 -116.880381) (xy 268.484308 -116.876367) (xy 268.421518 -116.864389) (xy 268.360725 -116.844636)
			(xy 268.302886 -116.817419) (xy 268.248915 -116.783168) (xy 268.199662 -116.742423) (xy 268.155905 -116.695826)
			(xy 268.118332 -116.644111) (xy 268.087538 -116.588096) (xy 268.064006 -116.528663) (xy 268.048109 -116.466749)
			(xy 268.040098 -116.403331) (xy 259.363827 -116.403331) (xy 259.362168 -116.409791) (xy 259.338636 -116.469224)
			(xy 259.307842 -116.525239) (xy 259.270269 -116.576954) (xy 259.226512 -116.623551) (xy 259.177259 -116.664296)
			(xy 259.123288 -116.698547) (xy 259.065449 -116.725764) (xy 259.004656 -116.745517) (xy 258.941866 -116.757495)
			(xy 258.87807 -116.761509) (xy 258.814274 -116.757495) (xy 258.751484 -116.745517) (xy 258.690691 -116.725764)
			(xy 258.632852 -116.698547) (xy 258.578881 -116.664296) (xy 258.529628 -116.623551) (xy 258.485871 -116.576954)
			(xy 258.448298 -116.525239) (xy 258.417504 -116.469224) (xy 258.393972 -116.409791) (xy 258.378075 -116.347877)
			(xy 258.370064 -116.284459) (xy 243.866039 -116.284459) (xy 243.866162 -116.292884) (xy 243.86566 -116.324845)
			(xy 243.857649 -116.388263) (xy 243.841752 -116.450177) (xy 243.81822 -116.50961) (xy 243.787426 -116.565625)
			(xy 243.749853 -116.61734) (xy 243.706096 -116.663937) (xy 243.656843 -116.704682) (xy 243.602872 -116.738933)
			(xy 243.545033 -116.76615) (xy 243.48424 -116.785903) (xy 243.42145 -116.797881) (xy 243.357654 -116.801895)
			(xy 243.293858 -116.797881) (xy 243.231068 -116.785903) (xy 243.170275 -116.76615) (xy 243.112436 -116.738933)
			(xy 243.058465 -116.704682) (xy 243.009212 -116.663937) (xy 242.965455 -116.61734) (xy 242.927882 -116.565625)
			(xy 242.897088 -116.50961) (xy 242.873556 -116.450177) (xy 242.857659 -116.388263) (xy 242.849648 -116.324845)
			(xy 242.849146 -116.292884) (xy 242.849582 -116.262796) (xy 242.856689 -116.203042) (xy 242.870803 -116.144545)
			(xy 242.891725 -116.088124) (xy 242.919164 -116.034569) (xy 242.952735 -115.984628) (xy 242.991967 -115.939001)
			(xy 243.036314 -115.898325) (xy 243.060474 -115.880388) (xy 243.070008 -115.872648) (xy 243.081026 -115.850747)
			(xy 243.081556 -115.838478) (xy 243.080286 -115.74272) (xy 243.068348 -115.720876) (xy 243.058188 -115.714018)
			(xy 243.032883 -115.696219) (xy 242.986353 -115.655442) (xy 242.945113 -115.609322) (xy 242.909774 -115.558539)
			(xy 242.880855 -115.503844) (xy 242.858786 -115.446045) (xy 242.843892 -115.385996) (xy 242.836393 -115.324583)
			(xy 242.835938 -115.293648) (xy 222.324049 -115.293648) (xy 222.301805 -115.342353) (xy 222.272339 -115.388203)
			(xy 222.236648 -115.429394) (xy 222.195457 -115.465085) (xy 222.149607 -115.494551) (xy 222.10003 -115.517193)
			(xy 222.047735 -115.532548) (xy 221.993787 -115.540304) (xy 221.939285 -115.540304) (xy 221.885337 -115.532548)
			(xy 221.833042 -115.517193) (xy 221.783465 -115.494551) (xy 221.737615 -115.465085) (xy 221.696424 -115.429394)
			(xy 221.660733 -115.388203) (xy 221.631267 -115.342353) (xy 221.608625 -115.292776) (xy 221.59327 -115.240481)
			(xy 221.585514 -115.186533) (xy 221.585028 -115.159282) (xy 221.585532 -115.13066) (xy 221.594071 -115.074057)
			(xy 221.610969 -115.019364) (xy 221.635848 -114.967809) (xy 221.651576 -114.94389) (xy 221.656477 -114.935972)
			(xy 221.660762 -114.917863) (xy 221.659958 -114.908584) (xy 221.650052 -114.831876) (xy 221.641416 -114.815874)
			(xy 221.634558 -114.809778) (xy 221.63405 -114.80927) (xy 221.610758 -114.788555) (xy 221.568921 -114.742346)
			(xy 221.53305 -114.691366) (xy 221.503684 -114.636381) (xy 221.481265 -114.578218) (xy 221.466128 -114.517748)
			(xy 221.458502 -114.455882) (xy 221.458028 -114.424714) (xy 218.065738 -114.424714) (xy 218.008985 -114.438696)
			(xy 217.947989 -114.446096) (xy 217.917268 -114.446558) (xy 217.885311 -114.445954) (xy 217.821903 -114.43794)
			(xy 217.759998 -114.422042) (xy 217.700574 -114.398511) (xy 217.644568 -114.367719) (xy 217.592863 -114.330149)
			(xy 217.546273 -114.286396) (xy 217.505535 -114.237149) (xy 217.47129 -114.183185) (xy 217.444078 -114.125354)
			(xy 217.424328 -114.064568) (xy 217.412352 -114.001787) (xy 217.408339 -113.938) (xy 214.584325 -113.938)
			(xy 214.585556 -113.947745) (xy 214.586058 -113.979706) (xy 214.58557 -114.010993) (xy 214.577897 -114.073096)
			(xy 214.562657 -114.133787) (xy 214.54008 -114.192146) (xy 214.510508 -114.247292) (xy 214.474387 -114.298389)
			(xy 214.432266 -114.344664) (xy 214.384781 -114.385417) (xy 214.358982 -114.403124) (xy 214.348846 -114.410664)
			(xy 214.336975 -114.432924) (xy 214.336376 -114.445542) (xy 214.336376 -114.52987) (xy 214.337013 -114.542477)
			(xy 214.348875 -114.564725) (xy 214.358982 -114.572288) (xy 214.384794 -114.589976) (xy 214.432272 -114.630737)
			(xy 214.474388 -114.677018) (xy 214.510504 -114.728119) (xy 214.540075 -114.783266) (xy 214.562654 -114.841626)
			(xy 214.570403 -114.872473) (xy 215.010994 -114.872473) (xy 215.010994 -114.808551) (xy 215.019005 -114.745133)
			(xy 215.034902 -114.683219) (xy 215.058434 -114.623786) (xy 215.089228 -114.567771) (xy 215.126801 -114.516056)
			(xy 215.170558 -114.469459) (xy 215.219811 -114.428714) (xy 215.273782 -114.394463) (xy 215.331621 -114.367246)
			(xy 215.392414 -114.347493) (xy 215.455204 -114.335515) (xy 215.519 -114.331502) (xy 215.582796 -114.335515)
			(xy 215.645586 -114.347493) (xy 215.706379 -114.367246) (xy 215.764218 -114.394463) (xy 215.818189 -114.428714)
			(xy 215.867442 -114.469459) (xy 215.911199 -114.516056) (xy 215.948772 -114.567771) (xy 215.979566 -114.623786)
			(xy 216.003098 -114.683219) (xy 216.018995 -114.745133) (xy 216.027006 -114.808551) (xy 216.027508 -114.840512)
			(xy 216.027006 -114.872473) (xy 216.018995 -114.935891) (xy 216.003098 -114.997805) (xy 215.979566 -115.057238)
			(xy 215.948772 -115.113253) (xy 215.911199 -115.164968) (xy 215.867442 -115.211565) (xy 215.818189 -115.25231)
			(xy 215.764218 -115.286561) (xy 215.706379 -115.313778) (xy 215.645586 -115.333531) (xy 215.582796 -115.345509)
			(xy 215.519 -115.349523) (xy 215.455204 -115.345509) (xy 215.392414 -115.333531) (xy 215.331621 -115.313778)
			(xy 215.273782 -115.286561) (xy 215.219811 -115.25231) (xy 215.170558 -115.211565) (xy 215.126801 -115.164968)
			(xy 215.089228 -115.113253) (xy 215.058434 -115.057238) (xy 215.034902 -114.997805) (xy 215.019005 -114.935891)
			(xy 215.010994 -114.872473) (xy 214.570403 -114.872473) (xy 214.577899 -114.902316) (xy 214.585579 -114.964418)
			(xy 214.586058 -114.995706) (xy 214.585556 -115.027667) (xy 214.577545 -115.091085) (xy 214.561648 -115.152999)
			(xy 214.538116 -115.212432) (xy 214.507322 -115.268447) (xy 214.469749 -115.320162) (xy 214.425992 -115.366759)
			(xy 214.376739 -115.407504) (xy 214.322768 -115.441755) (xy 214.264929 -115.468972) (xy 214.204136 -115.488725)
			(xy 214.141346 -115.500703) (xy 214.07755 -115.504717) (xy 214.013754 -115.500703) (xy 213.950964 -115.488725)
			(xy 213.890171 -115.468972) (xy 213.832332 -115.441755) (xy 213.778361 -115.407504) (xy 213.729108 -115.366759)
			(xy 213.685351 -115.320162) (xy 213.647778 -115.268447) (xy 213.616984 -115.212432) (xy 213.593452 -115.152999)
			(xy 213.577555 -115.091085) (xy 213.569544 -115.027667) (xy 213.569042 -114.995706) (xy 202.866398 -114.995706)
			(xy 202.856725 -115.006333) (xy 202.809239 -115.047087) (xy 202.78344 -115.064794) (xy 202.773311 -115.072341)
			(xy 202.761439 -115.094596) (xy 202.760834 -115.107212) (xy 202.760834 -115.19154) (xy 202.761506 -115.204142)
			(xy 202.773344 -115.226389) (xy 202.78344 -115.233958) (xy 202.809229 -115.251679) (xy 202.856709 -115.292434)
			(xy 202.898827 -115.33871) (xy 202.934946 -115.389805) (xy 202.964521 -115.444948) (xy 202.987103 -115.503304)
			(xy 203.002351 -115.56399) (xy 203.010035 -115.62609) (xy 203.010516 -115.657376) (xy 203.51699 -115.657376)
			(xy 203.521061 -115.601754) (xy 203.533187 -115.547317) (xy 203.55311 -115.495226) (xy 203.580406 -115.446591)
			(xy 203.614492 -115.402448) (xy 203.654641 -115.363739) (xy 203.699999 -115.331288) (xy 203.749599 -115.305787)
			(xy 203.802383 -115.28778) (xy 203.857226 -115.27765) (xy 203.91296 -115.275613) (xy 203.968397 -115.281713)
			(xy 204.022354 -115.295819) (xy 204.073683 -115.317631) (xy 204.121289 -115.346685) (xy 204.164157 -115.38236)
			(xy 204.201374 -115.423897) (xy 204.232147 -115.47041) (xy 204.255819 -115.520907) (xy 204.271887 -115.574314)
			(xy 204.280007 -115.62949) (xy 204.280516 -115.657376) (xy 204.280007 -115.685262) (xy 204.271887 -115.740438)
			(xy 204.255819 -115.793845) (xy 204.232147 -115.844342) (xy 204.201374 -115.890855) (xy 204.164157 -115.932392)
			(xy 204.121289 -115.968067) (xy 204.073683 -115.997121) (xy 204.022354 -116.018933) (xy 203.968397 -116.033039)
			(xy 203.91296 -116.039139) (xy 203.857226 -116.037102) (xy 203.802383 -116.026972) (xy 203.749599 -116.008965)
			(xy 203.699999 -115.983464) (xy 203.654641 -115.951013) (xy 203.614492 -115.912304) (xy 203.580406 -115.868161)
			(xy 203.55311 -115.819526) (xy 203.533187 -115.767435) (xy 203.521061 -115.712998) (xy 203.51699 -115.657376)
			(xy 203.010516 -115.657376) (xy 203.010014 -115.689337) (xy 203.002003 -115.752755) (xy 202.986106 -115.814669)
			(xy 202.962574 -115.874102) (xy 202.93178 -115.930117) (xy 202.894207 -115.981832) (xy 202.85045 -116.028429)
			(xy 202.801197 -116.069174) (xy 202.747226 -116.103425) (xy 202.689387 -116.130642) (xy 202.628594 -116.150395)
			(xy 202.565804 -116.162373) (xy 202.502008 -116.166387) (xy 202.438212 -116.162373) (xy 202.375422 -116.150395)
			(xy 202.314629 -116.130642) (xy 202.25679 -116.103425) (xy 202.202819 -116.069174) (xy 202.153566 -116.028429)
			(xy 202.109809 -115.981832) (xy 202.072236 -115.930117) (xy 202.041442 -115.874102) (xy 202.01791 -115.814669)
			(xy 202.002013 -115.752755) (xy 201.994002 -115.689337) (xy 201.9935 -115.657376) (xy 201.993993 -115.626089)
			(xy 202.001667 -115.563987) (xy 202.016908 -115.503298) (xy 202.039485 -115.444938) (xy 202.069057 -115.389793)
			(xy 202.105176 -115.338696) (xy 202.147295 -115.29242) (xy 202.194778 -115.251666) (xy 202.220576 -115.233958)
			(xy 202.23073 -115.226439) (xy 202.242589 -115.204163) (xy 202.243182 -115.19154) (xy 202.243182 -115.107212)
			(xy 202.242533 -115.094608) (xy 202.230677 -115.072361) (xy 202.220576 -115.064794) (xy 202.194769 -115.047099)
			(xy 202.147288 -115.00634) (xy 202.10517 -114.960061) (xy 202.069052 -114.908962) (xy 202.03948 -114.853816)
			(xy 202.016901 -114.795456) (xy 202.001657 -114.734766) (xy 201.993978 -114.672664) (xy 201.9935 -114.641376)
			(xy 201.993991 -114.610523) (xy 202.00145 -114.54927) (xy 202.016266 -114.489369) (xy 202.038223 -114.431702)
			(xy 202.066997 -114.377117) (xy 202.102166 -114.326414) (xy 202.143213 -114.28034) (xy 202.189533 -114.239573)
			(xy 202.214734 -114.221768) (xy 202.225148 -114.214656) (xy 202.236832 -114.19205) (xy 202.235562 -114.081814)
			(xy 202.223116 -114.059462) (xy 202.212448 -114.052604) (xy 202.186024 -114.035041) (xy 202.137386 -113.994296)
			(xy 202.094197 -113.947814) (xy 202.057129 -113.896318) (xy 202.026758 -113.840609) (xy 202.003558 -113.781553)
			(xy 201.987888 -113.720068) (xy 201.979993 -113.657112) (xy 198.697601 -113.657112) (xy 198.690425 -113.704729)
			(xy 198.674715 -113.755659) (xy 198.651589 -113.80368) (xy 198.621565 -113.847717) (xy 198.585313 -113.886788)
			(xy 198.543642 -113.920019) (xy 198.497484 -113.946668) (xy 198.44787 -113.96614) (xy 198.395908 -113.978)
			(xy 198.342758 -113.981984) (xy 198.289608 -113.978) (xy 198.237646 -113.96614) (xy 198.188032 -113.946668)
			(xy 198.141874 -113.920019) (xy 198.100203 -113.886788) (xy 198.063951 -113.847717) (xy 198.033927 -113.80368)
			(xy 198.010801 -113.755659) (xy 197.995091 -113.704729) (xy 197.987148 -113.652025) (xy 196.528944 -113.652025)
			(xy 196.528944 -114.3889) (xy 196.529706 -114.397536) (xy 196.531738 -114.40541) (xy 196.537072 -114.420904)
			(xy 196.541136 -114.429794) (xy 196.544438 -114.435128) (xy 196.561234 -114.458409) (xy 196.58795 -114.509216)
			(xy 196.606182 -114.563647) (xy 196.615458 -114.620295) (xy 196.615905 -114.6414) (xy 198.621168 -114.6414)
			(xy 198.625151 -114.588251) (xy 198.63701 -114.536289) (xy 198.656481 -114.486674) (xy 198.683128 -114.440516)
			(xy 198.716357 -114.398844) (xy 198.755425 -114.362589) (xy 198.79946 -114.332562) (xy 198.847478 -114.309433)
			(xy 198.898407 -114.293718) (xy 198.951109 -114.285769) (xy 198.977758 -114.285268) (xy 199.004061 -114.285732)
			(xy 199.056094 -114.293486) (xy 199.106423 -114.3088) (xy 199.153955 -114.331344) (xy 199.197659 -114.360627)
			(xy 199.236586 -114.396014) (xy 199.253602 -114.416078) (xy 199.261476 -114.425984) (xy 199.285098 -114.43589)
			(xy 199.381872 -114.426492) (xy 199.394303 -114.424671) (xy 199.41522 -114.410809) (xy 199.42175 -114.400076)
			(xy 199.436529 -114.373488) (xy 199.471573 -114.323762) (xy 199.512302 -114.278574) (xy 199.558132 -114.23857)
			(xy 199.60841 -114.204322) (xy 199.662415 -114.176319) (xy 199.719377 -114.154962) (xy 199.778481 -114.140557)
			(xy 199.838881 -114.133308) (xy 199.869298 -114.132868) (xy 199.900028 -114.133358) (xy 199.96104 -114.140766)
			(xy 200.020714 -114.155473) (xy 200.078181 -114.177267) (xy 200.132601 -114.205828) (xy 200.183183 -114.24074)
			(xy 200.229187 -114.281494) (xy 200.269944 -114.327497) (xy 200.304859 -114.378076) (xy 200.333423 -114.432495)
			(xy 200.355219 -114.489961) (xy 200.36993 -114.549634) (xy 200.377341 -114.610646) (xy 200.377806 -114.641376)
			(xy 200.377421 -114.672118) (xy 200.37001 -114.733154) (xy 200.355293 -114.792851) (xy 200.333485 -114.850337)
			(xy 200.304903 -114.904775) (xy 200.269966 -114.955368) (xy 200.229183 -115.00138) (xy 200.18315 -115.042137)
			(xy 200.132537 -115.077047) (xy 200.105518 -115.091718) (xy 200.093072 -115.098068) (xy 200.078594 -115.121182)
			(xy 200.075038 -115.23726) (xy 200.088246 -115.26139) (xy 200.09993 -115.268502) (xy 200.12752 -115.285836)
			(xy 200.178412 -115.326526) (xy 200.223691 -115.373383) (xy 200.262614 -115.42564) (xy 200.294544 -115.48244)
			(xy 200.318957 -115.542853) (xy 200.335454 -115.605889) (xy 200.343764 -115.670516) (xy 200.344278 -115.703096)
			(xy 200.343822 -115.733755) (xy 200.336448 -115.794627) (xy 200.321808 -115.854171) (xy 200.300112 -115.911522)
			(xy 200.271678 -115.965848) (xy 200.236916 -116.01636) (xy 200.196332 -116.062325) (xy 200.150515 -116.103076)
			(xy 200.125584 -116.120926) (xy 200.115604 -116.128612) (xy 200.10414 -116.151007) (xy 200.10374 -116.163598)
			(xy 200.105264 -116.247926) (xy 200.10613 -116.260497) (xy 200.118402 -116.282476) (xy 200.128632 -116.289836)
			(xy 200.155084 -116.307439) (xy 200.203821 -116.348208) (xy 200.2471 -116.39473) (xy 200.284249 -116.44628)
			(xy 200.314687 -116.502056) (xy 200.337941 -116.561188) (xy 200.35365 -116.622756) (xy 200.360007 -116.673376)
			(xy 202.11999 -116.673376) (xy 202.124061 -116.617754) (xy 202.136187 -116.563317) (xy 202.15611 -116.511226)
			(xy 202.183406 -116.462591) (xy 202.217492 -116.418448) (xy 202.257641 -116.379739) (xy 202.302999 -116.347288)
			(xy 202.352599 -116.321787) (xy 202.405383 -116.30378) (xy 202.460226 -116.29365) (xy 202.51596 -116.291613)
			(xy 202.571397 -116.297713) (xy 202.625354 -116.311819) (xy 202.676683 -116.333631) (xy 202.724289 -116.362685)
			(xy 202.767157 -116.39836) (xy 202.804374 -116.439897) (xy 202.835147 -116.48641) (xy 202.858819 -116.536907)
			(xy 202.874887 -116.590314) (xy 202.883007 -116.64549) (xy 202.883516 -116.673376) (xy 202.883007 -116.701262)
			(xy 202.874887 -116.756438) (xy 202.858819 -116.809845) (xy 202.835147 -116.860342) (xy 202.804374 -116.906855)
			(xy 202.767157 -116.948392) (xy 202.724289 -116.984067) (xy 202.676683 -117.013121) (xy 202.625354 -117.034933)
			(xy 202.571397 -117.049039) (xy 202.51596 -117.055139) (xy 202.460226 -117.053102) (xy 202.405383 -117.042972)
			(xy 202.352599 -117.024965) (xy 202.302999 -116.999464) (xy 202.257641 -116.967013) (xy 202.217492 -116.928304)
			(xy 202.183406 -116.884161) (xy 202.15611 -116.835526) (xy 202.136187 -116.783435) (xy 202.124061 -116.728998)
			(xy 202.11999 -116.673376) (xy 200.360007 -116.673376) (xy 200.361567 -116.685802) (xy 200.362058 -116.717572)
			(xy 200.361556 -116.749533) (xy 200.353545 -116.812951) (xy 200.337648 -116.874865) (xy 200.314116 -116.934298)
			(xy 200.283322 -116.990313) (xy 200.245749 -117.042028) (xy 200.201992 -117.088625) (xy 200.152739 -117.12937)
			(xy 200.098768 -117.163621) (xy 200.040929 -117.190838) (xy 199.980136 -117.210591) (xy 199.917346 -117.222569)
			(xy 199.85355 -117.226583) (xy 199.789754 -117.222569) (xy 199.726964 -117.210591) (xy 199.666171 -117.190838)
			(xy 199.608332 -117.163621) (xy 199.554361 -117.12937) (xy 199.505108 -117.088625) (xy 199.461351 -117.042028)
			(xy 199.423778 -116.990313) (xy 199.392984 -116.934298) (xy 199.369452 -116.874865) (xy 199.353555 -116.812951)
			(xy 199.345544 -116.749533) (xy 199.345042 -116.717572) (xy 199.345508 -116.686914) (xy 199.352884 -116.626043)
			(xy 199.367525 -116.5665) (xy 199.38922 -116.50915) (xy 199.417654 -116.454825) (xy 199.452413 -116.404313)
			(xy 199.492994 -116.358347) (xy 199.538807 -116.317594) (xy 199.563736 -116.299742) (xy 199.573735 -116.292076)
			(xy 199.585188 -116.269665) (xy 199.58558 -116.25707) (xy 199.584056 -116.172742) (xy 199.583141 -116.160179)
			(xy 199.570903 -116.138199) (xy 199.560688 -116.130832) (xy 199.534249 -116.113211) (xy 199.485515 -116.072441)
			(xy 199.442238 -116.025921) (xy 199.40509 -115.974373) (xy 199.374651 -115.918601) (xy 199.351394 -115.859472)
			(xy 199.335681 -115.797907) (xy 199.327757 -115.734865) (xy 199.327262 -115.703096) (xy 199.327723 -115.672356)
			(xy 199.335125 -115.611324) (xy 199.349833 -115.55163) (xy 199.371632 -115.494145) (xy 199.400204 -115.439708)
			(xy 199.435131 -115.389114) (xy 199.475905 -115.343101) (xy 199.52193 -115.30234) (xy 199.572535 -115.267427)
			(xy 199.59955 -115.252754) (xy 199.611996 -115.246404) (xy 199.626474 -115.22329) (xy 199.63003 -115.107212)
			(xy 199.616822 -115.083082) (xy 199.605138 -115.07597) (xy 199.576611 -115.057994) (xy 199.524136 -115.015652)
			(xy 199.477729 -114.966735) (xy 199.438207 -114.912105) (xy 199.42175 -114.882676) (xy 199.415202 -114.871959)
			(xy 199.394294 -114.858103) (xy 199.381872 -114.85626) (xy 199.285098 -114.846862) (xy 199.261476 -114.856768)
			(xy 199.253602 -114.866674) (xy 199.236599 -114.886751) (xy 199.197679 -114.92215) (xy 199.153975 -114.951438)
			(xy 199.106438 -114.973979) (xy 199.056102 -114.989283) (xy 199.004063 -114.997015) (xy 198.977758 -114.997484)
			(xy 198.951109 -114.997031) (xy 198.898407 -114.989082) (xy 198.847478 -114.973367) (xy 198.79946 -114.950238)
			(xy 198.755425 -114.920211) (xy 198.716357 -114.883956) (xy 198.683128 -114.842284) (xy 198.656481 -114.796126)
			(xy 198.63701 -114.746511) (xy 198.625151 -114.694549) (xy 198.621168 -114.6414) (xy 196.615905 -114.6414)
			(xy 196.616066 -114.648996) (xy 196.616066 -114.649504) (xy 196.615466 -114.67863) (xy 196.605941 -114.736099)
			(xy 196.587177 -114.791247) (xy 196.559678 -114.8426) (xy 196.524178 -114.888786) (xy 196.50329 -114.909092)
			(xy 196.49821 -114.914172) (xy 196.493406 -114.920687) (xy 196.487697 -114.935824) (xy 196.487034 -114.94389)
			(xy 196.487034 -115.684025) (xy 197.987148 -115.684025) (xy 197.987148 -115.630727) (xy 197.995091 -115.578023)
			(xy 198.010801 -115.527093) (xy 198.033927 -115.479072) (xy 198.063951 -115.435035) (xy 198.100203 -115.395964)
			(xy 198.141874 -115.362733) (xy 198.188032 -115.336084) (xy 198.237646 -115.316612) (xy 198.289608 -115.304752)
			(xy 198.342758 -115.300769) (xy 198.395908 -115.304752) (xy 198.44787 -115.316612) (xy 198.497484 -115.336084)
			(xy 198.543642 -115.362733) (xy 198.585313 -115.395964) (xy 198.621565 -115.435035) (xy 198.651589 -115.479072)
			(xy 198.674715 -115.527093) (xy 198.690425 -115.578023) (xy 198.698368 -115.630727) (xy 198.698866 -115.657376)
			(xy 198.698368 -115.684025) (xy 198.690425 -115.736729) (xy 198.674715 -115.787659) (xy 198.651589 -115.83568)
			(xy 198.621565 -115.879717) (xy 198.585313 -115.918788) (xy 198.543642 -115.952019) (xy 198.497484 -115.978668)
			(xy 198.44787 -115.99814) (xy 198.395908 -116.01) (xy 198.342758 -116.013984) (xy 198.289608 -116.01)
			(xy 198.237646 -115.99814) (xy 198.188032 -115.978668) (xy 198.141874 -115.952019) (xy 198.100203 -115.918788)
			(xy 198.063951 -115.879717) (xy 198.033927 -115.83568) (xy 198.010801 -115.787659) (xy 197.995091 -115.736729)
			(xy 197.987148 -115.684025) (xy 196.487034 -115.684025) (xy 196.487034 -116.745745) (xy 198.012548 -116.745745)
			(xy 198.012548 -116.692447) (xy 198.020491 -116.639743) (xy 198.036201 -116.588813) (xy 198.059327 -116.540792)
			(xy 198.089351 -116.496755) (xy 198.125603 -116.457684) (xy 198.167274 -116.424453) (xy 198.213432 -116.397804)
			(xy 198.263046 -116.378332) (xy 198.315008 -116.366472) (xy 198.368158 -116.362489) (xy 198.421308 -116.366472)
			(xy 198.47327 -116.378332) (xy 198.522884 -116.397804) (xy 198.569042 -116.424453) (xy 198.610713 -116.457684)
			(xy 198.646965 -116.496755) (xy 198.676989 -116.540792) (xy 198.700115 -116.588813) (xy 198.715825 -116.639743)
			(xy 198.723768 -116.692447) (xy 198.724266 -116.719096) (xy 198.723768 -116.745745) (xy 198.715825 -116.798449)
			(xy 198.700115 -116.849379) (xy 198.676989 -116.8974) (xy 198.646965 -116.941437) (xy 198.610713 -116.980508)
			(xy 198.569042 -117.013739) (xy 198.522884 -117.040388) (xy 198.47327 -117.05986) (xy 198.421308 -117.07172)
			(xy 198.368158 -117.075704) (xy 198.315008 -117.07172) (xy 198.263046 -117.05986) (xy 198.213432 -117.040388)
			(xy 198.167274 -117.013739) (xy 198.125603 -116.980508) (xy 198.089351 -116.941437) (xy 198.059327 -116.8974)
			(xy 198.036201 -116.849379) (xy 198.020491 -116.798449) (xy 198.012548 -116.745745) (xy 196.487034 -116.745745)
			(xy 196.487034 -117.716025) (xy 197.987148 -117.716025) (xy 197.987148 -117.662727) (xy 197.995091 -117.610023)
			(xy 198.010801 -117.559093) (xy 198.033927 -117.511072) (xy 198.063951 -117.467035) (xy 198.100203 -117.427964)
			(xy 198.141874 -117.394733) (xy 198.188032 -117.368084) (xy 198.237646 -117.348612) (xy 198.289608 -117.336752)
			(xy 198.342758 -117.332769) (xy 198.395908 -117.336752) (xy 198.44787 -117.348612) (xy 198.497484 -117.368084)
			(xy 198.543642 -117.394733) (xy 198.585313 -117.427964) (xy 198.621565 -117.467035) (xy 198.651589 -117.511072)
			(xy 198.674715 -117.559093) (xy 198.690425 -117.610023) (xy 198.698368 -117.662727) (xy 198.698866 -117.689376)
			(xy 198.698866 -117.6894) (xy 202.010765 -117.6894) (xy 202.014779 -117.625602) (xy 202.026757 -117.56281)
			(xy 202.046511 -117.502015) (xy 202.073728 -117.444174) (xy 202.10798 -117.390201) (xy 202.148726 -117.340946)
			(xy 202.195324 -117.297186) (xy 202.247039 -117.259612) (xy 202.303056 -117.228815) (xy 202.362491 -117.205282)
			(xy 202.424406 -117.189384) (xy 202.487826 -117.181371) (xy 202.519788 -117.180868) (xy 202.550048 -117.181315)
			(xy 202.610141 -117.188487) (xy 202.668958 -117.202741) (xy 202.725667 -117.223878) (xy 202.779465 -117.251597)
			(xy 202.829592 -117.285507) (xy 202.875339 -117.325129) (xy 202.916059 -117.369901) (xy 202.951175 -117.41919)
			(xy 202.966066 -117.445536) (xy 202.97267 -117.457982) (xy 202.9968 -117.472206) (xy 203.100178 -117.471698)
			(xy 203.109365 -117.471265) (xy 203.126527 -117.464686) (xy 203.140264 -117.452475) (xy 203.144882 -117.44452)
			(xy 203.159742 -117.417471) (xy 203.195047 -117.366848) (xy 203.236226 -117.320876) (xy 203.28267 -117.280231)
			(xy 203.333697 -117.245512) (xy 203.388554 -117.217231) (xy 203.446433 -117.195805) (xy 203.476352 -117.188234)
			(xy 203.484826 -117.185833) (xy 203.499507 -117.176122) (xy 203.510021 -117.162006) (xy 203.512928 -117.15369)
			(xy 203.542392 -117.056408) (xy 203.536296 -117.029992) (xy 203.526898 -117.020086) (xy 203.505619 -116.996453)
			(xy 203.468425 -116.944873) (xy 203.437947 -116.88906) (xy 203.41466 -116.829884) (xy 203.398928 -116.768268)
			(xy 203.390995 -116.705172) (xy 203.3905 -116.673376) (xy 203.391002 -116.641415) (xy 203.399013 -116.577997)
			(xy 203.41491 -116.516083) (xy 203.438442 -116.45665) (xy 203.469236 -116.400635) (xy 203.506809 -116.34892)
			(xy 203.550566 -116.302323) (xy 203.599819 -116.261578) (xy 203.65379 -116.227327) (xy 203.711629 -116.20011)
			(xy 203.772422 -116.180357) (xy 203.835212 -116.168379) (xy 203.899008 -116.164366) (xy 203.962804 -116.168379)
			(xy 204.025594 -116.180357) (xy 204.086387 -116.20011) (xy 204.144226 -116.227327) (xy 204.198197 -116.261578)
			(xy 204.24745 -116.302323) (xy 204.291207 -116.34892) (xy 204.32878 -116.400635) (xy 204.359574 -116.45665)
			(xy 204.383106 -116.516083) (xy 204.399003 -116.577997) (xy 204.407014 -116.641415) (xy 204.407516 -116.673376)
			(xy 204.407127 -116.704288) (xy 204.399641 -116.765656) (xy 204.384766 -116.825663) (xy 204.362721 -116.883423)
			(xy 204.333832 -116.938081) (xy 204.298525 -116.988831) (xy 204.257322 -117.034922) (xy 204.210832 -117.075675)
			(xy 204.159741 -117.110486) (xy 204.104804 -117.138842) (xy 204.046833 -117.160324) (xy 204.016864 -117.167914)
			(xy 204.008404 -117.170354) (xy 203.993723 -117.180049) (xy 203.983202 -117.19415) (xy 203.980288 -117.202458)
			(xy 203.950824 -117.29974) (xy 203.95692 -117.326156) (xy 203.966318 -117.336062) (xy 203.987622 -117.359672)
			(xy 204.024814 -117.411258) (xy 204.055288 -117.467076) (xy 204.07857 -117.526256) (xy 204.094297 -117.587876)
			(xy 204.102224 -117.650975) (xy 204.102716 -117.682772) (xy 204.102236 -117.713503) (xy 204.094831 -117.774518)
			(xy 204.080125 -117.834195) (xy 204.058333 -117.891664) (xy 204.029772 -117.946088) (xy 203.994859 -117.996672)
			(xy 203.954104 -118.042678) (xy 203.9081 -118.083437) (xy 203.857519 -118.118353) (xy 203.803097 -118.146918)
			(xy 203.745629 -118.168714) (xy 203.685953 -118.183424) (xy 203.624939 -118.190834) (xy 203.594208 -118.19128)
			(xy 203.563947 -118.190863) (xy 203.503852 -118.18369) (xy 203.445033 -118.169433) (xy 203.388323 -118.148294)
			(xy 203.334524 -118.120571) (xy 203.284397 -118.086657) (xy 203.238651 -118.047031) (xy 203.197933 -118.002254)
			(xy 203.162819 -117.95296) (xy 203.14793 -117.926612) (xy 203.141326 -117.914166) (xy 203.117196 -117.899942)
			(xy 203.013818 -117.90045) (xy 203.004634 -117.900907) (xy 202.987476 -117.90748) (xy 202.973737 -117.919679)
			(xy 202.969114 -117.927628) (xy 202.954344 -117.954446) (xy 202.919368 -118.004699) (xy 202.878612 -118.050388)
			(xy 202.832665 -118.090855) (xy 202.782193 -118.125512) (xy 202.727924 -118.153859) (xy 202.670645 -118.175486)
			(xy 202.611184 -118.190079) (xy 202.550401 -118.197428) (xy 202.519788 -118.197884) (xy 202.487826 -118.197429)
			(xy 202.424406 -118.189416) (xy 202.362491 -118.173518) (xy 202.303056 -118.149985) (xy 202.247039 -118.119188)
			(xy 202.195324 -118.081614) (xy 202.148726 -118.037854) (xy 202.10798 -117.988599) (xy 202.073728 -117.934626)
			(xy 202.046511 -117.876785) (xy 202.026757 -117.81599) (xy 202.014779 -117.753198) (xy 202.010765 -117.6894)
			(xy 198.698866 -117.6894) (xy 198.698368 -117.716025) (xy 198.690425 -117.768729) (xy 198.674715 -117.819659)
			(xy 198.651589 -117.86768) (xy 198.621565 -117.911717) (xy 198.585313 -117.950788) (xy 198.543642 -117.984019)
			(xy 198.497484 -118.010668) (xy 198.44787 -118.03014) (xy 198.395908 -118.042) (xy 198.342758 -118.045984)
			(xy 198.289608 -118.042) (xy 198.237646 -118.03014) (xy 198.188032 -118.010668) (xy 198.141874 -117.984019)
			(xy 198.100203 -117.950788) (xy 198.063951 -117.911717) (xy 198.033927 -117.86768) (xy 198.010801 -117.819659)
			(xy 197.995091 -117.768729) (xy 197.987148 -117.716025) (xy 196.487034 -117.716025) (xy 196.487034 -119.125238)
			(xy 196.48805 -119.134636) (xy 196.48805 -119.135144) (xy 196.489245 -119.140373) (xy 196.493476 -119.150226)
			(xy 196.496432 -119.154702) (xy 196.501766 -119.161052) (xy 197.000622 -119.659908) (xy 197.008033 -119.666588)
			(xy 197.026469 -119.674161) (xy 197.036436 -119.67464) (xy 199.31761 -119.67464) (xy 199.324214 -119.674132)
			(xy 199.330248 -119.673024) (xy 199.341556 -119.668274) (xy 199.346566 -119.664734) (xy 199.348344 -119.66321)
			(xy 199.352063 -119.660086) (xy 199.358322 -119.652662) (xy 199.36079 -119.648478) (xy 199.364346 -119.642128)
			(xy 199.366124 -119.63273) (xy 199.372242 -119.601049) (xy 199.391441 -119.539446) (xy 199.41828 -119.480767)
			(xy 199.452328 -119.425956) (xy 199.493038 -119.375893) (xy 199.539754 -119.331384) (xy 199.591727 -119.293143)
			(xy 199.648121 -119.261786) (xy 199.708029 -119.237816) (xy 199.770488 -119.221619) (xy 199.834495 -119.213455)
			(xy 199.899021 -119.213455) (xy 199.963028 -119.221619) (xy 200.025487 -119.237816) (xy 200.085395 -119.261786)
			(xy 200.141789 -119.293143) (xy 200.193762 -119.331384) (xy 200.240478 -119.375893) (xy 200.281188 -119.425956)
			(xy 200.315236 -119.480767) (xy 200.342075 -119.539446) (xy 200.361274 -119.601049) (xy 200.367392 -119.63273)
			(xy 200.3679 -119.63527) (xy 200.369809 -119.642511) (xy 200.377165 -119.655548) (xy 200.382378 -119.660924)
			(xy 200.383394 -119.66194) (xy 200.389236 -119.666512) (xy 200.391776 -119.668544) (xy 200.39965 -119.671592)
			(xy 200.407778 -119.673878) (xy 200.416922 -119.67464) (xy 202.08113 -119.67464) (xy 202.089584 -119.674294)
			(xy 202.105553 -119.668726) (xy 202.112372 -119.663718) (xy 202.11923 -119.658384) (xy 202.128374 -119.643906)
			(xy 202.130406 -119.63527) (xy 202.137355 -119.607652) (xy 202.158326 -119.554706) (xy 202.186934 -119.505465)
			(xy 202.222542 -119.461023) (xy 202.26436 -119.422367) (xy 202.311459 -119.390355) (xy 202.362793 -119.365699)
			(xy 202.417221 -119.348946) (xy 202.473534 -119.340469) (xy 202.502008 -119.339868) (xy 202.527647 -119.340284)
			(xy 202.578464 -119.347152) (xy 202.627904 -119.360762) (xy 202.675076 -119.380871) (xy 202.71913 -119.407115)
			(xy 202.759273 -119.439022) (xy 202.777344 -119.457216) (xy 202.777852 -119.457724) (xy 202.780841 -119.460676)
			(xy 202.787604 -119.465658) (xy 202.791314 -119.46763) (xy 202.795886 -119.469662) (xy 202.800005 -119.471046)
			(xy 202.80856 -119.472571) (xy 202.812904 -119.47271) (xy 202.884024 -119.473726) (xy 202.886056 -119.473726)
			(xy 202.889661 -119.473659) (xy 202.896798 -119.472632) (xy 202.90028 -119.471694) (xy 202.904191 -119.470517)
			(xy 202.911596 -119.467075) (xy 202.915012 -119.464836) (xy 202.922378 -119.45874) (xy 203.060554 -119.320564)
			(xy 203.083346 -119.298368) (xy 203.133079 -119.258689) (xy 203.186942 -119.224829) (xy 203.244259 -119.197214)
			(xy 203.304308 -119.176192) (xy 203.366333 -119.162027) (xy 203.429555 -119.154898) (xy 203.461366 -119.154448)
			(xy 203.899008 -119.154448) (xy 203.933271 -119.154966) (xy 204.001296 -119.163226) (xy 204.06783 -119.179626)
			(xy 204.131902 -119.203927) (xy 204.192578 -119.235773) (xy 204.248973 -119.2747) (xy 204.300265 -119.320141)
			(xy 204.345705 -119.371433) (xy 204.384632 -119.427829) (xy 204.416477 -119.488505) (xy 204.440776 -119.552577)
			(xy 204.457175 -119.619112) (xy 204.465435 -119.687137) (xy 204.465435 -119.7214) (xy 205.988665 -119.7214)
			(xy 205.992679 -119.657602) (xy 206.004657 -119.594811) (xy 206.02441 -119.534016) (xy 206.051627 -119.476176)
			(xy 206.085878 -119.422203) (xy 206.126624 -119.372948) (xy 206.173221 -119.329189) (xy 206.224936 -119.291614)
			(xy 206.280952 -119.260817) (xy 206.340386 -119.237284) (xy 206.402301 -119.221385) (xy 206.46572 -119.213371)
			(xy 206.497682 -119.212868) (xy 206.529507 -119.213397) (xy 206.59266 -119.221342) (xy 206.65433 -119.237097)
			(xy 206.713555 -119.260417) (xy 206.769411 -119.290938) (xy 206.821026 -119.328185) (xy 206.844646 -119.34952)
			(xy 206.851888 -119.355755) (xy 206.869643 -119.362791) (xy 206.87919 -119.363236) (xy 206.910178 -119.363236)
			(xy 206.919733 -119.362844) (xy 206.937489 -119.355777) (xy 206.944722 -119.34952) (xy 206.960499 -119.335162)
			(xy 206.994072 -119.30884) (xy 207.011778 -119.296942) (xy 207.021128 -119.290071) (xy 207.032892 -119.270096)
			(xy 207.034384 -119.258588) (xy 207.04175 -119.166894) (xy 207.033114 -119.145304) (xy 207.024478 -119.137176)
			(xy 207.002559 -119.116504) (xy 206.96323 -119.070859) (xy 206.929576 -119.020882) (xy 206.902068 -118.967277)
			(xy 206.881093 -118.910794) (xy 206.866945 -118.852227) (xy 206.859822 -118.792398) (xy 206.859378 -118.762272)
			(xy 206.859871 -118.730097) (xy 206.867993 -118.666261) (xy 206.884104 -118.60396) (xy 206.907946 -118.544189)
			(xy 206.939138 -118.487904) (xy 206.977181 -118.436004) (xy 207.021469 -118.389318) (xy 207.046068 -118.368572)
			(xy 207.046322 -118.368318) (xy 207.055628 -118.359794) (xy 207.065209 -118.336475) (xy 207.06461 -118.323868)
			(xy 207.055974 -118.23954) (xy 207.054022 -118.227005) (xy 207.039744 -118.206074) (xy 207.028796 -118.199662)
			(xy 207.002338 -118.18532) (xy 206.952679 -118.151321) (xy 206.929736 -118.131844) (xy 206.922603 -118.126031)
			(xy 206.905403 -118.119528) (xy 206.896208 -118.119144) (xy 206.865474 -118.119144) (xy 206.856371 -118.119517)
			(xy 206.839321 -118.125905) (xy 206.8322 -118.13159) (xy 206.808991 -118.15129) (xy 206.758705 -118.185606)
			(xy 206.704683 -118.213675) (xy 206.647697 -118.235093) (xy 206.588561 -118.249557) (xy 206.528121 -118.256857)
			(xy 206.497682 -118.25732) (xy 206.466951 -118.256861) (xy 206.405938 -118.249451) (xy 206.346262 -118.23474)
			(xy 206.288795 -118.212944) (xy 206.234373 -118.184381) (xy 206.183792 -118.149466) (xy 206.137787 -118.108709)
			(xy 206.097031 -118.062704) (xy 206.062116 -118.012121) (xy 206.033553 -117.9577) (xy 206.011758 -117.900232)
			(xy 205.997048 -117.840557) (xy 205.989639 -117.779543) (xy 205.989174 -117.748812) (xy 205.989641 -117.71742)
			(xy 205.997357 -117.655113) (xy 206.012687 -117.594231) (xy 206.035397 -117.535699) (xy 206.065141 -117.480409)
			(xy 206.101467 -117.429201) (xy 206.143821 -117.382857) (xy 206.191559 -117.34208) (xy 206.243955 -117.307491)
			(xy 206.271876 -117.293136) (xy 206.284576 -117.286786) (xy 206.299562 -117.263418) (xy 206.303118 -117.145562)
			(xy 206.289656 -117.121178) (xy 206.277464 -117.114066) (xy 206.24879 -117.09704) (xy 206.195816 -117.056527)
			(xy 206.148594 -117.009434) (xy 206.107935 -116.956572) (xy 206.074538 -116.898846) (xy 206.048976 -116.837249)
			(xy 206.031688 -116.772839) (xy 206.022971 -116.706721) (xy 206.022448 -116.673376) (xy 206.02292 -116.642088)
			(xy 206.030594 -116.579985) (xy 206.045837 -116.519294) (xy 206.068416 -116.460934) (xy 206.097991 -116.405788)
			(xy 206.134114 -116.354691) (xy 206.176237 -116.308416) (xy 206.223724 -116.267664) (xy 206.249524 -116.249958)
			(xy 206.259669 -116.242428) (xy 206.271535 -116.22016) (xy 206.27213 -116.20754) (xy 206.27213 -116.123212)
			(xy 206.271501 -116.110604) (xy 206.259633 -116.088356) (xy 206.249524 -116.080794) (xy 206.223705 -116.063116)
			(xy 206.176227 -116.022353) (xy 206.134111 -115.976071) (xy 206.097995 -115.924969) (xy 206.068425 -115.86982)
			(xy 206.045847 -115.811459) (xy 206.030604 -115.750767) (xy 206.022926 -115.688664) (xy 206.022448 -115.657376)
			(xy 206.022933 -115.626646) (xy 206.030344 -115.565635) (xy 206.045054 -115.505962) (xy 206.066849 -115.448496)
			(xy 206.095411 -115.394076) (xy 206.130323 -115.343496) (xy 206.171078 -115.297492) (xy 206.21708 -115.256736)
			(xy 206.267659 -115.221821) (xy 206.322078 -115.193257) (xy 206.379542 -115.17146) (xy 206.439215 -115.156747)
			(xy 206.500226 -115.149335) (xy 206.530956 -115.148868) (xy 206.561104 -115.149286) (xy 206.620977 -115.156417)
			(xy 206.679588 -115.170572) (xy 206.736116 -115.191554) (xy 206.789768 -115.219067) (xy 206.839794 -115.252728)
			(xy 206.862934 -115.272058) (xy 206.870002 -115.277707) (xy 206.886916 -115.284092) (xy 206.895954 -115.284504)
			(xy 206.926688 -115.284504) (xy 206.935725 -115.284089) (xy 206.952641 -115.277707) (xy 206.959708 -115.272058)
			(xy 206.982819 -115.252689) (xy 207.032837 -115.219006) (xy 207.086492 -115.191483) (xy 207.143028 -115.170506)
			(xy 207.201651 -115.156371) (xy 207.261534 -115.149276) (xy 207.291686 -115.148868) (xy 207.322416 -115.149369)
			(xy 207.383427 -115.156776) (xy 207.443101 -115.171482) (xy 207.500568 -115.193274) (xy 207.554989 -115.221834)
			(xy 207.60557 -115.256745) (xy 207.651575 -115.297499) (xy 207.692332 -115.3435) (xy 207.727247 -115.394079)
			(xy 207.75581 -115.448497) (xy 207.777607 -115.505962) (xy 207.792318 -115.565635) (xy 207.799729 -115.626646)
			(xy 207.800194 -115.657376) (xy 207.799737 -115.687221) (xy 207.792762 -115.746501) (xy 207.778891 -115.804556)
			(xy 207.758318 -115.860588) (xy 207.731324 -115.913825) (xy 207.698281 -115.963534) (xy 207.67929 -115.98656)
			(xy 207.679036 -115.986814) (xy 207.673452 -115.994034) (xy 207.667338 -116.011218) (xy 207.667098 -116.020342)
			(xy 207.668368 -116.09705) (xy 207.67548 -116.114322) (xy 207.68183 -116.12118) (xy 207.702756 -116.144706)
			(xy 207.739274 -116.196) (xy 207.769181 -116.251408) (xy 207.792021 -116.310084) (xy 207.807445 -116.37113)
			(xy 207.815217 -116.433614) (xy 207.815688 -116.465096) (xy 207.815259 -116.495829) (xy 207.80785 -116.556846)
			(xy 207.79314 -116.616526) (xy 207.771344 -116.673997) (xy 207.742779 -116.728422) (xy 207.707862 -116.779007)
			(xy 207.667102 -116.825014) (xy 207.621094 -116.865772) (xy 207.570508 -116.900688) (xy 207.516082 -116.929251)
			(xy 207.45861 -116.951045) (xy 207.398931 -116.965753) (xy 207.337913 -116.97316) (xy 207.30718 -116.973604)
			(xy 207.306926 -116.973604) (xy 207.277915 -116.973204) (xy 207.220272 -116.966601) (xy 207.163757 -116.953468)
			(xy 207.109108 -116.933975) (xy 207.082898 -116.921534) (xy 207.082644 -116.921534) (xy 207.074332 -116.917821)
			(xy 207.056228 -116.91601) (xy 207.047338 -116.917978) (xy 206.973678 -116.93779) (xy 206.958946 -116.948204)
			(xy 206.953612 -116.956078) (xy 206.934759 -116.983342) (xy 206.891084 -117.033206) (xy 206.84129 -117.076961)
			(xy 206.786224 -117.113861) (xy 206.756762 -117.129052) (xy 206.744062 -117.135402) (xy 206.729076 -117.15877)
			(xy 206.72552 -117.276626) (xy 206.738982 -117.30101) (xy 206.751174 -117.308122) (xy 206.772637 -117.320834)
			(xy 206.813223 -117.349843) (xy 206.8322 -117.366034) (xy 206.839306 -117.37174) (xy 206.856367 -117.378112)
			(xy 206.865474 -117.37848) (xy 206.896208 -117.37848) (xy 206.905309 -117.378093) (xy 206.92236 -117.371714)
			(xy 206.929482 -117.366034) (xy 206.952701 -117.346346) (xy 207.002984 -117.312028) (xy 207.057004 -117.283957)
			(xy 207.113989 -117.262536) (xy 207.173123 -117.248071) (xy 207.233561 -117.240768) (xy 207.264 -117.240304)
			(xy 207.294733 -117.240738) (xy 207.35575 -117.248147) (xy 207.415429 -117.262856) (xy 207.472899 -117.284653)
			(xy 207.527324 -117.313217) (xy 207.577908 -117.348134) (xy 207.623915 -117.388893) (xy 207.664674 -117.434901)
			(xy 207.699589 -117.485486) (xy 207.728152 -117.539912) (xy 207.749947 -117.597383) (xy 207.764656 -117.657062)
			(xy 207.772063 -117.718079) (xy 207.772508 -117.748812) (xy 207.771972 -117.780986) (xy 207.763854 -117.844818)
			(xy 207.747748 -117.907117) (xy 207.723912 -117.966887) (xy 207.692727 -118.023172) (xy 207.654692 -118.075074)
			(xy 207.610413 -118.121764) (xy 207.585818 -118.142512) (xy 207.585564 -118.142766) (xy 207.576279 -118.15131)
			(xy 207.566683 -118.174613) (xy 207.567276 -118.187216) (xy 207.575912 -118.271544) (xy 207.577879 -118.284075)
			(xy 207.592147 -118.305008) (xy 207.60309 -118.311422) (xy 207.630173 -118.3261) (xy 207.680949 -118.36098)
			(xy 207.727139 -118.401738) (xy 207.768067 -118.447778) (xy 207.803133 -118.498426) (xy 207.831824 -118.552938)
			(xy 207.853719 -118.610518) (xy 207.868497 -118.670321) (xy 207.875942 -118.731471) (xy 207.876394 -118.762272)
			(xy 207.875882 -118.793674) (xy 207.868158 -118.856001) (xy 207.852812 -118.916901) (xy 207.830078 -118.975446)
			(xy 207.800302 -119.030742) (xy 207.763938 -119.081948) (xy 207.721541 -119.128281) (xy 207.673758 -119.169037)
			(xy 207.647794 -119.186706) (xy 207.638478 -119.193616) (xy 207.626693 -119.213562) (xy 207.625188 -119.22506)
			(xy 207.617822 -119.316754) (xy 207.626458 -119.338344) (xy 207.635094 -119.346472) (xy 207.657002 -119.367155)
			(xy 207.696329 -119.4128) (xy 207.729983 -119.462775) (xy 207.757491 -119.516379) (xy 207.778468 -119.572859)
			(xy 207.79262 -119.631424) (xy 207.799747 -119.691251) (xy 207.800194 -119.721376) (xy 209.994246 -119.721376)
			(xy 209.994714 -119.688502) (xy 210.003202 -119.623304) (xy 210.020021 -119.559743) (xy 210.044891 -119.49888)
			(xy 210.077396 -119.441729) (xy 210.116995 -119.389243) (xy 210.163026 -119.342298) (xy 210.188556 -119.32158)
			(xy 210.197267 -119.314) (xy 210.207315 -119.293236) (xy 210.20786 -119.281702) (xy 210.20786 -119.201946)
			(xy 210.207317 -119.190411) (xy 210.197268 -119.169647) (xy 210.188556 -119.162068) (xy 210.163034 -119.141343)
			(xy 210.117001 -119.094402) (xy 210.077403 -119.041918) (xy 210.044903 -118.984768) (xy 210.020041 -118.923904)
			(xy 210.003234 -118.860342) (xy 209.994762 -118.795145) (xy 209.994246 -118.762272) (xy 209.994732 -118.731109)
			(xy 210.002332 -118.669247) (xy 210.017437 -118.608779) (xy 210.039823 -118.550612) (xy 210.069152 -118.495618)
			(xy 210.104985 -118.444622) (xy 210.146784 -118.39839) (xy 210.193922 -118.357615) (xy 210.219544 -118.33987)
			(xy 210.229643 -118.332385) (xy 210.241505 -118.31026) (xy 210.24215 -118.297706) (xy 210.24215 -118.213378)
			(xy 210.241454 -118.200839) (xy 210.229604 -118.178731) (xy 210.219544 -118.171214) (xy 210.193902 -118.153499)
			(xy 210.146778 -118.112708) (xy 210.10499 -118.066465) (xy 210.069164 -118.015464) (xy 210.039837 -117.960468)
			(xy 210.017449 -117.902301) (xy 210.002333 -117.841835) (xy 209.994718 -117.779975) (xy 209.994246 -117.748812)
			(xy 209.994689 -117.718334) (xy 210.001968 -117.657813) (xy 210.016435 -117.598598) (xy 210.037882 -117.541539)
			(xy 210.066002 -117.487455) (xy 210.100389 -117.437124) (xy 210.140551 -117.391268) (xy 210.18591 -117.350546)
			(xy 210.235815 -117.315543) (xy 210.26247 -117.300756) (xy 210.270397 -117.296071) (xy 210.282508 -117.282218)
			(xy 210.288994 -117.264998) (xy 210.289394 -117.255798) (xy 210.289394 -117.16639) (xy 210.289055 -117.157176)
			(xy 210.2826 -117.139919) (xy 210.27043 -117.126087) (xy 210.26247 -117.121432) (xy 210.235825 -117.106631)
			(xy 210.185933 -117.071617) (xy 210.140585 -117.03089) (xy 210.100431 -116.985033) (xy 210.066047 -116.934705)
			(xy 210.037927 -116.880626) (xy 210.016474 -116.823574) (xy 210.001996 -116.764366) (xy 209.994699 -116.703852)
			(xy 209.994246 -116.673376) (xy 209.994719 -116.642088) (xy 210.002393 -116.579985) (xy 210.017636 -116.519294)
			(xy 210.040215 -116.460934) (xy 210.06979 -116.405788) (xy 210.105912 -116.354691) (xy 210.148035 -116.308416)
			(xy 210.195522 -116.267664) (xy 210.221322 -116.249958) (xy 210.231467 -116.242427) (xy 210.243333 -116.22016)
			(xy 210.243928 -116.20754) (xy 210.243928 -116.123212) (xy 210.2433 -116.110604) (xy 210.231432 -116.088356)
			(xy 210.221322 -116.080794) (xy 210.195502 -116.063117) (xy 210.148024 -116.022354) (xy 210.105909 -115.976071)
			(xy 210.069793 -115.924969) (xy 210.040223 -115.86982) (xy 210.017645 -115.811459) (xy 210.002402 -115.750768)
			(xy 209.994724 -115.688664) (xy 209.994246 -115.657376) (xy 209.994733 -115.626646) (xy 210.002144 -115.565635)
			(xy 210.016854 -115.505962) (xy 210.038648 -115.448497) (xy 210.06721 -115.394077) (xy 210.102123 -115.343497)
			(xy 210.142877 -115.297493) (xy 210.188879 -115.256736) (xy 210.239458 -115.221822) (xy 210.293877 -115.193257)
			(xy 210.351341 -115.17146) (xy 210.411013 -115.156748) (xy 210.472024 -115.149335) (xy 210.502754 -115.148868)
			(xy 210.531974 -115.149286) (xy 210.590031 -115.155974) (xy 210.64694 -115.169267) (xy 210.701953 -115.188989)
			(xy 210.754344 -115.214883) (xy 210.779106 -115.230402) (xy 210.78855 -115.23592) (xy 210.810172 -115.2391)
			(xy 210.831171 -115.233047) (xy 210.839812 -115.226338) (xy 210.862913 -115.20713) (xy 210.912818 -115.173679)
			(xy 210.966316 -115.14634) (xy 211.022663 -115.125494) (xy 211.081074 -115.111433) (xy 211.140734 -115.104351)
			(xy 211.170774 -115.10391) (xy 211.202739 -115.104353) (xy 211.266164 -115.112363) (xy 211.328085 -115.128259)
			(xy 211.387526 -115.15179) (xy 211.443548 -115.182586) (xy 211.495269 -115.220161) (xy 211.541873 -115.263923)
			(xy 211.582624 -115.31318) (xy 211.616879 -115.367156) (xy 211.6441 -115.425001) (xy 211.663856 -115.485801)
			(xy 211.675835 -115.548597) (xy 211.67985 -115.6124) (xy 211.675835 -115.676203) (xy 211.663856 -115.738999)
			(xy 211.6441 -115.799799) (xy 211.616879 -115.857644) (xy 211.582624 -115.91162) (xy 211.541873 -115.960877)
			(xy 211.495269 -116.004639) (xy 211.443548 -116.042214) (xy 211.387526 -116.07301) (xy 211.328085 -116.096541)
			(xy 211.266164 -116.112437) (xy 211.202739 -116.120447) (xy 211.170774 -116.120926) (xy 211.141554 -116.120495)
			(xy 211.083497 -116.11381) (xy 211.026588 -116.100521) (xy 210.971576 -116.080801) (xy 210.919184 -116.05491)
			(xy 210.894422 -116.039392) (xy 210.884965 -116.033901) (xy 210.863352 -116.030713) (xy 210.842357 -116.036754)
			(xy 210.833716 -116.043456) (xy 210.821843 -116.053449) (xy 210.797061 -116.072131) (xy 210.784186 -116.080794)
			(xy 210.774047 -116.088329) (xy 210.762183 -116.110594) (xy 210.76158 -116.123212) (xy 210.76158 -116.20754)
			(xy 210.762234 -116.220145) (xy 210.774083 -116.242394) (xy 210.784186 -116.249958) (xy 210.809985 -116.267664)
			(xy 210.857463 -116.308423) (xy 210.899579 -116.354701) (xy 210.935697 -116.405799) (xy 210.96527 -116.460944)
			(xy 210.98785 -116.519301) (xy 211.003098 -116.579989) (xy 211.010781 -116.642089) (xy 211.011262 -116.673376)
			(xy 211.010805 -116.703854) (xy 211.007323 -116.732812) (xy 211.517736 -116.732812) (xy 211.521807 -116.67719)
			(xy 211.533933 -116.622753) (xy 211.553856 -116.570662) (xy 211.581152 -116.522027) (xy 211.615238 -116.477884)
			(xy 211.655387 -116.439175) (xy 211.700745 -116.406724) (xy 211.750345 -116.381223) (xy 211.803129 -116.363216)
			(xy 211.857972 -116.353086) (xy 211.913706 -116.351049) (xy 211.969143 -116.357149) (xy 212.0231 -116.371255)
			(xy 212.074429 -116.393067) (xy 212.122035 -116.422121) (xy 212.164903 -116.457796) (xy 212.20212 -116.499333)
			(xy 212.232893 -116.545846) (xy 212.256565 -116.596343) (xy 212.272633 -116.64975) (xy 212.280753 -116.704926)
			(xy 212.281262 -116.732812) (xy 212.280753 -116.760698) (xy 212.272633 -116.815874) (xy 212.267451 -116.833099)
			(xy 217.395292 -116.833099) (xy 217.395292 -116.769177) (xy 217.403303 -116.705759) (xy 217.4192 -116.643845)
			(xy 217.442732 -116.584412) (xy 217.473526 -116.528397) (xy 217.511099 -116.476682) (xy 217.554856 -116.430085)
			(xy 217.604109 -116.38934) (xy 217.65808 -116.355089) (xy 217.715919 -116.327872) (xy 217.776712 -116.308119)
			(xy 217.839502 -116.296141) (xy 217.903298 -116.292128) (xy 217.967094 -116.296141) (xy 218.029884 -116.308119)
			(xy 218.090677 -116.327872) (xy 218.148516 -116.355089) (xy 218.202487 -116.38934) (xy 218.25174 -116.430085)
			(xy 218.295497 -116.476682) (xy 218.33307 -116.528397) (xy 218.363864 -116.584412) (xy 218.387396 -116.643845)
			(xy 218.403293 -116.705759) (xy 218.411304 -116.769177) (xy 218.411806 -116.801138) (xy 218.411304 -116.833099)
			(xy 218.403293 -116.896517) (xy 218.399033 -116.913109) (xy 254.48488 -116.913109) (xy 254.48488 -116.849187)
			(xy 254.492891 -116.785769) (xy 254.508788 -116.723855) (xy 254.53232 -116.664422) (xy 254.563114 -116.608407)
			(xy 254.600687 -116.556692) (xy 254.644444 -116.510095) (xy 254.693697 -116.46935) (xy 254.747668 -116.435099)
			(xy 254.805507 -116.407882) (xy 254.8663 -116.388129) (xy 254.92909 -116.376151) (xy 254.992886 -116.372138)
			(xy 255.056682 -116.376151) (xy 255.119472 -116.388129) (xy 255.180265 -116.407882) (xy 255.238104 -116.435099)
			(xy 255.292075 -116.46935) (xy 255.341328 -116.510095) (xy 255.385085 -116.556692) (xy 255.422658 -116.608407)
			(xy 255.453452 -116.664422) (xy 255.476984 -116.723855) (xy 255.492881 -116.785769) (xy 255.500892 -116.849187)
			(xy 255.501394 -116.881148) (xy 255.500892 -116.913109) (xy 255.492881 -116.976527) (xy 255.476984 -117.038441)
			(xy 255.453452 -117.097874) (xy 255.422658 -117.153889) (xy 255.385085 -117.205604) (xy 255.341328 -117.252201)
			(xy 255.292075 -117.292946) (xy 255.238104 -117.327197) (xy 255.180265 -117.354414) (xy 255.119472 -117.374167)
			(xy 255.056682 -117.386145) (xy 254.992886 -117.390159) (xy 254.92909 -117.386145) (xy 254.8663 -117.374167)
			(xy 254.805507 -117.354414) (xy 254.747668 -117.327197) (xy 254.693697 -117.292946) (xy 254.644444 -117.252201)
			(xy 254.600687 -117.205604) (xy 254.563114 -117.153889) (xy 254.53232 -117.097874) (xy 254.508788 -117.038441)
			(xy 254.492891 -116.976527) (xy 254.48488 -116.913109) (xy 218.399033 -116.913109) (xy 218.387396 -116.958431)
			(xy 218.363864 -117.017864) (xy 218.33307 -117.073879) (xy 218.295497 -117.125594) (xy 218.25174 -117.172191)
			(xy 218.202487 -117.212936) (xy 218.148516 -117.247187) (xy 218.090677 -117.274404) (xy 218.029884 -117.294157)
			(xy 217.967094 -117.306135) (xy 217.903298 -117.310149) (xy 217.839502 -117.306135) (xy 217.776712 -117.294157)
			(xy 217.715919 -117.274404) (xy 217.65808 -117.247187) (xy 217.604109 -117.212936) (xy 217.554856 -117.172191)
			(xy 217.511099 -117.125594) (xy 217.473526 -117.073879) (xy 217.442732 -117.017864) (xy 217.4192 -116.958431)
			(xy 217.403303 -116.896517) (xy 217.395292 -116.833099) (xy 212.267451 -116.833099) (xy 212.256565 -116.869281)
			(xy 212.232893 -116.919778) (xy 212.20212 -116.966291) (xy 212.164903 -117.007828) (xy 212.122035 -117.043503)
			(xy 212.074429 -117.072557) (xy 212.0231 -117.094369) (xy 211.969143 -117.108475) (xy 211.913706 -117.114575)
			(xy 211.857972 -117.112538) (xy 211.803129 -117.102408) (xy 211.750345 -117.084401) (xy 211.700745 -117.0589)
			(xy 211.655387 -117.026449) (xy 211.615238 -116.98774) (xy 211.581152 -116.943597) (xy 211.553856 -116.894962)
			(xy 211.533933 -116.842871) (xy 211.521807 -116.788434) (xy 211.517736 -116.732812) (xy 211.007323 -116.732812)
			(xy 211.003527 -116.764374) (xy 210.989062 -116.823589) (xy 210.967616 -116.880647) (xy 210.939499 -116.934731)
			(xy 210.905113 -116.985062) (xy 210.864953 -117.030918) (xy 210.819596 -117.071641) (xy 210.769692 -117.106645)
			(xy 210.743038 -117.121432) (xy 210.735118 -117.126127) (xy 210.723005 -117.139975) (xy 210.716516 -117.157192)
			(xy 210.716114 -117.16639) (xy 210.716114 -117.255798) (xy 210.716509 -117.265006) (xy 210.722946 -117.282255)
			(xy 210.735091 -117.296092) (xy 210.743038 -117.300756) (xy 210.769679 -117.315562) (xy 210.819571 -117.350576)
			(xy 210.864919 -117.391303) (xy 210.905073 -117.437159) (xy 210.939457 -117.487487) (xy 210.967577 -117.541564)
			(xy 210.989031 -117.598616) (xy 211.003511 -117.657823) (xy 211.010808 -117.718336) (xy 211.011262 -117.748812)
			(xy 211.01076 -117.779975) (xy 211.010662 -117.780773) (xy 211.264748 -117.780773) (xy 211.264748 -117.716851)
			(xy 211.272759 -117.653433) (xy 211.288656 -117.591519) (xy 211.312188 -117.532086) (xy 211.342982 -117.476071)
			(xy 211.380555 -117.424356) (xy 211.424312 -117.377759) (xy 211.473565 -117.337014) (xy 211.527536 -117.302763)
			(xy 211.585375 -117.275546) (xy 211.646168 -117.255793) (xy 211.708958 -117.243815) (xy 211.772754 -117.239802)
			(xy 211.83655 -117.243815) (xy 211.89934 -117.255793) (xy 211.960133 -117.275546) (xy 212.017972 -117.302763)
			(xy 212.071943 -117.337014) (xy 212.121196 -117.377759) (xy 212.164953 -117.424356) (xy 212.202526 -117.476071)
			(xy 212.23332 -117.532086) (xy 212.256852 -117.591519) (xy 212.272749 -117.653433) (xy 212.28076 -117.716851)
			(xy 212.281262 -117.748812) (xy 212.28076 -117.780773) (xy 212.272749 -117.844191) (xy 212.256852 -117.906105)
			(xy 212.23332 -117.965538) (xy 212.202526 -118.021553) (xy 212.164953 -118.073268) (xy 212.121196 -118.119865)
			(xy 212.071943 -118.16061) (xy 212.017972 -118.194861) (xy 211.960133 -118.222078) (xy 211.89934 -118.241831)
			(xy 211.83655 -118.253809) (xy 211.772754 -118.257823) (xy 211.708958 -118.253809) (xy 211.646168 -118.241831)
			(xy 211.585375 -118.222078) (xy 211.527536 -118.194861) (xy 211.473565 -118.16061) (xy 211.424312 -118.119865)
			(xy 211.380555 -118.073268) (xy 211.342982 -118.021553) (xy 211.312188 -117.965538) (xy 211.288656 -117.906105)
			(xy 211.272759 -117.844191) (xy 211.264748 -117.780773) (xy 211.010662 -117.780773) (xy 211.003163 -117.841835)
			(xy 210.988059 -117.902303) (xy 210.965676 -117.96047) (xy 210.936349 -118.015464) (xy 210.900518 -118.06646)
			(xy 210.858721 -118.112693) (xy 210.811585 -118.153469) (xy 210.785964 -118.171214) (xy 210.775874 -118.178709)
			(xy 210.764007 -118.200827) (xy 210.763358 -118.213378) (xy 210.763358 -118.297706) (xy 210.76406 -118.310244)
			(xy 210.775906 -118.332352) (xy 210.785964 -118.33987) (xy 210.8116 -118.357593) (xy 210.858724 -118.398383)
			(xy 210.900512 -118.444625) (xy 210.936338 -118.495625) (xy 210.965666 -118.55062) (xy 210.988056 -118.608785)
			(xy 211.003172 -118.66925) (xy 211.010789 -118.731109) (xy 211.011262 -118.762272) (xy 211.010754 -118.795145)
			(xy 211.002272 -118.860341) (xy 210.997453 -118.878561) (xy 212.648794 -118.878561) (xy 212.648794 -118.814639)
			(xy 212.656805 -118.751221) (xy 212.672702 -118.689307) (xy 212.696234 -118.629874) (xy 212.727028 -118.573859)
			(xy 212.764601 -118.522144) (xy 212.808358 -118.475547) (xy 212.857611 -118.434802) (xy 212.911582 -118.400551)
			(xy 212.969421 -118.373334) (xy 213.030214 -118.353581) (xy 213.093004 -118.341603) (xy 213.1568 -118.33759)
			(xy 213.220596 -118.341603) (xy 213.283386 -118.353581) (xy 213.344179 -118.373334) (xy 213.402018 -118.400551)
			(xy 213.455989 -118.434802) (xy 213.505242 -118.475547) (xy 213.548999 -118.522144) (xy 213.586572 -118.573859)
			(xy 213.617366 -118.629874) (xy 213.630147 -118.662153) (xy 217.497146 -118.662153) (xy 217.497146 -118.598231)
			(xy 217.505157 -118.534813) (xy 217.521054 -118.472899) (xy 217.544586 -118.413466) (xy 217.57538 -118.357451)
			(xy 217.612953 -118.305736) (xy 217.65671 -118.259139) (xy 217.705963 -118.218394) (xy 217.759934 -118.184143)
			(xy 217.817773 -118.156926) (xy 217.878566 -118.137173) (xy 217.941356 -118.125195) (xy 218.005152 -118.121182)
			(xy 218.068948 -118.125195) (xy 218.131738 -118.137173) (xy 218.192531 -118.156926) (xy 218.25037 -118.184143)
			(xy 218.304341 -118.218394) (xy 218.353594 -118.259139) (xy 218.397351 -118.305736) (xy 218.434924 -118.357451)
			(xy 218.465718 -118.413466) (xy 218.48925 -118.472899) (xy 218.497539 -118.505181) (xy 226.155498 -118.505181)
			(xy 226.155498 -118.441259) (xy 226.163509 -118.377841) (xy 226.179406 -118.315927) (xy 226.202938 -118.256494)
			(xy 226.233732 -118.200479) (xy 226.271305 -118.148764) (xy 226.315062 -118.102167) (xy 226.364315 -118.061422)
			(xy 226.418286 -118.027171) (xy 226.476125 -117.999954) (xy 226.536918 -117.980201) (xy 226.599708 -117.968223)
			(xy 226.663504 -117.96421) (xy 226.7273 -117.968223) (xy 226.79009 -117.980201) (xy 226.850883 -117.999954)
			(xy 226.908722 -118.027171) (xy 226.962693 -118.061422) (xy 227.011946 -118.102167) (xy 227.055703 -118.148764)
			(xy 227.093276 -118.200479) (xy 227.12407 -118.256494) (xy 227.147602 -118.315927) (xy 227.155825 -118.347955)
			(xy 242.888764 -118.347955) (xy 242.888764 -118.284033) (xy 242.896775 -118.220615) (xy 242.912672 -118.158701)
			(xy 242.936204 -118.099268) (xy 242.966998 -118.043253) (xy 243.004571 -117.991538) (xy 243.048328 -117.944941)
			(xy 243.097581 -117.904196) (xy 243.151552 -117.869945) (xy 243.209391 -117.842728) (xy 243.270184 -117.822975)
			(xy 243.332974 -117.810997) (xy 243.39677 -117.806984) (xy 243.460566 -117.810997) (xy 243.523356 -117.822975)
			(xy 243.584149 -117.842728) (xy 243.641988 -117.869945) (xy 243.695959 -117.904196) (xy 243.745212 -117.944941)
			(xy 243.788969 -117.991538) (xy 243.826542 -118.043253) (xy 243.857336 -118.099268) (xy 243.880868 -118.158701)
			(xy 243.896765 -118.220615) (xy 243.896936 -118.221971) (xy 250.609094 -118.221971) (xy 250.609094 -118.158049)
			(xy 250.617105 -118.094631) (xy 250.633002 -118.032717) (xy 250.656534 -117.973284) (xy 250.687328 -117.917269)
			(xy 250.724901 -117.865554) (xy 250.768658 -117.818957) (xy 250.817911 -117.778212) (xy 250.871882 -117.743961)
			(xy 250.929721 -117.716744) (xy 250.990514 -117.696991) (xy 251.053304 -117.685013) (xy 251.1171 -117.681)
			(xy 251.180896 -117.685013) (xy 251.243686 -117.696991) (xy 251.304479 -117.716744) (xy 251.362318 -117.743961)
			(xy 251.416289 -117.778212) (xy 251.465542 -117.818957) (xy 251.509299 -117.865554) (xy 251.546872 -117.917269)
			(xy 251.577666 -117.973284) (xy 251.601198 -118.032717) (xy 251.617095 -118.094631) (xy 251.625106 -118.158049)
			(xy 251.625608 -118.19001) (xy 251.625106 -118.221971) (xy 251.879094 -118.221971) (xy 251.879094 -118.158049)
			(xy 251.887105 -118.094631) (xy 251.903002 -118.032717) (xy 251.926534 -117.973284) (xy 251.957328 -117.917269)
			(xy 251.994901 -117.865554) (xy 252.038658 -117.818957) (xy 252.087911 -117.778212) (xy 252.141882 -117.743961)
			(xy 252.199721 -117.716744) (xy 252.260514 -117.696991) (xy 252.323304 -117.685013) (xy 252.3871 -117.681)
			(xy 252.450896 -117.685013) (xy 252.513686 -117.696991) (xy 252.574479 -117.716744) (xy 252.632318 -117.743961)
			(xy 252.686289 -117.778212) (xy 252.735542 -117.818957) (xy 252.779299 -117.865554) (xy 252.816872 -117.917269)
			(xy 252.822404 -117.927331) (xy 257.865874 -117.927331) (xy 257.865874 -117.863409) (xy 257.873885 -117.799991)
			(xy 257.889782 -117.738077) (xy 257.913314 -117.678644) (xy 257.944108 -117.622629) (xy 257.981681 -117.570914)
			(xy 258.025438 -117.524317) (xy 258.074691 -117.483572) (xy 258.128662 -117.449321) (xy 258.186501 -117.422104)
			(xy 258.247294 -117.402351) (xy 258.310084 -117.390373) (xy 258.37388 -117.38636) (xy 258.437676 -117.390373)
			(xy 258.500466 -117.402351) (xy 258.561259 -117.422104) (xy 258.619098 -117.449321) (xy 258.673069 -117.483572)
			(xy 258.722322 -117.524317) (xy 258.766079 -117.570914) (xy 258.797306 -117.613895) (xy 259.440674 -117.613895)
			(xy 259.440674 -117.549973) (xy 259.448685 -117.486555) (xy 259.464582 -117.424641) (xy 259.488114 -117.365208)
			(xy 259.518908 -117.309193) (xy 259.556481 -117.257478) (xy 259.600238 -117.210881) (xy 259.649491 -117.170136)
			(xy 259.703462 -117.135885) (xy 259.761301 -117.108668) (xy 259.822094 -117.088915) (xy 259.884884 -117.076937)
			(xy 259.94868 -117.072924) (xy 260.012476 -117.076937) (xy 260.075266 -117.088915) (xy 260.136059 -117.108668)
			(xy 260.193898 -117.135885) (xy 260.247869 -117.170136) (xy 260.297122 -117.210881) (xy 260.340879 -117.257478)
			(xy 260.378452 -117.309193) (xy 260.409246 -117.365208) (xy 260.432778 -117.424641) (xy 260.448675 -117.486555)
			(xy 260.456686 -117.549973) (xy 260.457188 -117.581934) (xy 260.456686 -117.613895) (xy 260.448675 -117.677313)
			(xy 260.441756 -117.70426) (xy 273.270775 -117.70426) (xy 273.275987 -117.641388) (xy 273.288936 -117.579645)
			(xy 273.309423 -117.519977) (xy 273.337134 -117.463302) (xy 273.371642 -117.41049) (xy 273.412418 -117.362352)
			(xy 273.458835 -117.319627) (xy 273.51018 -117.282972) (xy 273.565665 -117.25295) (xy 273.624438 -117.230022)
			(xy 273.685596 -117.21454) (xy 273.748199 -117.206741) (xy 273.779742 -117.206268) (xy 273.779996 -117.206268)
			(xy 273.810565 -117.206763) (xy 273.871259 -117.21411) (xy 273.930637 -117.228674) (xy 273.987842 -117.250247)
			(xy 274.042052 -117.278516) (xy 274.067524 -117.295422) (xy 274.0787 -117.303296) (xy 274.10664 -117.305074)
			(xy 274.198842 -117.258338) (xy 274.206772 -117.253904) (xy 274.219059 -117.240535) (xy 274.225894 -117.223714)
			(xy 274.226528 -117.21465) (xy 274.226528 -117.214142) (xy 274.227696 -117.187348) (xy 274.236692 -117.134475)
			(xy 274.253019 -117.083388) (xy 274.276353 -117.035098) (xy 274.306233 -116.99056) (xy 274.32381 -116.970302)
			(xy 274.332446 -116.96065) (xy 274.338542 -116.935504) (xy 274.309332 -116.828062) (xy 274.291806 -116.809774)
			(xy 274.27936 -116.80571) (xy 274.248987 -116.795497) (xy 274.190938 -116.768354) (xy 274.136757 -116.734135)
			(xy 274.087304 -116.693382) (xy 274.043361 -116.64674) (xy 274.005625 -116.594947) (xy 273.974693 -116.538825)
			(xy 273.951055 -116.479262) (xy 273.935086 -116.417202) (xy 273.927039 -116.353627) (xy 273.926554 -116.321586)
			(xy 273.927056 -116.289625) (xy 273.935067 -116.226207) (xy 273.950964 -116.164293) (xy 273.974496 -116.10486)
			(xy 274.00529 -116.048845) (xy 274.042863 -115.99713) (xy 274.08662 -115.950533) (xy 274.135873 -115.909788)
			(xy 274.189844 -115.875537) (xy 274.247683 -115.84832) (xy 274.308476 -115.828567) (xy 274.371266 -115.816589)
			(xy 274.435062 -115.812576) (xy 274.498858 -115.816589) (xy 274.561648 -115.828567) (xy 274.622441 -115.84832)
			(xy 274.68028 -115.875537) (xy 274.734251 -115.909788) (xy 274.783504 -115.950533) (xy 274.827261 -115.99713)
			(xy 274.864834 -116.048845) (xy 274.890613 -116.095737) (xy 280.746194 -116.095737) (xy 280.746194 -116.031815)
			(xy 280.754205 -115.968397) (xy 280.770102 -115.906483) (xy 280.793634 -115.84705) (xy 280.824428 -115.791035)
			(xy 280.862001 -115.73932) (xy 280.905758 -115.692723) (xy 280.955011 -115.651978) (xy 281.008982 -115.617727)
			(xy 281.066821 -115.59051) (xy 281.127614 -115.570757) (xy 281.190404 -115.558779) (xy 281.2542 -115.554766)
			(xy 281.317996 -115.558779) (xy 281.380786 -115.570757) (xy 281.441579 -115.59051) (xy 281.499418 -115.617727)
			(xy 281.553389 -115.651978) (xy 281.569739 -115.665504) (xy 307.939946 -115.665504) (xy 307.944017 -115.609882)
			(xy 307.956143 -115.555445) (xy 307.976066 -115.503354) (xy 308.003362 -115.454719) (xy 308.037448 -115.410576)
			(xy 308.077597 -115.371867) (xy 308.122955 -115.339416) (xy 308.172555 -115.313915) (xy 308.225339 -115.295908)
			(xy 308.280182 -115.285778) (xy 308.335916 -115.283741) (xy 308.391353 -115.289841) (xy 308.44531 -115.303947)
			(xy 308.472377 -115.315449) (xy 318.550792 -115.315449) (xy 318.550792 -115.251527) (xy 318.558803 -115.188109)
			(xy 318.5747 -115.126195) (xy 318.598232 -115.066762) (xy 318.629026 -115.010747) (xy 318.666599 -114.959032)
			(xy 318.710356 -114.912435) (xy 318.759609 -114.87169) (xy 318.81358 -114.837439) (xy 318.871419 -114.810222)
			(xy 318.932212 -114.790469) (xy 318.995002 -114.778491) (xy 319.058798 -114.774478) (xy 319.122594 -114.778491)
			(xy 319.185384 -114.790469) (xy 319.246177 -114.810222) (xy 319.304016 -114.837439) (xy 319.357987 -114.87169)
			(xy 319.40724 -114.912435) (xy 319.450997 -114.959032) (xy 319.48857 -115.010747) (xy 319.519364 -115.066762)
			(xy 319.542896 -115.126195) (xy 319.558793 -115.188109) (xy 319.566804 -115.251527) (xy 319.567306 -115.283488)
			(xy 319.566804 -115.315449) (xy 319.558793 -115.378867) (xy 319.542896 -115.440781) (xy 319.519364 -115.500214)
			(xy 319.48857 -115.556229) (xy 319.450997 -115.607944) (xy 319.40724 -115.654541) (xy 319.357987 -115.695286)
			(xy 319.304016 -115.729537) (xy 319.246177 -115.756754) (xy 319.185384 -115.776507) (xy 319.122594 -115.788485)
			(xy 319.058798 -115.792499) (xy 318.995002 -115.788485) (xy 318.932212 -115.776507) (xy 318.871419 -115.756754)
			(xy 318.81358 -115.729537) (xy 318.759609 -115.695286) (xy 318.710356 -115.654541) (xy 318.666599 -115.607944)
			(xy 318.629026 -115.556229) (xy 318.598232 -115.500214) (xy 318.5747 -115.440781) (xy 318.558803 -115.378867)
			(xy 318.550792 -115.315449) (xy 308.472377 -115.315449) (xy 308.496639 -115.325759) (xy 308.544245 -115.354813)
			(xy 308.587113 -115.390488) (xy 308.62433 -115.432025) (xy 308.655103 -115.478538) (xy 308.678775 -115.529035)
			(xy 308.694843 -115.582442) (xy 308.702963 -115.637618) (xy 308.703472 -115.665504) (xy 308.702963 -115.69339)
			(xy 308.694843 -115.748566) (xy 308.678775 -115.801973) (xy 308.655103 -115.85247) (xy 308.62433 -115.898983)
			(xy 308.587113 -115.94052) (xy 308.544245 -115.976195) (xy 308.496639 -116.005249) (xy 308.44531 -116.027061)
			(xy 308.391353 -116.041167) (xy 308.335916 -116.047267) (xy 308.280182 -116.04523) (xy 308.225339 -116.0351)
			(xy 308.172555 -116.017093) (xy 308.122955 -115.991592) (xy 308.077597 -115.959141) (xy 308.037448 -115.920432)
			(xy 308.003362 -115.876289) (xy 307.976066 -115.827654) (xy 307.956143 -115.775563) (xy 307.944017 -115.721126)
			(xy 307.939946 -115.665504) (xy 281.569739 -115.665504) (xy 281.602642 -115.692723) (xy 281.646399 -115.73932)
			(xy 281.683972 -115.791035) (xy 281.714766 -115.84705) (xy 281.738298 -115.906483) (xy 281.754195 -115.968397)
			(xy 281.762206 -116.031815) (xy 281.762708 -116.063776) (xy 281.762206 -116.095737) (xy 281.754195 -116.159155)
			(xy 281.738298 -116.221069) (xy 281.714766 -116.280502) (xy 281.683972 -116.336517) (xy 281.646399 -116.388232)
			(xy 281.602642 -116.434829) (xy 281.553389 -116.475574) (xy 281.499418 -116.509825) (xy 281.441579 -116.537042)
			(xy 281.380786 -116.556795) (xy 281.317996 -116.568773) (xy 281.2542 -116.572787) (xy 281.190404 -116.568773)
			(xy 281.127614 -116.556795) (xy 281.066821 -116.537042) (xy 281.008982 -116.509825) (xy 280.955011 -116.475574)
			(xy 280.905758 -116.434829) (xy 280.862001 -116.388232) (xy 280.824428 -116.336517) (xy 280.793634 -116.280502)
			(xy 280.770102 -116.221069) (xy 280.754205 -116.159155) (xy 280.746194 -116.095737) (xy 274.890613 -116.095737)
			(xy 274.895628 -116.10486) (xy 274.91916 -116.164293) (xy 274.935057 -116.226207) (xy 274.943068 -116.289625)
			(xy 274.94357 -116.321586) (xy 274.943058 -116.353618) (xy 274.935003 -116.417173) (xy 274.919031 -116.479213)
			(xy 274.895395 -116.538757) (xy 274.864469 -116.594862) (xy 274.826743 -116.646639) (xy 274.782814 -116.693269)
			(xy 274.758404 -116.714016) (xy 274.748244 -116.722398) (xy 274.738592 -116.74602) (xy 274.751546 -116.856764)
			(xy 274.762993 -116.873231) (xy 275.041354 -116.873231) (xy 275.041354 -116.809309) (xy 275.049365 -116.745891)
			(xy 275.065262 -116.683977) (xy 275.088794 -116.624544) (xy 275.119588 -116.568529) (xy 275.157161 -116.516814)
			(xy 275.200918 -116.470217) (xy 275.250171 -116.429472) (xy 275.304142 -116.395221) (xy 275.361981 -116.368004)
			(xy 275.422774 -116.348251) (xy 275.485564 -116.336273) (xy 275.54936 -116.33226) (xy 275.613156 -116.336273)
			(xy 275.675946 -116.348251) (xy 275.736739 -116.368004) (xy 275.794578 -116.395221) (xy 275.848549 -116.429472)
			(xy 275.897802 -116.470217) (xy 275.941559 -116.516814) (xy 275.979132 -116.568529) (xy 276.009926 -116.624544)
			(xy 276.033458 -116.683977) (xy 276.049355 -116.745891) (xy 276.057366 -116.809309) (xy 276.057868 -116.84127)
			(xy 276.057366 -116.873231) (xy 276.049355 -116.936649) (xy 276.033458 -116.998563) (xy 276.009926 -117.057996)
			(xy 275.979132 -117.114011) (xy 275.941559 -117.165726) (xy 275.897802 -117.212323) (xy 275.852004 -117.25021)
			(xy 298.789852 -117.25021) (xy 298.790451 -117.215676) (xy 298.799792 -117.147243) (xy 298.818317 -117.080705)
			(xy 298.845683 -117.017291) (xy 298.881387 -116.958167) (xy 298.902628 -116.930932) (xy 298.907751 -116.924012)
			(xy 298.913467 -116.907785) (xy 298.913804 -116.899182) (xy 298.913804 -116.869464) (xy 298.913465 -116.860863)
			(xy 298.907746 -116.844636) (xy 298.902628 -116.837714) (xy 298.881389 -116.810477) (xy 298.845688 -116.751351)
			(xy 298.81832 -116.687937) (xy 298.799788 -116.621402) (xy 298.790433 -116.55297) (xy 298.789852 -116.518436)
			(xy 298.790354 -116.486475) (xy 298.798365 -116.423057) (xy 298.814262 -116.361143) (xy 298.837794 -116.30171)
			(xy 298.868588 -116.245695) (xy 298.906161 -116.19398) (xy 298.949918 -116.147383) (xy 298.999171 -116.106638)
			(xy 299.053142 -116.072387) (xy 299.110981 -116.04517) (xy 299.171774 -116.025417) (xy 299.234564 -116.013439)
			(xy 299.29836 -116.009426) (xy 299.362156 -116.013439) (xy 299.424946 -116.025417) (xy 299.485739 -116.04517)
			(xy 299.543578 -116.072387) (xy 299.597549 -116.106638) (xy 299.646802 -116.147383) (xy 299.690559 -116.19398)
			(xy 299.728132 -116.245695) (xy 299.758926 -116.30171) (xy 299.782458 -116.361143) (xy 299.798355 -116.423057)
			(xy 299.806366 -116.486475) (xy 299.806868 -116.518436) (xy 299.806312 -116.552972) (xy 299.796963 -116.621407)
			(xy 299.77843 -116.687946) (xy 299.751053 -116.75136) (xy 299.715338 -116.810481) (xy 299.694092 -116.837714)
			(xy 299.688953 -116.844623) (xy 299.683247 -116.860859) (xy 299.682916 -116.869464) (xy 299.682916 -116.891308)
			(xy 300.78756 -116.891308) (xy 300.791631 -116.835686) (xy 300.803757 -116.781249) (xy 300.82368 -116.729158)
			(xy 300.850976 -116.680523) (xy 300.885062 -116.63638) (xy 300.925211 -116.597671) (xy 300.970569 -116.56522)
			(xy 301.020169 -116.539719) (xy 301.072953 -116.521712) (xy 301.127796 -116.511582) (xy 301.18353 -116.509545)
			(xy 301.238967 -116.515645) (xy 301.292924 -116.529751) (xy 301.344253 -116.551563) (xy 301.391859 -116.580617)
			(xy 301.434727 -116.616292) (xy 301.471944 -116.657829) (xy 301.502717 -116.704342) (xy 301.526389 -116.754839)
			(xy 301.542457 -116.808246) (xy 301.550577 -116.863422) (xy 301.551086 -116.891308) (xy 301.550577 -116.919194)
			(xy 301.542457 -116.97437) (xy 301.528945 -117.019281) (xy 312.440568 -117.019281) (xy 312.440568 -116.955359)
			(xy 312.448579 -116.891941) (xy 312.464476 -116.830027) (xy 312.488008 -116.770594) (xy 312.518802 -116.714579)
			(xy 312.556375 -116.662864) (xy 312.600132 -116.616267) (xy 312.649385 -116.575522) (xy 312.703356 -116.541271)
			(xy 312.761195 -116.514054) (xy 312.821988 -116.494301) (xy 312.884778 -116.482323) (xy 312.948574 -116.47831)
			(xy 313.01237 -116.482323) (xy 313.07516 -116.494301) (xy 313.135953 -116.514054) (xy 313.193792 -116.541271)
			(xy 313.247763 -116.575522) (xy 313.297016 -116.616267) (xy 313.340773 -116.662864) (xy 313.341736 -116.664189)
			(xy 318.550792 -116.664189) (xy 318.550792 -116.600267) (xy 318.558803 -116.536849) (xy 318.5747 -116.474935)
			(xy 318.598232 -116.415502) (xy 318.629026 -116.359487) (xy 318.666599 -116.307772) (xy 318.710356 -116.261175)
			(xy 318.759609 -116.22043) (xy 318.81358 -116.186179) (xy 318.871419 -116.158962) (xy 318.932212 -116.139209)
			(xy 318.995002 -116.127231) (xy 319.058798 -116.123218) (xy 319.122594 -116.127231) (xy 319.185384 -116.139209)
			(xy 319.246177 -116.158962) (xy 319.304016 -116.186179) (xy 319.357987 -116.22043) (xy 319.40724 -116.261175)
			(xy 319.450997 -116.307772) (xy 319.48857 -116.359487) (xy 319.519364 -116.415502) (xy 319.524233 -116.4278)
			(xy 355.217948 -116.4278) (xy 355.221962 -116.363999) (xy 355.23394 -116.301204) (xy 355.253695 -116.240405)
			(xy 355.280914 -116.182562) (xy 355.315168 -116.128586) (xy 355.355917 -116.07933) (xy 355.402518 -116.035568)
			(xy 355.454236 -115.997993) (xy 355.510256 -115.967196) (xy 355.569694 -115.943662) (xy 355.631613 -115.927764)
			(xy 355.695036 -115.919752) (xy 355.727 -115.91925) (xy 355.759152 -115.919697) (xy 355.822943 -115.927798)
			(xy 355.885202 -115.943883) (xy 355.944934 -115.967695) (xy 356.001184 -115.998853) (xy 356.053053 -116.03686)
			(xy 356.099712 -116.081108) (xy 356.120446 -116.105686) (xy 356.126896 -116.112952) (xy 356.143886 -116.122349)
			(xy 356.153466 -116.123974) (xy 356.223316 -116.132356) (xy 356.233042 -116.133071) (xy 356.25185 -116.127968)
			(xy 356.259892 -116.12245) (xy 356.260146 -116.12245) (xy 356.285081 -116.104543) (xy 356.33947 -116.076079)
			(xy 356.397712 -116.056686) (xy 356.458307 -116.046863) (xy 356.489 -116.04625) (xy 356.519462 -116.046842)
			(xy 356.579612 -116.056531) (xy 356.637455 -116.075663) (xy 356.691519 -116.103749) (xy 356.71633 -116.121434)
			(xy 356.716584 -116.121434) (xy 356.724587 -116.126865) (xy 356.743263 -116.131828) (xy 356.752906 -116.131086)
			(xy 356.82301 -116.122196) (xy 356.8325 -116.120601) (xy 356.849343 -116.111321) (xy 356.855776 -116.104162)
			(xy 356.85603 -116.104162) (xy 356.85603 -116.103654) (xy 356.87677 -116.078865) (xy 356.923518 -116.034229)
			(xy 356.975545 -115.995876) (xy 357.032011 -115.964424) (xy 357.092008 -115.940381) (xy 357.154568 -115.924133)
			(xy 357.218682 -115.915943) (xy 357.251 -115.91544) (xy 357.282964 -115.915846) (xy 357.346388 -115.923858)
			(xy 357.408308 -115.939756) (xy 357.467747 -115.96329) (xy 357.523767 -115.994087) (xy 357.575486 -116.031663)
			(xy 357.622088 -116.075425) (xy 357.650658 -116.109961) (xy 369.442994 -116.109961) (xy 369.442994 -116.046039)
			(xy 369.451005 -115.982621) (xy 369.466902 -115.920707) (xy 369.490434 -115.861274) (xy 369.521228 -115.805259)
			(xy 369.558801 -115.753544) (xy 369.602558 -115.706947) (xy 369.651811 -115.666202) (xy 369.705782 -115.631951)
			(xy 369.763621 -115.604734) (xy 369.824414 -115.584981) (xy 369.887204 -115.573003) (xy 369.951 -115.56899)
			(xy 370.014796 -115.573003) (xy 370.077586 -115.584981) (xy 370.138379 -115.604734) (xy 370.196218 -115.631951)
			(xy 370.250189 -115.666202) (xy 370.299442 -115.706947) (xy 370.343199 -115.753544) (xy 370.380772 -115.805259)
			(xy 370.411566 -115.861274) (xy 370.435098 -115.920707) (xy 370.450995 -115.982621) (xy 370.459006 -116.046039)
			(xy 370.459508 -116.078) (xy 370.459006 -116.109961) (xy 370.450995 -116.173379) (xy 370.435098 -116.235293)
			(xy 370.411566 -116.294726) (xy 370.380772 -116.350741) (xy 370.343199 -116.402456) (xy 370.299442 -116.449053)
			(xy 370.250189 -116.489798) (xy 370.20513 -116.518393) (xy 372.01068 -116.518393) (xy 372.01068 -116.454471)
			(xy 372.018691 -116.391053) (xy 372.034588 -116.329139) (xy 372.05812 -116.269706) (xy 372.088914 -116.213691)
			(xy 372.126487 -116.161976) (xy 372.170244 -116.115379) (xy 372.219497 -116.074634) (xy 372.273468 -116.040383)
			(xy 372.331307 -116.013166) (xy 372.3921 -115.993413) (xy 372.45489 -115.981435) (xy 372.518686 -115.977422)
			(xy 372.582482 -115.981435) (xy 372.645272 -115.993413) (xy 372.706065 -116.013166) (xy 372.763904 -116.040383)
			(xy 372.817875 -116.074634) (xy 372.867128 -116.115379) (xy 372.910885 -116.161976) (xy 372.948458 -116.213691)
			(xy 372.962507 -116.239247) (xy 410.07385 -116.239247) (xy 410.07385 -116.175325) (xy 410.081861 -116.111907)
			(xy 410.097758 -116.049993) (xy 410.12129 -115.99056) (xy 410.152084 -115.934545) (xy 410.189657 -115.88283)
			(xy 410.233414 -115.836233) (xy 410.282667 -115.795488) (xy 410.336638 -115.761237) (xy 410.394477 -115.73402)
			(xy 410.45527 -115.714267) (xy 410.51806 -115.702289) (xy 410.581856 -115.698276) (xy 410.645652 -115.702289)
			(xy 410.708442 -115.714267) (xy 410.769235 -115.73402) (xy 410.827074 -115.761237) (xy 410.881045 -115.795488)
			(xy 410.930298 -115.836233) (xy 410.974055 -115.88283) (xy 411.011628 -115.934545) (xy 411.042422 -115.99056)
			(xy 411.065954 -116.049993) (xy 411.081851 -116.111907) (xy 411.089862 -116.175325) (xy 411.090364 -116.207286)
			(xy 411.089862 -116.239247) (xy 411.081851 -116.302665) (xy 411.065954 -116.364579) (xy 411.042422 -116.424012)
			(xy 411.011628 -116.480027) (xy 410.974055 -116.531742) (xy 410.930298 -116.578339) (xy 410.881045 -116.619084)
			(xy 410.827074 -116.653335) (xy 410.769235 -116.680552) (xy 410.708442 -116.700305) (xy 410.645652 -116.712283)
			(xy 410.581856 -116.716297) (xy 410.51806 -116.712283) (xy 410.45527 -116.700305) (xy 410.394477 -116.680552)
			(xy 410.336638 -116.653335) (xy 410.282667 -116.619084) (xy 410.233414 -116.578339) (xy 410.189657 -116.531742)
			(xy 410.152084 -116.480027) (xy 410.12129 -116.424012) (xy 410.097758 -116.364579) (xy 410.081861 -116.302665)
			(xy 410.07385 -116.239247) (xy 372.962507 -116.239247) (xy 372.979252 -116.269706) (xy 373.002784 -116.329139)
			(xy 373.018681 -116.391053) (xy 373.026692 -116.454471) (xy 373.027194 -116.486432) (xy 373.026692 -116.518393)
			(xy 373.018681 -116.581811) (xy 373.002784 -116.643725) (xy 372.979252 -116.703158) (xy 372.948458 -116.759173)
			(xy 372.910885 -116.810888) (xy 372.867128 -116.857485) (xy 372.817875 -116.89823) (xy 372.763904 -116.932481)
			(xy 372.706065 -116.959698) (xy 372.645272 -116.979451) (xy 372.582482 -116.991429) (xy 372.518686 -116.995443)
			(xy 372.45489 -116.991429) (xy 372.3921 -116.979451) (xy 372.331307 -116.959698) (xy 372.273468 -116.932481)
			(xy 372.219497 -116.89823) (xy 372.170244 -116.857485) (xy 372.126487 -116.810888) (xy 372.088914 -116.759173)
			(xy 372.05812 -116.703158) (xy 372.034588 -116.643725) (xy 372.018691 -116.581811) (xy 372.01068 -116.518393)
			(xy 370.20513 -116.518393) (xy 370.196218 -116.524049) (xy 370.138379 -116.551266) (xy 370.077586 -116.571019)
			(xy 370.014796 -116.582997) (xy 369.951 -116.587011) (xy 369.887204 -116.582997) (xy 369.824414 -116.571019)
			(xy 369.763621 -116.551266) (xy 369.705782 -116.524049) (xy 369.651811 -116.489798) (xy 369.602558 -116.449053)
			(xy 369.558801 -116.402456) (xy 369.521228 -116.350741) (xy 369.490434 -116.294726) (xy 369.466902 -116.235293)
			(xy 369.451005 -116.173379) (xy 369.442994 -116.109961) (xy 357.650658 -116.109961) (xy 357.662837 -116.124683)
			(xy 357.697092 -116.178659) (xy 357.724311 -116.236503) (xy 357.744066 -116.297302) (xy 357.756045 -116.360098)
			(xy 357.760059 -116.4239) (xy 357.756045 -116.487702) (xy 357.744066 -116.550498) (xy 357.724311 -116.611297)
			(xy 357.697092 -116.669141) (xy 357.662837 -116.723117) (xy 357.622088 -116.772375) (xy 357.575486 -116.816137)
			(xy 357.523767 -116.853713) (xy 357.467747 -116.88451) (xy 357.408308 -116.908044) (xy 357.346388 -116.923942)
			(xy 357.283391 -116.9319) (xy 357.885038 -116.9319) (xy 357.889051 -116.86811) (xy 357.901027 -116.805326)
			(xy 357.920779 -116.744538) (xy 357.947993 -116.686705) (xy 357.982241 -116.632739) (xy 358.022982 -116.583491)
			(xy 358.069575 -116.539738) (xy 358.121284 -116.502169) (xy 358.177294 -116.471377) (xy 358.236722 -116.447848)
			(xy 358.29863 -116.431953) (xy 358.362042 -116.423942) (xy 358.394 -116.42344) (xy 358.426152 -116.42389)
			(xy 358.489942 -116.431991) (xy 358.552201 -116.448076) (xy 358.611933 -116.471888) (xy 358.668183 -116.503045)
			(xy 358.720052 -116.541052) (xy 358.766712 -116.585299) (xy 358.787446 -116.609876) (xy 358.793898 -116.617141)
			(xy 358.810886 -116.626539) (xy 358.820466 -116.628164) (xy 358.890316 -116.636546) (xy 358.900042 -116.637263)
			(xy 358.91885 -116.632159) (xy 358.926892 -116.62664) (xy 358.927146 -116.62664) (xy 358.94926 -116.610657)
			(xy 358.997143 -116.5845) (xy 359.048263 -116.565426) (xy 359.101577 -116.553823) (xy 359.156 -116.549929)
			(xy 359.210423 -116.553823) (xy 359.263737 -116.565426) (xy 359.314857 -116.5845) (xy 359.36274 -116.610657)
			(xy 359.384854 -116.62664) (xy 359.385108 -116.62664) (xy 359.393149 -116.632167) (xy 359.411956 -116.637277)
			(xy 359.421684 -116.636546) (xy 359.491534 -116.628164) (xy 359.501102 -116.626507) (xy 359.518076 -116.617109)
			(xy 359.524554 -116.609876) (xy 359.545329 -116.585337) (xy 359.591993 -116.541108) (xy 359.64386 -116.503115)
			(xy 359.700104 -116.471963) (xy 359.759826 -116.448151) (xy 359.822073 -116.432057) (xy 359.885853 -116.423939)
			(xy 359.918 -116.42344) (xy 359.949964 -116.423846) (xy 360.013388 -116.431858) (xy 360.075308 -116.447756)
			(xy 360.134747 -116.47129) (xy 360.190767 -116.502087) (xy 360.242486 -116.539663) (xy 360.289088 -116.583425)
			(xy 360.329837 -116.632683) (xy 360.364092 -116.686659) (xy 360.391311 -116.744503) (xy 360.411066 -116.805302)
			(xy 360.423045 -116.868098) (xy 360.427059 -116.9319) (xy 360.423045 -116.995702) (xy 360.411066 -117.058498)
			(xy 360.391311 -117.119297) (xy 360.364092 -117.177141) (xy 360.329837 -117.231117) (xy 360.289088 -117.280375)
			(xy 360.242486 -117.324137) (xy 360.190767 -117.361713) (xy 360.134747 -117.39251) (xy 360.075308 -117.416044)
			(xy 360.013388 -117.431942) (xy 359.949964 -117.439954) (xy 359.918 -117.440456) (xy 359.885848 -117.440007)
			(xy 359.822057 -117.431906) (xy 359.759799 -117.415821) (xy 359.700067 -117.392009) (xy 359.643817 -117.360851)
			(xy 359.591947 -117.322845) (xy 359.545288 -117.278598) (xy 359.524554 -117.25402) (xy 359.518103 -117.246755)
			(xy 359.501114 -117.237357) (xy 359.491534 -117.235732) (xy 359.421684 -117.22735) (xy 359.411958 -117.226633)
			(xy 359.39315 -117.231737) (xy 359.385108 -117.237256) (xy 359.384854 -117.237256) (xy 359.36274 -117.253239)
			(xy 359.314857 -117.279396) (xy 359.263737 -117.29847) (xy 359.210423 -117.310073) (xy 359.156 -117.313967)
			(xy 359.101577 -117.310073) (xy 359.048263 -117.29847) (xy 358.997143 -117.279396) (xy 358.94926 -117.253239)
			(xy 358.927146 -117.237256) (xy 358.926892 -117.237256) (xy 358.918852 -117.231729) (xy 358.900044 -117.226619)
			(xy 358.890316 -117.22735) (xy 358.820466 -117.235732) (xy 358.810899 -117.23739) (xy 358.793925 -117.246788)
			(xy 358.787446 -117.25402) (xy 358.76667 -117.278558) (xy 358.720007 -117.322787) (xy 358.668139 -117.360781)
			(xy 358.611896 -117.391933) (xy 358.552174 -117.415745) (xy 358.489927 -117.431839) (xy 358.426147 -117.439957)
			(xy 358.394 -117.440456) (xy 358.362042 -117.439858) (xy 358.29863 -117.431847) (xy 358.236722 -117.415952)
			(xy 358.177294 -117.392423) (xy 358.121284 -117.361631) (xy 358.069575 -117.324062) (xy 358.022982 -117.280309)
			(xy 357.982241 -117.231061) (xy 357.947993 -117.177095) (xy 357.920779 -117.119262) (xy 357.901027 -117.058474)
			(xy 357.889051 -116.99569) (xy 357.885038 -116.9319) (xy 357.283391 -116.9319) (xy 357.282964 -116.931954)
			(xy 357.251 -116.932456) (xy 357.219031 -116.931964) (xy 357.155599 -116.923942) (xy 357.093671 -116.908036)
			(xy 357.034224 -116.884498) (xy 356.978193 -116.853698) (xy 356.926463 -116.816122) (xy 356.879847 -116.77236)
			(xy 356.859078 -116.748052) (xy 356.852728 -116.740432) (xy 356.83571 -116.731034) (xy 356.746302 -116.72062)
			(xy 356.727252 -116.725954) (xy 356.719378 -116.731796) (xy 356.694359 -116.750009) (xy 356.639662 -116.778947)
			(xy 356.581009 -116.798671) (xy 356.51994 -116.808664) (xy 356.489 -116.809266) (xy 356.458307 -116.808652)
			(xy 356.397712 -116.79883) (xy 356.339469 -116.779437) (xy 356.28508 -116.750975) (xy 356.260146 -116.733066)
			(xy 356.259892 -116.733066) (xy 356.251851 -116.72754) (xy 356.233044 -116.722429) (xy 356.223316 -116.72316)
			(xy 356.153466 -116.731542) (xy 356.143898 -116.733197) (xy 356.126924 -116.742596) (xy 356.120446 -116.74983)
			(xy 356.099673 -116.77437) (xy 356.053008 -116.818599) (xy 356.00114 -116.856592) (xy 355.944897 -116.887743)
			(xy 355.885175 -116.911556) (xy 355.822927 -116.927649) (xy 355.759147 -116.935767) (xy 355.727 -116.936266)
			(xy 355.695036 -116.935848) (xy 355.631613 -116.927836) (xy 355.569694 -116.911938) (xy 355.510256 -116.888404)
			(xy 355.454236 -116.857607) (xy 355.402518 -116.820032) (xy 355.355917 -116.77627) (xy 355.315168 -116.727014)
			(xy 355.280914 -116.673038) (xy 355.253695 -116.615195) (xy 355.23394 -116.554396) (xy 355.221962 -116.491601)
			(xy 355.217948 -116.4278) (xy 319.524233 -116.4278) (xy 319.542896 -116.474935) (xy 319.558793 -116.536849)
			(xy 319.566804 -116.600267) (xy 319.567306 -116.632228) (xy 319.566804 -116.664189) (xy 319.558793 -116.727607)
			(xy 319.542896 -116.789521) (xy 319.519364 -116.848954) (xy 319.48857 -116.904969) (xy 319.450997 -116.956684)
			(xy 319.40724 -117.003281) (xy 319.357987 -117.044026) (xy 319.304016 -117.078277) (xy 319.246177 -117.105494)
			(xy 319.185384 -117.125247) (xy 319.122594 -117.137225) (xy 319.058798 -117.141239) (xy 318.995002 -117.137225)
			(xy 318.932212 -117.125247) (xy 318.871419 -117.105494) (xy 318.81358 -117.078277) (xy 318.759609 -117.044026)
			(xy 318.710356 -117.003281) (xy 318.666599 -116.956684) (xy 318.629026 -116.904969) (xy 318.598232 -116.848954)
			(xy 318.5747 -116.789521) (xy 318.558803 -116.727607) (xy 318.550792 -116.664189) (xy 313.341736 -116.664189)
			(xy 313.378346 -116.714579) (xy 313.40914 -116.770594) (xy 313.432672 -116.830027) (xy 313.448569 -116.891941)
			(xy 313.45658 -116.955359) (xy 313.457082 -116.98732) (xy 313.45658 -117.019281) (xy 313.448569 -117.082699)
			(xy 313.432672 -117.144613) (xy 313.40914 -117.204046) (xy 313.378346 -117.260061) (xy 313.340773 -117.311776)
			(xy 313.297016 -117.358373) (xy 313.247763 -117.399118) (xy 313.193792 -117.433369) (xy 313.135953 -117.460586)
			(xy 313.07516 -117.480339) (xy 313.01237 -117.492317) (xy 312.948574 -117.496331) (xy 312.884778 -117.492317)
			(xy 312.821988 -117.480339) (xy 312.761195 -117.460586) (xy 312.703356 -117.433369) (xy 312.649385 -117.399118)
			(xy 312.600132 -117.358373) (xy 312.556375 -117.311776) (xy 312.518802 -117.260061) (xy 312.488008 -117.204046)
			(xy 312.464476 -117.144613) (xy 312.448579 -117.082699) (xy 312.440568 -117.019281) (xy 301.528945 -117.019281)
			(xy 301.526389 -117.027777) (xy 301.502717 -117.078274) (xy 301.471944 -117.124787) (xy 301.434727 -117.166324)
			(xy 301.391859 -117.201999) (xy 301.344253 -117.231053) (xy 301.292924 -117.252865) (xy 301.238967 -117.266971)
			(xy 301.18353 -117.273071) (xy 301.127796 -117.271034) (xy 301.072953 -117.260904) (xy 301.020169 -117.242897)
			(xy 300.970569 -117.217396) (xy 300.925211 -117.184945) (xy 300.885062 -117.146236) (xy 300.850976 -117.102093)
			(xy 300.82368 -117.053458) (xy 300.803757 -117.001367) (xy 300.791631 -116.94693) (xy 300.78756 -116.891308)
			(xy 299.682916 -116.891308) (xy 299.682916 -116.899182) (xy 299.683276 -116.907781) (xy 299.68898 -116.924008)
			(xy 299.694092 -116.930932) (xy 299.715355 -116.958151) (xy 299.751051 -117.017282) (xy 299.778415 -117.080701)
			(xy 299.796941 -117.14724) (xy 299.80629 -117.215675) (xy 299.806868 -117.25021) (xy 299.806366 -117.282171)
			(xy 299.798355 -117.345589) (xy 299.782458 -117.407503) (xy 299.758926 -117.466936) (xy 299.728132 -117.522951)
			(xy 299.690559 -117.574666) (xy 299.646802 -117.621263) (xy 299.597549 -117.662008) (xy 299.543578 -117.696259)
			(xy 299.485739 -117.723476) (xy 299.424946 -117.743229) (xy 299.362156 -117.755207) (xy 299.29836 -117.759221)
			(xy 299.234564 -117.755207) (xy 299.171774 -117.743229) (xy 299.110981 -117.723476) (xy 299.053142 -117.696259)
			(xy 298.999171 -117.662008) (xy 298.949918 -117.621263) (xy 298.906161 -117.574666) (xy 298.868588 -117.522951)
			(xy 298.837794 -117.466936) (xy 298.814262 -117.407503) (xy 298.798365 -117.345589) (xy 298.790354 -117.282171)
			(xy 298.789852 -117.25021) (xy 275.852004 -117.25021) (xy 275.848549 -117.253068) (xy 275.794578 -117.287319)
			(xy 275.736739 -117.314536) (xy 275.675946 -117.334289) (xy 275.613156 -117.346267) (xy 275.54936 -117.350281)
			(xy 275.485564 -117.346267) (xy 275.422774 -117.334289) (xy 275.361981 -117.314536) (xy 275.304142 -117.287319)
			(xy 275.250171 -117.253068) (xy 275.200918 -117.212323) (xy 275.157161 -117.165726) (xy 275.119588 -117.114011)
			(xy 275.088794 -117.057996) (xy 275.065262 -116.998563) (xy 275.049365 -116.936649) (xy 275.041354 -116.873231)
			(xy 274.762993 -116.873231) (xy 274.766024 -116.877592) (xy 274.777708 -116.883434) (xy 274.801203 -116.895614)
			(xy 274.844866 -116.92552) (xy 274.883978 -116.961171) (xy 274.91779 -117.001884) (xy 274.945653 -117.046877)
			(xy 274.967033 -117.095288) (xy 274.98152 -117.146189) (xy 274.988836 -117.198603) (xy 274.98929 -117.225064)
			(xy 274.988811 -117.252317) (xy 274.981059 -117.306268) (xy 274.965706 -117.358567) (xy 274.943067 -117.408148)
			(xy 274.913601 -117.454002) (xy 274.877908 -117.495196) (xy 274.836717 -117.53089) (xy 274.790864 -117.560358)
			(xy 274.741284 -117.583) (xy 274.688986 -117.598355) (xy 274.635035 -117.60611) (xy 274.607782 -117.606572)
			(xy 274.607528 -117.606572) (xy 274.577351 -117.605978) (xy 274.517753 -117.596452) (xy 274.460393 -117.577678)
			(xy 274.433284 -117.564408) (xy 274.421092 -117.558058) (xy 274.393152 -117.559582) (xy 274.296124 -117.625876)
			(xy 274.28444 -117.650768) (xy 274.28571 -117.664484) (xy 274.28571 -117.664992) (xy 274.28688 -117.677405)
			(xy 274.288149 -117.702308) (xy 274.28825 -117.714776) (xy 274.287758 -117.746319) (xy 274.279957 -117.808922)
			(xy 274.264473 -117.870079) (xy 274.241542 -117.928851) (xy 274.211518 -117.984335) (xy 274.174861 -118.035679)
			(xy 274.132135 -118.082095) (xy 274.083996 -118.122869) (xy 274.031182 -118.157375) (xy 273.974506 -118.185084)
			(xy 273.914838 -118.205569) (xy 273.853094 -118.218516) (xy 273.790222 -118.223726) (xy 273.72719 -118.221119)
			(xy 273.664963 -118.210735) (xy 273.604499 -118.192734) (xy 273.546726 -118.167392) (xy 273.492532 -118.135098)
			(xy 273.442748 -118.096349) (xy 273.398139 -118.051739) (xy 273.359392 -118.001954) (xy 273.3271 -117.947758)
			(xy 273.30176 -117.889984) (xy 273.283761 -117.829519) (xy 273.273379 -117.767293) (xy 273.270775 -117.70426)
			(xy 260.441756 -117.70426) (xy 260.432778 -117.739227) (xy 260.409246 -117.79866) (xy 260.378452 -117.854675)
			(xy 260.340879 -117.90639) (xy 260.297122 -117.952987) (xy 260.247869 -117.993732) (xy 260.193898 -118.027983)
			(xy 260.136059 -118.0552) (xy 260.075266 -118.074953) (xy 260.012476 -118.086931) (xy 259.94868 -118.090945)
			(xy 259.884884 -118.086931) (xy 259.822094 -118.074953) (xy 259.761301 -118.0552) (xy 259.703462 -118.027983)
			(xy 259.649491 -117.993732) (xy 259.600238 -117.952987) (xy 259.556481 -117.90639) (xy 259.518908 -117.854675)
			(xy 259.488114 -117.79866) (xy 259.464582 -117.739227) (xy 259.448685 -117.677313) (xy 259.440674 -117.613895)
			(xy 258.797306 -117.613895) (xy 258.803652 -117.622629) (xy 258.834446 -117.678644) (xy 258.857978 -117.738077)
			(xy 258.873875 -117.799991) (xy 258.881886 -117.863409) (xy 258.882388 -117.89537) (xy 258.881886 -117.927331)
			(xy 258.873875 -117.990749) (xy 258.857978 -118.052663) (xy 258.834446 -118.112096) (xy 258.803652 -118.168111)
			(xy 258.766079 -118.219826) (xy 258.722322 -118.266423) (xy 258.673069 -118.307168) (xy 258.619098 -118.341419)
			(xy 258.561259 -118.368636) (xy 258.500466 -118.388389) (xy 258.437676 -118.400367) (xy 258.37388 -118.404381)
			(xy 258.310084 -118.400367) (xy 258.247294 -118.388389) (xy 258.186501 -118.368636) (xy 258.128662 -118.341419)
			(xy 258.074691 -118.307168) (xy 258.025438 -118.266423) (xy 257.981681 -118.219826) (xy 257.944108 -118.168111)
			(xy 257.913314 -118.112096) (xy 257.889782 -118.052663) (xy 257.873885 -117.990749) (xy 257.865874 -117.927331)
			(xy 252.822404 -117.927331) (xy 252.847666 -117.973284) (xy 252.871198 -118.032717) (xy 252.887095 -118.094631)
			(xy 252.895106 -118.158049) (xy 252.895608 -118.19001) (xy 252.895106 -118.221971) (xy 252.887095 -118.285389)
			(xy 252.871198 -118.347303) (xy 252.847666 -118.406736) (xy 252.816872 -118.462751) (xy 252.779299 -118.514466)
			(xy 252.735542 -118.561063) (xy 252.686289 -118.601808) (xy 252.632318 -118.636059) (xy 252.574479 -118.663276)
			(xy 252.513686 -118.683029) (xy 252.450896 -118.695007) (xy 252.3871 -118.699021) (xy 252.323304 -118.695007)
			(xy 252.260514 -118.683029) (xy 252.199721 -118.663276) (xy 252.141882 -118.636059) (xy 252.087911 -118.601808)
			(xy 252.038658 -118.561063) (xy 251.994901 -118.514466) (xy 251.957328 -118.462751) (xy 251.926534 -118.406736)
			(xy 251.903002 -118.347303) (xy 251.887105 -118.285389) (xy 251.879094 -118.221971) (xy 251.625106 -118.221971)
			(xy 251.617095 -118.285389) (xy 251.601198 -118.347303) (xy 251.577666 -118.406736) (xy 251.546872 -118.462751)
			(xy 251.509299 -118.514466) (xy 251.465542 -118.561063) (xy 251.416289 -118.601808) (xy 251.362318 -118.636059)
			(xy 251.304479 -118.663276) (xy 251.243686 -118.683029) (xy 251.180896 -118.695007) (xy 251.1171 -118.699021)
			(xy 251.053304 -118.695007) (xy 250.990514 -118.683029) (xy 250.929721 -118.663276) (xy 250.871882 -118.636059)
			(xy 250.817911 -118.601808) (xy 250.768658 -118.561063) (xy 250.724901 -118.514466) (xy 250.687328 -118.462751)
			(xy 250.656534 -118.406736) (xy 250.633002 -118.347303) (xy 250.617105 -118.285389) (xy 250.609094 -118.221971)
			(xy 243.896936 -118.221971) (xy 243.904776 -118.284033) (xy 243.905278 -118.315994) (xy 243.904776 -118.347955)
			(xy 243.896765 -118.411373) (xy 243.880868 -118.473287) (xy 243.857336 -118.53272) (xy 243.826542 -118.588735)
			(xy 243.788969 -118.64045) (xy 243.745212 -118.687047) (xy 243.695959 -118.727792) (xy 243.641988 -118.762043)
			(xy 243.584149 -118.78926) (xy 243.523356 -118.809013) (xy 243.460566 -118.820991) (xy 243.39677 -118.825005)
			(xy 243.332974 -118.820991) (xy 243.270184 -118.809013) (xy 243.209391 -118.78926) (xy 243.151552 -118.762043)
			(xy 243.097581 -118.727792) (xy 243.048328 -118.687047) (xy 243.004571 -118.64045) (xy 242.966998 -118.588735)
			(xy 242.936204 -118.53272) (xy 242.912672 -118.473287) (xy 242.896775 -118.411373) (xy 242.888764 -118.347955)
			(xy 227.155825 -118.347955) (xy 227.163499 -118.377841) (xy 227.17151 -118.441259) (xy 227.172012 -118.47322)
			(xy 227.17151 -118.505181) (xy 227.163499 -118.568599) (xy 227.147602 -118.630513) (xy 227.12407 -118.689946)
			(xy 227.093276 -118.745961) (xy 227.055703 -118.797676) (xy 227.011946 -118.844273) (xy 226.962693 -118.885018)
			(xy 226.917234 -118.913867) (xy 259.440674 -118.913867) (xy 259.440674 -118.849945) (xy 259.448685 -118.786527)
			(xy 259.464582 -118.724613) (xy 259.488114 -118.66518) (xy 259.518908 -118.609165) (xy 259.556481 -118.55745)
			(xy 259.600238 -118.510853) (xy 259.649491 -118.470108) (xy 259.703462 -118.435857) (xy 259.761301 -118.40864)
			(xy 259.822094 -118.388887) (xy 259.884884 -118.376909) (xy 259.94868 -118.372896) (xy 260.012476 -118.376909)
			(xy 260.075266 -118.388887) (xy 260.136059 -118.40864) (xy 260.193898 -118.435857) (xy 260.247869 -118.470108)
			(xy 260.297122 -118.510853) (xy 260.340879 -118.55745) (xy 260.378452 -118.609165) (xy 260.400879 -118.649961)
			(xy 271.695412 -118.649961) (xy 271.695412 -118.586039) (xy 271.703423 -118.522621) (xy 271.71932 -118.460707)
			(xy 271.742852 -118.401274) (xy 271.773646 -118.345259) (xy 271.811219 -118.293544) (xy 271.854976 -118.246947)
			(xy 271.904229 -118.206202) (xy 271.9582 -118.171951) (xy 272.016039 -118.144734) (xy 272.076832 -118.124981)
			(xy 272.139622 -118.113003) (xy 272.203418 -118.10899) (xy 272.267214 -118.113003) (xy 272.330004 -118.124981)
			(xy 272.390797 -118.144734) (xy 272.448636 -118.171951) (xy 272.502607 -118.206202) (xy 272.55186 -118.246947)
			(xy 272.595617 -118.293544) (xy 272.63319 -118.345259) (xy 272.657991 -118.390373) (xy 275.298148 -118.390373)
			(xy 275.298148 -118.326451) (xy 275.306159 -118.263033) (xy 275.322056 -118.201119) (xy 275.345588 -118.141686)
			(xy 275.376382 -118.085671) (xy 275.413955 -118.033956) (xy 275.457712 -117.987359) (xy 275.506965 -117.946614)
			(xy 275.560936 -117.912363) (xy 275.618775 -117.885146) (xy 275.679568 -117.865393) (xy 275.742358 -117.853415)
			(xy 275.806154 -117.849402) (xy 275.86995 -117.853415) (xy 275.93274 -117.865393) (xy 275.993533 -117.885146)
			(xy 276.051372 -117.912363) (xy 276.105343 -117.946614) (xy 276.153573 -117.986513) (xy 281.705298 -117.986513)
			(xy 281.705298 -117.922591) (xy 281.713309 -117.859173) (xy 281.729206 -117.797259) (xy 281.752738 -117.737826)
			(xy 281.783532 -117.681811) (xy 281.821105 -117.630096) (xy 281.864862 -117.583499) (xy 281.914115 -117.542754)
			(xy 281.968086 -117.508503) (xy 282.025925 -117.481286) (xy 282.086718 -117.461533) (xy 282.149508 -117.449555)
			(xy 282.213304 -117.445542) (xy 282.2771 -117.449555) (xy 282.33989 -117.461533) (xy 282.400683 -117.481286)
			(xy 282.458522 -117.508503) (xy 282.512493 -117.542754) (xy 282.561746 -117.583499) (xy 282.605503 -117.630096)
			(xy 282.643076 -117.681811) (xy 282.67387 -117.737826) (xy 282.697402 -117.797259) (xy 282.713299 -117.859173)
			(xy 282.72131 -117.922591) (xy 282.721812 -117.954552) (xy 282.72131 -117.986513) (xy 282.713299 -118.049931)
			(xy 282.697402 -118.111845) (xy 282.67387 -118.171278) (xy 282.643076 -118.227293) (xy 282.605503 -118.279008)
			(xy 282.561746 -118.325605) (xy 282.512493 -118.36635) (xy 282.458522 -118.400601) (xy 282.400683 -118.427818)
			(xy 282.33989 -118.447571) (xy 282.2771 -118.459549) (xy 282.213304 -118.463563) (xy 282.149508 -118.459549)
			(xy 282.086718 -118.447571) (xy 282.025925 -118.427818) (xy 281.968086 -118.400601) (xy 281.914115 -118.36635)
			(xy 281.864862 -118.325605) (xy 281.821105 -118.279008) (xy 281.783532 -118.227293) (xy 281.752738 -118.171278)
			(xy 281.729206 -118.111845) (xy 281.713309 -118.049931) (xy 281.705298 -117.986513) (xy 276.153573 -117.986513)
			(xy 276.154596 -117.987359) (xy 276.198353 -118.033956) (xy 276.235926 -118.085671) (xy 276.26672 -118.141686)
			(xy 276.290252 -118.201119) (xy 276.306149 -118.263033) (xy 276.31416 -118.326451) (xy 276.314662 -118.358412)
			(xy 276.31416 -118.390373) (xy 276.306149 -118.453791) (xy 276.290252 -118.515705) (xy 276.26672 -118.575138)
			(xy 276.235926 -118.631153) (xy 276.198353 -118.682868) (xy 276.154596 -118.729465) (xy 276.105343 -118.77021)
			(xy 276.051372 -118.804461) (xy 275.993533 -118.831678) (xy 275.93274 -118.851431) (xy 275.86995 -118.863409)
			(xy 275.806154 -118.867423) (xy 275.742358 -118.863409) (xy 275.679568 -118.851431) (xy 275.618775 -118.831678)
			(xy 275.560936 -118.804461) (xy 275.506965 -118.77021) (xy 275.457712 -118.729465) (xy 275.413955 -118.682868)
			(xy 275.376382 -118.631153) (xy 275.345588 -118.575138) (xy 275.322056 -118.515705) (xy 275.306159 -118.453791)
			(xy 275.298148 -118.390373) (xy 272.657991 -118.390373) (xy 272.663984 -118.401274) (xy 272.687516 -118.460707)
			(xy 272.703413 -118.522621) (xy 272.711424 -118.586039) (xy 272.711926 -118.618) (xy 272.711424 -118.649961)
			(xy 272.703413 -118.713379) (xy 272.687516 -118.775293) (xy 272.663984 -118.834726) (xy 272.63319 -118.890741)
			(xy 272.595617 -118.942456) (xy 272.55186 -118.989053) (xy 272.502607 -119.029798) (xy 272.448636 -119.064049)
			(xy 272.390797 -119.091266) (xy 272.330004 -119.111019) (xy 272.267214 -119.122997) (xy 272.203418 -119.127011)
			(xy 272.139622 -119.122997) (xy 272.076832 -119.111019) (xy 272.016039 -119.091266) (xy 271.9582 -119.064049)
			(xy 271.904229 -119.029798) (xy 271.854976 -118.989053) (xy 271.811219 -118.942456) (xy 271.773646 -118.890741)
			(xy 271.742852 -118.834726) (xy 271.71932 -118.775293) (xy 271.703423 -118.713379) (xy 271.695412 -118.649961)
			(xy 260.400879 -118.649961) (xy 260.409246 -118.66518) (xy 260.432778 -118.724613) (xy 260.448675 -118.786527)
			(xy 260.456686 -118.849945) (xy 260.457188 -118.881906) (xy 260.456686 -118.913867) (xy 260.448675 -118.977285)
			(xy 260.432778 -119.039199) (xy 260.409246 -119.098632) (xy 260.378452 -119.154647) (xy 260.340879 -119.206362)
			(xy 260.297122 -119.252959) (xy 260.247869 -119.293704) (xy 260.193898 -119.327955) (xy 260.136059 -119.355172)
			(xy 260.075266 -119.374925) (xy 260.012476 -119.386903) (xy 259.94868 -119.390917) (xy 259.884884 -119.386903)
			(xy 259.822094 -119.374925) (xy 259.761301 -119.355172) (xy 259.703462 -119.327955) (xy 259.649491 -119.293704)
			(xy 259.600238 -119.252959) (xy 259.556481 -119.206362) (xy 259.518908 -119.154647) (xy 259.488114 -119.098632)
			(xy 259.464582 -119.039199) (xy 259.448685 -118.977285) (xy 259.440674 -118.913867) (xy 226.917234 -118.913867)
			(xy 226.908722 -118.919269) (xy 226.850883 -118.946486) (xy 226.79009 -118.966239) (xy 226.7273 -118.978217)
			(xy 226.663504 -118.982231) (xy 226.599708 -118.978217) (xy 226.536918 -118.966239) (xy 226.476125 -118.946486)
			(xy 226.418286 -118.919269) (xy 226.364315 -118.885018) (xy 226.315062 -118.844273) (xy 226.271305 -118.797676)
			(xy 226.233732 -118.745961) (xy 226.202938 -118.689946) (xy 226.179406 -118.630513) (xy 226.163509 -118.568599)
			(xy 226.155498 -118.505181) (xy 218.497539 -118.505181) (xy 218.505147 -118.534813) (xy 218.513158 -118.598231)
			(xy 218.51366 -118.630192) (xy 218.513158 -118.662153) (xy 218.505147 -118.725571) (xy 218.48925 -118.787485)
			(xy 218.465718 -118.846918) (xy 218.434924 -118.902933) (xy 218.397351 -118.954648) (xy 218.353594 -119.001245)
			(xy 218.304341 -119.04199) (xy 218.25037 -119.076241) (xy 218.192531 -119.103458) (xy 218.131738 -119.123211)
			(xy 218.068948 -119.135189) (xy 218.005152 -119.139203) (xy 217.941356 -119.135189) (xy 217.878566 -119.123211)
			(xy 217.817773 -119.103458) (xy 217.759934 -119.076241) (xy 217.705963 -119.04199) (xy 217.65671 -119.001245)
			(xy 217.612953 -118.954648) (xy 217.57538 -118.902933) (xy 217.544586 -118.846918) (xy 217.521054 -118.787485)
			(xy 217.505157 -118.725571) (xy 217.497146 -118.662153) (xy 213.630147 -118.662153) (xy 213.640898 -118.689307)
			(xy 213.656795 -118.751221) (xy 213.664806 -118.814639) (xy 213.665308 -118.8466) (xy 213.664806 -118.878561)
			(xy 213.656795 -118.941979) (xy 213.640898 -119.003893) (xy 213.617366 -119.063326) (xy 213.586572 -119.119341)
			(xy 213.548999 -119.171056) (xy 213.505242 -119.217653) (xy 213.455989 -119.258398) (xy 213.402018 -119.292649)
			(xy 213.344179 -119.319866) (xy 213.283386 -119.339619) (xy 213.220596 -119.351597) (xy 213.1568 -119.355611)
			(xy 213.093004 -119.351597) (xy 213.030214 -119.339619) (xy 212.969421 -119.319866) (xy 212.911582 -119.292649)
			(xy 212.857611 -119.258398) (xy 212.808358 -119.217653) (xy 212.764601 -119.171056) (xy 212.727028 -119.119341)
			(xy 212.696234 -119.063326) (xy 212.672702 -119.003893) (xy 212.656805 -118.941979) (xy 212.648794 -118.878561)
			(xy 210.997453 -118.878561) (xy 210.98546 -118.9239) (xy 210.960597 -118.984763) (xy 210.928098 -119.041915)
			(xy 210.888505 -119.094402) (xy 210.842479 -119.141349) (xy 210.816952 -119.162068) (xy 210.808266 -119.169671)
			(xy 210.798203 -119.190418) (xy 210.797648 -119.201946) (xy 210.797648 -119.281702) (xy 210.798218 -119.293233)
			(xy 210.808247 -119.313999) (xy 210.816952 -119.32158) (xy 210.842499 -119.342276) (xy 210.888531 -119.389222)
			(xy 210.928126 -119.441711) (xy 210.960623 -119.498867) (xy 210.98548 -119.559735) (xy 211.001485 -119.620284)
			(xy 216.086942 -119.620284) (xy 216.091013 -119.564662) (xy 216.103139 -119.510225) (xy 216.123062 -119.458134)
			(xy 216.150358 -119.409499) (xy 216.184444 -119.365356) (xy 216.224593 -119.326647) (xy 216.269951 -119.294196)
			(xy 216.319551 -119.268695) (xy 216.372335 -119.250688) (xy 216.427178 -119.240558) (xy 216.482912 -119.238521)
			(xy 216.538349 -119.244621) (xy 216.592306 -119.258727) (xy 216.594968 -119.259858) (xy 225.312222 -119.259858)
			(xy 225.316293 -119.204236) (xy 225.328419 -119.149799) (xy 225.348342 -119.097708) (xy 225.375638 -119.049073)
			(xy 225.409724 -119.00493) (xy 225.449873 -118.966221) (xy 225.495231 -118.93377) (xy 225.544831 -118.908269)
			(xy 225.597615 -118.890262) (xy 225.652458 -118.880132) (xy 225.708192 -118.878095) (xy 225.763629 -118.884195)
			(xy 225.817586 -118.898301) (xy 225.868915 -118.920113) (xy 225.916521 -118.949167) (xy 225.959389 -118.984842)
			(xy 225.996606 -119.026379) (xy 226.027379 -119.072892) (xy 226.051051 -119.123389) (xy 226.067119 -119.176796)
			(xy 226.075239 -119.231972) (xy 226.075748 -119.259858) (xy 226.075239 -119.287744) (xy 226.067119 -119.34292)
			(xy 226.051051 -119.396327) (xy 226.027379 -119.446824) (xy 226.014819 -119.465809) (xy 251.274574 -119.465809)
			(xy 251.274574 -119.401887) (xy 251.282585 -119.338469) (xy 251.298482 -119.276555) (xy 251.322014 -119.217122)
			(xy 251.352808 -119.161107) (xy 251.390381 -119.109392) (xy 251.434138 -119.062795) (xy 251.483391 -119.02205)
			(xy 251.537362 -118.987799) (xy 251.595201 -118.960582) (xy 251.655994 -118.940829) (xy 251.718784 -118.928851)
			(xy 251.78258 -118.924838) (xy 251.846376 -118.928851) (xy 251.909166 -118.940829) (xy 251.969959 -118.960582)
			(xy 252.027798 -118.987799) (xy 252.081769 -119.02205) (xy 252.131022 -119.062795) (xy 252.174779 -119.109392)
			(xy 252.212352 -119.161107) (xy 252.243146 -119.217122) (xy 252.266678 -119.276555) (xy 252.282575 -119.338469)
			(xy 252.290586 -119.401887) (xy 252.291088 -119.433848) (xy 252.290586 -119.465809) (xy 252.285709 -119.504417)
			(xy 252.557274 -119.504417) (xy 252.557274 -119.440495) (xy 252.565285 -119.377077) (xy 252.581182 -119.315163)
			(xy 252.604714 -119.25573) (xy 252.635508 -119.199715) (xy 252.673081 -119.148) (xy 252.716838 -119.101403)
			(xy 252.766091 -119.060658) (xy 252.820062 -119.026407) (xy 252.877901 -118.99919) (xy 252.938694 -118.979437)
			(xy 253.001484 -118.967459) (xy 253.06528 -118.963446) (xy 253.129076 -118.967459) (xy 253.191866 -118.979437)
			(xy 253.252659 -118.99919) (xy 253.310498 -119.026407) (xy 253.364469 -119.060658) (xy 253.413722 -119.101403)
			(xy 253.457479 -119.148) (xy 253.495052 -119.199715) (xy 253.525846 -119.25573) (xy 253.549378 -119.315163)
			(xy 253.565275 -119.377077) (xy 253.573286 -119.440495) (xy 253.573788 -119.472456) (xy 253.573286 -119.504417)
			(xy 253.565275 -119.567835) (xy 253.549378 -119.629749) (xy 253.525846 -119.689182) (xy 253.495052 -119.745197)
			(xy 253.457479 -119.796912) (xy 253.413722 -119.843509) (xy 253.364469 -119.884254) (xy 253.310498 -119.918505)
			(xy 253.252659 -119.945722) (xy 253.210775 -119.959331) (xy 257.898894 -119.959331) (xy 257.898894 -119.895409)
			(xy 257.906905 -119.831991) (xy 257.922802 -119.770077) (xy 257.946334 -119.710644) (xy 257.977128 -119.654629)
			(xy 258.014701 -119.602914) (xy 258.058458 -119.556317) (xy 258.107711 -119.515572) (xy 258.161682 -119.481321)
			(xy 258.219521 -119.454104) (xy 258.280314 -119.434351) (xy 258.343104 -119.422373) (xy 258.4069 -119.41836)
			(xy 258.470696 -119.422373) (xy 258.533486 -119.434351) (xy 258.594279 -119.454104) (xy 258.652118 -119.481321)
			(xy 258.706089 -119.515572) (xy 258.755342 -119.556317) (xy 258.799099 -119.602914) (xy 258.836672 -119.654629)
			(xy 258.867466 -119.710644) (xy 258.890998 -119.770077) (xy 258.896874 -119.792961) (xy 271.695412 -119.792961)
			(xy 271.695412 -119.729039) (xy 271.703423 -119.665621) (xy 271.71932 -119.603707) (xy 271.742852 -119.544274)
			(xy 271.773646 -119.488259) (xy 271.811219 -119.436544) (xy 271.854976 -119.389947) (xy 271.904229 -119.349202)
			(xy 271.9582 -119.314951) (xy 272.016039 -119.287734) (xy 272.076832 -119.267981) (xy 272.139622 -119.256003)
			(xy 272.203418 -119.25199) (xy 272.267214 -119.256003) (xy 272.330004 -119.267981) (xy 272.390797 -119.287734)
			(xy 272.448636 -119.314951) (xy 272.502607 -119.349202) (xy 272.55186 -119.389947) (xy 272.595617 -119.436544)
			(xy 272.63319 -119.488259) (xy 272.663984 -119.544274) (xy 272.687516 -119.603707) (xy 272.703413 -119.665621)
			(xy 272.711424 -119.729039) (xy 272.711926 -119.761) (xy 272.711424 -119.792961) (xy 272.70898 -119.812308)
			(xy 287.105852 -119.812308) (xy 287.106304 -119.782643) (xy 287.113197 -119.723714) (xy 287.126903 -119.665988)
			(xy 287.147235 -119.61025) (xy 287.173916 -119.557257) (xy 287.206584 -119.50773) (xy 287.244795 -119.462343)
			(xy 287.266126 -119.441722) (xy 287.273746 -119.43461) (xy 287.282128 -119.415306) (xy 287.282128 -119.32031)
			(xy 287.273746 -119.301006) (xy 287.266126 -119.293894) (xy 287.244784 -119.273284) (xy 287.206576 -119.227892)
			(xy 287.173908 -119.178362) (xy 287.147224 -119.125368) (xy 287.126888 -119.06963) (xy 287.113174 -119.011904)
			(xy 287.10627 -118.952974) (xy 287.105852 -118.923308) (xy 287.106354 -118.891347) (xy 287.114365 -118.827929)
			(xy 287.130262 -118.766015) (xy 287.153794 -118.706582) (xy 287.184588 -118.650567) (xy 287.222161 -118.598852)
			(xy 287.265918 -118.552255) (xy 287.315171 -118.51151) (xy 287.369142 -118.477259) (xy 287.426981 -118.450042)
			(xy 287.487774 -118.430289) (xy 287.550564 -118.418311) (xy 287.61436 -118.414298) (xy 287.678156 -118.418311)
			(xy 287.740946 -118.430289) (xy 287.801739 -118.450042) (xy 287.859578 -118.477259) (xy 287.913549 -118.51151)
			(xy 287.962802 -118.552255) (xy 288.006559 -118.598852) (xy 288.044132 -118.650567) (xy 288.066839 -118.691871)
			(xy 298.790354 -118.691871) (xy 298.790354 -118.627949) (xy 298.798365 -118.564531) (xy 298.814262 -118.502617)
			(xy 298.837794 -118.443184) (xy 298.868588 -118.387169) (xy 298.906161 -118.335454) (xy 298.949918 -118.288857)
			(xy 298.999171 -118.248112) (xy 299.053142 -118.213861) (xy 299.110981 -118.186644) (xy 299.171774 -118.166891)
			(xy 299.234564 -118.154913) (xy 299.29836 -118.1509) (xy 299.362156 -118.154913) (xy 299.424946 -118.166891)
			(xy 299.462484 -118.179088) (xy 300.78756 -118.179088) (xy 300.791631 -118.123466) (xy 300.803757 -118.069029)
			(xy 300.82368 -118.016938) (xy 300.850976 -117.968303) (xy 300.885062 -117.92416) (xy 300.925211 -117.885451)
			(xy 300.970569 -117.853) (xy 301.020169 -117.827499) (xy 301.072953 -117.809492) (xy 301.127796 -117.799362)
			(xy 301.18353 -117.797325) (xy 301.238967 -117.803425) (xy 301.292924 -117.817531) (xy 301.344253 -117.839343)
			(xy 301.391859 -117.868397) (xy 301.434727 -117.904072) (xy 301.471944 -117.945609) (xy 301.502717 -117.992122)
			(xy 301.526389 -118.042619) (xy 301.542457 -118.096026) (xy 301.548469 -118.136881) (xy 379.828038 -118.136881)
			(xy 379.828038 -118.072959) (xy 379.836049 -118.009541) (xy 379.851946 -117.947627) (xy 379.875478 -117.888194)
			(xy 379.906272 -117.832179) (xy 379.943845 -117.780464) (xy 379.987602 -117.733867) (xy 380.036855 -117.693122)
			(xy 380.090826 -117.658871) (xy 380.148665 -117.631654) (xy 380.209458 -117.611901) (xy 380.272248 -117.599923)
			(xy 380.336044 -117.59591) (xy 380.39984 -117.599923) (xy 380.46263 -117.611901) (xy 380.523423 -117.631654)
			(xy 380.581262 -117.658871) (xy 380.635233 -117.693122) (xy 380.684486 -117.733867) (xy 380.728243 -117.780464)
			(xy 380.765816 -117.832179) (xy 380.79661 -117.888194) (xy 380.820142 -117.947627) (xy 380.836039 -118.009541)
			(xy 380.84405 -118.072959) (xy 380.844396 -118.094971) (xy 381.453384 -118.094971) (xy 381.453384 -118.031049)
			(xy 381.461395 -117.967631) (xy 381.477292 -117.905717) (xy 381.500824 -117.846284) (xy 381.531618 -117.790269)
			(xy 381.569191 -117.738554) (xy 381.612948 -117.691957) (xy 381.662201 -117.651212) (xy 381.716172 -117.616961)
			(xy 381.774011 -117.589744) (xy 381.834804 -117.569991) (xy 381.897594 -117.558013) (xy 381.96139 -117.554)
			(xy 382.025186 -117.558013) (xy 382.087976 -117.569991) (xy 382.148769 -117.589744) (xy 382.206608 -117.616961)
			(xy 382.260579 -117.651212) (xy 382.309832 -117.691957) (xy 382.353589 -117.738554) (xy 382.391162 -117.790269)
			(xy 382.421956 -117.846284) (xy 382.445488 -117.905717) (xy 382.461385 -117.967631) (xy 382.469396 -118.031049)
			(xy 382.469898 -118.06301) (xy 382.469396 -118.094971) (xy 382.461385 -118.158389) (xy 382.445488 -118.220303)
			(xy 382.421956 -118.279736) (xy 382.391162 -118.335751) (xy 382.353589 -118.387466) (xy 382.309832 -118.434063)
			(xy 382.260579 -118.474808) (xy 382.206608 -118.509059) (xy 382.148769 -118.536276) (xy 382.087976 -118.556029)
			(xy 382.025186 -118.568007) (xy 381.96139 -118.572021) (xy 381.897594 -118.568007) (xy 381.834804 -118.556029)
			(xy 381.774011 -118.536276) (xy 381.716172 -118.509059) (xy 381.662201 -118.474808) (xy 381.612948 -118.434063)
			(xy 381.569191 -118.387466) (xy 381.531618 -118.335751) (xy 381.500824 -118.279736) (xy 381.477292 -118.220303)
			(xy 381.461395 -118.158389) (xy 381.453384 -118.094971) (xy 380.844396 -118.094971) (xy 380.844552 -118.10492)
			(xy 380.84405 -118.136881) (xy 380.836039 -118.200299) (xy 380.820142 -118.262213) (xy 380.79661 -118.321646)
			(xy 380.765816 -118.377661) (xy 380.728243 -118.429376) (xy 380.684486 -118.475973) (xy 380.635233 -118.516718)
			(xy 380.581262 -118.550969) (xy 380.523423 -118.578186) (xy 380.46263 -118.597939) (xy 380.39984 -118.609917)
			(xy 380.336044 -118.613931) (xy 380.272248 -118.609917) (xy 380.209458 -118.597939) (xy 380.148665 -118.578186)
			(xy 380.090826 -118.550969) (xy 380.036855 -118.516718) (xy 379.987602 -118.475973) (xy 379.943845 -118.429376)
			(xy 379.906272 -118.377661) (xy 379.875478 -118.321646) (xy 379.851946 -118.262213) (xy 379.836049 -118.200299)
			(xy 379.828038 -118.136881) (xy 301.548469 -118.136881) (xy 301.550577 -118.151202) (xy 301.551086 -118.179088)
			(xy 301.550577 -118.206974) (xy 301.542457 -118.26215) (xy 301.526389 -118.315557) (xy 301.502717 -118.366054)
			(xy 301.471944 -118.412567) (xy 301.434727 -118.454104) (xy 301.391859 -118.489779) (xy 301.344253 -118.518833)
			(xy 301.292924 -118.540645) (xy 301.238967 -118.554751) (xy 301.18353 -118.560851) (xy 301.127796 -118.558814)
			(xy 301.072953 -118.548684) (xy 301.020169 -118.530677) (xy 300.970569 -118.505176) (xy 300.925211 -118.472725)
			(xy 300.885062 -118.434016) (xy 300.850976 -118.389873) (xy 300.82368 -118.341238) (xy 300.803757 -118.289147)
			(xy 300.791631 -118.23471) (xy 300.78756 -118.179088) (xy 299.462484 -118.179088) (xy 299.485739 -118.186644)
			(xy 299.543578 -118.213861) (xy 299.597549 -118.248112) (xy 299.646802 -118.288857) (xy 299.690559 -118.335454)
			(xy 299.728132 -118.387169) (xy 299.758926 -118.443184) (xy 299.782458 -118.502617) (xy 299.798355 -118.564531)
			(xy 299.806366 -118.627949) (xy 299.806868 -118.65991) (xy 299.806517 -118.682262) (xy 318.900046 -118.682262)
			(xy 318.904117 -118.62664) (xy 318.916243 -118.572203) (xy 318.936166 -118.520112) (xy 318.963462 -118.471477)
			(xy 318.997548 -118.427334) (xy 319.037697 -118.388625) (xy 319.083055 -118.356174) (xy 319.132655 -118.330673)
			(xy 319.185439 -118.312666) (xy 319.240282 -118.302536) (xy 319.296016 -118.300499) (xy 319.351453 -118.306599)
			(xy 319.40541 -118.320705) (xy 319.456739 -118.342517) (xy 319.504345 -118.371571) (xy 319.547213 -118.407246)
			(xy 319.58443 -118.448783) (xy 319.615203 -118.495296) (xy 319.638875 -118.545793) (xy 319.654943 -118.5992)
			(xy 319.663063 -118.654376) (xy 319.663293 -118.666979) (xy 389.27633 -118.666979) (xy 389.27633 -118.603057)
			(xy 389.284341 -118.539639) (xy 389.300238 -118.477725) (xy 389.32377 -118.418292) (xy 389.354564 -118.362277)
			(xy 389.392137 -118.310562) (xy 389.435894 -118.263965) (xy 389.485147 -118.22322) (xy 389.539118 -118.188969)
			(xy 389.596957 -118.161752) (xy 389.65775 -118.141999) (xy 389.72054 -118.130021) (xy 389.784336 -118.126008)
			(xy 389.848132 -118.130021) (xy 389.910922 -118.141999) (xy 389.943638 -118.152629) (xy 410.019494 -118.152629)
			(xy 410.019494 -118.088707) (xy 410.027505 -118.025289) (xy 410.043402 -117.963375) (xy 410.066934 -117.903942)
			(xy 410.097728 -117.847927) (xy 410.135301 -117.796212) (xy 410.179058 -117.749615) (xy 410.228311 -117.70887)
			(xy 410.282282 -117.674619) (xy 410.340121 -117.647402) (xy 410.400914 -117.627649) (xy 410.463704 -117.615671)
			(xy 410.5275 -117.611658) (xy 410.591296 -117.615671) (xy 410.654086 -117.627649) (xy 410.714879 -117.647402)
			(xy 410.772718 -117.674619) (xy 410.826689 -117.70887) (xy 410.875942 -117.749615) (xy 410.919699 -117.796212)
			(xy 410.957272 -117.847927) (xy 410.988066 -117.903942) (xy 411.011598 -117.963375) (xy 411.027495 -118.025289)
			(xy 411.035506 -118.088707) (xy 411.036008 -118.120668) (xy 411.035506 -118.152629) (xy 411.027495 -118.216047)
			(xy 411.011598 -118.277961) (xy 410.988066 -118.337394) (xy 410.957272 -118.393409) (xy 410.919699 -118.445124)
			(xy 410.875942 -118.491721) (xy 410.826689 -118.532466) (xy 410.772718 -118.566717) (xy 410.714879 -118.593934)
			(xy 410.654086 -118.613687) (xy 410.591296 -118.625665) (xy 410.5275 -118.629679) (xy 410.463704 -118.625665)
			(xy 410.400914 -118.613687) (xy 410.340121 -118.593934) (xy 410.282282 -118.566717) (xy 410.228311 -118.532466)
			(xy 410.179058 -118.491721) (xy 410.135301 -118.445124) (xy 410.097728 -118.393409) (xy 410.066934 -118.337394)
			(xy 410.043402 -118.277961) (xy 410.027505 -118.216047) (xy 410.019494 -118.152629) (xy 389.943638 -118.152629)
			(xy 389.971715 -118.161752) (xy 390.029554 -118.188969) (xy 390.083525 -118.22322) (xy 390.132778 -118.263965)
			(xy 390.176535 -118.310562) (xy 390.214108 -118.362277) (xy 390.244902 -118.418292) (xy 390.268434 -118.477725)
			(xy 390.284331 -118.539639) (xy 390.292342 -118.603057) (xy 390.292844 -118.635018) (xy 390.292342 -118.666979)
			(xy 390.284331 -118.730397) (xy 390.268434 -118.792311) (xy 390.244902 -118.851744) (xy 390.214108 -118.907759)
			(xy 390.176535 -118.959474) (xy 390.132778 -119.006071) (xy 390.083525 -119.046816) (xy 390.029554 -119.081067)
			(xy 389.971715 -119.108284) (xy 389.910922 -119.128037) (xy 389.848132 -119.140015) (xy 389.784336 -119.144029)
			(xy 389.72054 -119.140015) (xy 389.65775 -119.128037) (xy 389.596957 -119.108284) (xy 389.539118 -119.081067)
			(xy 389.485147 -119.046816) (xy 389.435894 -119.006071) (xy 389.392137 -118.959474) (xy 389.354564 -118.907759)
			(xy 389.32377 -118.851744) (xy 389.300238 -118.792311) (xy 389.284341 -118.730397) (xy 389.27633 -118.666979)
			(xy 319.663293 -118.666979) (xy 319.663572 -118.682262) (xy 319.663063 -118.710148) (xy 319.654943 -118.765324)
			(xy 319.638875 -118.818731) (xy 319.615203 -118.869228) (xy 319.58443 -118.915741) (xy 319.547213 -118.957278)
			(xy 319.504345 -118.992953) (xy 319.456739 -119.022007) (xy 319.40541 -119.043819) (xy 319.351453 -119.057925)
			(xy 319.296016 -119.064025) (xy 319.240282 -119.061988) (xy 319.185439 -119.051858) (xy 319.132655 -119.033851)
			(xy 319.083055 -119.00835) (xy 319.037697 -118.975899) (xy 318.997548 -118.93719) (xy 318.963462 -118.893047)
			(xy 318.936166 -118.844412) (xy 318.916243 -118.792321) (xy 318.904117 -118.737884) (xy 318.900046 -118.682262)
			(xy 299.806517 -118.682262) (xy 299.806366 -118.691871) (xy 299.798355 -118.755289) (xy 299.782458 -118.817203)
			(xy 299.758926 -118.876636) (xy 299.728132 -118.932651) (xy 299.690559 -118.984366) (xy 299.646802 -119.030963)
			(xy 299.597549 -119.071708) (xy 299.543578 -119.105959) (xy 299.485739 -119.133176) (xy 299.424946 -119.152929)
			(xy 299.362156 -119.164907) (xy 299.29836 -119.168921) (xy 299.234564 -119.164907) (xy 299.171774 -119.152929)
			(xy 299.110981 -119.133176) (xy 299.053142 -119.105959) (xy 298.999171 -119.071708) (xy 298.949918 -119.030963)
			(xy 298.906161 -118.984366) (xy 298.868588 -118.932651) (xy 298.837794 -118.876636) (xy 298.814262 -118.817203)
			(xy 298.798365 -118.755289) (xy 298.790354 -118.691871) (xy 288.066839 -118.691871) (xy 288.074926 -118.706582)
			(xy 288.098458 -118.766015) (xy 288.114355 -118.827929) (xy 288.122366 -118.891347) (xy 288.122868 -118.923308)
			(xy 288.122452 -118.952975) (xy 288.115556 -119.011906) (xy 288.101846 -119.069633) (xy 288.081509 -119.125372)
			(xy 288.054821 -119.178365) (xy 288.022146 -119.22789) (xy 287.983928 -119.273275) (xy 287.962594 -119.293894)
			(xy 287.954974 -119.301006) (xy 287.946592 -119.32031) (xy 287.946592 -119.415306) (xy 287.954974 -119.43461)
			(xy 287.962594 -119.441722) (xy 287.983947 -119.462321) (xy 287.998463 -119.479568) (xy 300.78756 -119.479568)
			(xy 300.791631 -119.423946) (xy 300.803757 -119.369509) (xy 300.82368 -119.317418) (xy 300.850976 -119.268783)
			(xy 300.885062 -119.22464) (xy 300.925211 -119.185931) (xy 300.970569 -119.15348) (xy 301.020169 -119.127979)
			(xy 301.072953 -119.109972) (xy 301.127796 -119.099842) (xy 301.18353 -119.097805) (xy 301.238967 -119.103905)
			(xy 301.292924 -119.118011) (xy 301.344253 -119.139823) (xy 301.391859 -119.168877) (xy 301.434727 -119.204552)
			(xy 301.471944 -119.246089) (xy 301.502717 -119.292602) (xy 301.526389 -119.343099) (xy 301.542457 -119.396506)
			(xy 301.550577 -119.451682) (xy 301.551086 -119.479568) (xy 301.550577 -119.507454) (xy 301.542457 -119.56263)
			(xy 301.541388 -119.566182) (xy 316.83909 -119.566182) (xy 316.843161 -119.51056) (xy 316.855287 -119.456123)
			(xy 316.87521 -119.404032) (xy 316.902506 -119.355397) (xy 316.936592 -119.311254) (xy 316.976741 -119.272545)
			(xy 317.022099 -119.240094) (xy 317.071699 -119.214593) (xy 317.124483 -119.196586) (xy 317.179326 -119.186456)
			(xy 317.23506 -119.184419) (xy 317.290497 -119.190519) (xy 317.344454 -119.204625) (xy 317.395783 -119.226437)
			(xy 317.443389 -119.255491) (xy 317.486257 -119.291166) (xy 317.523474 -119.332703) (xy 317.554247 -119.379216)
			(xy 317.577919 -119.429713) (xy 317.593987 -119.48312) (xy 317.602107 -119.538296) (xy 317.602616 -119.566182)
			(xy 317.602482 -119.573505) (xy 382.00939 -119.573505) (xy 382.00939 -119.509583) (xy 382.017401 -119.446165)
			(xy 382.033298 -119.384251) (xy 382.05683 -119.324818) (xy 382.087624 -119.268803) (xy 382.125197 -119.217088)
			(xy 382.168954 -119.170491) (xy 382.218207 -119.129746) (xy 382.272178 -119.095495) (xy 382.330017 -119.068278)
			(xy 382.39081 -119.048525) (xy 382.4536 -119.036547) (xy 382.517396 -119.032534) (xy 382.581192 -119.036547)
			(xy 382.643982 -119.048525) (xy 382.704775 -119.068278) (xy 382.762614 -119.095495) (xy 382.816585 -119.129746)
			(xy 382.865838 -119.170491) (xy 382.909595 -119.217088) (xy 382.947168 -119.268803) (xy 382.977962 -119.324818)
			(xy 383.001494 -119.384251) (xy 383.017391 -119.446165) (xy 383.025402 -119.509583) (xy 383.025904 -119.541544)
			(xy 383.025402 -119.573505) (xy 383.017391 -119.636923) (xy 383.001494 -119.698837) (xy 382.977962 -119.75827)
			(xy 382.947168 -119.814285) (xy 382.909595 -119.866) (xy 382.865838 -119.912597) (xy 382.816585 -119.953342)
			(xy 382.762614 -119.987593) (xy 382.704775 -120.01481) (xy 382.643982 -120.034563) (xy 382.581192 -120.046541)
			(xy 382.517396 -120.050555) (xy 382.4536 -120.046541) (xy 382.39081 -120.034563) (xy 382.330017 -120.01481)
			(xy 382.272178 -119.987593) (xy 382.218207 -119.953342) (xy 382.168954 -119.912597) (xy 382.125197 -119.866)
			(xy 382.087624 -119.814285) (xy 382.05683 -119.75827) (xy 382.033298 -119.698837) (xy 382.017401 -119.636923)
			(xy 382.00939 -119.573505) (xy 317.602482 -119.573505) (xy 317.602107 -119.594068) (xy 317.593987 -119.649244)
			(xy 317.577919 -119.702651) (xy 317.554247 -119.753148) (xy 317.523474 -119.799661) (xy 317.486257 -119.841198)
			(xy 317.443389 -119.876873) (xy 317.395783 -119.905927) (xy 317.344454 -119.927739) (xy 317.290497 -119.941845)
			(xy 317.23506 -119.947945) (xy 317.179326 -119.945908) (xy 317.124483 -119.935778) (xy 317.071699 -119.917771)
			(xy 317.022099 -119.89227) (xy 316.976741 -119.859819) (xy 316.936592 -119.82111) (xy 316.902506 -119.776967)
			(xy 316.87521 -119.728332) (xy 316.855287 -119.676241) (xy 316.843161 -119.621804) (xy 316.83909 -119.566182)
			(xy 301.541388 -119.566182) (xy 301.526389 -119.616037) (xy 301.502717 -119.666534) (xy 301.471944 -119.713047)
			(xy 301.434727 -119.754584) (xy 301.391859 -119.790259) (xy 301.344253 -119.819313) (xy 301.292924 -119.841125)
			(xy 301.238967 -119.855231) (xy 301.18353 -119.861331) (xy 301.127796 -119.859294) (xy 301.072953 -119.849164)
			(xy 301.020169 -119.831157) (xy 300.970569 -119.805656) (xy 300.925211 -119.773205) (xy 300.885062 -119.734496)
			(xy 300.850976 -119.690353) (xy 300.82368 -119.641718) (xy 300.803757 -119.589627) (xy 300.791631 -119.53519)
			(xy 300.78756 -119.479568) (xy 287.998463 -119.479568) (xy 288.022154 -119.507715) (xy 288.054821 -119.557247)
			(xy 288.081502 -119.610243) (xy 288.101837 -119.665983) (xy 288.115549 -119.723711) (xy 288.122451 -119.782641)
			(xy 288.122868 -119.812308) (xy 288.122366 -119.844269) (xy 288.114355 -119.907687) (xy 288.098458 -119.969601)
			(xy 288.074926 -120.029034) (xy 288.044132 -120.085049) (xy 288.006559 -120.136764) (xy 287.962802 -120.183361)
			(xy 287.913549 -120.224106) (xy 287.859578 -120.258357) (xy 287.801739 -120.285574) (xy 287.740946 -120.305327)
			(xy 287.678156 -120.317305) (xy 287.61436 -120.321319) (xy 287.550564 -120.317305) (xy 287.487774 -120.305327)
			(xy 287.426981 -120.285574) (xy 287.369142 -120.258357) (xy 287.315171 -120.224106) (xy 287.265918 -120.183361)
			(xy 287.222161 -120.136764) (xy 287.184588 -120.085049) (xy 287.153794 -120.029034) (xy 287.130262 -119.969601)
			(xy 287.114365 -119.907687) (xy 287.106354 -119.844269) (xy 287.105852 -119.812308) (xy 272.70898 -119.812308)
			(xy 272.703413 -119.856379) (xy 272.687516 -119.918293) (xy 272.663984 -119.977726) (xy 272.63319 -120.033741)
			(xy 272.595617 -120.085456) (xy 272.55186 -120.132053) (xy 272.502607 -120.172798) (xy 272.448636 -120.207049)
			(xy 272.390797 -120.234266) (xy 272.330004 -120.254019) (xy 272.267214 -120.265997) (xy 272.203418 -120.270011)
			(xy 272.139622 -120.265997) (xy 272.076832 -120.254019) (xy 272.016039 -120.234266) (xy 271.9582 -120.207049)
			(xy 271.904229 -120.172798) (xy 271.854976 -120.132053) (xy 271.811219 -120.085456) (xy 271.773646 -120.033741)
			(xy 271.742852 -119.977726) (xy 271.71932 -119.918293) (xy 271.703423 -119.856379) (xy 271.695412 -119.792961)
			(xy 258.896874 -119.792961) (xy 258.906895 -119.831991) (xy 258.914906 -119.895409) (xy 258.915408 -119.92737)
			(xy 258.914906 -119.959331) (xy 258.906895 -120.022749) (xy 258.890998 -120.084663) (xy 258.867466 -120.144096)
			(xy 258.836672 -120.200111) (xy 258.799099 -120.251826) (xy 258.755342 -120.298423) (xy 258.706089 -120.339168)
			(xy 258.652118 -120.373419) (xy 258.594279 -120.400636) (xy 258.533486 -120.420389) (xy 258.470696 -120.432367)
			(xy 258.4069 -120.436381) (xy 258.343104 -120.432367) (xy 258.280314 -120.420389) (xy 258.219521 -120.400636)
			(xy 258.161682 -120.373419) (xy 258.107711 -120.339168) (xy 258.058458 -120.298423) (xy 258.014701 -120.251826)
			(xy 257.977128 -120.200111) (xy 257.946334 -120.144096) (xy 257.922802 -120.084663) (xy 257.906905 -120.022749)
			(xy 257.898894 -119.959331) (xy 253.210775 -119.959331) (xy 253.191866 -119.965475) (xy 253.129076 -119.977453)
			(xy 253.06528 -119.981467) (xy 253.001484 -119.977453) (xy 252.938694 -119.965475) (xy 252.877901 -119.945722)
			(xy 252.820062 -119.918505) (xy 252.766091 -119.884254) (xy 252.716838 -119.843509) (xy 252.673081 -119.796912)
			(xy 252.635508 -119.745197) (xy 252.604714 -119.689182) (xy 252.581182 -119.629749) (xy 252.565285 -119.567835)
			(xy 252.557274 -119.504417) (xy 252.285709 -119.504417) (xy 252.282575 -119.529227) (xy 252.266678 -119.591141)
			(xy 252.243146 -119.650574) (xy 252.212352 -119.706589) (xy 252.174779 -119.758304) (xy 252.131022 -119.804901)
			(xy 252.081769 -119.845646) (xy 252.027798 -119.879897) (xy 251.969959 -119.907114) (xy 251.909166 -119.926867)
			(xy 251.846376 -119.938845) (xy 251.78258 -119.942859) (xy 251.718784 -119.938845) (xy 251.655994 -119.926867)
			(xy 251.595201 -119.907114) (xy 251.537362 -119.879897) (xy 251.483391 -119.845646) (xy 251.434138 -119.804901)
			(xy 251.390381 -119.758304) (xy 251.352808 -119.706589) (xy 251.322014 -119.650574) (xy 251.298482 -119.591141)
			(xy 251.282585 -119.529227) (xy 251.274574 -119.465809) (xy 226.014819 -119.465809) (xy 225.996606 -119.493337)
			(xy 225.959389 -119.534874) (xy 225.916521 -119.570549) (xy 225.868915 -119.599603) (xy 225.817586 -119.621415)
			(xy 225.763629 -119.635521) (xy 225.708192 -119.641621) (xy 225.652458 -119.639584) (xy 225.597615 -119.629454)
			(xy 225.544831 -119.611447) (xy 225.495231 -119.585946) (xy 225.449873 -119.553495) (xy 225.409724 -119.514786)
			(xy 225.375638 -119.470643) (xy 225.348342 -119.422008) (xy 225.328419 -119.369917) (xy 225.316293 -119.31548)
			(xy 225.312222 -119.259858) (xy 216.594968 -119.259858) (xy 216.643635 -119.280539) (xy 216.691241 -119.309593)
			(xy 216.734109 -119.345268) (xy 216.771326 -119.386805) (xy 216.802099 -119.433318) (xy 216.825771 -119.483815)
			(xy 216.841839 -119.537222) (xy 216.849959 -119.592398) (xy 216.850468 -119.620284) (xy 216.849959 -119.64817)
			(xy 216.841839 -119.703346) (xy 216.825771 -119.756753) (xy 216.802099 -119.80725) (xy 216.771326 -119.853763)
			(xy 216.734109 -119.8953) (xy 216.691241 -119.930975) (xy 216.643635 -119.960029) (xy 216.592306 -119.981841)
			(xy 216.538349 -119.995947) (xy 216.482912 -120.002047) (xy 216.427178 -120.00001) (xy 216.372335 -119.98988)
			(xy 216.319551 -119.971873) (xy 216.269951 -119.946372) (xy 216.224593 -119.913921) (xy 216.184444 -119.875212)
			(xy 216.150358 -119.831069) (xy 216.123062 -119.782434) (xy 216.103139 -119.730343) (xy 216.091013 -119.675906)
			(xy 216.086942 -119.620284) (xy 211.001485 -119.620284) (xy 211.002283 -119.623301) (xy 211.01075 -119.688502)
			(xy 211.011262 -119.721376) (xy 211.01076 -119.753337) (xy 211.002749 -119.816755) (xy 210.986852 -119.878669)
			(xy 210.96332 -119.938102) (xy 210.932526 -119.994117) (xy 210.894953 -120.045832) (xy 210.851196 -120.092429)
			(xy 210.801943 -120.133174) (xy 210.747972 -120.167425) (xy 210.690133 -120.194642) (xy 210.62934 -120.214395)
			(xy 210.56655 -120.226373) (xy 210.502754 -120.230387) (xy 210.438958 -120.226373) (xy 210.376168 -120.214395)
			(xy 210.315375 -120.194642) (xy 210.257536 -120.167425) (xy 210.203565 -120.133174) (xy 210.154312 -120.092429)
			(xy 210.110555 -120.045832) (xy 210.072982 -119.994117) (xy 210.042188 -119.938102) (xy 210.018656 -119.878669)
			(xy 210.002759 -119.816755) (xy 209.994748 -119.753337) (xy 209.994246 -119.721376) (xy 207.800194 -119.721376)
			(xy 207.79974 -119.752108) (xy 207.792334 -119.813125) (xy 207.777626 -119.872803) (xy 207.755833 -119.930274)
			(xy 207.72727 -119.984699) (xy 207.692355 -120.035283) (xy 207.651598 -120.08129) (xy 207.605591 -120.122049)
			(xy 207.555007 -120.156965) (xy 207.500583 -120.185528) (xy 207.443113 -120.207323) (xy 207.383434 -120.222032)
			(xy 207.322418 -120.229439) (xy 207.291686 -120.229884) (xy 207.25986 -120.229388) (xy 207.196705 -120.221438)
			(xy 207.135034 -120.205677) (xy 207.075809 -120.182351) (xy 207.019954 -120.151824) (xy 206.96834 -120.114571)
			(xy 206.944722 -120.093232) (xy 206.937453 -120.087033) (xy 206.919719 -120.079974) (xy 206.910178 -120.079516)
			(xy 206.87919 -120.079516) (xy 206.869641 -120.079954) (xy 206.851885 -120.08699) (xy 206.844646 -120.093232)
			(xy 206.821066 -120.114619) (xy 206.769464 -120.151905) (xy 206.713607 -120.182449) (xy 206.654371 -120.205773)
			(xy 206.592684 -120.22151) (xy 206.529514 -120.229415) (xy 206.497682 -120.229884) (xy 206.46572 -120.229429)
			(xy 206.402301 -120.221415) (xy 206.340386 -120.205516) (xy 206.280952 -120.181983) (xy 206.224936 -120.151186)
			(xy 206.173221 -120.113611) (xy 206.126624 -120.069852) (xy 206.085878 -120.020597) (xy 206.051627 -119.966624)
			(xy 206.02441 -119.908784) (xy 206.004657 -119.847989) (xy 205.992679 -119.785198) (xy 205.988665 -119.7214)
			(xy 204.465435 -119.7214) (xy 204.465435 -119.755663) (xy 204.457175 -119.823688) (xy 204.440776 -119.890223)
			(xy 204.416477 -119.954295) (xy 204.384632 -120.014971) (xy 204.345705 -120.071367) (xy 204.300265 -120.122659)
			(xy 204.248973 -120.1681) (xy 204.192578 -120.207027) (xy 204.131902 -120.238873) (xy 204.06783 -120.263174)
			(xy 204.001296 -120.279574) (xy 203.933271 -120.287834) (xy 203.899008 -120.288304) (xy 203.717144 -120.288304)
			(xy 203.707181 -120.288789) (xy 203.688754 -120.296374) (xy 203.68133 -120.303036) (xy 203.6572 -120.327166)
			(xy 203.650721 -120.334261) (xy 203.643147 -120.351902) (xy 203.642611 -120.371094) (xy 203.645516 -120.380252)
			(xy 203.646278 -120.382284) (xy 203.649388 -120.389192) (xy 203.658953 -120.400932) (xy 203.665074 -120.405398)
			(xy 203.66609 -120.40616) (xy 203.668376 -120.407684) (xy 203.67117 -120.409462) (xy 203.678282 -120.411494)
			(xy 203.681878 -120.412527) (xy 203.689273 -120.41367) (xy 203.693014 -120.41378) (xy 205.017878 -120.41378)
			(xy 205.027942 -120.414217) (xy 205.046528 -120.421949) (xy 205.053946 -120.428766) (xy 205.656688 -121.031508)
			(xy 205.663038 -121.036842) (xy 205.667487 -121.039847) (xy 205.677352 -121.044075) (xy 205.682596 -121.045224)
			(xy 205.683104 -121.045224) (xy 205.692502 -121.04624) (xy 205.887574 -121.04624) (xy 205.897562 -121.045706)
			(xy 205.915995 -121.037992) (xy 205.923388 -121.031254) (xy 205.975712 -120.979184) (xy 205.978705 -120.975773)
			(xy 205.983558 -120.968107) (xy 205.985364 -120.963944) (xy 205.989174 -120.9548) (xy 205.989174 -120.944386)
			(xy 205.989676 -120.912425) (xy 205.997687 -120.849007) (xy 206.013584 -120.787093) (xy 206.037116 -120.72766)
			(xy 206.06791 -120.671645) (xy 206.105483 -120.61993) (xy 206.14924 -120.573333) (xy 206.198493 -120.532588)
			(xy 206.252464 -120.498337) (xy 206.310303 -120.47112) (xy 206.371096 -120.451367) (xy 206.433886 -120.439389)
			(xy 206.497682 -120.435376) (xy 206.561478 -120.439389) (xy 206.624268 -120.451367) (xy 206.685061 -120.47112)
			(xy 206.7429 -120.498337) (xy 206.796871 -120.532588) (xy 206.846124 -120.573333) (xy 206.889881 -120.61993)
			(xy 206.927454 -120.671645) (xy 206.958248 -120.72766) (xy 206.98178 -120.787093) (xy 206.997677 -120.849007)
			(xy 207.005688 -120.912425) (xy 207.00619 -120.944386) (xy 207.00619 -120.9548) (xy 207.01 -120.963944)
			(xy 207.011795 -120.968112) (xy 207.016656 -120.975775) (xy 207.019652 -120.979184) (xy 207.071976 -121.031254)
			(xy 207.079323 -121.038058) (xy 207.097786 -121.04577) (xy 207.10779 -121.04624) (xy 210.222592 -121.04624)
			(xy 210.22691 -121.045986) (xy 210.227418 -121.045986) (xy 210.231899 -121.045463) (xy 210.240589 -121.043041)
			(xy 210.24469 -121.04116) (xy 210.2483 -121.039353) (xy 210.25494 -121.034763) (xy 210.257898 -121.032016)
			(xy 210.287616 -121.00052) (xy 210.29295 -120.994932) (xy 210.312762 -120.97385) (xy 210.31518 -120.970699)
			(xy 210.319133 -120.963811) (xy 210.320636 -120.960134) (xy 210.324446 -120.94972) (xy 210.323938 -120.939306)
			(xy 210.323176 -120.911874) (xy 210.323678 -120.879913) (xy 210.331689 -120.816495) (xy 210.347586 -120.754581)
			(xy 210.371118 -120.695148) (xy 210.401912 -120.639133) (xy 210.439485 -120.587418) (xy 210.483242 -120.540821)
			(xy 210.532495 -120.500076) (xy 210.586466 -120.465825) (xy 210.644305 -120.438608) (xy 210.705098 -120.418855)
			(xy 210.767888 -120.406877) (xy 210.831684 -120.402864) (xy 210.89548 -120.406877) (xy 210.95827 -120.418855)
			(xy 211.019063 -120.438608) (xy 211.076902 -120.465825) (xy 211.130873 -120.500076) (xy 211.180126 -120.540821)
			(xy 211.223883 -120.587418) (xy 211.261456 -120.639133) (xy 211.29225 -120.695148) (xy 211.315782 -120.754581)
			(xy 211.331679 -120.816495) (xy 211.33969 -120.879913) (xy 211.340192 -120.911874) (xy 211.340148 -120.914371)
			(xy 214.804238 -120.914371) (xy 214.804238 -120.850449) (xy 214.812249 -120.787031) (xy 214.828146 -120.725117)
			(xy 214.851678 -120.665684) (xy 214.882472 -120.609669) (xy 214.920045 -120.557954) (xy 214.963802 -120.511357)
			(xy 215.013055 -120.470612) (xy 215.067026 -120.436361) (xy 215.124865 -120.409144) (xy 215.185658 -120.389391)
			(xy 215.248448 -120.377413) (xy 215.312244 -120.3734) (xy 215.37604 -120.377413) (xy 215.43883 -120.389391)
			(xy 215.499623 -120.409144) (xy 215.557462 -120.436361) (xy 215.611433 -120.470612) (xy 215.660686 -120.511357)
			(xy 215.704443 -120.557954) (xy 215.742016 -120.609669) (xy 215.77281 -120.665684) (xy 215.795547 -120.723109)
			(xy 218.015306 -120.723109) (xy 218.015306 -120.659187) (xy 218.023317 -120.595769) (xy 218.039214 -120.533855)
			(xy 218.062746 -120.474422) (xy 218.09354 -120.418407) (xy 218.131113 -120.366692) (xy 218.17487 -120.320095)
			(xy 218.224123 -120.27935) (xy 218.278094 -120.245099) (xy 218.335933 -120.217882) (xy 218.396726 -120.198129)
			(xy 218.459516 -120.186151) (xy 218.523312 -120.182138) (xy 218.587108 -120.186151) (xy 218.649898 -120.198129)
			(xy 218.710691 -120.217882) (xy 218.76853 -120.245099) (xy 218.822501 -120.27935) (xy 218.871754 -120.320095)
			(xy 218.915511 -120.366692) (xy 218.953084 -120.418407) (xy 218.983878 -120.474422) (xy 219.00741 -120.533855)
			(xy 219.015764 -120.566391) (xy 259.30199 -120.566391) (xy 259.30199 -120.502469) (xy 259.310001 -120.439051)
			(xy 259.325898 -120.377137) (xy 259.34943 -120.317704) (xy 259.380224 -120.261689) (xy 259.417797 -120.209974)
			(xy 259.461554 -120.163377) (xy 259.510807 -120.122632) (xy 259.564778 -120.088381) (xy 259.622617 -120.061164)
			(xy 259.68341 -120.041411) (xy 259.7462 -120.029433) (xy 259.809996 -120.02542) (xy 259.873792 -120.029433)
			(xy 259.936582 -120.041411) (xy 259.997375 -120.061164) (xy 260.055214 -120.088381) (xy 260.109185 -120.122632)
			(xy 260.158438 -120.163377) (xy 260.202195 -120.209974) (xy 260.239768 -120.261689) (xy 260.270562 -120.317704)
			(xy 260.294094 -120.377137) (xy 260.309991 -120.439051) (xy 260.318002 -120.502469) (xy 260.318504 -120.53443)
			(xy 260.318002 -120.566391) (xy 260.309991 -120.629809) (xy 260.294094 -120.691723) (xy 260.270562 -120.751156)
			(xy 260.239768 -120.807171) (xy 260.202195 -120.858886) (xy 260.158438 -120.905483) (xy 260.109185 -120.946228)
			(xy 260.055214 -120.980479) (xy 259.997375 -121.007696) (xy 259.936582 -121.027449) (xy 259.873792 -121.039427)
			(xy 259.809996 -121.043441) (xy 259.7462 -121.039427) (xy 259.68341 -121.027449) (xy 259.622617 -121.007696)
			(xy 259.564778 -120.980479) (xy 259.510807 -120.946228) (xy 259.461554 -120.905483) (xy 259.417797 -120.858886)
			(xy 259.380224 -120.807171) (xy 259.34943 -120.751156) (xy 259.325898 -120.691723) (xy 259.310001 -120.629809)
			(xy 259.30199 -120.566391) (xy 219.015764 -120.566391) (xy 219.023307 -120.595769) (xy 219.031318 -120.659187)
			(xy 219.03182 -120.691148) (xy 219.031318 -120.723109) (xy 219.023307 -120.786527) (xy 219.00741 -120.848441)
			(xy 218.983878 -120.907874) (xy 218.953084 -120.963889) (xy 218.915511 -121.015604) (xy 218.871754 -121.062201)
			(xy 218.822501 -121.102946) (xy 218.76853 -121.137197) (xy 218.710691 -121.164414) (xy 218.649898 -121.184167)
			(xy 218.587108 -121.196145) (xy 218.523312 -121.200159) (xy 218.459516 -121.196145) (xy 218.396726 -121.184167)
			(xy 218.335933 -121.164414) (xy 218.278094 -121.137197) (xy 218.224123 -121.102946) (xy 218.17487 -121.062201)
			(xy 218.131113 -121.015604) (xy 218.09354 -120.963889) (xy 218.062746 -120.907874) (xy 218.039214 -120.848441)
			(xy 218.023317 -120.786527) (xy 218.015306 -120.723109) (xy 215.795547 -120.723109) (xy 215.796342 -120.725117)
			(xy 215.812239 -120.787031) (xy 215.82025 -120.850449) (xy 215.820752 -120.88241) (xy 215.82025 -120.914371)
			(xy 215.812239 -120.977789) (xy 215.796342 -121.039703) (xy 215.77281 -121.099136) (xy 215.742016 -121.155151)
			(xy 215.704443 -121.206866) (xy 215.660686 -121.253463) (xy 215.611433 -121.294208) (xy 215.557462 -121.328459)
			(xy 215.499623 -121.355676) (xy 215.43883 -121.375429) (xy 215.37604 -121.387407) (xy 215.312244 -121.391421)
			(xy 215.248448 -121.387407) (xy 215.185658 -121.375429) (xy 215.124865 -121.355676) (xy 215.067026 -121.328459)
			(xy 215.013055 -121.294208) (xy 214.963802 -121.253463) (xy 214.920045 -121.206866) (xy 214.882472 -121.155151)
			(xy 214.851678 -121.099136) (xy 214.828146 -121.039703) (xy 214.812249 -120.977789) (xy 214.804238 -120.914371)
			(xy 211.340148 -120.914371) (xy 211.339544 -120.948332) (xy 211.329082 -121.020493) (xy 211.319364 -121.055638)
			(xy 211.319364 -121.055892) (xy 211.318856 -121.057416) (xy 211.318094 -121.059956) (xy 211.317206 -121.065466)
			(xy 211.317593 -121.076618) (xy 211.318856 -121.082054) (xy 211.319364 -121.084086) (xy 211.320126 -121.087388)
			(xy 211.320634 -121.089166) (xy 211.323936 -121.094754) (xy 211.332064 -121.105676) (xy 211.644738 -121.41835)
			(xy 211.648548 -121.421906) (xy 211.649056 -121.421906) (xy 211.65801 -121.428437) (xy 211.679479 -121.433836)
			(xy 211.690458 -121.43232) (xy 211.698332 -121.430034) (xy 211.784692 -121.397776) (xy 211.791402 -121.39505)
			(xy 211.803009 -121.386399) (xy 211.807552 -121.380758) (xy 211.811674 -121.374945) (xy 211.816829 -121.361667)
			(xy 211.817712 -121.354596) (xy 211.817712 -121.354342) (xy 211.820467 -121.325992) (xy 211.833315 -121.270502)
			(xy 211.85427 -121.217538) (xy 211.882865 -121.168278) (xy 211.918465 -121.123816) (xy 211.960279 -121.085141)
			(xy 212.007378 -121.05311) (xy 212.058715 -121.028438) (xy 212.113149 -121.01167) (xy 212.169471 -121.003181)
			(xy 212.19795 -121.002552) (xy 212.225206 -121.003011) (xy 212.279165 -121.010762) (xy 212.331471 -121.026114)
			(xy 212.38106 -121.048753) (xy 212.426922 -121.078219) (xy 212.468124 -121.113912) (xy 212.503827 -121.155106)
			(xy 212.533304 -121.200961) (xy 212.555955 -121.250545) (xy 212.571318 -121.302847) (xy 212.579082 -121.356804)
			(xy 212.579458 -121.38406) (xy 212.578932 -121.412535) (xy 212.570469 -121.468852) (xy 212.553726 -121.523284)
			(xy 212.529074 -121.574621) (xy 212.497062 -121.621721) (xy 212.458401 -121.663537) (xy 212.413952 -121.699139)
			(xy 212.364703 -121.727735) (xy 212.311749 -121.74869) (xy 212.256268 -121.761537) (xy 212.227922 -121.764298)
			(xy 212.227414 -121.764298) (xy 212.220302 -121.76506) (xy 212.207094 -121.769886) (xy 212.201252 -121.774458)
			(xy 212.195635 -121.779023) (xy 212.186998 -121.790629) (xy 212.184234 -121.797318) (xy 212.151976 -121.883678)
			(xy 212.14969 -121.891552) (xy 212.148196 -121.902527) (xy 212.153606 -121.923982) (xy 212.160104 -121.932954)
			(xy 212.160104 -121.933462) (xy 212.16366 -121.937272) (xy 212.713824 -122.487436) (xy 212.716872 -122.49023)
			(xy 212.724676 -122.496212) (xy 212.743353 -122.502307) (xy 212.762953 -122.500965) (xy 212.77199 -122.497088)
			(xy 212.798052 -122.484819) (xy 212.852345 -122.465567) (xy 212.908464 -122.452563) (xy 212.965692 -122.445973)
			(xy 212.994494 -122.445526) (xy 213.025226 -122.445971) (xy 213.086241 -122.45338) (xy 213.115177 -122.460512)
			(xy 214.479886 -122.460512) (xy 214.480388 -122.428551) (xy 214.488399 -122.365133) (xy 214.504296 -122.303219)
			(xy 214.527828 -122.243786) (xy 214.558622 -122.187771) (xy 214.596195 -122.136056) (xy 214.639952 -122.089459)
			(xy 214.689205 -122.048714) (xy 214.743176 -122.014463) (xy 214.801015 -121.987246) (xy 214.861808 -121.967493)
			(xy 214.924598 -121.955515) (xy 214.988394 -121.951502) (xy 215.05219 -121.955515) (xy 215.11498 -121.967493)
			(xy 215.175773 -121.987246) (xy 215.233612 -122.014463) (xy 215.287583 -122.048714) (xy 215.336836 -122.089459)
			(xy 215.380593 -122.136056) (xy 215.418166 -122.187771) (xy 215.433472 -122.215613) (xy 227.837994 -122.215613)
			(xy 227.837994 -122.151691) (xy 227.846005 -122.088273) (xy 227.861902 -122.026359) (xy 227.885434 -121.966926)
			(xy 227.916228 -121.910911) (xy 227.953801 -121.859196) (xy 227.997558 -121.812599) (xy 228.046811 -121.771854)
			(xy 228.100782 -121.737603) (xy 228.158621 -121.710386) (xy 228.219414 -121.690633) (xy 228.282204 -121.678655)
			(xy 228.346 -121.674642) (xy 228.409796 -121.678655) (xy 228.472586 -121.690633) (xy 228.533379 -121.710386)
			(xy 228.591218 -121.737603) (xy 228.645189 -121.771854) (xy 228.694442 -121.812599) (xy 228.738199 -121.859196)
			(xy 228.775772 -121.910911) (xy 228.806566 -121.966926) (xy 228.81472 -121.987521) (xy 250.136654 -121.987521)
			(xy 250.136654 -121.923599) (xy 250.144665 -121.860181) (xy 250.160562 -121.798267) (xy 250.184094 -121.738834)
			(xy 250.214888 -121.682819) (xy 250.252461 -121.631104) (xy 250.296218 -121.584507) (xy 250.345471 -121.543762)
			(xy 250.399442 -121.509511) (xy 250.457281 -121.482294) (xy 250.518074 -121.462541) (xy 250.580864 -121.450563)
			(xy 250.64466 -121.44655) (xy 250.708456 -121.450563) (xy 250.771246 -121.462541) (xy 250.832039 -121.482294)
			(xy 250.889878 -121.509511) (xy 250.943849 -121.543762) (xy 250.993102 -121.584507) (xy 251.036859 -121.631104)
			(xy 251.074432 -121.682819) (xy 251.105226 -121.738834) (xy 251.128758 -121.798267) (xy 251.144655 -121.860181)
			(xy 251.152666 -121.923599) (xy 251.153168 -121.95556) (xy 251.152666 -121.987521) (xy 251.152185 -121.991331)
			(xy 258.371334 -121.991331) (xy 258.371334 -121.927409) (xy 258.379345 -121.863991) (xy 258.395242 -121.802077)
			(xy 258.418774 -121.742644) (xy 258.449568 -121.686629) (xy 258.487141 -121.634914) (xy 258.530898 -121.588317)
			(xy 258.580151 -121.547572) (xy 258.634122 -121.513321) (xy 258.691961 -121.486104) (xy 258.752754 -121.466351)
			(xy 258.815544 -121.454373) (xy 258.87934 -121.45036) (xy 258.943136 -121.454373) (xy 259.005926 -121.466351)
			(xy 259.066719 -121.486104) (xy 259.124558 -121.513321) (xy 259.178529 -121.547572) (xy 259.227782 -121.588317)
			(xy 259.271539 -121.634914) (xy 259.309112 -121.686629) (xy 259.339906 -121.742644) (xy 259.363438 -121.802077)
			(xy 259.379335 -121.863991) (xy 259.379378 -121.864331) (xy 269.283936 -121.864331) (xy 269.283936 -121.800409)
			(xy 269.291947 -121.736991) (xy 269.307844 -121.675077) (xy 269.331376 -121.615644) (xy 269.36217 -121.559629)
			(xy 269.399743 -121.507914) (xy 269.4435 -121.461317) (xy 269.492753 -121.420572) (xy 269.546724 -121.386321)
			(xy 269.604563 -121.359104) (xy 269.665356 -121.339351) (xy 269.728146 -121.327373) (xy 269.791942 -121.32336)
			(xy 269.855738 -121.327373) (xy 269.918528 -121.339351) (xy 269.979321 -121.359104) (xy 270.03716 -121.386321)
			(xy 270.091131 -121.420572) (xy 270.140384 -121.461317) (xy 270.184141 -121.507914) (xy 270.221714 -121.559629)
			(xy 270.252508 -121.615644) (xy 270.27604 -121.675077) (xy 270.291937 -121.736991) (xy 270.299948 -121.800409)
			(xy 270.30045 -121.83237) (xy 271.712688 -121.83237) (xy 271.716759 -121.776748) (xy 271.728885 -121.722311)
			(xy 271.748808 -121.67022) (xy 271.776104 -121.621585) (xy 271.81019 -121.577442) (xy 271.850339 -121.538733)
			(xy 271.895697 -121.506282) (xy 271.945297 -121.480781) (xy 271.998081 -121.462774) (xy 272.052924 -121.452644)
			(xy 272.108658 -121.450607) (xy 272.164095 -121.456707) (xy 272.218052 -121.470813) (xy 272.269381 -121.492625)
			(xy 272.316987 -121.521679) (xy 272.359855 -121.557354) (xy 272.397072 -121.598891) (xy 272.427845 -121.645404)
			(xy 272.451517 -121.695901) (xy 272.467585 -121.749308) (xy 272.475705 -121.804484) (xy 272.476214 -121.83237)
			(xy 272.475705 -121.860256) (xy 272.467585 -121.915432) (xy 272.451517 -121.968839) (xy 272.427845 -122.019336)
			(xy 272.397072 -122.065849) (xy 272.359855 -122.107386) (xy 272.316987 -122.143061) (xy 272.269381 -122.172115)
			(xy 272.218052 -122.193927) (xy 272.164095 -122.208033) (xy 272.108658 -122.214133) (xy 272.052924 -122.212096)
			(xy 271.998081 -122.201966) (xy 271.945297 -122.183959) (xy 271.895697 -122.158458) (xy 271.850339 -122.126007)
			(xy 271.81019 -122.087298) (xy 271.776104 -122.043155) (xy 271.748808 -121.99452) (xy 271.728885 -121.942429)
			(xy 271.716759 -121.887992) (xy 271.712688 -121.83237) (xy 270.30045 -121.83237) (xy 270.299948 -121.864331)
			(xy 270.291937 -121.927749) (xy 270.27604 -121.989663) (xy 270.252508 -122.049096) (xy 270.221714 -122.105111)
			(xy 270.184141 -122.156826) (xy 270.140384 -122.203423) (xy 270.091131 -122.244168) (xy 270.03716 -122.278419)
			(xy 269.989173 -122.301) (xy 274.683728 -122.301) (xy 274.684182 -122.268794) (xy 274.692334 -122.204901)
			(xy 274.708484 -122.142547) (xy 274.732372 -122.082729) (xy 274.763618 -122.026403) (xy 274.80172 -121.97447)
			(xy 274.846072 -121.92776) (xy 274.895962 -121.88702) (xy 274.950595 -121.8529) (xy 274.979638 -121.838974)
			(xy 274.991322 -121.83364) (xy 275.006816 -121.813066) (xy 275.020786 -121.71553) (xy 275.021673 -121.707109)
			(xy 275.018429 -121.690498) (xy 275.009955 -121.675846) (xy 275.003768 -121.670064) (xy 275.003514 -121.66981)
			(xy 274.980209 -121.649084) (xy 274.938363 -121.602837) (xy 274.902487 -121.551818) (xy 274.873121 -121.496795)
			(xy 274.850705 -121.438594) (xy 274.835575 -121.378087) (xy 274.827959 -121.316185) (xy 274.827492 -121.285)
			(xy 274.827956 -121.254269) (xy 274.835365 -121.193255) (xy 274.850073 -121.133579) (xy 274.871868 -121.076111)
			(xy 274.900431 -121.021689) (xy 274.935345 -120.971107) (xy 274.976102 -120.925102) (xy 275.022107 -120.884345)
			(xy 275.072689 -120.849431) (xy 275.127111 -120.820868) (xy 275.184579 -120.799073) (xy 275.244255 -120.784365)
			(xy 275.305269 -120.776956) (xy 275.336 -120.776492) (xy 275.368151 -120.77696) (xy 275.43194 -120.78506)
			(xy 275.494198 -120.801143) (xy 275.553929 -120.824952) (xy 275.610179 -120.856107) (xy 275.662049 -120.89411)
			(xy 275.70871 -120.938353) (xy 275.729446 -120.962928) (xy 275.735906 -120.970185) (xy 275.752888 -120.979589)
			(xy 275.762466 -120.981216) (xy 275.832316 -120.989598) (xy 275.842042 -120.990305) (xy 275.860849 -120.985207)
			(xy 275.868892 -120.979692) (xy 275.869146 -120.979692) (xy 275.89126 -120.963709) (xy 275.939143 -120.937552)
			(xy 275.990263 -120.918478) (xy 276.043577 -120.906875) (xy 276.098 -120.902981) (xy 276.152423 -120.906875)
			(xy 276.205737 -120.918478) (xy 276.256857 -120.937552) (xy 276.30474 -120.963709) (xy 276.326854 -120.979692)
			(xy 276.327108 -120.979692) (xy 276.335145 -120.985223) (xy 276.353956 -120.990329) (xy 276.363684 -120.989598)
			(xy 276.433534 -120.981216) (xy 276.443098 -120.979543) (xy 276.460072 -120.970155) (xy 276.466554 -120.962928)
			(xy 276.487317 -120.938379) (xy 276.533984 -120.894153) (xy 276.585855 -120.856161) (xy 276.6421 -120.825012)
			(xy 276.701823 -120.801201) (xy 276.764072 -120.785108) (xy 276.827853 -120.776991) (xy 276.86 -120.776492)
			(xy 276.891961 -120.776994) (xy 276.955379 -120.785005) (xy 277.017293 -120.800902) (xy 277.076726 -120.824434)
			(xy 277.088306 -120.8308) (xy 307.516838 -120.8308) (xy 307.520851 -120.76701) (xy 307.532827 -120.704226)
			(xy 307.552579 -120.643438) (xy 307.579793 -120.585605) (xy 307.614041 -120.531639) (xy 307.654782 -120.482391)
			(xy 307.701375 -120.438638) (xy 307.753084 -120.401069) (xy 307.809094 -120.370277) (xy 307.868522 -120.346748)
			(xy 307.93043 -120.330853) (xy 307.993842 -120.322842) (xy 308.0258 -120.32234) (xy 308.056273 -120.32281)
			(xy 308.11678 -120.330105) (xy 308.175982 -120.344578) (xy 308.233031 -120.366021) (xy 308.287108 -120.394128)
			(xy 308.337439 -120.428495) (xy 308.383303 -120.468631) (xy 308.404006 -120.490996) (xy 308.411372 -120.499124)
			(xy 308.431184 -120.508014) (xy 308.529482 -120.506998) (xy 308.549294 -120.497854) (xy 308.556406 -120.489726)
			(xy 308.577129 -120.46656) (xy 308.623308 -120.424953) (xy 308.674215 -120.389287) (xy 308.729091 -120.360094)
			(xy 308.787117 -120.337809) (xy 308.847427 -120.322765) (xy 308.909121 -120.315187) (xy 308.9402 -120.31472)
			(xy 308.972163 -120.315166) (xy 309.035584 -120.323178) (xy 309.097502 -120.339076) (xy 309.156938 -120.362608)
			(xy 309.212956 -120.393405) (xy 309.264673 -120.430979) (xy 309.311273 -120.474739) (xy 309.352021 -120.523995)
			(xy 309.386274 -120.577969) (xy 309.413492 -120.63581) (xy 309.423948 -120.667991) (xy 317.239644 -120.667991)
			(xy 317.239644 -120.604069) (xy 317.247655 -120.540651) (xy 317.263552 -120.478737) (xy 317.287084 -120.419304)
			(xy 317.317878 -120.363289) (xy 317.355451 -120.311574) (xy 317.399208 -120.264977) (xy 317.448461 -120.224232)
			(xy 317.502432 -120.189981) (xy 317.560271 -120.162764) (xy 317.621064 -120.143011) (xy 317.683854 -120.131033)
			(xy 317.74765 -120.12702) (xy 317.811446 -120.131033) (xy 317.874236 -120.143011) (xy 317.935029 -120.162764)
			(xy 317.992868 -120.189981) (xy 318.046839 -120.224232) (xy 318.078796 -120.250669) (xy 379.395222 -120.250669)
			(xy 379.395222 -120.186747) (xy 379.403233 -120.123329) (xy 379.41913 -120.061415) (xy 379.442662 -120.001982)
			(xy 379.473456 -119.945967) (xy 379.511029 -119.894252) (xy 379.554786 -119.847655) (xy 379.604039 -119.80691)
			(xy 379.65801 -119.772659) (xy 379.715849 -119.745442) (xy 379.776642 -119.725689) (xy 379.839432 -119.713711)
			(xy 379.903228 -119.709698) (xy 379.967024 -119.713711) (xy 380.029814 -119.725689) (xy 380.090607 -119.745442)
			(xy 380.148446 -119.772659) (xy 380.202417 -119.80691) (xy 380.25167 -119.847655) (xy 380.295427 -119.894252)
			(xy 380.333 -119.945967) (xy 380.363794 -120.001982) (xy 380.387326 -120.061415) (xy 380.403223 -120.123329)
			(xy 380.411234 -120.186747) (xy 380.411736 -120.218708) (xy 380.411234 -120.250669) (xy 380.403223 -120.314087)
			(xy 380.387326 -120.376001) (xy 380.363794 -120.435434) (xy 380.333 -120.491449) (xy 380.295427 -120.543164)
			(xy 380.25167 -120.589761) (xy 380.202417 -120.630506) (xy 380.148446 -120.664757) (xy 380.090607 -120.691974)
			(xy 380.029814 -120.711727) (xy 379.967024 -120.723705) (xy 379.903228 -120.727719) (xy 379.839432 -120.723705)
			(xy 379.776642 -120.711727) (xy 379.715849 -120.691974) (xy 379.65801 -120.664757) (xy 379.604039 -120.630506)
			(xy 379.554786 -120.589761) (xy 379.511029 -120.543164) (xy 379.473456 -120.491449) (xy 379.442662 -120.435434)
			(xy 379.41913 -120.376001) (xy 379.403233 -120.314087) (xy 379.395222 -120.250669) (xy 318.078796 -120.250669)
			(xy 318.096092 -120.264977) (xy 318.139849 -120.311574) (xy 318.177422 -120.363289) (xy 318.208216 -120.419304)
			(xy 318.231748 -120.478737) (xy 318.247645 -120.540651) (xy 318.255656 -120.604069) (xy 318.256158 -120.63603)
			(xy 318.255656 -120.667991) (xy 318.247645 -120.731409) (xy 318.231748 -120.793323) (xy 318.208216 -120.852756)
			(xy 318.177422 -120.908771) (xy 318.139849 -120.960486) (xy 318.096092 -121.007083) (xy 318.046839 -121.047828)
			(xy 317.992868 -121.082079) (xy 317.935029 -121.109296) (xy 317.874236 -121.129049) (xy 317.811446 -121.141027)
			(xy 317.74765 -121.145041) (xy 317.683854 -121.141027) (xy 317.621064 -121.129049) (xy 317.560271 -121.109296)
			(xy 317.502432 -121.082079) (xy 317.448461 -121.047828) (xy 317.399208 -121.007083) (xy 317.355451 -120.960486)
			(xy 317.317878 -120.908771) (xy 317.287084 -120.852756) (xy 317.263552 -120.793323) (xy 317.247655 -120.731409)
			(xy 317.239644 -120.667991) (xy 309.423948 -120.667991) (xy 309.433246 -120.696607) (xy 309.445225 -120.759401)
			(xy 309.449239 -120.8232) (xy 309.445225 -120.886999) (xy 309.433246 -120.949793) (xy 309.413492 -121.01059)
			(xy 309.386274 -121.068431) (xy 309.352021 -121.122405) (xy 309.311273 -121.171661) (xy 309.264673 -121.215421)
			(xy 309.212956 -121.252995) (xy 309.156938 -121.283792) (xy 309.097502 -121.307324) (xy 309.035584 -121.323222)
			(xy 308.972163 -121.331234) (xy 308.9402 -121.331736) (xy 308.909728 -121.331241) (xy 308.849223 -121.323947)
			(xy 308.790022 -121.309477) (xy 308.732974 -121.288037) (xy 308.678897 -121.259934) (xy 308.628565 -121.225572)
			(xy 308.582698 -121.185442) (xy 308.561994 -121.16308) (xy 308.554628 -121.154952) (xy 308.534816 -121.146062)
			(xy 308.436518 -121.147078) (xy 308.416706 -121.156222) (xy 308.409594 -121.16435) (xy 308.388888 -121.187531)
			(xy 308.342704 -121.229134) (xy 308.291793 -121.264797) (xy 308.236914 -121.293987) (xy 308.178886 -121.316269)
			(xy 308.118575 -121.331312) (xy 308.05688 -121.338889) (xy 308.0258 -121.339356) (xy 307.993842 -121.338758)
			(xy 307.93043 -121.330747) (xy 307.868522 -121.314852) (xy 307.809094 -121.291323) (xy 307.753084 -121.260531)
			(xy 307.701375 -121.222962) (xy 307.654782 -121.179209) (xy 307.614041 -121.129961) (xy 307.579793 -121.075995)
			(xy 307.552579 -121.018162) (xy 307.532827 -120.957374) (xy 307.520851 -120.89459) (xy 307.516838 -120.8308)
			(xy 277.088306 -120.8308) (xy 277.132741 -120.855228) (xy 277.184456 -120.892801) (xy 277.231053 -120.936558)
			(xy 277.271798 -120.985811) (xy 277.306049 -121.039782) (xy 277.333266 -121.097621) (xy 277.353019 -121.158414)
			(xy 277.364997 -121.221204) (xy 277.369011 -121.285) (xy 277.364997 -121.348796) (xy 277.353019 -121.411586)
			(xy 277.333266 -121.472379) (xy 277.306049 -121.530218) (xy 277.271798 -121.584189) (xy 277.231053 -121.633442)
			(xy 277.205624 -121.657321) (xy 291.738552 -121.657321) (xy 291.738552 -121.593399) (xy 291.746563 -121.529981)
			(xy 291.76246 -121.468067) (xy 291.785992 -121.408634) (xy 291.816786 -121.352619) (xy 291.854359 -121.300904)
			(xy 291.898116 -121.254307) (xy 291.947369 -121.213562) (xy 292.00134 -121.179311) (xy 292.059179 -121.152094)
			(xy 292.119972 -121.132341) (xy 292.182762 -121.120363) (xy 292.246558 -121.11635) (xy 292.310354 -121.120363)
			(xy 292.373144 -121.132341) (xy 292.433937 -121.152094) (xy 292.491776 -121.179311) (xy 292.545747 -121.213562)
			(xy 292.595 -121.254307) (xy 292.638757 -121.300904) (xy 292.67633 -121.352619) (xy 292.707124 -121.408634)
			(xy 292.730656 -121.468067) (xy 292.746553 -121.529981) (xy 292.754564 -121.593399) (xy 292.755066 -121.62536)
			(xy 292.754676 -121.650209) (xy 293.088054 -121.650209) (xy 293.088054 -121.586287) (xy 293.096065 -121.522869)
			(xy 293.111962 -121.460955) (xy 293.135494 -121.401522) (xy 293.166288 -121.345507) (xy 293.203861 -121.293792)
			(xy 293.247618 -121.247195) (xy 293.296871 -121.20645) (xy 293.350842 -121.172199) (xy 293.408681 -121.144982)
			(xy 293.469474 -121.125229) (xy 293.532264 -121.113251) (xy 293.59606 -121.109238) (xy 293.659856 -121.113251)
			(xy 293.722646 -121.125229) (xy 293.783439 -121.144982) (xy 293.841278 -121.172199) (xy 293.895249 -121.20645)
			(xy 293.944502 -121.247195) (xy 293.988259 -121.293792) (xy 294.025832 -121.345507) (xy 294.056626 -121.401522)
			(xy 294.080158 -121.460955) (xy 294.096055 -121.522869) (xy 294.104066 -121.586287) (xy 294.104568 -121.618248)
			(xy 294.104066 -121.650209) (xy 294.096055 -121.713627) (xy 294.080158 -121.775541) (xy 294.056626 -121.834974)
			(xy 294.025832 -121.890989) (xy 293.988259 -121.942704) (xy 293.944502 -121.989301) (xy 293.895249 -122.030046)
			(xy 293.841278 -122.064297) (xy 293.783439 -122.091514) (xy 293.722646 -122.111267) (xy 293.659856 -122.123245)
			(xy 293.59606 -122.127259) (xy 293.532264 -122.123245) (xy 293.469474 -122.111267) (xy 293.408681 -122.091514)
			(xy 293.350842 -122.064297) (xy 293.296871 -122.030046) (xy 293.247618 -121.989301) (xy 293.203861 -121.942704)
			(xy 293.166288 -121.890989) (xy 293.135494 -121.834974) (xy 293.111962 -121.775541) (xy 293.096065 -121.713627)
			(xy 293.088054 -121.650209) (xy 292.754676 -121.650209) (xy 292.754564 -121.657321) (xy 292.746553 -121.720739)
			(xy 292.730656 -121.782653) (xy 292.707124 -121.842086) (xy 292.67633 -121.898101) (xy 292.638757 -121.949816)
			(xy 292.595 -121.996413) (xy 292.545747 -122.037158) (xy 292.491776 -122.071409) (xy 292.433937 -122.098626)
			(xy 292.373144 -122.118379) (xy 292.310354 -122.130357) (xy 292.246558 -122.134371) (xy 292.182762 -122.130357)
			(xy 292.119972 -122.118379) (xy 292.059179 -122.098626) (xy 292.00134 -122.071409) (xy 291.947369 -122.037158)
			(xy 291.898116 -121.996413) (xy 291.854359 -121.949816) (xy 291.816786 -121.898101) (xy 291.785992 -121.842086)
			(xy 291.76246 -121.782653) (xy 291.746563 -121.720739) (xy 291.738552 -121.657321) (xy 277.205624 -121.657321)
			(xy 277.184456 -121.677199) (xy 277.132741 -121.714772) (xy 277.076726 -121.745566) (xy 277.017293 -121.769098)
			(xy 276.955379 -121.784995) (xy 276.891961 -121.793006) (xy 276.86 -121.793508) (xy 276.827849 -121.79304)
			(xy 276.76406 -121.78494) (xy 276.701802 -121.768857) (xy 276.642071 -121.745048) (xy 276.585821 -121.713893)
			(xy 276.533951 -121.67589) (xy 276.48729 -121.631647) (xy 276.466554 -121.607072) (xy 276.460094 -121.599815)
			(xy 276.443112 -121.590411) (xy 276.433534 -121.588784) (xy 276.363684 -121.580402) (xy 276.353958 -121.579695)
			(xy 276.335151 -121.584793) (xy 276.327108 -121.590308) (xy 276.326854 -121.590308) (xy 276.30474 -121.606291)
			(xy 276.256857 -121.632448) (xy 276.205737 -121.651522) (xy 276.152423 -121.663125) (xy 276.098 -121.667019)
			(xy 276.043577 -121.663125) (xy 275.990263 -121.651522) (xy 275.939143 -121.632448) (xy 275.89126 -121.606291)
			(xy 275.869146 -121.590308) (xy 275.868892 -121.590308) (xy 275.860855 -121.584777) (xy 275.842044 -121.579671)
			(xy 275.832316 -121.580402) (xy 275.762466 -121.588784) (xy 275.752902 -121.590457) (xy 275.735928 -121.599845)
			(xy 275.729446 -121.607072) (xy 275.710883 -121.629146) (xy 275.66955 -121.669374) (xy 275.623934 -121.704672)
			(xy 275.57462 -121.734587) (xy 275.548598 -121.747026) (xy 275.536914 -121.75236) (xy 275.52142 -121.772934)
			(xy 275.50745 -121.87047) (xy 275.506551 -121.878891) (xy 275.509797 -121.895505) (xy 275.518277 -121.910156)
			(xy 275.524468 -121.915936) (xy 275.524722 -121.91619) (xy 275.548034 -121.936908) (xy 275.589879 -121.983158)
			(xy 275.625752 -122.034178) (xy 275.655117 -122.089202) (xy 275.677533 -122.147405) (xy 275.692661 -122.207912)
			(xy 275.700277 -122.269815) (xy 275.700744 -122.301) (xy 275.700242 -122.332961) (xy 275.698151 -122.349514)
			(xy 295.048684 -122.349514) (xy 295.052755 -122.293892) (xy 295.064881 -122.239455) (xy 295.084804 -122.187364)
			(xy 295.1121 -122.138729) (xy 295.146186 -122.094586) (xy 295.186335 -122.055877) (xy 295.231693 -122.023426)
			(xy 295.281293 -121.997925) (xy 295.334077 -121.979918) (xy 295.38892 -121.969788) (xy 295.444654 -121.967751)
			(xy 295.500091 -121.973851) (xy 295.554048 -121.987957) (xy 295.605377 -122.009769) (xy 295.652983 -122.038823)
			(xy 295.695851 -122.074498) (xy 295.733068 -122.116035) (xy 295.763841 -122.162548) (xy 295.787513 -122.213045)
			(xy 295.803581 -122.266452) (xy 295.811701 -122.321628) (xy 295.81221 -122.3495) (xy 300.745203 -122.3495)
			(xy 300.749217 -122.285709) (xy 300.761193 -122.222924) (xy 300.780943 -122.162135) (xy 300.808157 -122.1043)
			(xy 300.842404 -122.050332) (xy 300.883144 -122.001082) (xy 300.929736 -121.957326) (xy 300.981444 -121.919754)
			(xy 301.037454 -121.888958) (xy 301.096881 -121.865425) (xy 301.158789 -121.849526) (xy 301.222201 -121.84151)
			(xy 301.25416 -121.841006) (xy 301.286866 -121.841518) (xy 301.351738 -121.849901) (xy 301.415 -121.866533)
			(xy 301.475606 -121.891141) (xy 301.532556 -121.923318) (xy 301.58491 -121.962532) (xy 301.631803 -122.008136)
			(xy 301.672461 -122.059377) (xy 301.68977 -122.087132) (xy 301.696558 -122.097085) (xy 301.716961 -122.109822)
			(xy 301.728886 -122.111516) (xy 301.810928 -122.118374) (xy 301.823051 -122.118791) (xy 301.845472 -122.109618)
			(xy 301.853854 -122.100848) (xy 301.872058 -122.080393) (xy 301.913321 -122.044397) (xy 301.959306 -122.014671)
			(xy 302.009069 -121.991824) (xy 302.061587 -121.976327) (xy 302.115782 -121.968499) (xy 302.170538 -121.968499)
			(xy 302.224733 -121.976327) (xy 302.277251 -121.991824) (xy 302.327014 -122.014671) (xy 302.372999 -122.044397)
			(xy 302.414262 -122.080393) (xy 302.432466 -122.100848) (xy 302.440866 -122.109584) (xy 302.463277 -122.118725)
			(xy 302.475392 -122.118374) (xy 302.557434 -122.111516) (xy 302.569364 -122.109838) (xy 302.589776 -122.097097)
			(xy 302.59655 -122.087132) (xy 302.613871 -122.059386) (xy 302.654531 -122.008148) (xy 302.701424 -121.962547)
			(xy 302.753776 -121.923333) (xy 302.810724 -121.891155) (xy 302.871327 -121.866544) (xy 302.934586 -121.849906)
			(xy 302.999455 -121.841515) (xy 303.03216 -121.841006) (xy 303.064125 -121.841457) (xy 303.127551 -121.849464)
			(xy 303.189473 -121.865359) (xy 303.248915 -121.88889) (xy 303.304939 -121.919685) (xy 303.356661 -121.957259)
			(xy 303.403265 -122.00102) (xy 303.444017 -122.050278) (xy 303.478274 -122.104254) (xy 303.505495 -122.162099)
			(xy 303.525251 -122.222899) (xy 303.527407 -122.2342) (xy 305.121266 -122.2342) (xy 305.125281 -122.170399)
			(xy 305.13726 -122.107604) (xy 305.157015 -122.046806) (xy 305.184235 -121.988964) (xy 305.218489 -121.934989)
			(xy 305.259239 -121.885733) (xy 305.305841 -121.841974) (xy 305.35756 -121.8044) (xy 305.413581 -121.773605)
			(xy 305.47302 -121.750074) (xy 305.534939 -121.734179) (xy 305.598362 -121.726169) (xy 305.630326 -121.72569)
			(xy 305.664847 -121.726295) (xy 305.733255 -121.735639) (xy 305.794093 -121.752571) (xy 385.348474 -121.752571)
			(xy 385.348474 -121.688649) (xy 385.356485 -121.625231) (xy 385.372382 -121.563317) (xy 385.395914 -121.503884)
			(xy 385.426708 -121.447869) (xy 385.464281 -121.396154) (xy 385.508038 -121.349557) (xy 385.557291 -121.308812)
			(xy 385.611262 -121.274561) (xy 385.669101 -121.247344) (xy 385.729894 -121.227591) (xy 385.792684 -121.215613)
			(xy 385.85648 -121.2116) (xy 385.920276 -121.215613) (xy 385.983066 -121.227591) (xy 386.043859 -121.247344)
			(xy 386.101698 -121.274561) (xy 386.155669 -121.308812) (xy 386.204922 -121.349557) (xy 386.248679 -121.396154)
			(xy 386.286252 -121.447869) (xy 386.317046 -121.503884) (xy 386.340578 -121.563317) (xy 386.356475 -121.625231)
			(xy 386.364486 -121.688649) (xy 386.364884 -121.713963) (xy 393.99311 -121.713963) (xy 393.99311 -121.650041)
			(xy 394.001121 -121.586623) (xy 394.017018 -121.524709) (xy 394.04055 -121.465276) (xy 394.071344 -121.409261)
			(xy 394.108917 -121.357546) (xy 394.152674 -121.310949) (xy 394.201927 -121.270204) (xy 394.255898 -121.235953)
			(xy 394.313737 -121.208736) (xy 394.37453 -121.188983) (xy 394.43732 -121.177005) (xy 394.501116 -121.172992)
			(xy 394.564912 -121.177005) (xy 394.627702 -121.188983) (xy 394.688495 -121.208736) (xy 394.746334 -121.235953)
			(xy 394.800305 -121.270204) (xy 394.849558 -121.310949) (xy 394.893315 -121.357546) (xy 394.930888 -121.409261)
			(xy 394.961682 -121.465276) (xy 394.985214 -121.524709) (xy 395.001111 -121.586623) (xy 395.009122 -121.650041)
			(xy 395.009624 -121.682002) (xy 395.009122 -121.713963) (xy 395.001111 -121.777381) (xy 394.985214 -121.839295)
			(xy 394.961682 -121.898728) (xy 394.930888 -121.954743) (xy 394.893315 -122.006458) (xy 394.849558 -122.053055)
			(xy 394.800305 -122.0938) (xy 394.746334 -122.128051) (xy 394.688495 -122.155268) (xy 394.627702 -122.175021)
			(xy 394.564912 -122.186999) (xy 394.501116 -122.191013) (xy 394.43732 -122.186999) (xy 394.37453 -122.175021)
			(xy 394.313737 -122.155268) (xy 394.255898 -122.128051) (xy 394.201927 -122.0938) (xy 394.152674 -122.053055)
			(xy 394.108917 -122.006458) (xy 394.071344 -121.954743) (xy 394.04055 -121.898728) (xy 394.017018 -121.839295)
			(xy 394.001121 -121.777381) (xy 393.99311 -121.713963) (xy 386.364884 -121.713963) (xy 386.364988 -121.72061)
			(xy 386.364486 -121.752571) (xy 386.356475 -121.815989) (xy 386.340578 -121.877903) (xy 386.317046 -121.937336)
			(xy 386.286252 -121.993351) (xy 386.248679 -122.045066) (xy 386.204922 -122.091663) (xy 386.155669 -122.132408)
			(xy 386.101698 -122.166659) (xy 386.043859 -122.193876) (xy 385.983066 -122.213629) (xy 385.920276 -122.225607)
			(xy 385.85648 -122.229621) (xy 385.792684 -122.225607) (xy 385.729894 -122.213629) (xy 385.669101 -122.193876)
			(xy 385.611262 -122.166659) (xy 385.557291 -122.132408) (xy 385.508038 -122.091663) (xy 385.464281 -122.045066)
			(xy 385.426708 -121.993351) (xy 385.395914 -121.937336) (xy 385.372382 -121.877903) (xy 385.356485 -121.815989)
			(xy 385.348474 -121.752571) (xy 305.794093 -121.752571) (xy 305.79977 -121.754151) (xy 305.863168 -121.781492)
			(xy 305.922286 -121.817158) (xy 305.976034 -121.860494) (xy 306.00015 -121.885202) (xy 306.006754 -121.892314)
			(xy 306.024788 -121.900696) (xy 306.105052 -121.904506) (xy 306.114635 -121.904552) (xy 306.132776 -121.898427)
			(xy 306.140358 -121.892568) (xy 306.140866 -121.89206) (xy 306.164044 -121.872593) (xy 306.214167 -121.83866)
			(xy 306.267964 -121.810918) (xy 306.324674 -121.78976) (xy 306.383495 -121.775484) (xy 306.443596 -121.768293)
			(xy 306.47386 -121.767854) (xy 306.505822 -121.768408) (xy 306.569241 -121.776416) (xy 306.631157 -121.792309)
			(xy 306.690593 -121.815837) (xy 306.746611 -121.846629) (xy 306.798327 -121.884199) (xy 306.844927 -121.927956)
			(xy 306.885675 -121.977208) (xy 306.919928 -122.031179) (xy 306.947147 -122.089018) (xy 306.966901 -122.149812)
			(xy 306.97888 -122.212603) (xy 306.982894 -122.2764) (xy 306.97888 -122.340197) (xy 306.966901 -122.402988)
			(xy 306.947147 -122.463782) (xy 306.919928 -122.521621) (xy 306.885675 -122.575592) (xy 306.844927 -122.624844)
			(xy 306.798327 -122.668601) (xy 306.746611 -122.706171) (xy 306.690593 -122.736963) (xy 306.631157 -122.760491)
			(xy 306.569241 -122.776384) (xy 306.505822 -122.784392) (xy 306.47386 -122.78487) (xy 306.439338 -122.784287)
			(xy 306.370929 -122.77494) (xy 306.304413 -122.756425) (xy 306.241014 -122.72908) (xy 306.181898 -122.693409)
			(xy 306.128151 -122.650068) (xy 306.104036 -122.625358) (xy 306.097432 -122.618246) (xy 306.079398 -122.609864)
			(xy 305.999134 -122.606054) (xy 305.989552 -122.606009) (xy 305.971411 -122.612135) (xy 305.963828 -122.617992)
			(xy 305.96332 -122.6185) (xy 305.940142 -122.637967) (xy 305.89002 -122.671901) (xy 305.836223 -122.699644)
			(xy 305.779513 -122.720803) (xy 305.720691 -122.735078) (xy 305.660591 -122.742268) (xy 305.630326 -122.742706)
			(xy 305.598362 -122.742231) (xy 305.534939 -122.734221) (xy 305.47302 -122.718326) (xy 305.413581 -122.694795)
			(xy 305.35756 -122.664) (xy 305.305841 -122.626426) (xy 305.259239 -122.582667) (xy 305.218489 -122.533411)
			(xy 305.184235 -122.479436) (xy 305.157015 -122.421594) (xy 305.13726 -122.360796) (xy 305.125281 -122.298001)
			(xy 305.121266 -122.2342) (xy 303.527407 -122.2342) (xy 303.537231 -122.285697) (xy 303.541246 -122.3495)
			(xy 303.537231 -122.413303) (xy 303.525251 -122.476101) (xy 303.505495 -122.536901) (xy 303.478274 -122.594746)
			(xy 303.444017 -122.648722) (xy 303.403265 -122.69798) (xy 303.356661 -122.741741) (xy 303.304939 -122.779315)
			(xy 303.265587 -122.800946) (xy 315.134829 -122.800946) (xy 315.137857 -122.73642) (xy 315.149033 -122.672796)
			(xy 315.168177 -122.6111) (xy 315.19498 -122.552325) (xy 315.229011 -122.497418) (xy 315.269721 -122.447263)
			(xy 315.316456 -122.402668) (xy 315.368462 -122.36435) (xy 315.424902 -122.332927) (xy 315.484867 -122.308905)
			(xy 315.547392 -122.292671) (xy 315.611469 -122.284486) (xy 315.643768 -122.283982) (xy 315.675006 -122.284502)
			(xy 315.737011 -122.292174) (xy 315.797608 -122.307383) (xy 315.855887 -122.329898) (xy 315.91097 -122.359382)
			(xy 315.962027 -122.39539) (xy 316.00829 -122.437379) (xy 316.049062 -122.484719) (xy 316.083729 -122.536696)
			(xy 316.098174 -122.564398) (xy 316.104729 -122.576465) (xy 316.123135 -122.596831) (xy 316.146302 -122.611557)
			(xy 316.172555 -122.61958) (xy 316.199996 -122.620319) (xy 316.226642 -122.613721) (xy 316.250568 -122.600264)
			(xy 316.270045 -122.580919) (xy 316.277244 -122.569224) (xy 316.291914 -122.544594) (xy 316.327516 -122.499664)
			(xy 316.369439 -122.460564) (xy 316.416738 -122.428175) (xy 316.468351 -122.403225) (xy 316.523114 -122.386277)
			(xy 316.579797 -122.37771) (xy 316.60846 -122.3772) (xy 316.635715 -122.377645) (xy 316.689672 -122.385397)
			(xy 316.741975 -122.40075) (xy 316.791562 -122.423391) (xy 316.837421 -122.452858) (xy 316.878619 -122.488553)
			(xy 316.914318 -122.529747) (xy 316.94379 -122.575603) (xy 316.966436 -122.625187) (xy 316.981794 -122.677489)
			(xy 316.989553 -122.731445) (xy 316.989553 -122.785955) (xy 316.981794 -122.839911) (xy 316.966436 -122.892213)
			(xy 316.94379 -122.941797) (xy 316.914318 -122.987653) (xy 316.878619 -123.028847) (xy 316.837421 -123.064542)
			(xy 316.791562 -123.094009) (xy 316.741975 -123.11665) (xy 316.689672 -123.132003) (xy 316.635715 -123.139755)
			(xy 316.60846 -123.140216) (xy 316.581699 -123.139763) (xy 316.528703 -123.132283) (xy 316.477271 -123.117475)
			(xy 316.428411 -123.095629) (xy 316.38308 -123.067174) (xy 316.342167 -123.032668) (xy 316.306475 -122.992786)
			(xy 316.291214 -122.970798) (xy 316.283218 -122.959653) (xy 316.262476 -122.941724) (xy 316.237705 -122.929973)
			(xy 316.210698 -122.925249) (xy 316.183409 -122.927895) (xy 316.157812 -122.937719) (xy 316.13576 -122.95401)
			(xy 316.118849 -122.975589) (xy 316.11316 -122.98807) (xy 316.100314 -123.017708) (xy 316.068116 -123.07371)
			(xy 316.029086 -123.125183) (xy 315.983851 -123.171299) (xy 315.93314 -123.211315) (xy 315.877769 -123.244586)
			(xy 315.818631 -123.270577) (xy 315.756677 -123.288869) (xy 315.692906 -123.299167) (xy 315.628343 -123.301307)
			(xy 315.56403 -123.295252) (xy 315.501001 -123.281102) (xy 315.440272 -123.259083) (xy 315.38282 -123.22955)
			(xy 315.329571 -123.192979) (xy 315.281383 -123.149959) (xy 315.23903 -123.101182) (xy 315.203196 -123.047435)
			(xy 315.174458 -122.989582) (xy 315.153278 -122.928555) (xy 315.139996 -122.865337) (xy 315.134829 -122.800946)
			(xy 303.265587 -122.800946) (xy 303.248915 -122.81011) (xy 303.189473 -122.833641) (xy 303.127551 -122.849536)
			(xy 303.064125 -122.857543) (xy 303.03216 -122.858022) (xy 302.999453 -122.857529) (xy 302.934579 -122.849147)
			(xy 302.871315 -122.832514) (xy 302.810707 -122.807905) (xy 302.753756 -122.775725) (xy 302.701403 -122.736508)
			(xy 302.654512 -122.690899) (xy 302.613857 -122.639653) (xy 302.59655 -122.611896) (xy 302.589794 -122.601917)
			(xy 302.569368 -122.589191) (xy 302.557434 -122.587512) (xy 302.475392 -122.580654) (xy 302.463269 -122.580241)
			(xy 302.440848 -122.589409) (xy 302.432466 -122.59818) (xy 302.414262 -122.618635) (xy 302.372999 -122.654631)
			(xy 302.327014 -122.684357) (xy 302.277251 -122.707204) (xy 302.224733 -122.722701) (xy 302.170538 -122.730529)
			(xy 302.115782 -122.730529) (xy 302.061587 -122.722701) (xy 302.009069 -122.707204) (xy 301.959306 -122.684357)
			(xy 301.913321 -122.654631) (xy 301.872058 -122.618635) (xy 301.853854 -122.59818) (xy 301.845441 -122.589458)
			(xy 301.82304 -122.580308) (xy 301.810928 -122.580654) (xy 301.728886 -122.587512) (xy 301.716955 -122.58919)
			(xy 301.696543 -122.60193) (xy 301.68977 -122.611896) (xy 301.672445 -122.63964) (xy 301.631785 -122.690876)
			(xy 301.584892 -122.736477) (xy 301.53254 -122.77569) (xy 301.475593 -122.807867) (xy 301.414991 -122.832479)
			(xy 301.351733 -122.849119) (xy 301.286865 -122.857512) (xy 301.25416 -122.858022) (xy 301.222201 -122.85749)
			(xy 301.158789 -122.849474) (xy 301.096881 -122.833575) (xy 301.037454 -122.810042) (xy 300.981444 -122.779246)
			(xy 300.929736 -122.741674) (xy 300.883144 -122.697918) (xy 300.842404 -122.648668) (xy 300.808157 -122.5947)
			(xy 300.780943 -122.536865) (xy 300.761193 -122.476076) (xy 300.749217 -122.413291) (xy 300.745203 -122.3495)
			(xy 295.81221 -122.3495) (xy 295.81221 -122.349514) (xy 295.811701 -122.3774) (xy 295.803581 -122.432576)
			(xy 295.787513 -122.485983) (xy 295.763841 -122.53648) (xy 295.733068 -122.582993) (xy 295.695851 -122.62453)
			(xy 295.652983 -122.660205) (xy 295.605377 -122.689259) (xy 295.554048 -122.711071) (xy 295.500091 -122.725177)
			(xy 295.444654 -122.731277) (xy 295.38892 -122.72924) (xy 295.334077 -122.71911) (xy 295.281293 -122.701103)
			(xy 295.231693 -122.675602) (xy 295.186335 -122.643151) (xy 295.146186 -122.604442) (xy 295.1121 -122.560299)
			(xy 295.084804 -122.511664) (xy 295.064881 -122.459573) (xy 295.052755 -122.405136) (xy 295.048684 -122.349514)
			(xy 275.698151 -122.349514) (xy 275.692231 -122.396379) (xy 275.676334 -122.458293) (xy 275.652802 -122.517726)
			(xy 275.622008 -122.573741) (xy 275.584435 -122.625456) (xy 275.540678 -122.672053) (xy 275.491425 -122.712798)
			(xy 275.437454 -122.747049) (xy 275.379615 -122.774266) (xy 275.318822 -122.794019) (xy 275.256032 -122.805997)
			(xy 275.192236 -122.810011) (xy 275.12844 -122.805997) (xy 275.06565 -122.794019) (xy 275.004857 -122.774266)
			(xy 274.947018 -122.747049) (xy 274.893047 -122.712798) (xy 274.843794 -122.672053) (xy 274.800037 -122.625456)
			(xy 274.762464 -122.573741) (xy 274.73167 -122.517726) (xy 274.708138 -122.458293) (xy 274.692241 -122.396379)
			(xy 274.68423 -122.332961) (xy 274.683728 -122.301) (xy 269.989173 -122.301) (xy 269.979321 -122.305636)
			(xy 269.918528 -122.325389) (xy 269.855738 -122.337367) (xy 269.791942 -122.341381) (xy 269.728146 -122.337367)
			(xy 269.665356 -122.325389) (xy 269.604563 -122.305636) (xy 269.546724 -122.278419) (xy 269.492753 -122.244168)
			(xy 269.4435 -122.203423) (xy 269.399743 -122.156826) (xy 269.36217 -122.105111) (xy 269.331376 -122.049096)
			(xy 269.307844 -121.989663) (xy 269.291947 -121.927749) (xy 269.283936 -121.864331) (xy 259.379378 -121.864331)
			(xy 259.387346 -121.927409) (xy 259.387848 -121.95937) (xy 259.387346 -121.991331) (xy 259.379335 -122.054749)
			(xy 259.363438 -122.116663) (xy 259.339906 -122.176096) (xy 259.309112 -122.232111) (xy 259.271539 -122.283826)
			(xy 259.227782 -122.330423) (xy 259.178529 -122.371168) (xy 259.124558 -122.405419) (xy 259.066719 -122.432636)
			(xy 259.005926 -122.452389) (xy 258.943136 -122.464367) (xy 258.87934 -122.468381) (xy 258.815544 -122.464367)
			(xy 258.752754 -122.452389) (xy 258.691961 -122.432636) (xy 258.634122 -122.405419) (xy 258.580151 -122.371168)
			(xy 258.530898 -122.330423) (xy 258.487141 -122.283826) (xy 258.449568 -122.232111) (xy 258.418774 -122.176096)
			(xy 258.395242 -122.116663) (xy 258.379345 -122.054749) (xy 258.371334 -121.991331) (xy 251.152185 -121.991331)
			(xy 251.144655 -122.050939) (xy 251.128758 -122.112853) (xy 251.105226 -122.172286) (xy 251.074432 -122.228301)
			(xy 251.036859 -122.280016) (xy 250.993102 -122.326613) (xy 250.943849 -122.367358) (xy 250.889878 -122.401609)
			(xy 250.832039 -122.428826) (xy 250.771246 -122.448579) (xy 250.708456 -122.460557) (xy 250.64466 -122.464571)
			(xy 250.580864 -122.460557) (xy 250.518074 -122.448579) (xy 250.457281 -122.428826) (xy 250.399442 -122.401609)
			(xy 250.345471 -122.367358) (xy 250.296218 -122.326613) (xy 250.252461 -122.280016) (xy 250.214888 -122.228301)
			(xy 250.184094 -122.172286) (xy 250.160562 -122.112853) (xy 250.144665 -122.050939) (xy 250.136654 -121.987521)
			(xy 228.81472 -121.987521) (xy 228.830098 -122.026359) (xy 228.845995 -122.088273) (xy 228.854006 -122.151691)
			(xy 228.854508 -122.183652) (xy 228.854006 -122.215613) (xy 228.845995 -122.279031) (xy 228.830098 -122.340945)
			(xy 228.806566 -122.400378) (xy 228.775772 -122.456393) (xy 228.738199 -122.508108) (xy 228.72092 -122.526509)
			(xy 267.959834 -122.526509) (xy 267.959834 -122.462587) (xy 267.967845 -122.399169) (xy 267.983742 -122.337255)
			(xy 268.007274 -122.277822) (xy 268.038068 -122.221807) (xy 268.075641 -122.170092) (xy 268.119398 -122.123495)
			(xy 268.168651 -122.08275) (xy 268.222622 -122.048499) (xy 268.280461 -122.021282) (xy 268.341254 -122.001529)
			(xy 268.404044 -121.989551) (xy 268.46784 -121.985538) (xy 268.531636 -121.989551) (xy 268.594426 -122.001529)
			(xy 268.655219 -122.021282) (xy 268.713058 -122.048499) (xy 268.767029 -122.08275) (xy 268.816282 -122.123495)
			(xy 268.860039 -122.170092) (xy 268.897612 -122.221807) (xy 268.928406 -122.277822) (xy 268.951938 -122.337255)
			(xy 268.967835 -122.399169) (xy 268.975846 -122.462587) (xy 268.976348 -122.494548) (xy 268.975846 -122.526509)
			(xy 268.967835 -122.589927) (xy 268.951938 -122.651841) (xy 268.928406 -122.711274) (xy 268.897612 -122.767289)
			(xy 268.860039 -122.819004) (xy 268.816282 -122.865601) (xy 268.767029 -122.906346) (xy 268.713058 -122.940597)
			(xy 268.655219 -122.967814) (xy 268.594426 -122.987567) (xy 268.531636 -122.999545) (xy 268.46784 -123.003559)
			(xy 268.404044 -122.999545) (xy 268.341254 -122.987567) (xy 268.280461 -122.967814) (xy 268.222622 -122.940597)
			(xy 268.168651 -122.906346) (xy 268.119398 -122.865601) (xy 268.075641 -122.819004) (xy 268.038068 -122.767289)
			(xy 268.007274 -122.711274) (xy 267.983742 -122.651841) (xy 267.967845 -122.589927) (xy 267.959834 -122.526509)
			(xy 228.72092 -122.526509) (xy 228.694442 -122.554705) (xy 228.645189 -122.59545) (xy 228.591218 -122.629701)
			(xy 228.533379 -122.656918) (xy 228.472586 -122.676671) (xy 228.409796 -122.688649) (xy 228.346 -122.692663)
			(xy 228.282204 -122.688649) (xy 228.219414 -122.676671) (xy 228.158621 -122.656918) (xy 228.100782 -122.629701)
			(xy 228.046811 -122.59545) (xy 227.997558 -122.554705) (xy 227.953801 -122.508108) (xy 227.916228 -122.456393)
			(xy 227.885434 -122.400378) (xy 227.861902 -122.340945) (xy 227.846005 -122.279031) (xy 227.837994 -122.215613)
			(xy 215.433472 -122.215613) (xy 215.44896 -122.243786) (xy 215.472492 -122.303219) (xy 215.488389 -122.365133)
			(xy 215.4964 -122.428551) (xy 215.496902 -122.460512) (xy 215.496373 -122.494199) (xy 215.487468 -122.560981)
			(xy 215.46983 -122.626004) (xy 215.443767 -122.688132) (xy 215.409734 -122.746278) (xy 215.38946 -122.773186)
			(xy 215.382348 -122.78233) (xy 215.377268 -122.80519) (xy 215.398858 -122.89409) (xy 215.402149 -122.905063)
			(xy 215.416689 -122.922731) (xy 215.426798 -122.928126) (xy 215.427306 -122.928126) (xy 215.456393 -122.941989)
			(xy 215.511074 -122.976077) (xy 215.561009 -123.016801) (xy 215.6054 -123.063508) (xy 215.643534 -123.115449)
			(xy 215.6748 -123.171791) (xy 215.698697 -123.231632) (xy 215.714842 -123.294013) (xy 215.722976 -123.357934)
			(xy 215.72347 -123.390152) (xy 215.722968 -123.422113) (xy 215.714957 -123.485531) (xy 215.69906 -123.547445)
			(xy 215.675528 -123.606878) (xy 215.644734 -123.662893) (xy 215.607161 -123.714608) (xy 215.563404 -123.761205)
			(xy 215.514151 -123.80195) (xy 215.46018 -123.836201) (xy 215.402341 -123.863418) (xy 215.341548 -123.883171)
			(xy 215.278758 -123.895149) (xy 215.214962 -123.899163) (xy 215.151166 -123.895149) (xy 215.088376 -123.883171)
			(xy 215.027583 -123.863418) (xy 214.969744 -123.836201) (xy 214.915773 -123.80195) (xy 214.86652 -123.761205)
			(xy 214.822763 -123.714608) (xy 214.78519 -123.662893) (xy 214.754396 -123.606878) (xy 214.730864 -123.547445)
			(xy 214.714967 -123.485531) (xy 214.706956 -123.422113) (xy 214.706454 -123.390152) (xy 214.707007 -123.356466)
			(xy 214.715904 -123.289684) (xy 214.733536 -123.224661) (xy 214.759594 -123.162533) (xy 214.793624 -123.104387)
			(xy 214.813896 -123.077478) (xy 214.821008 -123.068334) (xy 214.826088 -123.045474) (xy 214.804498 -122.956574)
			(xy 214.801155 -122.945622) (xy 214.786651 -122.927944) (xy 214.776558 -122.922538) (xy 214.77605 -122.922538)
			(xy 214.747002 -122.908599) (xy 214.69232 -122.874521) (xy 214.642383 -122.833808) (xy 214.59799 -122.787112)
			(xy 214.559852 -122.735181) (xy 214.528581 -122.678847) (xy 214.504678 -122.619015) (xy 214.488526 -122.556641)
			(xy 214.480384 -122.492727) (xy 214.479886 -122.460512) (xy 213.115177 -122.460512) (xy 213.145918 -122.468089)
			(xy 213.203387 -122.489884) (xy 213.257809 -122.518448) (xy 213.308392 -122.553364) (xy 213.354397 -122.594123)
			(xy 213.395153 -122.64013) (xy 213.430066 -122.690715) (xy 213.458627 -122.745139) (xy 213.48042 -122.802609)
			(xy 213.495126 -122.862287) (xy 213.50253 -122.923302) (xy 213.503002 -122.954034) (xy 213.502526 -122.985564)
			(xy 213.49473 -123.048142) (xy 213.479263 -123.109276) (xy 213.45636 -123.168031) (xy 213.426373 -123.223506)
			(xy 213.389762 -123.274851) (xy 213.347087 -123.321279) (xy 213.299003 -123.362078) (xy 213.272878 -123.379738)
			(xy 213.272624 -123.379738) (xy 213.264242 -123.386596) (xy 213.255606 -123.397772) (xy 213.24443 -123.418092)
			(xy 213.24189 -123.42368) (xy 213.240353 -123.427585) (xy 213.238429 -123.435754) (xy 213.23808 -123.439936)
			(xy 213.23808 -124.113544) (xy 218.002612 -124.113544) (xy 218.003114 -124.081583) (xy 218.011125 -124.018165)
			(xy 218.027022 -123.956251) (xy 218.050554 -123.896818) (xy 218.081348 -123.840803) (xy 218.118921 -123.789088)
			(xy 218.162678 -123.742491) (xy 218.211931 -123.701746) (xy 218.265902 -123.667495) (xy 218.323741 -123.640278)
			(xy 218.384534 -123.620525) (xy 218.447324 -123.608547) (xy 218.51112 -123.604534) (xy 218.574916 -123.608547)
			(xy 218.637706 -123.620525) (xy 218.698499 -123.640278) (xy 218.750362 -123.664683) (xy 231.524042 -123.664683)
			(xy 231.524042 -123.600761) (xy 231.532053 -123.537343) (xy 231.54795 -123.475429) (xy 231.571482 -123.415996)
			(xy 231.602276 -123.359981) (xy 231.639849 -123.308266) (xy 231.683606 -123.261669) (xy 231.732859 -123.220924)
			(xy 231.78683 -123.186673) (xy 231.844669 -123.159456) (xy 231.905462 -123.139703) (xy 231.968252 -123.127725)
			(xy 232.032048 -123.123712) (xy 232.095844 -123.127725) (xy 232.158634 -123.139703) (xy 232.219427 -123.159456)
			(xy 232.277266 -123.186673) (xy 232.331237 -123.220924) (xy 232.38049 -123.261669) (xy 232.424247 -123.308266)
			(xy 232.46182 -123.359981) (xy 232.492614 -123.415996) (xy 232.516146 -123.475429) (xy 232.532043 -123.537343)
			(xy 232.540054 -123.600761) (xy 232.540556 -123.632722) (xy 232.540054 -123.664683) (xy 232.532043 -123.728101)
			(xy 232.516146 -123.790015) (xy 232.510859 -123.803367) (xy 243.086376 -123.803367) (xy 243.086376 -123.739445)
			(xy 243.094387 -123.676027) (xy 243.110284 -123.614113) (xy 243.133816 -123.55468) (xy 243.16461 -123.498665)
			(xy 243.202183 -123.44695) (xy 243.24594 -123.400353) (xy 243.295193 -123.359608) (xy 243.349164 -123.325357)
			(xy 243.407003 -123.29814) (xy 243.467796 -123.278387) (xy 243.530586 -123.266409) (xy 243.594382 -123.262396)
			(xy 243.658178 -123.266409) (xy 243.682155 -123.270983) (xy 250.475744 -123.270983) (xy 250.475744 -123.207061)
			(xy 250.483755 -123.143643) (xy 250.499652 -123.081729) (xy 250.523184 -123.022296) (xy 250.553978 -122.966281)
			(xy 250.591551 -122.914566) (xy 250.635308 -122.867969) (xy 250.684561 -122.827224) (xy 250.738532 -122.792973)
			(xy 250.796371 -122.765756) (xy 250.857164 -122.746003) (xy 250.919954 -122.734025) (xy 250.98375 -122.730012)
			(xy 251.047546 -122.734025) (xy 251.110336 -122.746003) (xy 251.171129 -122.765756) (xy 251.228968 -122.792973)
			(xy 251.282939 -122.827224) (xy 251.332192 -122.867969) (xy 251.375949 -122.914566) (xy 251.413522 -122.966281)
			(xy 251.444316 -123.022296) (xy 251.467848 -123.081729) (xy 251.483745 -123.143643) (xy 251.491756 -123.207061)
			(xy 251.492258 -123.239022) (xy 251.491756 -123.270983) (xy 251.490146 -123.283726) (xy 251.59538 -123.283726)
			(xy 251.599451 -123.228104) (xy 251.611577 -123.173667) (xy 251.6315 -123.121576) (xy 251.658796 -123.072941)
			(xy 251.692882 -123.028798) (xy 251.733031 -122.990089) (xy 251.778389 -122.957638) (xy 251.827989 -122.932137)
			(xy 251.880773 -122.91413) (xy 251.935616 -122.904) (xy 251.99135 -122.901963) (xy 252.046787 -122.908063)
			(xy 252.100744 -122.922169) (xy 252.152073 -122.943981) (xy 252.199679 -122.973035) (xy 252.242547 -123.00871)
			(xy 252.279764 -123.050247) (xy 252.310537 -123.09676) (xy 252.334209 -123.147257) (xy 252.350277 -123.200664)
			(xy 252.351056 -123.205959) (xy 255.289552 -123.205959) (xy 255.289552 -123.142037) (xy 255.297563 -123.078619)
			(xy 255.31346 -123.016705) (xy 255.336992 -122.957272) (xy 255.367786 -122.901257) (xy 255.405359 -122.849542)
			(xy 255.449116 -122.802945) (xy 255.498369 -122.7622) (xy 255.55234 -122.727949) (xy 255.610179 -122.700732)
			(xy 255.670972 -122.680979) (xy 255.733762 -122.669001) (xy 255.797558 -122.664988) (xy 255.861354 -122.669001)
			(xy 255.924144 -122.680979) (xy 255.984937 -122.700732) (xy 256.042776 -122.727949) (xy 256.096747 -122.7622)
			(xy 256.146 -122.802945) (xy 256.189757 -122.849542) (xy 256.22733 -122.901257) (xy 256.258124 -122.957272)
			(xy 256.281656 -123.016705) (xy 256.297553 -123.078619) (xy 256.305564 -123.142037) (xy 256.306066 -123.173998)
			(xy 256.305564 -123.205959) (xy 256.297553 -123.269377) (xy 256.281656 -123.331291) (xy 256.260882 -123.383759)
			(xy 260.47801 -123.383759) (xy 260.47801 -123.319837) (xy 260.486021 -123.256419) (xy 260.501918 -123.194505)
			(xy 260.52545 -123.135072) (xy 260.556244 -123.079057) (xy 260.593817 -123.027342) (xy 260.637574 -122.980745)
			(xy 260.686827 -122.94) (xy 260.740798 -122.905749) (xy 260.798637 -122.878532) (xy 260.85943 -122.858779)
			(xy 260.92222 -122.846801) (xy 260.986016 -122.842788) (xy 261.049812 -122.846801) (xy 261.112602 -122.858779)
			(xy 261.173395 -122.878532) (xy 261.231234 -122.905749) (xy 261.285205 -122.94) (xy 261.334458 -122.980745)
			(xy 261.378215 -123.027342) (xy 261.415788 -123.079057) (xy 261.446582 -123.135072) (xy 261.470114 -123.194505)
			(xy 261.486011 -123.256419) (xy 261.494022 -123.319837) (xy 261.494524 -123.351798) (xy 261.494022 -123.383759)
			(xy 261.486011 -123.447177) (xy 261.480186 -123.469865) (xy 262.600434 -123.469865) (xy 262.600434 -123.405943)
			(xy 262.608445 -123.342525) (xy 262.624342 -123.280611) (xy 262.647874 -123.221178) (xy 262.678668 -123.165163)
			(xy 262.716241 -123.113448) (xy 262.759998 -123.066851) (xy 262.809251 -123.026106) (xy 262.863222 -122.991855)
			(xy 262.921061 -122.964638) (xy 262.981854 -122.944885) (xy 263.044644 -122.932907) (xy 263.10844 -122.928894)
			(xy 263.172236 -122.932907) (xy 263.235026 -122.944885) (xy 263.295819 -122.964638) (xy 263.353658 -122.991855)
			(xy 263.407629 -123.026106) (xy 263.456882 -123.066851) (xy 263.500639 -123.113448) (xy 263.518949 -123.138649)
			(xy 269.303494 -123.138649) (xy 269.303494 -123.074727) (xy 269.311505 -123.011309) (xy 269.327402 -122.949395)
			(xy 269.350934 -122.889962) (xy 269.381728 -122.833947) (xy 269.419301 -122.782232) (xy 269.463058 -122.735635)
			(xy 269.512311 -122.69489) (xy 269.566282 -122.660639) (xy 269.624121 -122.633422) (xy 269.684914 -122.613669)
			(xy 269.747704 -122.601691) (xy 269.8115 -122.597678) (xy 269.875296 -122.601691) (xy 269.938086 -122.613669)
			(xy 269.998879 -122.633422) (xy 270.056718 -122.660639) (xy 270.110689 -122.69489) (xy 270.159942 -122.735635)
			(xy 270.203699 -122.782232) (xy 270.241272 -122.833947) (xy 270.266771 -122.880331) (xy 271.706334 -122.880331)
			(xy 271.706334 -122.816409) (xy 271.714345 -122.752991) (xy 271.730242 -122.691077) (xy 271.753774 -122.631644)
			(xy 271.784568 -122.575629) (xy 271.822141 -122.523914) (xy 271.865898 -122.477317) (xy 271.915151 -122.436572)
			(xy 271.969122 -122.402321) (xy 272.026961 -122.375104) (xy 272.087754 -122.355351) (xy 272.150544 -122.343373)
			(xy 272.21434 -122.33936) (xy 272.278136 -122.343373) (xy 272.340926 -122.355351) (xy 272.401719 -122.375104)
			(xy 272.459558 -122.402321) (xy 272.513529 -122.436572) (xy 272.562782 -122.477317) (xy 272.606539 -122.523914)
			(xy 272.644112 -122.575629) (xy 272.674906 -122.631644) (xy 272.698438 -122.691077) (xy 272.714335 -122.752991)
			(xy 272.722346 -122.816409) (xy 272.722848 -122.84837) (xy 272.722346 -122.880331) (xy 272.714335 -122.943749)
			(xy 272.698438 -123.005663) (xy 272.686698 -123.035314) (xy 278.122124 -123.035314) (xy 278.126195 -122.979692)
			(xy 278.138321 -122.925255) (xy 278.158244 -122.873164) (xy 278.18554 -122.824529) (xy 278.219626 -122.780386)
			(xy 278.259775 -122.741677) (xy 278.305133 -122.709226) (xy 278.354733 -122.683725) (xy 278.407517 -122.665718)
			(xy 278.46236 -122.655588) (xy 278.518094 -122.653551) (xy 278.573531 -122.659651) (xy 278.627488 -122.673757)
			(xy 278.678817 -122.695569) (xy 278.726423 -122.724623) (xy 278.769291 -122.760298) (xy 278.806508 -122.801835)
			(xy 278.837281 -122.848348) (xy 278.860953 -122.898845) (xy 278.877021 -122.952252) (xy 278.885141 -123.007428)
			(xy 278.88565 -123.035314) (xy 278.885141 -123.0632) (xy 278.877021 -123.118376) (xy 278.860953 -123.171783)
			(xy 278.837281 -123.22228) (xy 278.806508 -123.268793) (xy 278.769291 -123.31033) (xy 278.726423 -123.346005)
			(xy 278.678817 -123.375059) (xy 278.627488 -123.396871) (xy 278.573531 -123.410977) (xy 278.518094 -123.417077)
			(xy 278.46236 -123.41504) (xy 278.407517 -123.40491) (xy 278.354733 -123.386903) (xy 278.305133 -123.361402)
			(xy 278.259775 -123.328951) (xy 278.219626 -123.290242) (xy 278.18554 -123.246099) (xy 278.158244 -123.197464)
			(xy 278.138321 -123.145373) (xy 278.126195 -123.090936) (xy 278.122124 -123.035314) (xy 272.686698 -123.035314)
			(xy 272.674906 -123.065096) (xy 272.644112 -123.121111) (xy 272.606539 -123.172826) (xy 272.562782 -123.219423)
			(xy 272.513529 -123.260168) (xy 272.459558 -123.294419) (xy 272.401719 -123.321636) (xy 272.340926 -123.341389)
			(xy 272.278136 -123.353367) (xy 272.21434 -123.357381) (xy 272.150544 -123.353367) (xy 272.087754 -123.341389)
			(xy 272.026961 -123.321636) (xy 271.969122 -123.294419) (xy 271.915151 -123.260168) (xy 271.865898 -123.219423)
			(xy 271.822141 -123.172826) (xy 271.784568 -123.121111) (xy 271.753774 -123.065096) (xy 271.730242 -123.005663)
			(xy 271.714345 -122.943749) (xy 271.706334 -122.880331) (xy 270.266771 -122.880331) (xy 270.272066 -122.889962)
			(xy 270.295598 -122.949395) (xy 270.311495 -123.011309) (xy 270.319506 -123.074727) (xy 270.320008 -123.106688)
			(xy 270.319506 -123.138649) (xy 270.311495 -123.202067) (xy 270.295598 -123.263981) (xy 270.272066 -123.323414)
			(xy 270.241272 -123.379429) (xy 270.203699 -123.431144) (xy 270.159942 -123.477741) (xy 270.110689 -123.518486)
			(xy 270.056718 -123.552737) (xy 269.998879 -123.579954) (xy 269.938086 -123.599707) (xy 269.875296 -123.611685)
			(xy 269.8115 -123.615699) (xy 269.747704 -123.611685) (xy 269.684914 -123.599707) (xy 269.624121 -123.579954)
			(xy 269.566282 -123.552737) (xy 269.512311 -123.518486) (xy 269.463058 -123.477741) (xy 269.419301 -123.431144)
			(xy 269.381728 -123.379429) (xy 269.350934 -123.323414) (xy 269.327402 -123.263981) (xy 269.311505 -123.202067)
			(xy 269.303494 -123.138649) (xy 263.518949 -123.138649) (xy 263.538212 -123.165163) (xy 263.569006 -123.221178)
			(xy 263.592538 -123.280611) (xy 263.608435 -123.342525) (xy 263.616446 -123.405943) (xy 263.616948 -123.437904)
			(xy 263.616446 -123.469865) (xy 263.608435 -123.533283) (xy 263.592538 -123.595197) (xy 263.569006 -123.65463)
			(xy 263.538212 -123.710645) (xy 263.500639 -123.76236) (xy 263.456882 -123.808957) (xy 263.407629 -123.849702)
			(xy 263.353658 -123.883953) (xy 263.295819 -123.91117) (xy 263.235026 -123.930923) (xy 263.172236 -123.942901)
			(xy 263.10844 -123.946915) (xy 263.044644 -123.942901) (xy 262.981854 -123.930923) (xy 262.921061 -123.91117)
			(xy 262.863222 -123.883953) (xy 262.809251 -123.849702) (xy 262.759998 -123.808957) (xy 262.716241 -123.76236)
			(xy 262.678668 -123.710645) (xy 262.647874 -123.65463) (xy 262.624342 -123.595197) (xy 262.608445 -123.533283)
			(xy 262.600434 -123.469865) (xy 261.480186 -123.469865) (xy 261.470114 -123.509091) (xy 261.446582 -123.568524)
			(xy 261.415788 -123.624539) (xy 261.378215 -123.676254) (xy 261.334458 -123.722851) (xy 261.285205 -123.763596)
			(xy 261.231234 -123.797847) (xy 261.173395 -123.825064) (xy 261.112602 -123.844817) (xy 261.049812 -123.856795)
			(xy 260.986016 -123.860809) (xy 260.92222 -123.856795) (xy 260.85943 -123.844817) (xy 260.798637 -123.825064)
			(xy 260.740798 -123.797847) (xy 260.686827 -123.763596) (xy 260.637574 -123.722851) (xy 260.593817 -123.676254)
			(xy 260.556244 -123.624539) (xy 260.52545 -123.568524) (xy 260.501918 -123.509091) (xy 260.486021 -123.447177)
			(xy 260.47801 -123.383759) (xy 256.260882 -123.383759) (xy 256.258124 -123.390724) (xy 256.22733 -123.446739)
			(xy 256.189757 -123.498454) (xy 256.146 -123.545051) (xy 256.096747 -123.585796) (xy 256.042776 -123.620047)
			(xy 255.984937 -123.647264) (xy 255.924144 -123.667017) (xy 255.861354 -123.678995) (xy 255.797558 -123.683009)
			(xy 255.733762 -123.678995) (xy 255.670972 -123.667017) (xy 255.610179 -123.647264) (xy 255.55234 -123.620047)
			(xy 255.498369 -123.585796) (xy 255.449116 -123.545051) (xy 255.405359 -123.498454) (xy 255.367786 -123.446739)
			(xy 255.336992 -123.390724) (xy 255.31346 -123.331291) (xy 255.297563 -123.269377) (xy 255.289552 -123.205959)
			(xy 252.351056 -123.205959) (xy 252.358397 -123.25584) (xy 252.358906 -123.283726) (xy 252.358397 -123.311612)
			(xy 252.350277 -123.366788) (xy 252.334209 -123.420195) (xy 252.310537 -123.470692) (xy 252.279764 -123.517205)
			(xy 252.242547 -123.558742) (xy 252.199679 -123.594417) (xy 252.152073 -123.623471) (xy 252.100744 -123.645283)
			(xy 252.046787 -123.659389) (xy 251.99135 -123.665489) (xy 251.935616 -123.663452) (xy 251.880773 -123.653322)
			(xy 251.827989 -123.635315) (xy 251.778389 -123.609814) (xy 251.733031 -123.577363) (xy 251.692882 -123.538654)
			(xy 251.658796 -123.494511) (xy 251.6315 -123.445876) (xy 251.611577 -123.393785) (xy 251.599451 -123.339348)
			(xy 251.59538 -123.283726) (xy 251.490146 -123.283726) (xy 251.483745 -123.334401) (xy 251.467848 -123.396315)
			(xy 251.444316 -123.455748) (xy 251.413522 -123.511763) (xy 251.375949 -123.563478) (xy 251.332192 -123.610075)
			(xy 251.282939 -123.65082) (xy 251.228968 -123.685071) (xy 251.171129 -123.712288) (xy 251.110336 -123.732041)
			(xy 251.047546 -123.744019) (xy 250.98375 -123.748033) (xy 250.919954 -123.744019) (xy 250.857164 -123.732041)
			(xy 250.796371 -123.712288) (xy 250.738532 -123.685071) (xy 250.684561 -123.65082) (xy 250.635308 -123.610075)
			(xy 250.591551 -123.563478) (xy 250.553978 -123.511763) (xy 250.523184 -123.455748) (xy 250.499652 -123.396315)
			(xy 250.483755 -123.334401) (xy 250.475744 -123.270983) (xy 243.682155 -123.270983) (xy 243.720968 -123.278387)
			(xy 243.781761 -123.29814) (xy 243.8396 -123.325357) (xy 243.893571 -123.359608) (xy 243.942824 -123.400353)
			(xy 243.986581 -123.44695) (xy 244.024154 -123.498665) (xy 244.054948 -123.55468) (xy 244.07848 -123.614113)
			(xy 244.094377 -123.676027) (xy 244.102388 -123.739445) (xy 244.10289 -123.771406) (xy 244.102388 -123.803367)
			(xy 244.094377 -123.866785) (xy 244.07848 -123.928699) (xy 244.054948 -123.988132) (xy 244.024154 -124.044147)
			(xy 243.986581 -124.095862) (xy 243.968546 -124.115068) (xy 255.850388 -124.115068) (xy 255.854459 -124.059446)
			(xy 255.866585 -124.005009) (xy 255.886508 -123.952918) (xy 255.913804 -123.904283) (xy 255.94789 -123.86014)
			(xy 255.988039 -123.821431) (xy 256.033397 -123.78898) (xy 256.082997 -123.763479) (xy 256.135781 -123.745472)
			(xy 256.190624 -123.735342) (xy 256.246358 -123.733305) (xy 256.301795 -123.739405) (xy 256.355752 -123.753511)
			(xy 256.407081 -123.775323) (xy 256.454687 -123.804377) (xy 256.497555 -123.840052) (xy 256.534772 -123.881589)
			(xy 256.565545 -123.928102) (xy 256.589217 -123.978599) (xy 256.605285 -124.032006) (xy 256.613405 -124.087182)
			(xy 256.613914 -124.115068) (xy 256.613405 -124.142954) (xy 256.605285 -124.19813) (xy 256.589217 -124.251537)
			(xy 256.565545 -124.302034) (xy 256.534772 -124.348547) (xy 256.497555 -124.390084) (xy 256.454687 -124.425759)
			(xy 256.407081 -124.454813) (xy 256.355752 -124.476625) (xy 256.301795 -124.490731) (xy 256.246358 -124.496831)
			(xy 256.190624 -124.494794) (xy 256.135781 -124.484664) (xy 256.082997 -124.466657) (xy 256.033397 -124.441156)
			(xy 255.988039 -124.408705) (xy 255.94789 -124.369996) (xy 255.913804 -124.325853) (xy 255.886508 -124.277218)
			(xy 255.866585 -124.225127) (xy 255.854459 -124.17069) (xy 255.850388 -124.115068) (xy 243.968546 -124.115068)
			(xy 243.942824 -124.142459) (xy 243.893571 -124.183204) (xy 243.8396 -124.217455) (xy 243.781761 -124.244672)
			(xy 243.720968 -124.264425) (xy 243.658178 -124.276403) (xy 243.594382 -124.280417) (xy 243.530586 -124.276403)
			(xy 243.467796 -124.264425) (xy 243.407003 -124.244672) (xy 243.349164 -124.217455) (xy 243.295193 -124.183204)
			(xy 243.24594 -124.142459) (xy 243.202183 -124.095862) (xy 243.16461 -124.044147) (xy 243.133816 -123.988132)
			(xy 243.110284 -123.928699) (xy 243.094387 -123.866785) (xy 243.086376 -123.803367) (xy 232.510859 -123.803367)
			(xy 232.492614 -123.849448) (xy 232.46182 -123.905463) (xy 232.424247 -123.957178) (xy 232.38049 -124.003775)
			(xy 232.331237 -124.04452) (xy 232.277266 -124.078771) (xy 232.219427 -124.105988) (xy 232.158634 -124.125741)
			(xy 232.095844 -124.137719) (xy 232.032048 -124.141733) (xy 231.968252 -124.137719) (xy 231.905462 -124.125741)
			(xy 231.844669 -124.105988) (xy 231.78683 -124.078771) (xy 231.732859 -124.04452) (xy 231.683606 -124.003775)
			(xy 231.639849 -123.957178) (xy 231.602276 -123.905463) (xy 231.571482 -123.849448) (xy 231.54795 -123.790015)
			(xy 231.532053 -123.728101) (xy 231.524042 -123.664683) (xy 218.750362 -123.664683) (xy 218.756338 -123.667495)
			(xy 218.810309 -123.701746) (xy 218.859562 -123.742491) (xy 218.903319 -123.789088) (xy 218.940892 -123.840803)
			(xy 218.971686 -123.896818) (xy 218.995218 -123.956251) (xy 219.011115 -124.018165) (xy 219.019126 -124.081583)
			(xy 219.019628 -124.113544) (xy 219.019181 -124.143281) (xy 219.012245 -124.20235) (xy 218.998462 -124.260206)
			(xy 218.97802 -124.316057) (xy 218.951197 -124.369141) (xy 218.918362 -124.41873) (xy 218.899486 -124.441712)
			(xy 218.893932 -124.448874) (xy 218.887822 -124.465926) (xy 218.887548 -124.474986) (xy 218.887548 -124.505212)
			(xy 218.887988 -124.514247) (xy 218.894352 -124.531164) (xy 218.899554 -124.537681) (xy 269.461736 -124.537681)
			(xy 269.461736 -124.473759) (xy 269.469747 -124.410341) (xy 269.485644 -124.348427) (xy 269.509176 -124.288994)
			(xy 269.53997 -124.232979) (xy 269.577543 -124.181264) (xy 269.6213 -124.134667) (xy 269.670553 -124.093922)
			(xy 269.724524 -124.059671) (xy 269.782363 -124.032454) (xy 269.843156 -124.012701) (xy 269.905946 -124.000723)
			(xy 269.969742 -123.99671) (xy 270.033538 -124.000723) (xy 270.096328 -124.012701) (xy 270.157121 -124.032454)
			(xy 270.21496 -124.059671) (xy 270.268931 -124.093922) (xy 270.318184 -124.134667) (xy 270.361941 -124.181264)
			(xy 270.362904 -124.182589) (xy 271.706334 -124.182589) (xy 271.706334 -124.118667) (xy 271.714345 -124.055249)
			(xy 271.730242 -123.993335) (xy 271.753774 -123.933902) (xy 271.784568 -123.877887) (xy 271.822141 -123.826172)
			(xy 271.865898 -123.779575) (xy 271.915151 -123.73883) (xy 271.969122 -123.704579) (xy 272.026961 -123.677362)
			(xy 272.087754 -123.657609) (xy 272.150544 -123.645631) (xy 272.21434 -123.641618) (xy 272.278136 -123.645631)
			(xy 272.340926 -123.657609) (xy 272.401719 -123.677362) (xy 272.459558 -123.704579) (xy 272.513529 -123.73883)
			(xy 272.562782 -123.779575) (xy 272.606539 -123.826172) (xy 272.644112 -123.877887) (xy 272.674906 -123.933902)
			(xy 272.698438 -123.993335) (xy 272.714335 -124.055249) (xy 272.722346 -124.118667) (xy 272.722848 -124.150628)
			(xy 272.722346 -124.182589) (xy 272.714335 -124.246007) (xy 272.699107 -124.305314) (xy 278.122124 -124.305314)
			(xy 278.126195 -124.249692) (xy 278.138321 -124.195255) (xy 278.158244 -124.143164) (xy 278.18554 -124.094529)
			(xy 278.219626 -124.050386) (xy 278.259775 -124.011677) (xy 278.305133 -123.979226) (xy 278.354733 -123.953725)
			(xy 278.407517 -123.935718) (xy 278.46236 -123.925588) (xy 278.518094 -123.923551) (xy 278.573531 -123.929651)
			(xy 278.627488 -123.943757) (xy 278.678817 -123.965569) (xy 278.726423 -123.994623) (xy 278.769291 -124.030298)
			(xy 278.806508 -124.071835) (xy 278.837281 -124.118348) (xy 278.860953 -124.168845) (xy 278.877021 -124.222252)
			(xy 278.885141 -124.277428) (xy 278.88565 -124.305314) (xy 278.885141 -124.3332) (xy 278.884567 -124.3371)
			(xy 293.817053 -124.3371) (xy 293.821067 -124.273303) (xy 293.833044 -124.210512) (xy 293.852797 -124.149717)
			(xy 293.880012 -124.091877) (xy 293.914262 -124.037904) (xy 293.955007 -123.988649) (xy 294.001603 -123.944889)
			(xy 294.053315 -123.907313) (xy 294.10933 -123.876514) (xy 294.168762 -123.852979) (xy 294.230676 -123.837077)
			(xy 294.294095 -123.829061) (xy 294.326056 -123.828556) (xy 294.362352 -123.829206) (xy 294.434203 -123.839558)
			(xy 294.503849 -123.860031) (xy 294.53713 -123.87453) (xy 294.54972 -123.879792) (xy 294.576649 -123.884137)
			(xy 294.603768 -123.881196) (xy 294.629138 -123.871177) (xy 294.65095 -123.854797) (xy 294.667645 -123.833226)
			(xy 294.67803 -123.808003) (xy 294.680132 -123.79452) (xy 294.684354 -123.764171) (xy 294.699247 -123.704731)
			(xy 294.721177 -123.647513) (xy 294.749826 -123.593345) (xy 294.784778 -123.543014) (xy 294.825527 -123.497249)
			(xy 294.871481 -123.456714) (xy 294.921974 -123.421997) (xy 294.976275 -123.393601) (xy 295.033595 -123.371938)
			(xy 295.093104 -123.357323) (xy 295.153937 -123.349966) (xy 295.184576 -123.349512) (xy 295.216541 -123.349952)
			(xy 295.279966 -123.357961) (xy 295.296358 -123.362169) (xy 348.452942 -123.362169) (xy 348.452942 -123.298247)
			(xy 348.460953 -123.234829) (xy 348.47685 -123.172915) (xy 348.500382 -123.113482) (xy 348.531176 -123.057467)
			(xy 348.568749 -123.005752) (xy 348.612506 -122.959155) (xy 348.661759 -122.91841) (xy 348.71573 -122.884159)
			(xy 348.773569 -122.856942) (xy 348.834362 -122.837189) (xy 348.897152 -122.825211) (xy 348.960948 -122.821198)
			(xy 349.024744 -122.825211) (xy 349.087534 -122.837189) (xy 349.148327 -122.856942) (xy 349.206166 -122.884159)
			(xy 349.260137 -122.91841) (xy 349.30939 -122.959155) (xy 349.353147 -123.005752) (xy 349.39072 -123.057467)
			(xy 349.421514 -123.113482) (xy 349.445046 -123.172915) (xy 349.460943 -123.234829) (xy 349.468954 -123.298247)
			(xy 349.469456 -123.330208) (xy 349.469028 -123.357454) (xy 349.595863 -123.357454) (xy 349.595863 -123.302946)
			(xy 349.603622 -123.248992) (xy 349.61898 -123.196691) (xy 349.641625 -123.147109) (xy 349.671097 -123.101254)
			(xy 349.706795 -123.060061) (xy 349.747993 -123.024368) (xy 349.793851 -122.994902) (xy 349.843436 -122.972263)
			(xy 349.895738 -122.956911) (xy 349.949693 -122.94916) (xy 349.976948 -122.9487) (xy 350.00579 -122.949224)
			(xy 350.062816 -122.957908) (xy 350.117886 -122.975072) (xy 350.169748 -123.000325) (xy 350.217222 -123.033092)
			(xy 350.259226 -123.072627) (xy 350.27743 -123.095004) (xy 350.28671 -123.105886) (xy 350.30991 -123.122577)
			(xy 350.336825 -123.13219) (xy 350.36535 -123.133974) (xy 350.393252 -123.127787) (xy 350.41835 -123.114115)
			(xy 350.43868 -123.094027) (xy 350.446086 -123.081796) (xy 350.463041 -123.052608) (xy 350.503456 -122.998542)
			(xy 350.550668 -122.950299) (xy 350.603848 -122.908726) (xy 350.662061 -122.874554) (xy 350.724283 -122.848385)
			(xy 350.78942 -122.830678) (xy 350.856327 -122.821744) (xy 350.890078 -122.821192) (xy 350.922041 -122.821672)
			(xy 350.985464 -122.829681) (xy 351.047383 -122.845577) (xy 351.106821 -122.869108) (xy 351.162841 -122.899903)
			(xy 351.169857 -122.905) (xy 383.51788 -122.905) (xy 383.521894 -122.841202) (xy 383.533873 -122.778409)
			(xy 383.553627 -122.717613) (xy 383.580846 -122.659773) (xy 383.615099 -122.6058) (xy 383.655847 -122.556546)
			(xy 383.702447 -122.512787) (xy 383.754163 -122.475214) (xy 383.810182 -122.44442) (xy 383.869618 -122.420889)
			(xy 383.931535 -122.404994) (xy 383.994956 -122.396984) (xy 384.026918 -122.396504) (xy 384.059041 -122.396986)
			(xy 384.122777 -122.405063) (xy 384.184987 -122.421109) (xy 384.244677 -122.44487) (xy 384.300896 -122.475965)
			(xy 384.352746 -122.5139) (xy 384.399401 -122.558069) (xy 384.440115 -122.607767) (xy 384.47424 -122.6622)
			(xy 384.488182 -122.691144) (xy 384.494714 -122.704256) (xy 384.514021 -122.726275) (xy 384.53878 -122.741913)
			(xy 384.566959 -122.749886) (xy 384.596241 -122.749539) (xy 384.624223 -122.740899) (xy 384.648604 -122.724677)
			(xy 384.658362 -122.71375) (xy 384.679074 -122.689751) (xy 384.725545 -122.646629) (xy 384.777017 -122.609621)
			(xy 384.832693 -122.579302) (xy 384.891706 -122.556143) (xy 384.953142 -122.540502) (xy 385.016046 -122.532623)
			(xy 385.047744 -122.53214) (xy 385.079706 -122.532548) (xy 385.143126 -122.540565) (xy 385.205041 -122.556467)
			(xy 385.264475 -122.580003) (xy 385.320491 -122.610802) (xy 385.372205 -122.648379) (xy 385.418803 -122.692141)
			(xy 385.459548 -122.741397) (xy 385.493799 -122.795371) (xy 385.521015 -122.853213) (xy 385.540768 -122.914009)
			(xy 385.552745 -122.976801) (xy 385.556759 -123.0406) (xy 385.556471 -123.045177) (xy 402.493728 -123.045177)
			(xy 402.493728 -122.981255) (xy 402.501739 -122.917837) (xy 402.517636 -122.855923) (xy 402.541168 -122.79649)
			(xy 402.571962 -122.740475) (xy 402.609535 -122.68876) (xy 402.653292 -122.642163) (xy 402.702545 -122.601418)
			(xy 402.756516 -122.567167) (xy 402.814355 -122.53995) (xy 402.875148 -122.520197) (xy 402.937938 -122.508219)
			(xy 403.001734 -122.504206) (xy 403.06553 -122.508219) (xy 403.12832 -122.520197) (xy 403.189113 -122.53995)
			(xy 403.246952 -122.567167) (xy 403.300923 -122.601418) (xy 403.350176 -122.642163) (xy 403.393933 -122.68876)
			(xy 403.431506 -122.740475) (xy 403.4623 -122.79649) (xy 403.485832 -122.855923) (xy 403.501729 -122.917837)
			(xy 403.50974 -122.981255) (xy 403.510242 -123.013216) (xy 403.50974 -123.045177) (xy 442.061086 -123.045177)
			(xy 442.061086 -122.981255) (xy 442.069097 -122.917837) (xy 442.084994 -122.855923) (xy 442.108526 -122.79649)
			(xy 442.13932 -122.740475) (xy 442.176893 -122.68876) (xy 442.22065 -122.642163) (xy 442.269903 -122.601418)
			(xy 442.323874 -122.567167) (xy 442.381713 -122.53995) (xy 442.442506 -122.520197) (xy 442.505296 -122.508219)
			(xy 442.569092 -122.504206) (xy 442.632888 -122.508219) (xy 442.695678 -122.520197) (xy 442.756471 -122.53995)
			(xy 442.81431 -122.567167) (xy 442.868281 -122.601418) (xy 442.917534 -122.642163) (xy 442.961291 -122.68876)
			(xy 442.998864 -122.740475) (xy 443.029658 -122.79649) (xy 443.05319 -122.855923) (xy 443.069087 -122.917837)
			(xy 443.077098 -122.981255) (xy 443.0776 -123.013216) (xy 443.077098 -123.045177) (xy 443.069087 -123.108595)
			(xy 443.05319 -123.170509) (xy 443.029658 -123.229942) (xy 442.998864 -123.285957) (xy 442.961291 -123.337672)
			(xy 442.917534 -123.384269) (xy 442.868281 -123.425014) (xy 442.81431 -123.459265) (xy 442.756471 -123.486482)
			(xy 442.695678 -123.506235) (xy 442.632888 -123.518213) (xy 442.569092 -123.522227) (xy 442.505296 -123.518213)
			(xy 442.442506 -123.506235) (xy 442.381713 -123.486482) (xy 442.323874 -123.459265) (xy 442.269903 -123.425014)
			(xy 442.22065 -123.384269) (xy 442.176893 -123.337672) (xy 442.13932 -123.285957) (xy 442.108526 -123.229942)
			(xy 442.084994 -123.170509) (xy 442.069097 -123.108595) (xy 442.061086 -123.045177) (xy 403.50974 -123.045177)
			(xy 403.501729 -123.108595) (xy 403.485832 -123.170509) (xy 403.4623 -123.229942) (xy 403.431506 -123.285957)
			(xy 403.393933 -123.337672) (xy 403.350176 -123.384269) (xy 403.300923 -123.425014) (xy 403.246952 -123.459265)
			(xy 403.189113 -123.486482) (xy 403.12832 -123.506235) (xy 403.06553 -123.518213) (xy 403.001734 -123.522227)
			(xy 402.937938 -123.518213) (xy 402.875148 -123.506235) (xy 402.814355 -123.486482) (xy 402.756516 -123.459265)
			(xy 402.702545 -123.425014) (xy 402.653292 -123.384269) (xy 402.609535 -123.337672) (xy 402.571962 -123.285957)
			(xy 402.541168 -123.229942) (xy 402.517636 -123.170509) (xy 402.501739 -123.108595) (xy 402.493728 -123.045177)
			(xy 385.556471 -123.045177) (xy 385.552745 -123.104399) (xy 385.540768 -123.167191) (xy 385.521015 -123.227987)
			(xy 385.493799 -123.285829) (xy 385.459548 -123.339803) (xy 385.418803 -123.389059) (xy 385.372205 -123.432821)
			(xy 385.320491 -123.470398) (xy 385.264475 -123.501197) (xy 385.205041 -123.524733) (xy 385.143126 -123.540635)
			(xy 385.079706 -123.548652) (xy 385.047744 -123.549156) (xy 385.015619 -123.548729) (xy 384.95188 -123.540647)
			(xy 384.889668 -123.524595) (xy 384.829976 -123.500828) (xy 384.773756 -123.469725) (xy 384.721906 -123.431783)
			(xy 384.675253 -123.387608) (xy 384.634541 -123.337903) (xy 384.60042 -123.283463) (xy 384.58648 -123.254516)
			(xy 384.579864 -123.241453) (xy 384.56057 -123.219447) (xy 384.535827 -123.203815) (xy 384.507668 -123.19584)
			(xy 384.478403 -123.196177) (xy 384.450435 -123.204798) (xy 384.426059 -123.220996) (xy 384.4163 -123.23191)
			(xy 384.395545 -123.25587) (xy 384.349083 -123.298996) (xy 384.297619 -123.336009) (xy 384.241951 -123.366333)
			(xy 384.182943 -123.389499) (xy 384.121513 -123.405147) (xy 384.058614 -123.413033) (xy 384.026918 -123.41352)
			(xy 383.994956 -123.413016) (xy 383.931535 -123.405006) (xy 383.869618 -123.389111) (xy 383.810182 -123.36558)
			(xy 383.754163 -123.334786) (xy 383.702447 -123.297213) (xy 383.655847 -123.253454) (xy 383.615099 -123.2042)
			(xy 383.580846 -123.150227) (xy 383.553627 -123.092387) (xy 383.533873 -123.031591) (xy 383.521894 -122.968798)
			(xy 383.51788 -122.905) (xy 351.169857 -122.905) (xy 351.214559 -122.937477) (xy 351.261161 -122.981236)
			(xy 351.30191 -123.030492) (xy 351.336164 -123.084466) (xy 351.363384 -123.142308) (xy 351.383138 -123.203106)
			(xy 351.395117 -123.2659) (xy 351.399132 -123.3297) (xy 351.395117 -123.3935) (xy 351.383138 -123.456294)
			(xy 351.363384 -123.517092) (xy 351.336164 -123.574934) (xy 351.30191 -123.628908) (xy 351.261161 -123.678164)
			(xy 351.214559 -123.721923) (xy 351.162841 -123.759497) (xy 351.106821 -123.790292) (xy 351.047383 -123.813823)
			(xy 350.985464 -123.829719) (xy 350.922041 -123.837728) (xy 350.890078 -123.838208) (xy 350.85636 -123.837678)
			(xy 350.789514 -123.828773) (xy 350.724432 -123.81111) (xy 350.662257 -123.784998) (xy 350.604079 -123.750895)
			(xy 350.55092 -123.709401) (xy 350.503713 -123.661243) (xy 350.463287 -123.607267) (xy 350.44634 -123.578112)
			(xy 350.438925 -123.565871) (xy 350.41858 -123.545761) (xy 350.393454 -123.532086) (xy 350.365521 -123.52592)
			(xy 350.336973 -123.527746) (xy 350.310053 -123.537422) (xy 350.286874 -123.554188) (xy 350.277684 -123.565158)
			(xy 350.25947 -123.587566) (xy 350.217445 -123.627168) (xy 350.169937 -123.659991) (xy 350.118029 -123.685288)
			(xy 350.062905 -123.702483) (xy 350.00582 -123.711183) (xy 349.976948 -123.711716) (xy 349.949693 -123.71124)
			(xy 349.895738 -123.703489) (xy 349.843436 -123.688137) (xy 349.793851 -123.665498) (xy 349.747993 -123.636032)
			(xy 349.706795 -123.600339) (xy 349.671097 -123.559146) (xy 349.641625 -123.513291) (xy 349.61898 -123.463709)
			(xy 349.603622 -123.411408) (xy 349.595863 -123.357454) (xy 349.469028 -123.357454) (xy 349.468954 -123.362169)
			(xy 349.460943 -123.425587) (xy 349.445046 -123.487501) (xy 349.421514 -123.546934) (xy 349.39072 -123.602949)
			(xy 349.353147 -123.654664) (xy 349.30939 -123.701261) (xy 349.260137 -123.742006) (xy 349.206166 -123.776257)
			(xy 349.148327 -123.803474) (xy 349.087534 -123.823227) (xy 349.024744 -123.835205) (xy 348.960948 -123.839219)
			(xy 348.897152 -123.835205) (xy 348.834362 -123.823227) (xy 348.773569 -123.803474) (xy 348.71573 -123.776257)
			(xy 348.661759 -123.742006) (xy 348.612506 -123.701261) (xy 348.568749 -123.654664) (xy 348.531176 -123.602949)
			(xy 348.500382 -123.546934) (xy 348.47685 -123.487501) (xy 348.460953 -123.425587) (xy 348.452942 -123.362169)
			(xy 295.296358 -123.362169) (xy 295.341887 -123.373857) (xy 295.401328 -123.397389) (xy 295.45735 -123.428185)
			(xy 295.509071 -123.465761) (xy 295.555675 -123.509522) (xy 295.596426 -123.558779) (xy 295.630682 -123.612756)
			(xy 295.657902 -123.6706) (xy 295.677658 -123.7314) (xy 295.689637 -123.794197) (xy 295.692884 -123.8458)
			(xy 371.701296 -123.8458) (xy 371.70531 -123.782003) (xy 371.717289 -123.719211) (xy 371.737043 -123.658417)
			(xy 371.764261 -123.600577) (xy 371.798515 -123.546606) (xy 371.839262 -123.497353) (xy 371.885862 -123.453595)
			(xy 371.937579 -123.416024) (xy 371.993596 -123.385231) (xy 372.053032 -123.361701) (xy 372.114948 -123.345807)
			(xy 372.178368 -123.337799) (xy 372.21033 -123.33732) (xy 372.24248 -123.337827) (xy 372.306268 -123.345919)
			(xy 372.368525 -123.361995) (xy 372.428257 -123.385797) (xy 372.484507 -123.416946) (xy 372.536378 -123.454944)
			(xy 372.58304 -123.499182) (xy 372.603776 -123.523756) (xy 372.61022 -123.531029) (xy 372.627214 -123.540423)
			(xy 372.636796 -123.542044) (xy 372.706646 -123.550426) (xy 372.716372 -123.551144) (xy 372.735179 -123.546037)
			(xy 372.743222 -123.54052) (xy 372.743476 -123.54052) (xy 372.76559 -123.524537) (xy 372.813473 -123.49838)
			(xy 372.864593 -123.479306) (xy 372.917907 -123.467703) (xy 372.97233 -123.463809) (xy 373.026753 -123.467703)
			(xy 373.080067 -123.479306) (xy 373.131187 -123.49838) (xy 373.17907 -123.524537) (xy 373.201184 -123.54052)
			(xy 373.201438 -123.54052) (xy 373.209471 -123.546059) (xy 373.228285 -123.551162) (xy 373.238014 -123.550426)
			(xy 373.307864 -123.542044) (xy 373.317437 -123.540407) (xy 373.334409 -123.530995) (xy 373.340884 -123.523756)
			(xy 373.361637 -123.499199) (xy 373.408306 -123.454971) (xy 373.460177 -123.41698) (xy 373.516424 -123.385831)
			(xy 373.57615 -123.362022) (xy 373.6384 -123.345931) (xy 373.702182 -123.337817) (xy 373.73433 -123.33732)
			(xy 373.766292 -123.337768) (xy 373.82971 -123.345783) (xy 373.891624 -123.361683) (xy 373.951058 -123.385217)
			(xy 374.007073 -123.416015) (xy 374.058786 -123.45359) (xy 374.105383 -123.49735) (xy 374.146128 -123.546604)
			(xy 374.180378 -123.600577) (xy 374.207595 -123.658417) (xy 374.227347 -123.719212) (xy 374.239325 -123.782003)
			(xy 374.243339 -123.8458) (xy 374.241326 -123.877789) (xy 376.528324 -123.877789) (xy 376.528324 -123.813867)
			(xy 376.536335 -123.750449) (xy 376.552232 -123.688535) (xy 376.575764 -123.629102) (xy 376.606558 -123.573087)
			(xy 376.644131 -123.521372) (xy 376.687888 -123.474775) (xy 376.737141 -123.43403) (xy 376.791112 -123.399779)
			(xy 376.848951 -123.372562) (xy 376.909744 -123.352809) (xy 376.972534 -123.340831) (xy 377.03633 -123.336818)
			(xy 377.100126 -123.340831) (xy 377.162916 -123.352809) (xy 377.223709 -123.372562) (xy 377.281548 -123.399779)
			(xy 377.335519 -123.43403) (xy 377.384772 -123.474775) (xy 377.428529 -123.521372) (xy 377.466102 -123.573087)
			(xy 377.496896 -123.629102) (xy 377.520428 -123.688535) (xy 377.536325 -123.750449) (xy 377.544336 -123.813867)
			(xy 377.544838 -123.845828) (xy 377.544336 -123.877789) (xy 377.536325 -123.941207) (xy 377.520428 -124.003121)
			(xy 377.496896 -124.062554) (xy 377.480897 -124.091657) (xy 380.429002 -124.091657) (xy 380.429002 -124.027735)
			(xy 380.437013 -123.964317) (xy 380.45291 -123.902403) (xy 380.476442 -123.84297) (xy 380.507236 -123.786955)
			(xy 380.544809 -123.73524) (xy 380.588566 -123.688643) (xy 380.637819 -123.647898) (xy 380.69179 -123.613647)
			(xy 380.749629 -123.58643) (xy 380.810422 -123.566677) (xy 380.873212 -123.554699) (xy 380.937008 -123.550686)
			(xy 381.000804 -123.554699) (xy 381.063594 -123.566677) (xy 381.124387 -123.58643) (xy 381.182226 -123.613647)
			(xy 381.236197 -123.647898) (xy 381.271225 -123.676875) (xy 395.274286 -123.676875) (xy 395.274286 -123.612953)
			(xy 395.282297 -123.549535) (xy 395.298194 -123.487621) (xy 395.321726 -123.428188) (xy 395.35252 -123.372173)
			(xy 395.390093 -123.320458) (xy 395.43385 -123.273861) (xy 395.483103 -123.233116) (xy 395.537074 -123.198865)
			(xy 395.594913 -123.171648) (xy 395.655706 -123.151895) (xy 395.718496 -123.139917) (xy 395.782292 -123.135904)
			(xy 395.846088 -123.139917) (xy 395.908878 -123.151895) (xy 395.969671 -123.171648) (xy 396.02751 -123.198865)
			(xy 396.081481 -123.233116) (xy 396.130734 -123.273861) (xy 396.174491 -123.320458) (xy 396.212064 -123.372173)
			(xy 396.242858 -123.428188) (xy 396.26639 -123.487621) (xy 396.282287 -123.549535) (xy 396.290298 -123.612953)
			(xy 396.2908 -123.644914) (xy 396.290298 -123.676875) (xy 396.282287 -123.740293) (xy 396.26639 -123.802207)
			(xy 396.242858 -123.86164) (xy 396.212064 -123.917655) (xy 396.174491 -123.96937) (xy 396.130734 -124.015967)
			(xy 396.081481 -124.056712) (xy 396.02751 -124.090963) (xy 395.969671 -124.11818) (xy 395.908878 -124.137933)
			(xy 395.846088 -124.149911) (xy 395.782292 -124.153925) (xy 395.718496 -124.149911) (xy 395.655706 -124.137933)
			(xy 395.594913 -124.11818) (xy 395.537074 -124.090963) (xy 395.483103 -124.056712) (xy 395.43385 -124.015967)
			(xy 395.390093 -123.96937) (xy 395.35252 -123.917655) (xy 395.321726 -123.86164) (xy 395.298194 -123.802207)
			(xy 395.282297 -123.740293) (xy 395.274286 -123.676875) (xy 381.271225 -123.676875) (xy 381.28545 -123.688643)
			(xy 381.329207 -123.73524) (xy 381.36678 -123.786955) (xy 381.397574 -123.84297) (xy 381.421106 -123.902403)
			(xy 381.437003 -123.964317) (xy 381.445014 -124.027735) (xy 381.445516 -124.059696) (xy 381.445014 -124.091657)
			(xy 381.437003 -124.155075) (xy 381.421106 -124.216989) (xy 381.397574 -124.276422) (xy 381.36678 -124.332437)
			(xy 381.329207 -124.384152) (xy 381.28545 -124.430749) (xy 381.236197 -124.471494) (xy 381.182226 -124.505745)
			(xy 381.124387 -124.532962) (xy 381.063594 -124.552715) (xy 381.000804 -124.564693) (xy 380.937008 -124.568707)
			(xy 380.873212 -124.564693) (xy 380.810422 -124.552715) (xy 380.749629 -124.532962) (xy 380.69179 -124.505745)
			(xy 380.637819 -124.471494) (xy 380.588566 -124.430749) (xy 380.544809 -124.384152) (xy 380.507236 -124.332437)
			(xy 380.476442 -124.276422) (xy 380.45291 -124.216989) (xy 380.437013 -124.155075) (xy 380.429002 -124.091657)
			(xy 377.480897 -124.091657) (xy 377.466102 -124.118569) (xy 377.428529 -124.170284) (xy 377.384772 -124.216881)
			(xy 377.335519 -124.257626) (xy 377.281548 -124.291877) (xy 377.223709 -124.319094) (xy 377.162916 -124.338847)
			(xy 377.100126 -124.350825) (xy 377.03633 -124.354839) (xy 376.972534 -124.350825) (xy 376.909744 -124.338847)
			(xy 376.848951 -124.319094) (xy 376.791112 -124.291877) (xy 376.737141 -124.257626) (xy 376.687888 -124.216881)
			(xy 376.644131 -124.170284) (xy 376.606558 -124.118569) (xy 376.575764 -124.062554) (xy 376.552232 -124.003121)
			(xy 376.536335 -123.941207) (xy 376.528324 -123.877789) (xy 374.241326 -123.877789) (xy 374.239325 -123.909597)
			(xy 374.227347 -123.972388) (xy 374.207595 -124.033183) (xy 374.180378 -124.091023) (xy 374.146128 -124.144996)
			(xy 374.105383 -124.19425) (xy 374.058786 -124.23801) (xy 374.007073 -124.275585) (xy 373.951058 -124.306383)
			(xy 373.891624 -124.329917) (xy 373.82971 -124.345817) (xy 373.766292 -124.353832) (xy 373.73433 -124.354336)
			(xy 373.702179 -124.353873) (xy 373.638388 -124.345776) (xy 373.576129 -124.329694) (xy 373.516397 -124.305884)
			(xy 373.460147 -124.274728) (xy 373.408278 -124.236723) (xy 373.361618 -124.192477) (xy 373.340884 -124.1679)
			(xy 373.334426 -124.160642) (xy 373.317442 -124.151241) (xy 373.307864 -124.149612) (xy 373.238014 -124.14123)
			(xy 373.228288 -124.140533) (xy 373.209482 -124.145624) (xy 373.201438 -124.151136) (xy 373.201184 -124.151136)
			(xy 373.17907 -124.167119) (xy 373.131187 -124.193276) (xy 373.080067 -124.21235) (xy 373.026753 -124.223953)
			(xy 372.97233 -124.227847) (xy 372.917907 -124.223953) (xy 372.864593 -124.21235) (xy 372.813473 -124.193276)
			(xy 372.76559 -124.167119) (xy 372.743476 -124.151136) (xy 372.743222 -124.151136) (xy 372.735203 -124.145573)
			(xy 372.716378 -124.140486) (xy 372.706646 -124.14123) (xy 372.636796 -124.149612) (xy 372.627222 -124.151244)
			(xy 372.610252 -124.160661) (xy 372.603776 -124.1679) (xy 372.583034 -124.192468) (xy 372.536365 -124.236696)
			(xy 372.484492 -124.274687) (xy 372.428243 -124.305836) (xy 372.368515 -124.329643) (xy 372.306263 -124.345731)
			(xy 372.242479 -124.353841) (xy 372.21033 -124.354336) (xy 372.178368 -124.353801) (xy 372.114948 -124.345793)
			(xy 372.053032 -124.329899) (xy 371.993596 -124.306369) (xy 371.937579 -124.275576) (xy 371.885862 -124.238005)
			(xy 371.839262 -124.194247) (xy 371.798515 -124.144994) (xy 371.764261 -124.091023) (xy 371.737043 -124.033183)
			(xy 371.717289 -123.972389) (xy 371.70531 -123.909597) (xy 371.701296 -123.8458) (xy 295.692884 -123.8458)
			(xy 295.693652 -123.858) (xy 295.689637 -123.921803) (xy 295.677658 -123.9846) (xy 295.657902 -124.0454)
			(xy 295.630682 -124.103244) (xy 295.596426 -124.157221) (xy 295.555675 -124.206478) (xy 295.509071 -124.250239)
			(xy 295.45735 -124.287815) (xy 295.401328 -124.318611) (xy 295.341887 -124.342143) (xy 295.279966 -124.358039)
			(xy 295.216541 -124.366048) (xy 295.184576 -124.366528) (xy 295.148278 -124.365899) (xy 295.076423 -124.35555)
			(xy 295.006773 -124.33508) (xy 294.973502 -124.320554) (xy 294.960939 -124.315223) (xy 294.934 -124.310892)
			(xy 294.906875 -124.313846) (xy 294.881501 -124.323877) (xy 294.859687 -124.340267) (xy 294.84299 -124.361847)
			(xy 294.832603 -124.387077) (xy 294.8305 -124.400564) (xy 294.826234 -124.430906) (xy 294.811344 -124.490343)
			(xy 294.789418 -124.54756) (xy 294.760773 -124.601726) (xy 294.725825 -124.652057) (xy 294.68508 -124.697821)
			(xy 294.63913 -124.738357) (xy 294.588641 -124.773075) (xy 294.534344 -124.801472) (xy 294.477028 -124.823137)
			(xy 294.417524 -124.837756) (xy 294.356693 -124.845116) (xy 294.326056 -124.845572) (xy 294.294095 -124.845139)
			(xy 294.230676 -124.837123) (xy 294.168762 -124.821221) (xy 294.10933 -124.797686) (xy 294.053315 -124.766887)
			(xy 294.001603 -124.729311) (xy 293.955007 -124.685551) (xy 293.914262 -124.636296) (xy 293.880012 -124.582323)
			(xy 293.852797 -124.524483) (xy 293.833044 -124.463688) (xy 293.821067 -124.400897) (xy 293.817053 -124.3371)
			(xy 278.884567 -124.3371) (xy 278.877021 -124.388376) (xy 278.860953 -124.441783) (xy 278.837281 -124.49228)
			(xy 278.806508 -124.538793) (xy 278.769291 -124.58033) (xy 278.726423 -124.616005) (xy 278.678817 -124.645059)
			(xy 278.627488 -124.666871) (xy 278.573531 -124.680977) (xy 278.518094 -124.687077) (xy 278.46236 -124.68504)
			(xy 278.407517 -124.67491) (xy 278.354733 -124.656903) (xy 278.305133 -124.631402) (xy 278.259775 -124.598951)
			(xy 278.219626 -124.560242) (xy 278.18554 -124.516099) (xy 278.158244 -124.467464) (xy 278.138321 -124.415373)
			(xy 278.126195 -124.360936) (xy 278.122124 -124.305314) (xy 272.699107 -124.305314) (xy 272.698438 -124.307921)
			(xy 272.674906 -124.367354) (xy 272.644112 -124.423369) (xy 272.606539 -124.475084) (xy 272.562782 -124.521681)
			(xy 272.513529 -124.562426) (xy 272.459558 -124.596677) (xy 272.401719 -124.623894) (xy 272.340926 -124.643647)
			(xy 272.278136 -124.655625) (xy 272.21434 -124.659639) (xy 272.150544 -124.655625) (xy 272.087754 -124.643647)
			(xy 272.026961 -124.623894) (xy 271.969122 -124.596677) (xy 271.915151 -124.562426) (xy 271.865898 -124.521681)
			(xy 271.822141 -124.475084) (xy 271.784568 -124.423369) (xy 271.753774 -124.367354) (xy 271.730242 -124.307921)
			(xy 271.714345 -124.246007) (xy 271.706334 -124.182589) (xy 270.362904 -124.182589) (xy 270.399514 -124.232979)
			(xy 270.430308 -124.288994) (xy 270.45384 -124.348427) (xy 270.469737 -124.410341) (xy 270.477748 -124.473759)
			(xy 270.47825 -124.50572) (xy 270.477748 -124.537681) (xy 270.469737 -124.601099) (xy 270.45384 -124.663013)
			(xy 270.430308 -124.722446) (xy 270.399514 -124.778461) (xy 270.361941 -124.830176) (xy 270.318184 -124.876773)
			(xy 270.268931 -124.917518) (xy 270.21496 -124.951769) (xy 270.157121 -124.978986) (xy 270.096328 -124.998739)
			(xy 270.033538 -125.010717) (xy 269.969742 -125.014731) (xy 269.905946 -125.010717) (xy 269.843156 -124.998739)
			(xy 269.782363 -124.978986) (xy 269.724524 -124.951769) (xy 269.670553 -124.917518) (xy 269.6213 -124.876773)
			(xy 269.577543 -124.830176) (xy 269.53997 -124.778461) (xy 269.509176 -124.722446) (xy 269.485644 -124.663013)
			(xy 269.469747 -124.601099) (xy 269.461736 -124.537681) (xy 218.899554 -124.537681) (xy 218.899994 -124.538232)
			(xy 218.918872 -124.560636) (xy 218.951937 -124.609) (xy 218.979232 -124.66084) (xy 219.000396 -124.715471)
			(xy 219.015148 -124.77217) (xy 219.019628 -124.801122) (xy 219.02166 -124.8156) (xy 219.039694 -124.837444)
			(xy 219.153232 -124.876052) (xy 219.180918 -124.869702) (xy 219.191332 -124.859542) (xy 219.215189 -124.836853)
			(xy 219.267708 -124.797149) (xy 219.324912 -124.764558) (xy 219.385846 -124.739625) (xy 219.449489 -124.722767)
			(xy 219.514775 -124.714267) (xy 219.547694 -124.713746) (xy 219.579654 -124.714319) (xy 219.643069 -124.722329)
			(xy 219.704981 -124.738225) (xy 219.764412 -124.761754) (xy 219.820425 -124.792547) (xy 219.872137 -124.830118)
			(xy 219.918732 -124.873873) (xy 219.959477 -124.923124) (xy 219.993726 -124.977093) (xy 220.020942 -125.034929)
			(xy 220.040695 -125.09572) (xy 220.052672 -125.158507) (xy 220.056686 -125.2223) (xy 220.052672 -125.286093)
			(xy 220.040695 -125.34888) (xy 220.020942 -125.409671) (xy 219.993726 -125.467507) (xy 219.959477 -125.521476)
			(xy 219.918732 -125.570727) (xy 219.872137 -125.614482) (xy 219.871918 -125.614641) (xy 251.026162 -125.614641)
			(xy 251.026162 -125.550719) (xy 251.034173 -125.487301) (xy 251.05007 -125.425387) (xy 251.073602 -125.365954)
			(xy 251.104396 -125.309939) (xy 251.141969 -125.258224) (xy 251.185726 -125.211627) (xy 251.234979 -125.170882)
			(xy 251.28895 -125.136631) (xy 251.346789 -125.109414) (xy 251.407582 -125.089661) (xy 251.470372 -125.077683)
			(xy 251.534168 -125.07367) (xy 251.597964 -125.077683) (xy 251.660754 -125.089661) (xy 251.721547 -125.109414)
			(xy 251.779386 -125.136631) (xy 251.833357 -125.170882) (xy 251.88261 -125.211627) (xy 251.926367 -125.258224)
			(xy 251.96394 -125.309939) (xy 251.994734 -125.365954) (xy 252.003609 -125.38837) (xy 255.850388 -125.38837)
			(xy 255.854459 -125.332748) (xy 255.866585 -125.278311) (xy 255.886508 -125.22622) (xy 255.913804 -125.177585)
			(xy 255.94789 -125.133442) (xy 255.988039 -125.094733) (xy 256.033397 -125.062282) (xy 256.082997 -125.036781)
			(xy 256.135781 -125.018774) (xy 256.190624 -125.008644) (xy 256.246358 -125.006607) (xy 256.301795 -125.012707)
			(xy 256.355752 -125.026813) (xy 256.407081 -125.048625) (xy 256.454687 -125.077679) (xy 256.486793 -125.104398)
			(xy 268.617952 -125.104398) (xy 268.622023 -125.048776) (xy 268.634149 -124.994339) (xy 268.654072 -124.942248)
			(xy 268.681368 -124.893613) (xy 268.715454 -124.84947) (xy 268.755603 -124.810761) (xy 268.800961 -124.77831)
			(xy 268.850561 -124.752809) (xy 268.903345 -124.734802) (xy 268.958188 -124.724672) (xy 269.013922 -124.722635)
			(xy 269.069359 -124.728735) (xy 269.123316 -124.742841) (xy 269.174645 -124.764653) (xy 269.222251 -124.793707)
			(xy 269.265119 -124.829382) (xy 269.302336 -124.870919) (xy 269.333109 -124.917432) (xy 269.356781 -124.967929)
			(xy 269.372849 -125.021336) (xy 269.376924 -125.049026) (xy 291.162484 -125.049026) (xy 291.166555 -124.993404)
			(xy 291.178681 -124.938967) (xy 291.198604 -124.886876) (xy 291.2259 -124.838241) (xy 291.259986 -124.794098)
			(xy 291.300135 -124.755389) (xy 291.345493 -124.722938) (xy 291.395093 -124.697437) (xy 291.447877 -124.67943)
			(xy 291.50272 -124.6693) (xy 291.558454 -124.667263) (xy 291.613891 -124.673363) (xy 291.667848 -124.687469)
			(xy 291.719177 -124.709281) (xy 291.766783 -124.738335) (xy 291.809651 -124.77401) (xy 291.846868 -124.815547)
			(xy 291.877641 -124.86206) (xy 291.901313 -124.912557) (xy 291.917381 -124.965964) (xy 291.925501 -125.02114)
			(xy 291.925898 -125.042887) (xy 373.874532 -125.042887) (xy 373.874532 -124.978965) (xy 373.882543 -124.915547)
			(xy 373.89844 -124.853633) (xy 373.921972 -124.7942) (xy 373.952766 -124.738185) (xy 373.990339 -124.68647)
			(xy 374.034096 -124.639873) (xy 374.083349 -124.599128) (xy 374.13732 -124.564877) (xy 374.195159 -124.53766)
			(xy 374.255952 -124.517907) (xy 374.318742 -124.505929) (xy 374.382538 -124.501916) (xy 374.446334 -124.505929)
			(xy 374.509124 -124.517907) (xy 374.569917 -124.53766) (xy 374.627756 -124.564877) (xy 374.681727 -124.599128)
			(xy 374.73098 -124.639873) (xy 374.774737 -124.68647) (xy 374.81231 -124.738185) (xy 374.843104 -124.7942)
			(xy 374.866636 -124.853633) (xy 374.882533 -124.915547) (xy 374.890544 -124.978965) (xy 374.891046 -125.010926)
			(xy 374.890544 -125.042887) (xy 374.882533 -125.106305) (xy 374.866636 -125.168219) (xy 374.843104 -125.227652)
			(xy 374.81231 -125.283667) (xy 374.774737 -125.335382) (xy 374.73098 -125.381979) (xy 374.681727 -125.422724)
			(xy 374.627756 -125.456975) (xy 374.569917 -125.484192) (xy 374.509124 -125.503945) (xy 374.446334 -125.515923)
			(xy 374.382538 -125.519937) (xy 374.318742 -125.515923) (xy 374.255952 -125.503945) (xy 374.195159 -125.484192)
			(xy 374.13732 -125.456975) (xy 374.083349 -125.422724) (xy 374.034096 -125.381979) (xy 373.990339 -125.335382)
			(xy 373.952766 -125.283667) (xy 373.921972 -125.227652) (xy 373.89844 -125.168219) (xy 373.882543 -125.106305)
			(xy 373.874532 -125.042887) (xy 291.925898 -125.042887) (xy 291.92601 -125.049026) (xy 291.925501 -125.076912)
			(xy 291.917381 -125.132088) (xy 291.901313 -125.185495) (xy 291.877641 -125.235992) (xy 291.846868 -125.282505)
			(xy 291.809651 -125.324042) (xy 291.766783 -125.359717) (xy 291.719177 -125.388771) (xy 291.667848 -125.410583)
			(xy 291.613891 -125.424689) (xy 291.558454 -125.430789) (xy 291.50272 -125.428752) (xy 291.447877 -125.418622)
			(xy 291.395093 -125.400615) (xy 291.345493 -125.375114) (xy 291.300135 -125.342663) (xy 291.259986 -125.303954)
			(xy 291.2259 -125.259811) (xy 291.198604 -125.211176) (xy 291.178681 -125.159085) (xy 291.166555 -125.104648)
			(xy 291.162484 -125.049026) (xy 269.376924 -125.049026) (xy 269.380969 -125.076512) (xy 269.381478 -125.104398)
			(xy 269.380969 -125.132284) (xy 269.372849 -125.18746) (xy 269.356781 -125.240867) (xy 269.333109 -125.291364)
			(xy 269.302336 -125.337877) (xy 269.265119 -125.379414) (xy 269.222251 -125.415089) (xy 269.174645 -125.444143)
			(xy 269.123316 -125.465955) (xy 269.069359 -125.480061) (xy 269.013922 -125.486161) (xy 268.958188 -125.484124)
			(xy 268.903345 -125.473994) (xy 268.850561 -125.455987) (xy 268.800961 -125.430486) (xy 268.755603 -125.398035)
			(xy 268.715454 -125.359326) (xy 268.681368 -125.315183) (xy 268.654072 -125.266548) (xy 268.634149 -125.214457)
			(xy 268.622023 -125.16002) (xy 268.617952 -125.104398) (xy 256.486793 -125.104398) (xy 256.497555 -125.113354)
			(xy 256.534772 -125.154891) (xy 256.565545 -125.201404) (xy 256.589217 -125.251901) (xy 256.605285 -125.305308)
			(xy 256.613405 -125.360484) (xy 256.613914 -125.38837) (xy 256.613405 -125.416256) (xy 256.605285 -125.471432)
			(xy 256.589217 -125.524839) (xy 256.565545 -125.575336) (xy 256.534772 -125.621849) (xy 256.497555 -125.663386)
			(xy 256.454687 -125.699061) (xy 256.407081 -125.728115) (xy 256.355752 -125.749927) (xy 256.301795 -125.764033)
			(xy 256.246358 -125.770133) (xy 256.190624 -125.768096) (xy 256.135781 -125.757966) (xy 256.082997 -125.739959)
			(xy 256.033397 -125.714458) (xy 255.988039 -125.682007) (xy 255.94789 -125.643298) (xy 255.913804 -125.599155)
			(xy 255.886508 -125.55052) (xy 255.866585 -125.498429) (xy 255.854459 -125.443992) (xy 255.850388 -125.38837)
			(xy 252.003609 -125.38837) (xy 252.018266 -125.425387) (xy 252.034163 -125.487301) (xy 252.042174 -125.550719)
			(xy 252.042676 -125.58268) (xy 252.042174 -125.614641) (xy 252.034163 -125.678059) (xy 252.018266 -125.739973)
			(xy 251.994734 -125.799406) (xy 251.96394 -125.855421) (xy 251.926367 -125.907136) (xy 251.88261 -125.953733)
			(xy 251.833357 -125.994478) (xy 251.779386 -126.028729) (xy 251.721547 -126.055946) (xy 251.660754 -126.075699)
			(xy 251.597964 -126.087677) (xy 251.534168 -126.091691) (xy 251.470372 -126.087677) (xy 251.407582 -126.075699)
			(xy 251.346789 -126.055946) (xy 251.28895 -126.028729) (xy 251.234979 -125.994478) (xy 251.185726 -125.953733)
			(xy 251.141969 -125.907136) (xy 251.104396 -125.855421) (xy 251.073602 -125.799406) (xy 251.05007 -125.739973)
			(xy 251.034173 -125.678059) (xy 251.026162 -125.614641) (xy 219.871918 -125.614641) (xy 219.820425 -125.652053)
			(xy 219.764412 -125.682846) (xy 219.704981 -125.706375) (xy 219.643069 -125.722271) (xy 219.579654 -125.730281)
			(xy 219.547694 -125.730762) (xy 219.514579 -125.730246) (xy 219.448908 -125.721659) (xy 219.384908 -125.704618)
			(xy 219.323662 -125.679412) (xy 219.266207 -125.646467) (xy 219.213516 -125.606341) (xy 219.166481 -125.559714)
			(xy 219.125898 -125.507374) (xy 219.092455 -125.450209) (xy 219.066716 -125.389185) (xy 219.049119 -125.325335)
			(xy 219.044012 -125.292612) (xy 219.04198 -125.278134) (xy 219.023946 -125.25629) (xy 218.910408 -125.217682)
			(xy 218.882722 -125.224032) (xy 218.872308 -125.234192) (xy 218.848467 -125.256898) (xy 218.795946 -125.296602)
			(xy 218.738738 -125.329192) (xy 218.677801 -125.354123) (xy 218.614155 -125.370977) (xy 218.548866 -125.379471)
			(xy 218.515946 -125.379988) (xy 218.485214 -125.379519) (xy 218.424198 -125.372115) (xy 218.364519 -125.35741)
			(xy 218.307048 -125.335618) (xy 218.252623 -125.307058) (xy 218.202038 -125.272144) (xy 218.156031 -125.231388)
			(xy 218.115272 -125.185382) (xy 218.080356 -125.134799) (xy 218.051792 -125.080376) (xy 218.029997 -125.022906)
			(xy 218.015289 -124.963228) (xy 218.007882 -124.902212) (xy 218.007438 -124.87148) (xy 218.007848 -124.841742)
			(xy 218.014792 -124.782671) (xy 218.028583 -124.724815) (xy 218.049033 -124.668964) (xy 218.075861 -124.615882)
			(xy 218.108701 -124.566293) (xy 218.12758 -124.543312) (xy 218.13312 -124.53614) (xy 218.139239 -124.519096)
			(xy 218.139518 -124.510038) (xy 218.139518 -124.479812) (xy 218.1391 -124.470775) (xy 218.13272 -124.453859)
			(xy 218.127072 -124.446792) (xy 218.10756 -124.423616) (xy 218.073588 -124.373453) (xy 218.045807 -124.319613)
			(xy 218.02461 -124.262857) (xy 218.010296 -124.203988) (xy 218.003068 -124.143836) (xy 218.002612 -124.113544)
			(xy 213.23808 -124.113544) (xy 213.23808 -125.643894) (xy 214.401908 -125.643894) (xy 214.402376 -125.612699)
			(xy 214.41001 -125.550777) (xy 214.425163 -125.490254) (xy 214.447607 -125.43204) (xy 214.477005 -125.377009)
			(xy 214.512915 -125.325989) (xy 214.554798 -125.279745) (xy 214.602023 -125.238973) (xy 214.653883 -125.204286)
			(xy 214.709596 -125.176204) (xy 214.768327 -125.15515) (xy 214.798656 -125.147832) (xy 214.810846 -125.14436)
			(xy 214.829904 -125.127698) (xy 214.834978 -125.116082) (xy 214.869268 -125.024642) (xy 214.865966 -124.999496)
			(xy 214.858346 -124.989082) (xy 214.839898 -124.962931) (xy 214.809055 -124.906854) (xy 214.785487 -124.847352)
			(xy 214.769566 -124.785365) (xy 214.761544 -124.72187) (xy 214.761064 -124.68987) (xy 214.761566 -124.657909)
			(xy 214.769577 -124.594491) (xy 214.785474 -124.532577) (xy 214.809006 -124.473144) (xy 214.8398 -124.417129)
			(xy 214.877373 -124.365414) (xy 214.92113 -124.318817) (xy 214.970383 -124.278072) (xy 215.024354 -124.243821)
			(xy 215.082193 -124.216604) (xy 215.142986 -124.196851) (xy 215.205776 -124.184873) (xy 215.269572 -124.18086)
			(xy 215.333368 -124.184873) (xy 215.396158 -124.196851) (xy 215.456951 -124.216604) (xy 215.51479 -124.243821)
			(xy 215.568761 -124.278072) (xy 215.618014 -124.318817) (xy 215.661771 -124.365414) (xy 215.699344 -124.417129)
			(xy 215.730138 -124.473144) (xy 215.75367 -124.532577) (xy 215.769567 -124.594491) (xy 215.777578 -124.657909)
			(xy 215.77808 -124.68987) (xy 215.777681 -124.718676) (xy 215.771148 -124.775918) (xy 215.758184 -124.832053)
			(xy 215.738955 -124.886363) (xy 215.713709 -124.93815) (xy 215.698578 -124.962666) (xy 215.698578 -124.96292)
			(xy 215.693813 -124.97109) (xy 215.690159 -124.989636) (xy 215.693477 -125.008245) (xy 215.69807 -125.016514)
			(xy 215.745822 -125.094238) (xy 215.751124 -125.102084) (xy 215.766186 -125.113535) (xy 215.784366 -125.118775)
			(xy 215.793828 -125.118368) (xy 215.794082 -125.118368) (xy 215.806055 -125.117301) (xy 215.830068 -125.116159)
			(xy 215.842088 -125.116082) (xy 215.87405 -125.116582) (xy 215.937471 -125.124593) (xy 215.999387 -125.140489)
			(xy 216.058823 -125.16402) (xy 216.114841 -125.194815) (xy 216.166557 -125.232388) (xy 216.213157 -125.276147)
			(xy 216.253904 -125.325401) (xy 216.288157 -125.379374) (xy 216.315375 -125.437214) (xy 216.335129 -125.49801)
			(xy 216.347108 -125.560802) (xy 216.351122 -125.6246) (xy 216.347108 -125.688398) (xy 216.335129 -125.75119)
			(xy 216.315375 -125.811986) (xy 216.288157 -125.869826) (xy 216.253904 -125.923799) (xy 216.213157 -125.973053)
			(xy 216.166557 -126.016812) (xy 216.114841 -126.054385) (xy 216.058823 -126.08518) (xy 215.999387 -126.108711)
			(xy 215.937471 -126.124607) (xy 215.87405 -126.132618) (xy 215.842088 -126.133098) (xy 215.811265 -126.132655)
			(xy 215.750071 -126.125195) (xy 215.690227 -126.110397) (xy 215.632608 -126.088479) (xy 215.57806 -126.059761)
			(xy 215.527379 -126.024664) (xy 215.481309 -125.983702) (xy 215.46058 -125.960886) (xy 215.453214 -125.952504)
			(xy 215.43264 -125.94336) (xy 215.34374 -125.945138) (xy 215.33277 -125.94592) (xy 215.313013 -125.955521)
			(xy 215.30564 -125.96368) (xy 215.305386 -125.963934) (xy 215.284629 -125.988719) (xy 215.237897 -126.033392)
			(xy 215.185882 -126.071783) (xy 215.129422 -126.103274) (xy 215.069426 -126.127359) (xy 215.006863 -126.143648)
			(xy 214.94274 -126.151878) (xy 214.910416 -126.152402) (xy 214.879684 -126.151947) (xy 214.818668 -126.14454)
			(xy 214.75899 -126.129833) (xy 214.701519 -126.108038) (xy 214.647095 -126.079476) (xy 214.596511 -126.044561)
			(xy 214.550504 -126.003803) (xy 214.509745 -125.957797) (xy 214.47483 -125.907213) (xy 214.446266 -125.85279)
			(xy 214.42447 -125.79532) (xy 214.409761 -125.735642) (xy 214.402353 -125.674626) (xy 214.401908 -125.643894)
			(xy 213.23808 -125.643894) (xy 213.23808 -126.795741) (xy 215.227148 -126.795741) (xy 215.227148 -126.731819)
			(xy 215.235159 -126.668401) (xy 215.251056 -126.606487) (xy 215.274588 -126.547054) (xy 215.305382 -126.491039)
			(xy 215.342955 -126.439324) (xy 215.386712 -126.392727) (xy 215.435965 -126.351982) (xy 215.489936 -126.317731)
			(xy 215.547775 -126.290514) (xy 215.608568 -126.270761) (xy 215.671358 -126.258783) (xy 215.735154 -126.25477)
			(xy 215.79895 -126.258783) (xy 215.86174 -126.270761) (xy 215.922533 -126.290514) (xy 215.980372 -126.317731)
			(xy 216.034343 -126.351982) (xy 216.083596 -126.392727) (xy 216.127353 -126.439324) (xy 216.14677 -126.466049)
			(xy 218.061026 -126.466049) (xy 218.061026 -126.402127) (xy 218.069037 -126.338709) (xy 218.084934 -126.276795)
			(xy 218.108466 -126.217362) (xy 218.13926 -126.161347) (xy 218.176833 -126.109632) (xy 218.22059 -126.063035)
			(xy 218.269843 -126.02229) (xy 218.323814 -125.988039) (xy 218.381653 -125.960822) (xy 218.442446 -125.941069)
			(xy 218.505236 -125.929091) (xy 218.569032 -125.925078) (xy 218.632828 -125.929091) (xy 218.695618 -125.941069)
			(xy 218.756411 -125.960822) (xy 218.81425 -125.988039) (xy 218.868221 -126.02229) (xy 218.917474 -126.063035)
			(xy 218.961231 -126.109632) (xy 218.998804 -126.161347) (xy 219.012574 -126.186395) (xy 233.830108 -126.186395)
			(xy 233.830108 -126.122473) (xy 233.838119 -126.059055) (xy 233.854016 -125.997141) (xy 233.877548 -125.937708)
			(xy 233.908342 -125.881693) (xy 233.945915 -125.829978) (xy 233.989672 -125.783381) (xy 234.038925 -125.742636)
			(xy 234.092896 -125.708385) (xy 234.150735 -125.681168) (xy 234.211528 -125.661415) (xy 234.274318 -125.649437)
			(xy 234.338114 -125.645424) (xy 234.40191 -125.649437) (xy 234.4647 -125.661415) (xy 234.525493 -125.681168)
			(xy 234.583332 -125.708385) (xy 234.637303 -125.742636) (xy 234.686556 -125.783381) (xy 234.730313 -125.829978)
			(xy 234.767886 -125.881693) (xy 234.79868 -125.937708) (xy 234.822212 -125.997141) (xy 234.838109 -126.059055)
			(xy 234.84612 -126.122473) (xy 234.846622 -126.154434) (xy 234.84612 -126.186395) (xy 234.838109 -126.249813)
			(xy 234.822212 -126.311727) (xy 234.79868 -126.37116) (xy 234.767886 -126.427175) (xy 234.730313 -126.47889)
			(xy 234.686556 -126.525487) (xy 234.637303 -126.566232) (xy 234.583332 -126.600483) (xy 234.525493 -126.6277)
			(xy 234.4647 -126.647453) (xy 234.40191 -126.659431) (xy 234.338114 -126.663445) (xy 234.274318 -126.659431)
			(xy 234.211528 -126.647453) (xy 234.150735 -126.6277) (xy 234.092896 -126.600483) (xy 234.038925 -126.566232)
			(xy 233.989672 -126.525487) (xy 233.945915 -126.47889) (xy 233.908342 -126.427175) (xy 233.877548 -126.37116)
			(xy 233.854016 -126.311727) (xy 233.838119 -126.249813) (xy 233.830108 -126.186395) (xy 219.012574 -126.186395)
			(xy 219.029598 -126.217362) (xy 219.05313 -126.276795) (xy 219.069027 -126.338709) (xy 219.077038 -126.402127)
			(xy 219.07754 -126.434088) (xy 219.077038 -126.466049) (xy 219.069027 -126.529467) (xy 219.05313 -126.591381)
			(xy 219.029598 -126.650814) (xy 219.014716 -126.677885) (xy 249.124718 -126.677885) (xy 249.124718 -126.613963)
			(xy 249.132729 -126.550545) (xy 249.148626 -126.488631) (xy 249.172158 -126.429198) (xy 249.202952 -126.373183)
			(xy 249.240525 -126.321468) (xy 249.284282 -126.274871) (xy 249.333535 -126.234126) (xy 249.387506 -126.199875)
			(xy 249.445345 -126.172658) (xy 249.506138 -126.152905) (xy 249.568928 -126.140927) (xy 249.632724 -126.136914)
			(xy 249.69652 -126.140927) (xy 249.75931 -126.152905) (xy 249.820103 -126.172658) (xy 249.877942 -126.199875)
			(xy 249.931913 -126.234126) (xy 249.981166 -126.274871) (xy 250.024923 -126.321468) (xy 250.062496 -126.373183)
			(xy 250.09329 -126.429198) (xy 250.102754 -126.4531) (xy 397.780827 -126.4531) (xy 397.784841 -126.38931)
			(xy 397.796817 -126.326527) (xy 397.816568 -126.265739) (xy 397.843781 -126.207906) (xy 397.878028 -126.15394)
			(xy 397.918768 -126.104691) (xy 397.96536 -126.060937) (xy 398.017068 -126.023367) (xy 398.073077 -125.992574)
			(xy 398.132504 -125.969043) (xy 398.194411 -125.953146) (xy 398.257822 -125.945133) (xy 398.28978 -125.94463)
			(xy 398.3205 -125.945107) (xy 398.381494 -125.952504) (xy 398.441153 -125.967193) (xy 398.498608 -125.988961)
			(xy 398.553024 -126.017489) (xy 398.578578 -126.034546) (xy 398.587263 -126.039939) (xy 398.60728 -126.044)
			(xy 398.627297 -126.039939) (xy 398.635982 -126.034546) (xy 398.661536 -126.017488) (xy 398.715951 -125.988957)
			(xy 398.773406 -125.967186) (xy 398.833065 -125.952494) (xy 398.894059 -125.945094) (xy 398.955501 -125.945094)
			(xy 399.016495 -125.952494) (xy 399.076154 -125.967186) (xy 399.133609 -125.988957) (xy 399.188024 -126.017488)
			(xy 399.213578 -126.034546) (xy 399.222263 -126.039939) (xy 399.24228 -126.044) (xy 399.262297 -126.039939)
			(xy 399.270982 -126.034546) (xy 399.296536 -126.017488) (xy 399.350951 -125.988957) (xy 399.408406 -125.967186)
			(xy 399.468065 -125.952494) (xy 399.529059 -125.945094) (xy 399.590501 -125.945094) (xy 399.651495 -125.952494)
			(xy 399.711154 -125.967186) (xy 399.768609 -125.988957) (xy 399.823024 -126.017488) (xy 399.848578 -126.034546)
			(xy 399.857263 -126.039939) (xy 399.87728 -126.044) (xy 399.897297 -126.039939) (xy 399.905982 -126.034546)
			(xy 399.93154 -126.017494) (xy 399.985954 -125.988961) (xy 400.043408 -125.967189) (xy 400.103066 -125.952496)
			(xy 400.16406 -125.945094) (xy 400.19478 -125.94463) (xy 400.226746 -125.945034) (xy 400.290173 -125.953044)
			(xy 400.352096 -125.968941) (xy 400.411538 -125.992474) (xy 400.467562 -126.023272) (xy 400.519284 -126.060848)
			(xy 400.565889 -126.104611) (xy 400.606641 -126.15387) (xy 400.640898 -126.207848) (xy 400.668119 -126.265695)
			(xy 400.687875 -126.326496) (xy 400.699855 -126.389295) (xy 400.702735 -126.435061) (xy 400.94382 -126.435061)
			(xy 400.94382 -126.371139) (xy 400.951831 -126.307721) (xy 400.967728 -126.245807) (xy 400.99126 -126.186374)
			(xy 401.022054 -126.130359) (xy 401.059627 -126.078644) (xy 401.103384 -126.032047) (xy 401.152637 -125.991302)
			(xy 401.206608 -125.957051) (xy 401.264447 -125.929834) (xy 401.32524 -125.910081) (xy 401.38803 -125.898103)
			(xy 401.451826 -125.89409) (xy 401.515622 -125.898103) (xy 401.578412 -125.910081) (xy 401.639205 -125.929834)
			(xy 401.697044 -125.957051) (xy 401.751015 -125.991302) (xy 401.800268 -126.032047) (xy 401.844025 -126.078644)
			(xy 401.881598 -126.130359) (xy 401.912392 -126.186374) (xy 401.935924 -126.245807) (xy 401.951821 -126.307721)
			(xy 401.959832 -126.371139) (xy 401.960334 -126.4031) (xy 401.959832 -126.435061) (xy 401.951821 -126.498479)
			(xy 401.935924 -126.560393) (xy 401.912392 -126.619826) (xy 401.881598 -126.675841) (xy 401.844025 -126.727556)
			(xy 401.800268 -126.774153) (xy 401.751015 -126.814898) (xy 401.697044 -126.849149) (xy 401.639205 -126.876366)
			(xy 401.578412 -126.896119) (xy 401.515622 -126.908097) (xy 401.451826 -126.912111) (xy 401.38803 -126.908097)
			(xy 401.32524 -126.896119) (xy 401.264447 -126.876366) (xy 401.206608 -126.849149) (xy 401.152637 -126.814898)
			(xy 401.103384 -126.774153) (xy 401.059627 -126.727556) (xy 401.022054 -126.675841) (xy 400.99126 -126.619826)
			(xy 400.967728 -126.560393) (xy 400.951831 -126.498479) (xy 400.94382 -126.435061) (xy 400.702735 -126.435061)
			(xy 400.70387 -126.4531) (xy 400.699855 -126.516905) (xy 400.687875 -126.579704) (xy 400.668119 -126.640505)
			(xy 400.640898 -126.698352) (xy 400.606641 -126.75233) (xy 400.565889 -126.801589) (xy 400.519284 -126.845352)
			(xy 400.467562 -126.882928) (xy 400.411538 -126.913726) (xy 400.352096 -126.937259) (xy 400.290173 -126.953156)
			(xy 400.226746 -126.961166) (xy 400.19478 -126.961646) (xy 400.164059 -126.961194) (xy 400.103064 -126.953792)
			(xy 400.043405 -126.939097) (xy 399.98595 -126.917324) (xy 399.931535 -126.888789) (xy 399.905982 -126.87173)
			(xy 399.897297 -126.866337) (xy 399.87728 -126.862276) (xy 399.857263 -126.866337) (xy 399.848578 -126.87173)
			(xy 399.823024 -126.888788) (xy 399.768609 -126.917319) (xy 399.711154 -126.93909) (xy 399.651495 -126.953782)
			(xy 399.590501 -126.961182) (xy 399.529059 -126.961182) (xy 399.468065 -126.953782) (xy 399.408406 -126.93909)
			(xy 399.350951 -126.917319) (xy 399.296536 -126.888788) (xy 399.270982 -126.87173) (xy 399.262297 -126.866337)
			(xy 399.24228 -126.862276) (xy 399.222263 -126.866337) (xy 399.213578 -126.87173) (xy 399.188024 -126.888788)
			(xy 399.133609 -126.917319) (xy 399.076154 -126.93909) (xy 399.016495 -126.953782) (xy 398.955501 -126.961182)
			(xy 398.894059 -126.961182) (xy 398.833065 -126.953782) (xy 398.773406 -126.93909) (xy 398.715951 -126.917319)
			(xy 398.661536 -126.888788) (xy 398.635982 -126.87173) (xy 398.627297 -126.866337) (xy 398.60728 -126.862276)
			(xy 398.587263 -126.866337) (xy 398.578578 -126.87173) (xy 398.55303 -126.888797) (xy 398.498613 -126.917327)
			(xy 398.441157 -126.939096) (xy 398.381496 -126.953787) (xy 398.320501 -126.961185) (xy 398.28978 -126.961646)
			(xy 398.257822 -126.961067) (xy 398.194411 -126.953054) (xy 398.132504 -126.937157) (xy 398.073077 -126.913626)
			(xy 398.017068 -126.882833) (xy 397.96536 -126.845263) (xy 397.918768 -126.801509) (xy 397.878028 -126.75226)
			(xy 397.843781 -126.698294) (xy 397.816568 -126.640461) (xy 397.796817 -126.579673) (xy 397.784841 -126.51689)
			(xy 397.780827 -126.4531) (xy 250.102754 -126.4531) (xy 250.116822 -126.488631) (xy 250.132719 -126.550545)
			(xy 250.14073 -126.613963) (xy 250.141232 -126.645924) (xy 250.14073 -126.677885) (xy 250.132719 -126.741303)
			(xy 250.116822 -126.803217) (xy 250.09329 -126.86265) (xy 250.062496 -126.918665) (xy 250.024923 -126.97038)
			(xy 249.981166 -127.016977) (xy 249.952614 -127.040597) (xy 252.356614 -127.040597) (xy 252.356614 -126.976675)
			(xy 252.364625 -126.913257) (xy 252.380522 -126.851343) (xy 252.404054 -126.79191) (xy 252.434848 -126.735895)
			(xy 252.472421 -126.68418) (xy 252.516178 -126.637583) (xy 252.565431 -126.596838) (xy 252.619402 -126.562587)
			(xy 252.677241 -126.53537) (xy 252.738034 -126.515617) (xy 252.800824 -126.503639) (xy 252.86462 -126.499626)
			(xy 252.928416 -126.503639) (xy 252.991206 -126.515617) (xy 253.051999 -126.53537) (xy 253.109838 -126.562587)
			(xy 253.163809 -126.596838) (xy 253.213062 -126.637583) (xy 253.256819 -126.68418) (xy 253.294392 -126.735895)
			(xy 253.325186 -126.79191) (xy 253.348718 -126.851343) (xy 253.364615 -126.913257) (xy 253.372626 -126.976675)
			(xy 253.373128 -127.008636) (xy 253.372626 -127.040597) (xy 253.368327 -127.074633) (xy 259.71728 -127.074633)
			(xy 259.71728 -127.010711) (xy 259.725291 -126.947293) (xy 259.741188 -126.885379) (xy 259.76472 -126.825946)
			(xy 259.795514 -126.769931) (xy 259.833087 -126.718216) (xy 259.876844 -126.671619) (xy 259.926097 -126.630874)
			(xy 259.980068 -126.596623) (xy 260.037907 -126.569406) (xy 260.0987 -126.549653) (xy 260.16149 -126.537675)
			(xy 260.225286 -126.533662) (xy 260.289082 -126.537675) (xy 260.351872 -126.549653) (xy 260.412665 -126.569406)
			(xy 260.470504 -126.596623) (xy 260.524475 -126.630874) (xy 260.573728 -126.671619) (xy 260.617485 -126.718216)
			(xy 260.655058 -126.769931) (xy 260.685852 -126.825946) (xy 260.709384 -126.885379) (xy 260.725281 -126.947293)
			(xy 260.733292 -127.010711) (xy 260.733794 -127.042672) (xy 260.733292 -127.074633) (xy 260.73322 -127.0752)
			(xy 289.372752 -127.0752) (xy 289.376767 -127.011398) (xy 289.388746 -126.948602) (xy 289.408501 -126.887803)
			(xy 289.435721 -126.829959) (xy 289.469976 -126.775984) (xy 289.510726 -126.726727) (xy 289.557329 -126.682966)
			(xy 289.609048 -126.645391) (xy 289.66507 -126.614595) (xy 289.724509 -126.591063) (xy 289.78643 -126.575166)
			(xy 289.849854 -126.567156) (xy 289.881818 -126.566676) (xy 289.915395 -126.567237) (xy 289.981963 -126.576088)
			(xy 290.046787 -126.593621) (xy 290.108742 -126.619531) (xy 290.166748 -126.653366) (xy 290.219799 -126.69454)
			(xy 290.243768 -126.71806) (xy 290.25088 -126.725172) (xy 290.269422 -126.733046) (xy 290.36137 -126.733808)
			(xy 290.379912 -126.726188) (xy 290.387278 -126.718822) (xy 290.411132 -126.696043) (xy 290.463701 -126.656204)
			(xy 290.520981 -126.6235) (xy 290.58201 -126.59848) (xy 290.645763 -126.581565) (xy 290.711169 -126.573039)
			(xy 290.744148 -126.572518) (xy 290.744402 -126.572518) (xy 290.776365 -126.572968) (xy 290.839786 -126.58098)
			(xy 290.901702 -126.596878) (xy 290.961139 -126.620411) (xy 291.017156 -126.651207) (xy 291.068873 -126.688781)
			(xy 291.115472 -126.732541) (xy 291.15622 -126.781797) (xy 291.190472 -126.83577) (xy 291.21769 -126.893612)
			(xy 291.237444 -126.954408) (xy 291.249423 -127.017201) (xy 291.253437 -127.081) (xy 291.249423 -127.144799)
			(xy 291.237444 -127.207592) (xy 291.21769 -127.268388) (xy 291.190472 -127.32623) (xy 291.15622 -127.380203)
			(xy 291.115472 -127.429459) (xy 291.09869 -127.445219) (xy 291.855138 -127.445219) (xy 291.855138 -127.381297)
			(xy 291.863149 -127.317879) (xy 291.879046 -127.255965) (xy 291.902578 -127.196532) (xy 291.933372 -127.140517)
			(xy 291.970945 -127.088802) (xy 292.014702 -127.042205) (xy 292.063955 -127.00146) (xy 292.117926 -126.967209)
			(xy 292.175765 -126.939992) (xy 292.236558 -126.920239) (xy 292.299348 -126.908261) (xy 292.363144 -126.904248)
			(xy 292.42694 -126.908261) (xy 292.48973 -126.920239) (xy 292.550523 -126.939992) (xy 292.608362 -126.967209)
			(xy 292.662333 -127.00146) (xy 292.711586 -127.042205) (xy 292.755343 -127.088802) (xy 292.792916 -127.140517)
			(xy 292.82371 -127.196532) (xy 292.847242 -127.255965) (xy 292.863139 -127.317879) (xy 292.87115 -127.381297)
			(xy 292.871652 -127.413258) (xy 292.87115 -127.445219) (xy 292.863139 -127.508637) (xy 292.847242 -127.570551)
			(xy 292.82371 -127.629984) (xy 292.792916 -127.685999) (xy 292.755343 -127.737714) (xy 292.711586 -127.784311)
			(xy 292.662333 -127.825056) (xy 292.608362 -127.859307) (xy 292.550523 -127.886524) (xy 292.48973 -127.906277)
			(xy 292.42694 -127.918255) (xy 292.363144 -127.922269) (xy 292.299348 -127.918255) (xy 292.236558 -127.906277)
			(xy 292.175765 -127.886524) (xy 292.117926 -127.859307) (xy 292.063955 -127.825056) (xy 292.014702 -127.784311)
			(xy 291.970945 -127.737714) (xy 291.933372 -127.685999) (xy 291.902578 -127.629984) (xy 291.879046 -127.570551)
			(xy 291.863149 -127.508637) (xy 291.855138 -127.445219) (xy 291.09869 -127.445219) (xy 291.068873 -127.473219)
			(xy 291.017156 -127.510793) (xy 290.961139 -127.541589) (xy 290.901702 -127.565122) (xy 290.839786 -127.58102)
			(xy 290.776365 -127.589032) (xy 290.744402 -127.589534) (xy 290.710826 -127.588957) (xy 290.644259 -127.580109)
			(xy 290.579434 -127.562579) (xy 290.51748 -127.536672) (xy 290.459473 -127.502839) (xy 290.406422 -127.461668)
			(xy 290.382452 -127.43815) (xy 290.37534 -127.431038) (xy 290.356798 -127.423164) (xy 290.26485 -127.422402)
			(xy 290.246308 -127.430022) (xy 290.238942 -127.437388) (xy 290.21508 -127.460159) (xy 290.162514 -127.499998)
			(xy 290.105235 -127.532703) (xy 290.044207 -127.557724) (xy 289.980455 -127.574641) (xy 289.915051 -127.583169)
			(xy 289.882072 -127.583692) (xy 289.881818 -127.583692) (xy 289.849854 -127.583244) (xy 289.78643 -127.575234)
			(xy 289.724509 -127.559337) (xy 289.66507 -127.535805) (xy 289.609048 -127.505009) (xy 289.557329 -127.467434)
			(xy 289.510726 -127.423673) (xy 289.469976 -127.374416) (xy 289.435721 -127.320441) (xy 289.408501 -127.262597)
			(xy 289.388746 -127.201798) (xy 289.376767 -127.139002) (xy 289.372752 -127.0752) (xy 260.73322 -127.0752)
			(xy 260.725281 -127.138051) (xy 260.709384 -127.199965) (xy 260.685852 -127.259398) (xy 260.655058 -127.315413)
			(xy 260.617485 -127.367128) (xy 260.573728 -127.413725) (xy 260.524475 -127.45447) (xy 260.470504 -127.488721)
			(xy 260.412665 -127.515938) (xy 260.351872 -127.535691) (xy 260.289082 -127.547669) (xy 260.225286 -127.551683)
			(xy 260.16149 -127.547669) (xy 260.0987 -127.535691) (xy 260.037907 -127.515938) (xy 259.980068 -127.488721)
			(xy 259.926097 -127.45447) (xy 259.876844 -127.413725) (xy 259.833087 -127.367128) (xy 259.795514 -127.315413)
			(xy 259.76472 -127.259398) (xy 259.741188 -127.199965) (xy 259.725291 -127.138051) (xy 259.71728 -127.074633)
			(xy 253.368327 -127.074633) (xy 253.364615 -127.104015) (xy 253.348718 -127.165929) (xy 253.325186 -127.225362)
			(xy 253.294392 -127.281377) (xy 253.256819 -127.333092) (xy 253.213062 -127.379689) (xy 253.163809 -127.420434)
			(xy 253.109838 -127.454685) (xy 253.051999 -127.481902) (xy 252.991206 -127.501655) (xy 252.928416 -127.513633)
			(xy 252.86462 -127.517647) (xy 252.800824 -127.513633) (xy 252.738034 -127.501655) (xy 252.677241 -127.481902)
			(xy 252.619402 -127.454685) (xy 252.565431 -127.420434) (xy 252.516178 -127.379689) (xy 252.472421 -127.333092)
			(xy 252.434848 -127.281377) (xy 252.404054 -127.225362) (xy 252.380522 -127.165929) (xy 252.364625 -127.104015)
			(xy 252.356614 -127.040597) (xy 249.952614 -127.040597) (xy 249.931913 -127.057722) (xy 249.877942 -127.091973)
			(xy 249.820103 -127.11919) (xy 249.75931 -127.138943) (xy 249.69652 -127.150921) (xy 249.632724 -127.154935)
			(xy 249.568928 -127.150921) (xy 249.506138 -127.138943) (xy 249.445345 -127.11919) (xy 249.387506 -127.091973)
			(xy 249.333535 -127.057722) (xy 249.284282 -127.016977) (xy 249.240525 -126.97038) (xy 249.202952 -126.918665)
			(xy 249.172158 -126.86265) (xy 249.148626 -126.803217) (xy 249.132729 -126.741303) (xy 249.124718 -126.677885)
			(xy 219.014716 -126.677885) (xy 218.998804 -126.706829) (xy 218.961231 -126.758544) (xy 218.917474 -126.805141)
			(xy 218.868221 -126.845886) (xy 218.81425 -126.880137) (xy 218.756411 -126.907354) (xy 218.695618 -126.927107)
			(xy 218.632828 -126.939085) (xy 218.569032 -126.943099) (xy 218.505236 -126.939085) (xy 218.442446 -126.927107)
			(xy 218.381653 -126.907354) (xy 218.323814 -126.880137) (xy 218.269843 -126.845886) (xy 218.22059 -126.805141)
			(xy 218.176833 -126.758544) (xy 218.13926 -126.706829) (xy 218.108466 -126.650814) (xy 218.084934 -126.591381)
			(xy 218.069037 -126.529467) (xy 218.061026 -126.466049) (xy 216.14677 -126.466049) (xy 216.164926 -126.491039)
			(xy 216.19572 -126.547054) (xy 216.219252 -126.606487) (xy 216.235149 -126.668401) (xy 216.24316 -126.731819)
			(xy 216.243662 -126.76378) (xy 216.24316 -126.795741) (xy 216.235149 -126.859159) (xy 216.219252 -126.921073)
			(xy 216.19572 -126.980506) (xy 216.164926 -127.036521) (xy 216.127353 -127.088236) (xy 216.083596 -127.134833)
			(xy 216.034343 -127.175578) (xy 215.980372 -127.209829) (xy 215.922533 -127.237046) (xy 215.86174 -127.256799)
			(xy 215.79895 -127.268777) (xy 215.735154 -127.272791) (xy 215.671358 -127.268777) (xy 215.608568 -127.256799)
			(xy 215.547775 -127.237046) (xy 215.489936 -127.209829) (xy 215.435965 -127.175578) (xy 215.386712 -127.134833)
			(xy 215.342955 -127.088236) (xy 215.305382 -127.036521) (xy 215.274588 -126.980506) (xy 215.251056 -126.921073)
			(xy 215.235159 -126.859159) (xy 215.227148 -126.795741) (xy 213.23808 -126.795741) (xy 213.23808 -127.900938)
			(xy 213.238539 -127.911628) (xy 213.247219 -127.931167) (xy 213.2631 -127.945481) (xy 213.273132 -127.949198)
			(xy 213.364826 -127.979424) (xy 213.36635 -127.979932) (xy 213.379812 -127.981964) (xy 213.385446 -127.981901)
			(xy 213.396473 -127.9796) (xy 213.401656 -127.977392) (xy 213.416388 -127.965454) (xy 213.425024 -127.956564)
			(xy 213.445688 -127.930083) (xy 213.492859 -127.882263) (xy 213.545916 -127.841071) (xy 213.603934 -127.807222)
			(xy 213.665903 -127.781307) (xy 213.730745 -127.763776) (xy 213.797331 -127.754934) (xy 213.830916 -127.75438)
			(xy 213.862877 -127.754883) (xy 213.926295 -127.762896) (xy 213.988209 -127.778795) (xy 214.047642 -127.802328)
			(xy 214.103657 -127.833124) (xy 214.15537 -127.870697) (xy 214.158856 -127.873971) (xy 214.908632 -127.873971)
			(xy 214.908632 -127.810049) (xy 214.916643 -127.746631) (xy 214.93254 -127.684717) (xy 214.956072 -127.625284)
			(xy 214.986866 -127.569269) (xy 215.024439 -127.517554) (xy 215.068196 -127.470957) (xy 215.117449 -127.430212)
			(xy 215.17142 -127.395961) (xy 215.229259 -127.368744) (xy 215.290052 -127.348991) (xy 215.352842 -127.337013)
			(xy 215.416638 -127.333) (xy 215.480434 -127.337013) (xy 215.543224 -127.348991) (xy 215.604017 -127.368744)
			(xy 215.661856 -127.395961) (xy 215.715827 -127.430212) (xy 215.76508 -127.470957) (xy 215.808837 -127.517554)
			(xy 215.84641 -127.569269) (xy 215.877204 -127.625284) (xy 215.900736 -127.684717) (xy 215.916633 -127.746631)
			(xy 215.924644 -127.810049) (xy 215.925006 -127.833077) (xy 218.018608 -127.833077) (xy 218.018608 -127.769155)
			(xy 218.026619 -127.705737) (xy 218.042516 -127.643823) (xy 218.066048 -127.58439) (xy 218.096842 -127.528375)
			(xy 218.134415 -127.47666) (xy 218.178172 -127.430063) (xy 218.227425 -127.389318) (xy 218.281396 -127.355067)
			(xy 218.339235 -127.32785) (xy 218.400028 -127.308097) (xy 218.462818 -127.296119) (xy 218.526614 -127.292106)
			(xy 218.59041 -127.296119) (xy 218.6532 -127.308097) (xy 218.713993 -127.32785) (xy 218.771832 -127.355067)
			(xy 218.825803 -127.389318) (xy 218.875056 -127.430063) (xy 218.918813 -127.47666) (xy 218.956386 -127.528375)
			(xy 218.98718 -127.58439) (xy 219.010712 -127.643823) (xy 219.026609 -127.705737) (xy 219.03462 -127.769155)
			(xy 219.035122 -127.801116) (xy 219.03462 -127.833077) (xy 219.026609 -127.896495) (xy 219.010712 -127.958409)
			(xy 218.98718 -128.017842) (xy 218.956386 -128.073857) (xy 218.918813 -128.125572) (xy 218.875056 -128.172169)
			(xy 218.825803 -128.212914) (xy 218.771832 -128.247165) (xy 218.713993 -128.274382) (xy 218.6532 -128.294135)
			(xy 218.59041 -128.306113) (xy 218.526614 -128.310127) (xy 218.462818 -128.306113) (xy 218.400028 -128.294135)
			(xy 218.339235 -128.274382) (xy 218.281396 -128.247165) (xy 218.227425 -128.212914) (xy 218.178172 -128.172169)
			(xy 218.134415 -128.125572) (xy 218.096842 -128.073857) (xy 218.066048 -128.017842) (xy 218.042516 -127.958409)
			(xy 218.026619 -127.896495) (xy 218.018608 -127.833077) (xy 215.925006 -127.833077) (xy 215.925146 -127.84201)
			(xy 215.924644 -127.873971) (xy 215.916633 -127.937389) (xy 215.900736 -127.999303) (xy 215.877204 -128.058736)
			(xy 215.84641 -128.114751) (xy 215.808837 -128.166466) (xy 215.76508 -128.213063) (xy 215.715827 -128.253808)
			(xy 215.661856 -128.288059) (xy 215.604017 -128.315276) (xy 215.543224 -128.335029) (xy 215.480434 -128.347007)
			(xy 215.416638 -128.351021) (xy 215.352842 -128.347007) (xy 215.290052 -128.335029) (xy 215.229259 -128.315276)
			(xy 215.17142 -128.288059) (xy 215.117449 -128.253808) (xy 215.068196 -128.213063) (xy 215.024439 -128.166466)
			(xy 214.986866 -128.114751) (xy 214.956072 -128.058736) (xy 214.93254 -127.999303) (xy 214.916643 -127.937389)
			(xy 214.908632 -127.873971) (xy 214.158856 -127.873971) (xy 214.201967 -127.914456) (xy 214.242712 -127.963709)
			(xy 214.276962 -128.017681) (xy 214.304179 -128.07552) (xy 214.323931 -128.136314) (xy 214.335909 -128.199104)
			(xy 214.339923 -128.2629) (xy 214.335909 -128.326696) (xy 214.323931 -128.389486) (xy 214.304179 -128.45028)
			(xy 214.276962 -128.508119) (xy 214.242712 -128.562091) (xy 214.201967 -128.611344) (xy 214.15537 -128.655103)
			(xy 214.103657 -128.692676) (xy 214.047642 -128.723472) (xy 213.988209 -128.747005) (xy 213.926295 -128.762904)
			(xy 213.862877 -128.770917) (xy 213.830916 -128.771396) (xy 213.796902 -128.770853) (xy 213.72948 -128.761783)
			(xy 213.663871 -128.743804) (xy 213.601245 -128.717235) (xy 213.542721 -128.682552) (xy 213.489346 -128.640374)
			(xy 213.442071 -128.591456) (xy 213.421468 -128.564386) (xy 213.416446 -128.557993) (xy 213.40323 -128.54854)
			(xy 213.39556 -128.545844) (xy 213.388448 -128.543812) (xy 213.381082 -128.543812) (xy 213.377074 -128.543883)
			(xy 213.369163 -128.545165) (xy 213.365334 -128.546352) (xy 213.273132 -128.576578) (xy 213.263164 -128.58041)
			(xy 213.247318 -128.59469) (xy 213.238634 -128.614173) (xy 213.23808 -128.624838) (xy 213.23808 -128.8316)
			(xy 215.952083 -128.8316) (xy 215.956097 -128.767804) (xy 215.968075 -128.705015) (xy 215.987827 -128.644222)
			(xy 216.015043 -128.586383) (xy 216.049294 -128.532412) (xy 216.090038 -128.483159) (xy 216.136635 -128.439401)
			(xy 216.188348 -128.401828) (xy 216.244362 -128.371032) (xy 216.303795 -128.3475) (xy 216.365708 -128.331602)
			(xy 216.429125 -128.323589) (xy 216.461086 -128.323086) (xy 216.492973 -128.323556) (xy 216.556246 -128.331537)
			(xy 216.618026 -128.347361) (xy 216.677344 -128.370781) (xy 216.733271 -128.401431) (xy 216.784929 -128.438828)
			(xy 216.808558 -128.460246) (xy 216.815416 -128.46685) (xy 216.83345 -128.473962) (xy 216.912952 -128.473708)
			(xy 216.922414 -128.473289) (xy 216.940035 -128.466389) (xy 216.947242 -128.460246) (xy 216.947496 -128.459992)
			(xy 216.971122 -128.43835) (xy 217.022908 -128.400617) (xy 217.079024 -128.369689) (xy 217.13858 -128.346055)
			(xy 217.200633 -128.330089) (xy 217.264201 -128.322045) (xy 217.296238 -128.321562) (xy 217.328196 -128.322126)
			(xy 217.37966 -128.328631) (xy 228.940354 -128.328631) (xy 228.940354 -128.264709) (xy 228.948365 -128.201291)
			(xy 228.964262 -128.139377) (xy 228.987794 -128.079944) (xy 229.018588 -128.023929) (xy 229.056161 -127.972214)
			(xy 229.099918 -127.925617) (xy 229.149171 -127.884872) (xy 229.203142 -127.850621) (xy 229.260981 -127.823404)
			(xy 229.321774 -127.803651) (xy 229.384564 -127.791673) (xy 229.44836 -127.78766) (xy 229.512156 -127.791673)
			(xy 229.574946 -127.803651) (xy 229.635739 -127.823404) (xy 229.693578 -127.850621) (xy 229.716831 -127.865378)
			(xy 233.51871 -127.865378) (xy 233.519135 -127.834646) (xy 233.526547 -127.77363) (xy 233.541259 -127.713952)
			(xy 233.563057 -127.656483) (xy 233.591623 -127.60206) (xy 233.62654 -127.551477) (xy 233.667301 -127.505472)
			(xy 233.713309 -127.464716) (xy 233.763895 -127.429802) (xy 233.81832 -127.40124) (xy 233.875791 -127.379447)
			(xy 233.935469 -127.36474) (xy 233.996486 -127.357333) (xy 234.027218 -127.35687) (xy 234.027472 -127.35687)
			(xy 234.057679 -127.357327) (xy 234.11767 -127.364462) (xy 234.176392 -127.378661) (xy 234.233016 -127.399721)
			(xy 234.286744 -127.427346) (xy 234.336818 -127.461146) (xy 234.359958 -127.480568) (xy 234.367018 -127.486228)
			(xy 234.383938 -127.492606) (xy 234.392978 -127.493014) (xy 234.423458 -127.493014) (xy 234.432493 -127.492583)
			(xy 234.449409 -127.486212) (xy 234.456478 -127.480568) (xy 234.479617 -127.461146) (xy 234.529698 -127.427358)
			(xy 234.583428 -127.399737) (xy 234.640051 -127.378673) (xy 234.698769 -127.364462) (xy 234.758757 -127.357304)
			(xy 234.788964 -127.35687) (xy 234.789218 -127.35687) (xy 234.819949 -127.357339) (xy 234.880961 -127.364749)
			(xy 234.940636 -127.379459) (xy 234.998103 -127.401255) (xy 235.052524 -127.429818) (xy 235.103105 -127.464732)
			(xy 235.149109 -127.505488) (xy 235.189866 -127.551492) (xy 235.22478 -127.602073) (xy 235.253344 -127.656494)
			(xy 235.27514 -127.71396) (xy 235.28985 -127.773635) (xy 235.297261 -127.834647) (xy 235.297726 -127.865378)
			(xy 235.297202 -127.897294) (xy 235.289216 -127.960624) (xy 235.273366 -128.022456) (xy 235.249902 -128.081819)
			(xy 235.219193 -128.137778) (xy 235.181721 -128.189453) (xy 235.138077 -128.236033) (xy 235.137614 -128.236429)
			(xy 250.301754 -128.236429) (xy 250.301754 -128.172507) (xy 250.309765 -128.109089) (xy 250.325662 -128.047175)
			(xy 250.349194 -127.987742) (xy 250.379988 -127.931727) (xy 250.417561 -127.880012) (xy 250.461318 -127.833415)
			(xy 250.510571 -127.79267) (xy 250.564542 -127.758419) (xy 250.622381 -127.731202) (xy 250.683174 -127.711449)
			(xy 250.745964 -127.699471) (xy 250.80976 -127.695458) (xy 250.873556 -127.699471) (xy 250.936346 -127.711449)
			(xy 250.997139 -127.731202) (xy 251.054978 -127.758419) (xy 251.108949 -127.79267) (xy 251.158202 -127.833415)
			(xy 251.201959 -127.880012) (xy 251.239532 -127.931727) (xy 251.270326 -127.987742) (xy 251.293858 -128.047175)
			(xy 251.309755 -128.109089) (xy 251.317766 -128.172507) (xy 251.318268 -128.204468) (xy 251.317766 -128.236429)
			(xy 251.309755 -128.299847) (xy 251.293858 -128.361761) (xy 251.270326 -128.421194) (xy 251.239532 -128.477209)
			(xy 251.201959 -128.528924) (xy 251.158202 -128.575521) (xy 251.108949 -128.616266) (xy 251.054978 -128.650517)
			(xy 250.997139 -128.677734) (xy 250.936346 -128.697487) (xy 250.873556 -128.709465) (xy 250.80976 -128.713479)
			(xy 250.745964 -128.709465) (xy 250.683174 -128.697487) (xy 250.622381 -128.677734) (xy 250.564542 -128.650517)
			(xy 250.510571 -128.616266) (xy 250.461318 -128.575521) (xy 250.417561 -128.528924) (xy 250.379988 -128.477209)
			(xy 250.349194 -128.421194) (xy 250.325662 -128.361761) (xy 250.309765 -128.299847) (xy 250.301754 -128.236429)
			(xy 235.137614 -128.236429) (xy 235.11383 -128.256792) (xy 235.113576 -128.257046) (xy 235.105316 -128.26478)
			(xy 235.095968 -128.28536) (xy 235.095542 -128.29667) (xy 235.096558 -128.376172) (xy 235.097291 -128.387635)
			(xy 235.107591 -128.408137) (xy 235.11637 -128.415542) (xy 235.142265 -128.436235) (xy 235.188989 -128.483255)
			(xy 235.229202 -128.535951) (xy 235.262224 -128.593427) (xy 235.287492 -128.654709) (xy 235.304579 -128.718756)
			(xy 235.313194 -128.784481) (xy 235.313728 -128.817624) (xy 235.313267 -128.848355) (xy 235.305856 -128.909368)
			(xy 235.291145 -128.969043) (xy 235.269349 -129.02651) (xy 235.240785 -129.080931) (xy 235.20587 -129.131512)
			(xy 235.165113 -129.177516) (xy 235.119109 -129.218273) (xy 235.068527 -129.253187) (xy 235.014106 -129.28175)
			(xy 234.956639 -129.303546) (xy 234.896964 -129.318256) (xy 234.835951 -129.325667) (xy 234.80522 -129.326132)
			(xy 234.804966 -129.326132) (xy 234.774758 -129.325712) (xy 234.714765 -129.318569) (xy 234.656043 -129.304363)
			(xy 234.599419 -129.283296) (xy 234.545691 -129.255665) (xy 234.495619 -129.221858) (xy 234.47248 -129.202434)
			(xy 234.465409 -129.19679) (xy 234.448497 -129.190403) (xy 234.43946 -129.189988) (xy 234.40898 -129.189988)
			(xy 234.399947 -129.190437) (xy 234.38303 -129.196796) (xy 234.37596 -129.202434) (xy 234.352806 -129.221838)
			(xy 234.302729 -129.255629) (xy 234.249002 -129.283252) (xy 234.192382 -129.304319) (xy 234.133666 -129.318534)
			(xy 234.07368 -129.325696) (xy 234.043474 -129.326132) (xy 234.04322 -129.326132) (xy 234.01249 -129.325625)
			(xy 233.951479 -129.31822) (xy 233.891805 -129.303514) (xy 233.834339 -129.281722) (xy 233.779918 -129.253163)
			(xy 233.729336 -129.218252) (xy 233.683332 -129.177499) (xy 233.642575 -129.131498) (xy 233.60766 -129.08092)
			(xy 233.579096 -129.026502) (xy 233.557299 -128.969037) (xy 233.542588 -128.909364) (xy 233.535177 -128.848354)
			(xy 233.534712 -128.817624) (xy 233.535223 -128.785708) (xy 233.54321 -128.722377) (xy 233.559061 -128.660543)
			(xy 233.582527 -128.60118) (xy 233.613238 -128.545221) (xy 233.650712 -128.493546) (xy 233.69436 -128.446968)
			(xy 233.718608 -128.42621) (xy 233.718862 -128.425956) (xy 233.727111 -128.418211) (xy 233.736468 -128.39764)
			(xy 233.736896 -128.386332) (xy 233.73588 -128.30683) (xy 233.735167 -128.295363) (xy 233.724855 -128.274861)
			(xy 233.716068 -128.26746) (xy 233.69016 -128.246782) (xy 233.64344 -128.199758) (xy 233.603229 -128.147059)
			(xy 233.57021 -128.08958) (xy 233.544944 -128.028296) (xy 233.527858 -127.964248) (xy 233.519244 -127.898522)
			(xy 233.51871 -127.865378) (xy 229.716831 -127.865378) (xy 229.747549 -127.884872) (xy 229.796802 -127.925617)
			(xy 229.840559 -127.972214) (xy 229.878132 -128.023929) (xy 229.908926 -128.079944) (xy 229.932458 -128.139377)
			(xy 229.948355 -128.201291) (xy 229.956366 -128.264709) (xy 229.956868 -128.29667) (xy 229.956366 -128.328631)
			(xy 229.948355 -128.392049) (xy 229.932458 -128.453963) (xy 229.908926 -128.513396) (xy 229.878132 -128.569411)
			(xy 229.840559 -128.621126) (xy 229.796802 -128.667723) (xy 229.747549 -128.708468) (xy 229.693578 -128.742719)
			(xy 229.635739 -128.769936) (xy 229.574946 -128.789689) (xy 229.512156 -128.801667) (xy 229.44836 -128.805681)
			(xy 229.384564 -128.801667) (xy 229.321774 -128.789689) (xy 229.260981 -128.769936) (xy 229.203142 -128.742719)
			(xy 229.149171 -128.708468) (xy 229.099918 -128.667723) (xy 229.056161 -128.621126) (xy 229.018588 -128.569411)
			(xy 228.987794 -128.513396) (xy 228.964262 -128.453963) (xy 228.948365 -128.392049) (xy 228.940354 -128.328631)
			(xy 217.37966 -128.328631) (xy 217.391606 -128.330141) (xy 217.453513 -128.34604) (xy 217.512938 -128.369572)
			(xy 217.568946 -128.400367) (xy 217.620653 -128.437937) (xy 217.667243 -128.481692) (xy 217.707983 -128.530941)
			(xy 217.742229 -128.584907) (xy 217.769441 -128.64274) (xy 217.789191 -128.703528) (xy 217.801167 -128.766311)
			(xy 217.805181 -128.8301) (xy 217.801573 -128.887431) (xy 218.690692 -128.887431) (xy 218.690692 -128.823509)
			(xy 218.698703 -128.760091) (xy 218.7146 -128.698177) (xy 218.738132 -128.638744) (xy 218.768926 -128.582729)
			(xy 218.806499 -128.531014) (xy 218.850256 -128.484417) (xy 218.899509 -128.443672) (xy 218.95348 -128.409421)
			(xy 219.011319 -128.382204) (xy 219.072112 -128.362451) (xy 219.134902 -128.350473) (xy 219.198698 -128.34646)
			(xy 219.262494 -128.350473) (xy 219.325284 -128.362451) (xy 219.386077 -128.382204) (xy 219.443916 -128.409421)
			(xy 219.497887 -128.443672) (xy 219.54714 -128.484417) (xy 219.590897 -128.531014) (xy 219.62847 -128.582729)
			(xy 219.659264 -128.638744) (xy 219.682796 -128.698177) (xy 219.698693 -128.760091) (xy 219.706704 -128.823509)
			(xy 219.707206 -128.85547) (xy 219.706704 -128.887431) (xy 219.698693 -128.950849) (xy 219.682796 -129.012763)
			(xy 219.659264 -129.072196) (xy 219.62847 -129.128211) (xy 219.590897 -129.179926) (xy 219.54714 -129.226523)
			(xy 219.497887 -129.267268) (xy 219.443916 -129.301519) (xy 219.386077 -129.328736) (xy 219.325284 -129.348489)
			(xy 219.262494 -129.360467) (xy 219.198698 -129.364481) (xy 219.134902 -129.360467) (xy 219.072112 -129.348489)
			(xy 219.011319 -129.328736) (xy 218.95348 -129.301519) (xy 218.899509 -129.267268) (xy 218.850256 -129.226523)
			(xy 218.806499 -129.179926) (xy 218.768926 -129.128211) (xy 218.738132 -129.072196) (xy 218.7146 -129.012763)
			(xy 218.698703 -128.950849) (xy 218.690692 -128.887431) (xy 217.801573 -128.887431) (xy 217.801167 -128.893889)
			(xy 217.789191 -128.956672) (xy 217.769441 -129.01746) (xy 217.742229 -129.075293) (xy 217.707983 -129.129259)
			(xy 217.667243 -129.178508) (xy 217.620653 -129.222263) (xy 217.568946 -129.259833) (xy 217.512938 -129.290628)
			(xy 217.453513 -129.31416) (xy 217.391606 -129.330059) (xy 217.328196 -129.338074) (xy 217.296238 -129.338578)
			(xy 217.264352 -129.338076) (xy 217.201081 -129.330099) (xy 217.139302 -129.31428) (xy 217.079984 -129.290866)
			(xy 217.024057 -129.260223) (xy 216.972396 -129.222832) (xy 216.948766 -129.201418) (xy 216.941908 -129.194814)
			(xy 216.923874 -129.187702) (xy 216.844372 -129.187956) (xy 216.834904 -129.188322) (xy 216.817283 -129.195258)
			(xy 216.810082 -129.201418) (xy 216.809828 -129.201672) (xy 216.786186 -129.223296) (xy 216.734404 -129.261032)
			(xy 216.678292 -129.291963) (xy 216.618739 -129.315601) (xy 216.556688 -129.33157) (xy 216.493122 -129.339617)
			(xy 216.461086 -129.340102) (xy 216.429125 -129.339611) (xy 216.365708 -129.331598) (xy 216.303795 -129.3157)
			(xy 216.244362 -129.292168) (xy 216.188348 -129.261372) (xy 216.136635 -129.223799) (xy 216.090038 -129.180041)
			(xy 216.049294 -129.130788) (xy 216.015043 -129.076817) (xy 215.987827 -129.018978) (xy 215.968075 -128.958185)
			(xy 215.956097 -128.895396) (xy 215.952083 -128.8316) (xy 213.23808 -128.8316) (xy 213.23808 -129.649177)
			(xy 255.068318 -129.649177) (xy 255.068318 -129.585255) (xy 255.076329 -129.521837) (xy 255.092226 -129.459923)
			(xy 255.115758 -129.40049) (xy 255.146552 -129.344475) (xy 255.184125 -129.29276) (xy 255.227882 -129.246163)
			(xy 255.277135 -129.205418) (xy 255.331106 -129.171167) (xy 255.388945 -129.14395) (xy 255.449738 -129.124197)
			(xy 255.512528 -129.112219) (xy 255.576324 -129.108206) (xy 255.64012 -129.112219) (xy 255.70291 -129.124197)
			(xy 255.763703 -129.14395) (xy 255.821542 -129.171167) (xy 255.875513 -129.205418) (xy 255.924766 -129.246163)
			(xy 255.968523 -129.29276) (xy 256.006096 -129.344475) (xy 256.03689 -129.40049) (xy 256.060422 -129.459923)
			(xy 256.076319 -129.521837) (xy 256.08433 -129.585255) (xy 256.084832 -129.617216) (xy 257.226306 -129.617216)
			(xy 257.230377 -129.561594) (xy 257.242503 -129.507157) (xy 257.262426 -129.455066) (xy 257.289722 -129.406431)
			(xy 257.323808 -129.362288) (xy 257.363957 -129.323579) (xy 257.409315 -129.291128) (xy 257.458915 -129.265627)
			(xy 257.511699 -129.24762) (xy 257.566542 -129.23749) (xy 257.622276 -129.235453) (xy 257.677713 -129.241553)
			(xy 257.73167 -129.255659) (xy 257.782999 -129.277471) (xy 257.830605 -129.306525) (xy 257.873473 -129.3422)
			(xy 257.91069 -129.383737) (xy 257.941463 -129.43025) (xy 257.965135 -129.480747) (xy 257.981203 -129.534154)
			(xy 257.989323 -129.58933) (xy 257.989832 -129.617216) (xy 257.989323 -129.645102) (xy 257.981203 -129.700278)
			(xy 257.965135 -129.753685) (xy 257.941463 -129.804182) (xy 257.91069 -129.850695) (xy 257.875045 -129.890477)
			(xy 259.726678 -129.890477) (xy 259.726678 -129.826555) (xy 259.734689 -129.763137) (xy 259.750586 -129.701223)
			(xy 259.774118 -129.64179) (xy 259.804912 -129.585775) (xy 259.842485 -129.53406) (xy 259.886242 -129.487463)
			(xy 259.935495 -129.446718) (xy 259.989466 -129.412467) (xy 260.047305 -129.38525) (xy 260.108098 -129.365497)
			(xy 260.170888 -129.353519) (xy 260.234684 -129.349506) (xy 260.29848 -129.353519) (xy 260.36127 -129.365497)
			(xy 260.422063 -129.38525) (xy 260.479902 -129.412467) (xy 260.533873 -129.446718) (xy 260.583126 -129.487463)
			(xy 260.626883 -129.53406) (xy 260.664456 -129.585775) (xy 260.69525 -129.64179) (xy 260.718782 -129.701223)
			(xy 260.734679 -129.763137) (xy 260.740101 -129.806058) (xy 263.070715 -129.806058) (xy 263.070715 -129.751542)
			(xy 263.078474 -129.697581) (xy 263.093834 -129.645274) (xy 263.116483 -129.595685) (xy 263.145958 -129.549825)
			(xy 263.181661 -129.508627) (xy 263.222864 -129.472929) (xy 263.268728 -129.44346) (xy 263.318319 -129.420817)
			(xy 263.370628 -129.405464) (xy 263.42459 -129.397712) (xy 263.451848 -129.397252) (xy 263.480765 -129.397788)
			(xy 263.537936 -129.40651) (xy 263.593135 -129.423764) (xy 263.645097 -129.449152) (xy 263.692632 -129.482093)
			(xy 263.734648 -129.521833) (xy 263.752838 -129.544318) (xy 263.762181 -129.555408) (xy 263.785684 -129.572362)
			(xy 263.813006 -129.582022) (xy 263.841942 -129.583608) (xy 263.870157 -129.576992) (xy 263.895372 -129.562708)
			(xy 263.915552 -129.54191) (xy 263.922764 -129.529332) (xy 263.937497 -129.502458) (xy 263.972467 -129.452126)
			(xy 264.01323 -129.406359) (xy 264.059197 -129.365821) (xy 264.109701 -129.3311) (xy 264.164011 -129.302698)
			(xy 264.221339 -129.281026) (xy 264.280857 -129.266399) (xy 264.3417 -129.259029) (xy 264.372344 -129.258568)
			(xy 264.404302 -129.259121) (xy 264.467713 -129.267136) (xy 264.529619 -129.283036) (xy 264.589045 -129.306569)
			(xy 264.645052 -129.337364) (xy 264.696759 -129.374935) (xy 264.74335 -129.41869) (xy 264.784089 -129.467939)
			(xy 264.818335 -129.521906) (xy 264.845548 -129.579739) (xy 264.865298 -129.640527) (xy 264.877273 -129.703311)
			(xy 264.881287 -129.7671) (xy 264.877273 -129.830889) (xy 264.865298 -129.893673) (xy 264.845548 -129.954461)
			(xy 264.818335 -130.012294) (xy 264.784089 -130.066261) (xy 264.74335 -130.11551) (xy 264.696759 -130.159265)
			(xy 264.645052 -130.196836) (xy 264.589045 -130.227631) (xy 264.537866 -130.247898) (xy 267.97381 -130.247898)
			(xy 267.974315 -130.219265) (xy 267.982875 -130.162643) (xy 267.999802 -130.107936) (xy 268.024715 -130.056373)
			(xy 268.057055 -130.009114) (xy 268.096095 -129.967219) (xy 268.140959 -129.931629) (xy 268.190638 -129.903145)
			(xy 268.217142 -129.892298) (xy 268.230726 -129.886504) (xy 268.254018 -129.868366) (xy 268.271157 -129.844329)
			(xy 268.280716 -129.816398) (xy 268.281897 -129.7869) (xy 268.274603 -129.758294) (xy 268.25944 -129.732964)
			(xy 268.248892 -129.722626) (xy 268.226948 -129.701957) (xy 268.187623 -129.656264) (xy 268.153974 -129.606243)
			(xy 268.126471 -129.552597) (xy 268.1055 -129.496077) (xy 268.091356 -129.437474) (xy 268.084235 -129.377611)
			(xy 268.083792 -129.347468) (xy 268.084294 -129.315507) (xy 268.092305 -129.252089) (xy 268.108202 -129.190175)
			(xy 268.131734 -129.130742) (xy 268.162528 -129.074727) (xy 268.200101 -129.023012) (xy 268.243858 -128.976415)
			(xy 268.293111 -128.93567) (xy 268.347082 -128.901419) (xy 268.404921 -128.874202) (xy 268.465714 -128.854449)
			(xy 268.528504 -128.842471) (xy 268.5923 -128.838458) (xy 268.656096 -128.842471) (xy 268.718886 -128.854449)
			(xy 268.779679 -128.874202) (xy 268.837518 -128.901419) (xy 268.891489 -128.93567) (xy 268.940742 -128.976415)
			(xy 268.984499 -129.023012) (xy 269.022072 -129.074727) (xy 269.052866 -129.130742) (xy 269.076398 -129.190175)
			(xy 269.092295 -129.252089) (xy 269.100306 -129.315507) (xy 269.100529 -129.3297) (xy 274.250356 -129.3297)
			(xy 274.254371 -129.265898) (xy 274.26635 -129.203103) (xy 274.286105 -129.142304) (xy 274.313325 -129.084461)
			(xy 274.34758 -129.030485) (xy 274.38833 -128.981229) (xy 274.434932 -128.937468) (xy 274.486652 -128.899893)
			(xy 274.542673 -128.869098) (xy 274.602112 -128.845566) (xy 274.664032 -128.82967) (xy 274.727456 -128.82166)
			(xy 274.75942 -128.82118) (xy 274.792264 -128.821662) (xy 274.857402 -128.830138) (xy 274.920905 -128.846934)
			(xy 274.981717 -128.87177) (xy 275.038823 -128.904231) (xy 275.091271 -128.943778) (xy 275.138189 -128.989751)
			(xy 275.178795 -129.041385) (xy 275.196046 -129.069338) (xy 275.20265 -129.08026) (xy 275.224494 -129.093468)
			(xy 275.32203 -129.09804) (xy 275.334655 -129.098026) (xy 275.357441 -129.087216) (xy 275.365464 -129.077466)
			(xy 275.365464 -129.077212) (xy 275.386095 -129.050084) (xy 275.433371 -129.000995) (xy 275.486783 -128.958662)
			(xy 275.545371 -128.923845) (xy 275.608086 -128.897168) (xy 275.673803 -128.87911) (xy 275.741344 -128.869993)
			(xy 275.77542 -128.86944) (xy 275.80757 -128.869947) (xy 275.871358 -128.878038) (xy 275.933616 -128.894113)
			(xy 275.993347 -128.917916) (xy 276.049598 -128.949065) (xy 276.101469 -128.987063) (xy 276.14813 -129.031302)
			(xy 276.168866 -129.055876) (xy 276.175311 -129.063148) (xy 276.192304 -129.072542) (xy 276.201886 -129.074164)
			(xy 276.271736 -129.082546) (xy 276.281462 -129.083274) (xy 276.300271 -129.078163) (xy 276.308312 -129.07264)
			(xy 276.308566 -129.07264) (xy 276.33068 -129.056657) (xy 276.378563 -129.0305) (xy 276.429683 -129.011426)
			(xy 276.482997 -128.999823) (xy 276.53742 -128.995929) (xy 276.591843 -128.999823) (xy 276.645157 -129.011426)
			(xy 276.696277 -129.0305) (xy 276.74416 -129.056657) (xy 276.766274 -129.07264) (xy 276.766528 -129.07264)
			(xy 276.774563 -129.078176) (xy 276.793375 -129.083281) (xy 276.803104 -129.082546) (xy 276.872954 -129.074164)
			(xy 276.882524 -129.072516) (xy 276.899497 -129.063111) (xy 276.905974 -129.055876) (xy 276.926738 -129.031328)
			(xy 276.973404 -128.987099) (xy 277.025273 -128.949107) (xy 277.081519 -128.917956) (xy 277.141242 -128.894145)
			(xy 277.203491 -128.878053) (xy 277.267272 -128.869938) (xy 277.29942 -128.86944) (xy 277.330708 -128.869919)
			(xy 277.392811 -128.877592) (xy 277.453501 -128.892834) (xy 277.511861 -128.915413) (xy 277.567007 -128.944987)
			(xy 277.618104 -128.981108) (xy 277.664379 -129.02323) (xy 277.705131 -129.070716) (xy 277.722838 -129.096516)
			(xy 277.730351 -129.106676) (xy 277.752632 -129.118529) (xy 277.765256 -129.119122) (xy 277.849584 -129.119122)
			(xy 277.862192 -129.118494) (xy 277.884441 -129.106626) (xy 277.892002 -129.096516) (xy 277.90968 -129.070697)
			(xy 277.950443 -129.023219) (xy 277.996726 -128.981104) (xy 278.047828 -128.944988) (xy 278.102976 -128.915418)
			(xy 278.161337 -128.89284) (xy 278.222029 -128.877597) (xy 278.284132 -128.869919) (xy 278.31542 -128.86944)
			(xy 278.347383 -128.869847) (xy 278.410805 -128.877861) (xy 278.472723 -128.893761) (xy 278.53216 -128.917296)
			(xy 278.588178 -128.948094) (xy 278.639895 -128.98567) (xy 278.686495 -129.029432) (xy 278.69972 -129.045419)
			(xy 446.37426 -129.045419) (xy 446.37426 -128.981497) (xy 446.382271 -128.918079) (xy 446.398168 -128.856165)
			(xy 446.4217 -128.796732) (xy 446.452494 -128.740717) (xy 446.490067 -128.689002) (xy 446.533824 -128.642405)
			(xy 446.583077 -128.60166) (xy 446.637048 -128.567409) (xy 446.694887 -128.540192) (xy 446.75568 -128.520439)
			(xy 446.81847 -128.508461) (xy 446.882266 -128.504448) (xy 446.946062 -128.508461) (xy 447.008852 -128.520439)
			(xy 447.069645 -128.540192) (xy 447.127484 -128.567409) (xy 447.181455 -128.60166) (xy 447.230708 -128.642405)
			(xy 447.274465 -128.689002) (xy 447.312038 -128.740717) (xy 447.342832 -128.796732) (xy 447.366364 -128.856165)
			(xy 447.382261 -128.918079) (xy 447.390272 -128.981497) (xy 447.390774 -129.013458) (xy 447.390272 -129.045419)
			(xy 447.382261 -129.108837) (xy 447.366364 -129.170751) (xy 447.342832 -129.230184) (xy 447.312038 -129.286199)
			(xy 447.274465 -129.337914) (xy 447.230708 -129.384511) (xy 447.181455 -129.425256) (xy 447.127484 -129.459507)
			(xy 447.069645 -129.486724) (xy 447.008852 -129.506477) (xy 446.946062 -129.518455) (xy 446.882266 -129.522469)
			(xy 446.81847 -129.518455) (xy 446.75568 -129.506477) (xy 446.694887 -129.486724) (xy 446.637048 -129.459507)
			(xy 446.583077 -129.425256) (xy 446.533824 -129.384511) (xy 446.490067 -129.337914) (xy 446.452494 -129.286199)
			(xy 446.4217 -129.230184) (xy 446.398168 -129.170751) (xy 446.382271 -129.108837) (xy 446.37426 -129.045419)
			(xy 278.69972 -129.045419) (xy 278.727242 -129.078689) (xy 278.761495 -129.132665) (xy 278.788713 -129.190507)
			(xy 278.808467 -129.251305) (xy 278.820445 -129.3141) (xy 278.824459 -129.3779) (xy 278.820445 -129.4417)
			(xy 278.808467 -129.504495) (xy 278.788713 -129.565293) (xy 278.761495 -129.623135) (xy 278.727242 -129.677111)
			(xy 278.686495 -129.726368) (xy 278.639895 -129.77013) (xy 278.588178 -129.807706) (xy 278.53216 -129.838504)
			(xy 278.472723 -129.862039) (xy 278.410805 -129.877939) (xy 278.347383 -129.885953) (xy 278.31542 -129.886456)
			(xy 278.284131 -129.886026) (xy 278.222026 -129.878344) (xy 278.161334 -129.863095) (xy 278.102974 -129.84051)
			(xy 278.047828 -129.810929) (xy 277.996732 -129.774802) (xy 277.950458 -129.732673) (xy 277.909708 -129.685182)
			(xy 277.892002 -129.65938) (xy 277.884449 -129.649256) (xy 277.862199 -129.637379) (xy 277.849584 -129.636774)
			(xy 277.765256 -129.636774) (xy 277.752651 -129.637427) (xy 277.730402 -129.649277) (xy 277.722838 -129.65938)
			(xy 277.705133 -129.68518) (xy 277.664374 -129.732658) (xy 277.618095 -129.774774) (xy 277.566997 -129.810892)
			(xy 277.511853 -129.840465) (xy 277.453495 -129.863045) (xy 277.392807 -129.878292) (xy 277.330707 -129.885975)
			(xy 277.29942 -129.886456) (xy 277.267269 -129.885993) (xy 277.203478 -129.877894) (xy 277.14122 -129.861812)
			(xy 277.081488 -129.838002) (xy 277.025238 -129.806847) (xy 276.973368 -129.768842) (xy 276.926709 -129.724597)
			(xy 276.905974 -129.70002) (xy 276.899516 -129.692762) (xy 276.882532 -129.68336) (xy 276.872954 -129.681732)
			(xy 276.803104 -129.67335) (xy 276.793378 -129.672644) (xy 276.774571 -129.67774) (xy 276.766528 -129.683256)
			(xy 276.766274 -129.683256) (xy 276.74416 -129.699239) (xy 276.696277 -129.725396) (xy 276.645157 -129.74447)
			(xy 276.591843 -129.756073) (xy 276.53742 -129.759967) (xy 276.482997 -129.756073) (xy 276.429683 -129.74447)
			(xy 276.378563 -129.725396) (xy 276.33068 -129.699239) (xy 276.308566 -129.683256) (xy 276.308312 -129.683256)
			(xy 276.300295 -129.67769) (xy 276.281469 -129.672604) (xy 276.271736 -129.67335) (xy 276.201886 -129.681732)
			(xy 276.192321 -129.683399) (xy 276.175346 -129.69279) (xy 276.168866 -129.70002) (xy 276.148134 -129.724596)
			(xy 276.101463 -129.768824) (xy 276.049588 -129.806814) (xy 275.993337 -129.837961) (xy 275.933608 -129.861767)
			(xy 275.871354 -129.877853) (xy 275.807569 -129.885962) (xy 275.77542 -129.886456) (xy 275.742578 -129.885925)
			(xy 275.677443 -129.877454) (xy 275.613941 -129.860665) (xy 275.553131 -129.835836) (xy 275.496025 -129.803381)
			(xy 275.443575 -129.763841) (xy 275.396655 -129.717875) (xy 275.356047 -129.666248) (xy 275.338794 -129.638298)
			(xy 275.33219 -129.627376) (xy 275.310346 -129.614168) (xy 275.21281 -129.609596) (xy 275.200185 -129.609622)
			(xy 275.177399 -129.620422) (xy 275.169376 -129.63017) (xy 275.169376 -129.630424) (xy 275.148791 -129.657588)
			(xy 275.101506 -129.706675) (xy 275.048086 -129.749003) (xy 274.989489 -129.783815) (xy 274.926767 -129.810486)
			(xy 274.861044 -129.828538) (xy 274.793499 -129.837647) (xy 274.75942 -129.838196) (xy 274.727456 -129.83774)
			(xy 274.664032 -129.82973) (xy 274.602112 -129.813834) (xy 274.542673 -129.790302) (xy 274.486652 -129.759507)
			(xy 274.434932 -129.721932) (xy 274.38833 -129.678171) (xy 274.34758 -129.628915) (xy 274.313325 -129.574939)
			(xy 274.286105 -129.517096) (xy 274.26635 -129.456297) (xy 274.254371 -129.393502) (xy 274.250356 -129.3297)
			(xy 269.100529 -129.3297) (xy 269.100808 -129.347468) (xy 269.100311 -129.378556) (xy 269.092734 -129.44027)
			(xy 269.077687 -129.500598) (xy 269.055397 -129.558642) (xy 269.026195 -129.613535) (xy 268.990518 -129.664458)
			(xy 268.948898 -129.71065) (xy 268.901956 -129.751422) (xy 268.850393 -129.786166) (xy 268.794978 -129.814364)
			(xy 268.736537 -129.835594) (xy 268.706346 -129.843022) (xy 268.692081 -129.846798) (xy 268.666467 -129.861436)
			(xy 268.646097 -129.882775) (xy 268.632663 -129.909041) (xy 268.627284 -129.938047) (xy 268.630407 -129.967383)
			(xy 268.641772 -129.994607) (xy 268.65072 -130.006344) (xy 268.666927 -130.026855) (xy 268.694151 -130.071482)
			(xy 268.71504 -130.119404) (xy 268.729202 -130.169725) (xy 268.736374 -130.221506) (xy 268.736826 -130.247644)
			(xy 268.736826 -130.247898) (xy 268.73634 -130.275149) (xy 268.728584 -130.329097) (xy 268.713229 -130.381392)
			(xy 268.690587 -130.430969) (xy 268.661121 -130.476819) (xy 268.62543 -130.51801) (xy 268.584239 -130.553701)
			(xy 268.538389 -130.583167) (xy 268.488812 -130.605809) (xy 268.436517 -130.621164) (xy 268.382569 -130.62892)
			(xy 268.328067 -130.62892) (xy 268.274119 -130.621164) (xy 268.221824 -130.605809) (xy 268.172247 -130.583167)
			(xy 268.126397 -130.553701) (xy 268.085206 -130.51801) (xy 268.049515 -130.476819) (xy 268.020049 -130.430969)
			(xy 267.997407 -130.381392) (xy 267.982052 -130.329097) (xy 267.974296 -130.275149) (xy 267.97381 -130.247898)
			(xy 264.537866 -130.247898) (xy 264.529619 -130.251164) (xy 264.467713 -130.267064) (xy 264.404302 -130.275079)
			(xy 264.372344 -130.275584) (xy 264.338661 -130.275042) (xy 264.271882 -130.266164) (xy 264.20686 -130.248543)
			(xy 264.144736 -130.22249) (xy 264.086596 -130.188459) (xy 264.033461 -130.147048) (xy 263.98626 -130.098982)
			(xy 263.945821 -130.045102) (xy 263.92886 -130.015996) (xy 263.921303 -130.003627) (xy 263.900583 -129.983381)
			(xy 263.875005 -129.969779) (xy 263.846634 -129.963918) (xy 263.81776 -129.966272) (xy 263.790713 -129.976652)
			(xy 263.767676 -129.994218) (xy 263.75868 -130.005582) (xy 263.740557 -130.029143) (xy 263.698231 -130.070874)
			(xy 263.649947 -130.105537) (xy 263.596871 -130.132293) (xy 263.540288 -130.150496) (xy 263.481567 -130.159705)
			(xy 263.451848 -130.160268) (xy 263.42459 -130.159888) (xy 263.370628 -130.152136) (xy 263.318319 -130.136783)
			(xy 263.268728 -130.11414) (xy 263.222864 -130.084671) (xy 263.181661 -130.048973) (xy 263.145958 -130.007775)
			(xy 263.116483 -129.961915) (xy 263.093834 -129.912326) (xy 263.078474 -129.860019) (xy 263.070715 -129.806058)
			(xy 260.740101 -129.806058) (xy 260.74269 -129.826555) (xy 260.743192 -129.858516) (xy 260.74269 -129.890477)
			(xy 260.734679 -129.953895) (xy 260.718782 -130.015809) (xy 260.69525 -130.075242) (xy 260.664456 -130.131257)
			(xy 260.626883 -130.182972) (xy 260.583126 -130.229569) (xy 260.533873 -130.270314) (xy 260.479902 -130.304565)
			(xy 260.422063 -130.331782) (xy 260.36127 -130.351535) (xy 260.29848 -130.363513) (xy 260.234684 -130.367527)
			(xy 260.170888 -130.363513) (xy 260.108098 -130.351535) (xy 260.047305 -130.331782) (xy 259.989466 -130.304565)
			(xy 259.935495 -130.270314) (xy 259.886242 -130.229569) (xy 259.842485 -130.182972) (xy 259.804912 -130.131257)
			(xy 259.774118 -130.075242) (xy 259.750586 -130.015809) (xy 259.734689 -129.953895) (xy 259.726678 -129.890477)
			(xy 257.875045 -129.890477) (xy 257.873473 -129.892232) (xy 257.830605 -129.927907) (xy 257.782999 -129.956961)
			(xy 257.73167 -129.978773) (xy 257.677713 -129.992879) (xy 257.622276 -129.998979) (xy 257.566542 -129.996942)
			(xy 257.511699 -129.986812) (xy 257.458915 -129.968805) (xy 257.409315 -129.943304) (xy 257.363957 -129.910853)
			(xy 257.323808 -129.872144) (xy 257.289722 -129.828001) (xy 257.262426 -129.779366) (xy 257.242503 -129.727275)
			(xy 257.230377 -129.672838) (xy 257.226306 -129.617216) (xy 256.084832 -129.617216) (xy 256.08433 -129.649177)
			(xy 256.076319 -129.712595) (xy 256.060422 -129.774509) (xy 256.03689 -129.833942) (xy 256.006096 -129.889957)
			(xy 255.968523 -129.941672) (xy 255.924766 -129.988269) (xy 255.875513 -130.029014) (xy 255.821542 -130.063265)
			(xy 255.763703 -130.090482) (xy 255.70291 -130.110235) (xy 255.64012 -130.122213) (xy 255.576324 -130.126227)
			(xy 255.512528 -130.122213) (xy 255.449738 -130.110235) (xy 255.388945 -130.090482) (xy 255.331106 -130.063265)
			(xy 255.277135 -130.029014) (xy 255.227882 -129.988269) (xy 255.184125 -129.941672) (xy 255.146552 -129.889957)
			(xy 255.115758 -129.833942) (xy 255.092226 -129.774509) (xy 255.076329 -129.712595) (xy 255.068318 -129.649177)
			(xy 213.23808 -129.649177) (xy 213.23808 -130.262884) (xy 213.238232 -130.268608) (xy 213.240802 -130.279764)
			(xy 213.24316 -130.284982) (xy 213.252558 -130.304286) (xy 213.254964 -130.308953) (xy 213.261368 -130.31727)
			(xy 213.265258 -130.320796) (xy 213.265512 -130.32105) (xy 213.289523 -130.341813) (xy 213.332718 -130.38833)
			(xy 213.369787 -130.439861) (xy 213.400156 -130.495605) (xy 213.42335 -130.554695) (xy 213.439011 -130.616212)
			(xy 213.446894 -130.6792) (xy 213.447376 -130.71094) (xy 213.44691 -130.741669) (xy 213.439497 -130.802678)
			(xy 213.424785 -130.862348) (xy 213.402987 -130.91981) (xy 213.374422 -130.974226) (xy 213.339507 -131.024802)
			(xy 213.29875 -131.070801) (xy 213.281529 -131.086055) (xy 218.099126 -131.086055) (xy 218.099126 -131.022133)
			(xy 218.107137 -130.958715) (xy 218.123034 -130.896801) (xy 218.146566 -130.837368) (xy 218.17736 -130.781353)
			(xy 218.214933 -130.729638) (xy 218.25869 -130.683041) (xy 218.307943 -130.642296) (xy 218.361914 -130.608045)
			(xy 218.419753 -130.580828) (xy 218.480546 -130.561075) (xy 218.543336 -130.549097) (xy 218.607132 -130.545084)
			(xy 218.670928 -130.549097) (xy 218.733718 -130.561075) (xy 218.794511 -130.580828) (xy 218.85235 -130.608045)
			(xy 218.906321 -130.642296) (xy 218.955574 -130.683041) (xy 218.999331 -130.729638) (xy 219.036904 -130.781353)
			(xy 219.067698 -130.837368) (xy 219.080302 -130.8692) (xy 242.66545 -130.8692) (xy 242.669465 -130.805398)
			(xy 242.681444 -130.742601) (xy 242.7012 -130.681802) (xy 242.72842 -130.623958) (xy 242.762675 -130.569982)
			(xy 242.803425 -130.520725) (xy 242.850028 -130.476963) (xy 242.901748 -130.439388) (xy 242.95777 -130.408592)
			(xy 243.01721 -130.38506) (xy 243.079131 -130.369164) (xy 243.142556 -130.361154) (xy 243.17452 -130.360674)
			(xy 243.207766 -130.361256) (xy 243.273693 -130.369901) (xy 243.337931 -130.387068) (xy 243.399382 -130.412463)
			(xy 243.456998 -130.445653) (xy 243.509795 -130.486071) (xy 243.556871 -130.533028) (xy 243.597425 -130.585722)
			(xy 243.630762 -130.643252) (xy 243.656314 -130.704638) (xy 243.665502 -130.736594) (xy 243.668042 -130.745484)
			(xy 243.678964 -130.76047) (xy 243.7511 -130.807968) (xy 243.769388 -130.811778) (xy 243.778532 -130.810508)
			(xy 243.797217 -130.807887) (xy 243.834849 -130.805091) (xy 243.853716 -130.80492) (xy 243.88522 -130.805409)
			(xy 243.947745 -130.813184) (xy 244.008831 -130.828625) (xy 244.067541 -130.851495) (xy 244.122975 -130.881443)
			(xy 244.174284 -130.918012) (xy 244.220681 -130.96064) (xy 244.261456 -131.008674) (xy 244.295984 -131.061378)
			(xy 244.314694 -131.099517) (xy 251.982218 -131.099517) (xy 251.982218 -131.035595) (xy 251.990229 -130.972177)
			(xy 252.006126 -130.910263) (xy 252.029658 -130.85083) (xy 252.060452 -130.794815) (xy 252.098025 -130.7431)
			(xy 252.141782 -130.696503) (xy 252.191035 -130.655758) (xy 252.245006 -130.621507) (xy 252.302845 -130.59429)
			(xy 252.363638 -130.574537) (xy 252.426428 -130.562559) (xy 252.490224 -130.558546) (xy 252.55402 -130.562559)
			(xy 252.61681 -130.574537) (xy 252.677603 -130.59429) (xy 252.735442 -130.621507) (xy 252.789413 -130.655758)
			(xy 252.838666 -130.696503) (xy 252.882423 -130.7431) (xy 252.919996 -130.794815) (xy 252.95079 -130.85083)
			(xy 252.974322 -130.910263) (xy 252.990219 -130.972177) (xy 252.99823 -131.035595) (xy 252.998732 -131.067556)
			(xy 252.99823 -131.099517) (xy 254.014218 -131.099517) (xy 254.014218 -131.035595) (xy 254.022229 -130.972177)
			(xy 254.038126 -130.910263) (xy 254.061658 -130.85083) (xy 254.092452 -130.794815) (xy 254.130025 -130.7431)
			(xy 254.173782 -130.696503) (xy 254.223035 -130.655758) (xy 254.277006 -130.621507) (xy 254.334845 -130.59429)
			(xy 254.395638 -130.574537) (xy 254.458428 -130.562559) (xy 254.522224 -130.558546) (xy 254.58602 -130.562559)
			(xy 254.64881 -130.574537) (xy 254.709603 -130.59429) (xy 254.767442 -130.621507) (xy 254.821413 -130.655758)
			(xy 254.870666 -130.696503) (xy 254.914423 -130.7431) (xy 254.951996 -130.794815) (xy 254.961577 -130.812243)
			(xy 262.815826 -130.812243) (xy 262.815826 -130.748321) (xy 262.823837 -130.684903) (xy 262.839734 -130.622989)
			(xy 262.863266 -130.563556) (xy 262.89406 -130.507541) (xy 262.931633 -130.455826) (xy 262.97539 -130.409229)
			(xy 263.024643 -130.368484) (xy 263.078614 -130.334233) (xy 263.136453 -130.307016) (xy 263.197246 -130.287263)
			(xy 263.260036 -130.275285) (xy 263.323832 -130.271272) (xy 263.387628 -130.275285) (xy 263.450418 -130.287263)
			(xy 263.511211 -130.307016) (xy 263.56905 -130.334233) (xy 263.623021 -130.368484) (xy 263.672274 -130.409229)
			(xy 263.716031 -130.455826) (xy 263.753604 -130.507541) (xy 263.784398 -130.563556) (xy 263.80793 -130.622989)
			(xy 263.823827 -130.684903) (xy 263.831838 -130.748321) (xy 263.83234 -130.780282) (xy 263.831838 -130.812243)
			(xy 263.823827 -130.875661) (xy 263.80793 -130.937575) (xy 263.784398 -130.997008) (xy 263.753604 -131.053023)
			(xy 263.719824 -131.099517) (xy 264.98651 -131.099517) (xy 264.98651 -131.035595) (xy 264.994521 -130.972177)
			(xy 265.010418 -130.910263) (xy 265.03395 -130.85083) (xy 265.064744 -130.794815) (xy 265.102317 -130.7431)
			(xy 265.146074 -130.696503) (xy 265.195327 -130.655758) (xy 265.249298 -130.621507) (xy 265.307137 -130.59429)
			(xy 265.36793 -130.574537) (xy 265.43072 -130.562559) (xy 265.494516 -130.558546) (xy 265.558312 -130.562559)
			(xy 265.621102 -130.574537) (xy 265.681895 -130.59429) (xy 265.739734 -130.621507) (xy 265.793705 -130.655758)
			(xy 265.842958 -130.696503) (xy 265.886715 -130.7431) (xy 265.924288 -130.794815) (xy 265.955082 -130.85083)
			(xy 265.978614 -130.910263) (xy 265.994511 -130.972177) (xy 266.002522 -131.035595) (xy 266.003024 -131.067556)
			(xy 266.002844 -131.078986) (xy 268.914118 -131.078986) (xy 268.914603 -131.047042) (xy 268.922597 -130.983656)
			(xy 268.938471 -130.921771) (xy 268.961973 -130.862362) (xy 268.992733 -130.806367) (xy 269.030267 -130.754667)
			(xy 269.073983 -130.708077) (xy 269.098268 -130.687318) (xy 269.106596 -130.679748) (xy 269.116224 -130.65944)
			(xy 269.11681 -130.648202) (xy 269.11681 -130.56997) (xy 269.116172 -130.558746) (xy 269.106551 -130.538455)
			(xy 269.098268 -130.530854) (xy 269.073963 -130.51012) (xy 269.030261 -130.463518) (xy 268.992738 -130.41181)
			(xy 268.961986 -130.35581) (xy 268.938489 -130.2964) (xy 268.922616 -130.234515) (xy 268.914617 -130.17113)
			(xy 268.914118 -130.139186) (xy 268.91462 -130.107225) (xy 268.922631 -130.043807) (xy 268.938528 -129.981893)
			(xy 268.96206 -129.92246) (xy 268.992854 -129.866445) (xy 269.030427 -129.81473) (xy 269.074184 -129.768133)
			(xy 269.123437 -129.727388) (xy 269.177408 -129.693137) (xy 269.235247 -129.66592) (xy 269.29604 -129.646167)
			(xy 269.35883 -129.634189) (xy 269.422626 -129.630176) (xy 269.486422 -129.634189) (xy 269.549212 -129.646167)
			(xy 269.610005 -129.66592) (xy 269.667844 -129.693137) (xy 269.721815 -129.727388) (xy 269.771068 -129.768133)
			(xy 269.814825 -129.81473) (xy 269.852398 -129.866445) (xy 269.882114 -129.9205) (xy 284.244581 -129.9205)
			(xy 284.248595 -129.856706) (xy 284.260572 -129.793919) (xy 284.280323 -129.733127) (xy 284.307537 -129.67529)
			(xy 284.341785 -129.62132) (xy 284.382528 -129.572068) (xy 284.429121 -129.52831) (xy 284.480832 -129.490736)
			(xy 284.536843 -129.459939) (xy 284.596273 -129.436405) (xy 284.658183 -129.420505) (xy 284.721598 -129.412488)
			(xy 284.753558 -129.411984) (xy 284.784846 -129.412458) (xy 284.846948 -129.420136) (xy 284.907638 -129.43538)
			(xy 284.965997 -129.45796) (xy 285.021142 -129.487534) (xy 285.072239 -129.523656) (xy 285.118514 -129.565777)
			(xy 285.159268 -129.613261) (xy 285.176976 -129.63906) (xy 285.184532 -129.649181) (xy 285.20678 -129.661057)
			(xy 285.219394 -129.661666) (xy 285.303722 -129.661666) (xy 285.31633 -129.661043) (xy 285.338577 -129.64917)
			(xy 285.34614 -129.63906) (xy 285.363872 -129.61328) (xy 285.404626 -129.5658) (xy 285.4509 -129.523681)
			(xy 285.501994 -129.487561) (xy 285.557135 -129.457985) (xy 285.615489 -129.435402) (xy 285.676174 -129.420152)
			(xy 285.738272 -129.412466) (xy 285.769558 -129.411984) (xy 285.801522 -129.412478) (xy 285.864945 -129.420486)
			(xy 285.926865 -129.436379) (xy 285.986304 -129.459909) (xy 286.042326 -129.490703) (xy 286.094046 -129.528276)
			(xy 286.140648 -129.572035) (xy 286.181399 -129.62129) (xy 286.215654 -129.675264) (xy 286.242874 -129.733107)
			(xy 286.26263 -129.793904) (xy 286.274609 -129.856699) (xy 286.278624 -129.9205) (xy 286.274609 -129.984301)
			(xy 286.26263 -130.047096) (xy 286.242874 -130.107893) (xy 286.215654 -130.165736) (xy 286.181399 -130.21971)
			(xy 286.140648 -130.268965) (xy 286.094046 -130.312724) (xy 286.042326 -130.350297) (xy 285.986304 -130.381091)
			(xy 285.926865 -130.404621) (xy 285.864945 -130.420514) (xy 285.801522 -130.428522) (xy 285.769558 -130.429)
			(xy 285.738271 -130.428521) (xy 285.676168 -130.420845) (xy 285.615478 -130.405602) (xy 285.557119 -130.383023)
			(xy 285.501974 -130.353449) (xy 285.450877 -130.317328) (xy 285.404601 -130.275207) (xy 285.363848 -130.227723)
			(xy 285.34614 -130.201924) (xy 285.33863 -130.191761) (xy 285.316347 -130.179907) (xy 285.303722 -130.179318)
			(xy 285.219394 -130.179318) (xy 285.206788 -130.179957) (xy 285.184541 -130.19182) (xy 285.176976 -130.201924)
			(xy 285.159228 -130.227693) (xy 285.118477 -130.275174) (xy 285.072206 -130.317294) (xy 285.021114 -130.353415)
			(xy 284.965976 -130.382992) (xy 284.907623 -130.405577) (xy 284.84694 -130.420829) (xy 284.784843 -130.428517)
			(xy 284.753558 -130.429) (xy 284.721598 -130.428512) (xy 284.658183 -130.420495) (xy 284.596273 -130.404595)
			(xy 284.536843 -130.381061) (xy 284.480832 -130.350264) (xy 284.429121 -130.31269) (xy 284.382528 -130.268932)
			(xy 284.341785 -130.21968) (xy 284.307537 -130.16571) (xy 284.280323 -130.107873) (xy 284.260572 -130.047081)
			(xy 284.248595 -129.984294) (xy 284.244581 -129.9205) (xy 269.882114 -129.9205) (xy 269.883192 -129.92246)
			(xy 269.906724 -129.981893) (xy 269.922621 -130.043807) (xy 269.930632 -130.107225) (xy 269.931134 -130.139186)
			(xy 269.930646 -130.17113) (xy 269.922655 -130.234517) (xy 269.906783 -130.296403) (xy 269.883282 -130.355812)
			(xy 269.852522 -130.411807) (xy 269.814987 -130.463507) (xy 269.77127 -130.510096) (xy 269.746984 -130.530854)
			(xy 269.738678 -130.538445) (xy 269.730839 -130.554941) (xy 287.672012 -130.554941) (xy 287.672012 -130.491019)
			(xy 287.680023 -130.427601) (xy 287.69592 -130.365687) (xy 287.719452 -130.306254) (xy 287.750246 -130.250239)
			(xy 287.787819 -130.198524) (xy 287.831576 -130.151927) (xy 287.880829 -130.111182) (xy 287.9348 -130.076931)
			(xy 287.992639 -130.049714) (xy 288.053432 -130.029961) (xy 288.116222 -130.017983) (xy 288.180018 -130.01397)
			(xy 288.243814 -130.017983) (xy 288.306604 -130.029961) (xy 288.367397 -130.049714) (xy 288.425236 -130.076931)
			(xy 288.479207 -130.111182) (xy 288.52846 -130.151927) (xy 288.572217 -130.198524) (xy 288.60979 -130.250239)
			(xy 288.640584 -130.306254) (xy 288.664116 -130.365687) (xy 288.680013 -130.427601) (xy 288.688024 -130.491019)
			(xy 288.688526 -130.52298) (xy 288.688024 -130.554941) (xy 288.680013 -130.618359) (xy 288.664116 -130.680273)
			(xy 288.640584 -130.739706) (xy 288.60979 -130.795721) (xy 288.572217 -130.847436) (xy 288.52846 -130.894033)
			(xy 288.479207 -130.934778) (xy 288.425236 -130.969029) (xy 288.367397 -130.996246) (xy 288.306604 -131.015999)
			(xy 288.243814 -131.027977) (xy 288.180018 -131.031991) (xy 288.116222 -131.027977) (xy 288.053432 -131.015999)
			(xy 287.992639 -130.996246) (xy 287.9348 -130.969029) (xy 287.880829 -130.934778) (xy 287.831576 -130.894033)
			(xy 287.787819 -130.847436) (xy 287.750246 -130.795721) (xy 287.719452 -130.739706) (xy 287.69592 -130.680273)
			(xy 287.680023 -130.618359) (xy 287.672012 -130.554941) (xy 269.730839 -130.554941) (xy 269.729035 -130.558736)
			(xy 269.728442 -130.56997) (xy 269.728442 -130.648202) (xy 269.729111 -130.659422) (xy 269.738712 -130.679712)
			(xy 269.746984 -130.687318) (xy 269.771266 -130.708078) (xy 269.814971 -130.754675) (xy 269.852497 -130.806378)
			(xy 269.883253 -130.862373) (xy 269.906754 -130.921779) (xy 269.922631 -130.983661) (xy 269.930633 -131.047043)
			(xy 269.931023 -131.0719) (xy 288.888342 -131.0719) (xy 288.892357 -131.008095) (xy 288.904337 -130.945296)
			(xy 288.924094 -130.884495) (xy 288.951316 -130.826648) (xy 288.985573 -130.772671) (xy 289.026326 -130.723412)
			(xy 289.072932 -130.67965) (xy 289.124655 -130.642075) (xy 289.18068 -130.611279) (xy 289.240123 -130.587748)
			(xy 289.302047 -130.571853) (xy 289.365474 -130.563845) (xy 289.39744 -130.563366) (xy 289.429474 -130.563875)
			(xy 289.493033 -130.571934) (xy 289.555078 -130.587907) (xy 289.614628 -130.61154) (xy 289.67074 -130.642461)
			(xy 289.722528 -130.680181) (xy 289.769172 -130.724102) (xy 289.809935 -130.77353) (xy 289.827462 -130.800348)
			(xy 289.834052 -130.809652) (xy 289.853309 -130.821793) (xy 289.864546 -130.823716) (xy 289.953954 -130.834384)
			(xy 289.975798 -130.827018) (xy 289.983926 -130.819144) (xy 290.00772 -130.796912) (xy 290.059954 -130.758027)
			(xy 290.116723 -130.726125) (xy 290.177099 -130.701728) (xy 290.240095 -130.685236) (xy 290.304681 -130.676918)
			(xy 290.33724 -130.676396) (xy 290.3692 -130.676892) (xy 290.432614 -130.684908) (xy 290.494525 -130.700808)
			(xy 290.553954 -130.724342) (xy 290.609965 -130.755139) (xy 290.661675 -130.792712) (xy 290.708269 -130.83647)
			(xy 290.749011 -130.885722) (xy 290.783259 -130.939692) (xy 290.810473 -130.997528) (xy 290.830224 -131.058319)
			(xy 290.842201 -131.121107) (xy 290.846215 -131.1849) (xy 290.842201 -131.248693) (xy 290.830224 -131.311481)
			(xy 290.810473 -131.372272) (xy 290.783259 -131.430108) (xy 290.749011 -131.484078) (xy 290.708269 -131.53333)
			(xy 290.661675 -131.577088) (xy 290.609965 -131.614661) (xy 290.553954 -131.645458) (xy 290.494525 -131.668992)
			(xy 290.432614 -131.684892) (xy 290.3692 -131.692908) (xy 290.33724 -131.693412) (xy 290.305205 -131.692929)
			(xy 290.241645 -131.684867) (xy 290.179598 -131.668891) (xy 290.120048 -131.645254) (xy 290.063935 -131.614329)
			(xy 290.012148 -131.576606) (xy 289.965505 -131.532682) (xy 289.924744 -131.48325) (xy 289.907218 -131.45643)
			(xy 289.900694 -131.447059) (xy 289.881405 -131.434885) (xy 289.870134 -131.433062) (xy 289.780726 -131.422394)
			(xy 289.758882 -131.42976) (xy 289.750754 -131.437634) (xy 289.726965 -131.459871) (xy 289.674731 -131.498757)
			(xy 289.61796 -131.530659) (xy 289.557583 -131.555055) (xy 289.494586 -131.571545) (xy 289.43 -131.579861)
			(xy 289.39744 -131.580382) (xy 289.365474 -131.579955) (xy 289.302047 -131.571947) (xy 289.240123 -131.556052)
			(xy 289.18068 -131.532521) (xy 289.124655 -131.501725) (xy 289.072932 -131.46415) (xy 289.026326 -131.420388)
			(xy 288.985573 -131.371129) (xy 288.951316 -131.317152) (xy 288.924094 -131.259306) (xy 288.904337 -131.198504)
			(xy 288.892357 -131.135705) (xy 288.888342 -131.0719) (xy 269.931023 -131.0719) (xy 269.931134 -131.078986)
			(xy 269.930707 -131.109794) (xy 269.923248 -131.170957) (xy 269.908449 -131.23077) (xy 269.886528 -131.288355)
			(xy 269.857806 -131.342868) (xy 269.822705 -131.393508) (xy 269.781739 -131.439534) (xy 269.758922 -131.46024)
			(xy 269.752256 -131.466618) (xy 269.74366 -131.482929) (xy 269.741386 -131.501226) (xy 269.743174 -131.510278)
			(xy 269.764256 -131.597654) (xy 269.766759 -131.606539) (xy 269.777116 -131.621801) (xy 269.792237 -131.632362)
			(xy 269.801086 -131.634992) (xy 269.828103 -131.642368) (xy 269.879755 -131.664014) (xy 269.927687 -131.692982)
			(xy 269.970866 -131.728647) (xy 270.008366 -131.770244) (xy 270.03938 -131.816877) (xy 270.063241 -131.867544)
			(xy 270.079436 -131.921156) (xy 270.087617 -131.97656) (xy 270.088106 -132.004562) (xy 270.08762 -132.031813)
			(xy 270.079864 -132.085761) (xy 270.064509 -132.138056) (xy 270.041867 -132.187633) (xy 270.012401 -132.233483)
			(xy 269.97671 -132.274674) (xy 269.935519 -132.310365) (xy 269.889669 -132.339831) (xy 269.840092 -132.362473)
			(xy 269.787797 -132.377828) (xy 269.733849 -132.385584) (xy 269.679347 -132.385584) (xy 269.625399 -132.377828)
			(xy 269.573104 -132.362473) (xy 269.523527 -132.339831) (xy 269.477677 -132.310365) (xy 269.436486 -132.274674)
			(xy 269.400795 -132.233483) (xy 269.371329 -132.187633) (xy 269.348687 -132.138056) (xy 269.333332 -132.085761)
			(xy 269.325576 -132.031813) (xy 269.32509 -132.004562) (xy 269.325598 -131.976888) (xy 269.333594 -131.92212)
			(xy 269.349426 -131.869085) (xy 269.372761 -131.818897) (xy 269.40311 -131.772611) (xy 269.421102 -131.751578)
			(xy 269.4305 -131.74091) (xy 269.435834 -131.713478) (xy 269.399004 -131.615942) (xy 269.395408 -131.607448)
			(xy 269.383234 -131.593609) (xy 269.36695 -131.584977) (xy 269.357856 -131.58343) (xy 269.32758 -131.579064)
			(xy 269.268283 -131.564034) (xy 269.211217 -131.542002) (xy 269.157206 -131.513285) (xy 269.107028 -131.478298)
			(xy 269.061408 -131.437545) (xy 269.021004 -131.391615) (xy 268.986401 -131.341172) (xy 268.958097 -131.286942)
			(xy 268.936501 -131.22971) (xy 268.921924 -131.1703) (xy 268.914578 -131.109572) (xy 268.914118 -131.078986)
			(xy 266.002844 -131.078986) (xy 266.002522 -131.099517) (xy 265.994511 -131.162935) (xy 265.978614 -131.224849)
			(xy 265.955082 -131.284282) (xy 265.924288 -131.340297) (xy 265.886715 -131.392012) (xy 265.842958 -131.438609)
			(xy 265.793705 -131.479354) (xy 265.739734 -131.513605) (xy 265.681895 -131.540822) (xy 265.621102 -131.560575)
			(xy 265.558312 -131.572553) (xy 265.494516 -131.576567) (xy 265.43072 -131.572553) (xy 265.36793 -131.560575)
			(xy 265.307137 -131.540822) (xy 265.249298 -131.513605) (xy 265.195327 -131.479354) (xy 265.146074 -131.438609)
			(xy 265.102317 -131.392012) (xy 265.064744 -131.340297) (xy 265.03395 -131.284282) (xy 265.010418 -131.224849)
			(xy 264.994521 -131.162935) (xy 264.98651 -131.099517) (xy 263.719824 -131.099517) (xy 263.716031 -131.104738)
			(xy 263.672274 -131.151335) (xy 263.623021 -131.19208) (xy 263.56905 -131.226331) (xy 263.511211 -131.253548)
			(xy 263.450418 -131.273301) (xy 263.387628 -131.285279) (xy 263.323832 -131.289293) (xy 263.260036 -131.285279)
			(xy 263.197246 -131.273301) (xy 263.136453 -131.253548) (xy 263.078614 -131.226331) (xy 263.024643 -131.19208)
			(xy 262.97539 -131.151335) (xy 262.931633 -131.104738) (xy 262.89406 -131.053023) (xy 262.863266 -130.997008)
			(xy 262.839734 -130.937575) (xy 262.823837 -130.875661) (xy 262.815826 -130.812243) (xy 254.961577 -130.812243)
			(xy 254.98279 -130.85083) (xy 255.006322 -130.910263) (xy 255.022219 -130.972177) (xy 255.03023 -131.035595)
			(xy 255.030732 -131.067556) (xy 255.03023 -131.099517) (xy 255.022219 -131.162935) (xy 255.006322 -131.224849)
			(xy 254.98279 -131.284282) (xy 254.951996 -131.340297) (xy 254.914423 -131.392012) (xy 254.870666 -131.438609)
			(xy 254.821413 -131.479354) (xy 254.767442 -131.513605) (xy 254.709603 -131.540822) (xy 254.64881 -131.560575)
			(xy 254.58602 -131.572553) (xy 254.522224 -131.576567) (xy 254.458428 -131.572553) (xy 254.395638 -131.560575)
			(xy 254.334845 -131.540822) (xy 254.277006 -131.513605) (xy 254.223035 -131.479354) (xy 254.173782 -131.438609)
			(xy 254.130025 -131.392012) (xy 254.092452 -131.340297) (xy 254.061658 -131.284282) (xy 254.038126 -131.224849)
			(xy 254.022229 -131.162935) (xy 254.014218 -131.099517) (xy 252.99823 -131.099517) (xy 252.990219 -131.162935)
			(xy 252.974322 -131.224849) (xy 252.95079 -131.284282) (xy 252.919996 -131.340297) (xy 252.882423 -131.392012)
			(xy 252.838666 -131.438609) (xy 252.789413 -131.479354) (xy 252.735442 -131.513605) (xy 252.677603 -131.540822)
			(xy 252.61681 -131.560575) (xy 252.55402 -131.572553) (xy 252.490224 -131.576567) (xy 252.426428 -131.572553)
			(xy 252.363638 -131.560575) (xy 252.302845 -131.540822) (xy 252.245006 -131.513605) (xy 252.191035 -131.479354)
			(xy 252.141782 -131.438609) (xy 252.098025 -131.392012) (xy 252.060452 -131.340297) (xy 252.029658 -131.284282)
			(xy 252.006126 -131.224849) (xy 251.990229 -131.162935) (xy 251.982218 -131.099517) (xy 244.314694 -131.099517)
			(xy 244.323735 -131.117945) (xy 244.344284 -131.177506) (xy 244.357316 -131.239151) (xy 244.360446 -131.270502)
			(xy 244.361539 -131.279291) (xy 244.368943 -131.295368) (xy 244.381393 -131.307949) (xy 244.397391 -131.315522)
			(xy 244.406166 -131.31673) (xy 244.437211 -131.320224) (xy 244.498179 -131.333869) (xy 244.557016 -131.354877)
			(xy 244.612838 -131.382933) (xy 244.664804 -131.417614) (xy 244.712131 -131.458398) (xy 244.754107 -131.504671)
			(xy 244.790101 -131.555737) (xy 244.819569 -131.610826) (xy 244.825564 -131.626356) (xy 253.124206 -131.626356)
			(xy 253.128277 -131.570734) (xy 253.140403 -131.516297) (xy 253.160326 -131.464206) (xy 253.187622 -131.415571)
			(xy 253.221708 -131.371428) (xy 253.261857 -131.332719) (xy 253.307215 -131.300268) (xy 253.356815 -131.274767)
			(xy 253.409599 -131.25676) (xy 253.464442 -131.24663) (xy 253.520176 -131.244593) (xy 253.575613 -131.250693)
			(xy 253.62957 -131.264799) (xy 253.680899 -131.286611) (xy 253.728505 -131.315665) (xy 253.771373 -131.35134)
			(xy 253.80859 -131.392877) (xy 253.839363 -131.43939) (xy 253.863035 -131.489887) (xy 253.879103 -131.543294)
			(xy 253.887223 -131.59847) (xy 253.887732 -131.626356) (xy 253.887223 -131.654242) (xy 253.879103 -131.709418)
			(xy 253.863035 -131.762825) (xy 253.839363 -131.813322) (xy 253.80859 -131.859835) (xy 253.771373 -131.901372)
			(xy 253.728505 -131.937047) (xy 253.680899 -131.966101) (xy 253.62957 -131.987913) (xy 253.575613 -132.002019)
			(xy 253.520176 -132.008119) (xy 253.464442 -132.006082) (xy 253.409599 -131.995952) (xy 253.356815 -131.977945)
			(xy 253.307215 -131.952444) (xy 253.261857 -131.919993) (xy 253.221708 -131.881284) (xy 253.187622 -131.837141)
			(xy 253.160326 -131.788506) (xy 253.140403 -131.736415) (xy 253.128277 -131.681978) (xy 253.124206 -131.626356)
			(xy 244.825564 -131.626356) (xy 244.842069 -131.669109) (xy 244.857262 -131.72971) (xy 244.864919 -131.791714)
			(xy 244.865398 -131.822952) (xy 244.864945 -131.855355) (xy 244.856718 -131.919636) (xy 244.840392 -131.982351)
			(xy 244.81623 -132.042483) (xy 244.784624 -132.099059) (xy 244.746087 -132.151161) (xy 244.701244 -132.197945)
			(xy 244.65082 -132.238654) (xy 244.595633 -132.272626) (xy 244.536577 -132.299312) (xy 244.474609 -132.318279)
			(xy 244.410734 -132.32922) (xy 244.345987 -132.331957) (xy 244.281416 -132.326447) (xy 244.218069 -132.312778)
			(xy 244.156971 -132.291172) (xy 244.099114 -132.261979) (xy 244.045434 -132.225673) (xy 243.996801 -132.182841)
			(xy 243.954004 -132.134177) (xy 243.917736 -132.080471) (xy 243.888584 -132.022593) (xy 243.867022 -131.96148)
			(xy 243.853399 -131.898122) (xy 243.85016 -131.865878) (xy 243.849077 -131.857087) (xy 243.841668 -131.841011)
			(xy 243.829215 -131.828431) (xy 243.813216 -131.820858) (xy 243.80444 -131.81965) (xy 243.773848 -131.816225)
			(xy 243.713747 -131.8029) (xy 243.655694 -131.782419) (xy 243.600536 -131.755081) (xy 243.549082 -131.721287)
			(xy 243.502082 -131.681529) (xy 243.460224 -131.63639) (xy 243.424119 -131.586529) (xy 243.394296 -131.532675)
			(xy 243.371191 -131.475615) (xy 243.362734 -131.446016) (xy 243.360194 -131.437126) (xy 243.349272 -131.42214)
			(xy 243.277136 -131.374642) (xy 243.258848 -131.370832) (xy 243.249704 -131.372102) (xy 243.231018 -131.374719)
			(xy 243.193387 -131.377517) (xy 243.17452 -131.37769) (xy 243.142556 -131.377246) (xy 243.079131 -131.369236)
			(xy 243.01721 -131.35334) (xy 242.95777 -131.329808) (xy 242.901748 -131.299012) (xy 242.850028 -131.261437)
			(xy 242.803425 -131.217675) (xy 242.762675 -131.168418) (xy 242.72842 -131.114442) (xy 242.7012 -131.056598)
			(xy 242.681444 -130.995799) (xy 242.669465 -130.933002) (xy 242.66545 -130.8692) (xy 219.080302 -130.8692)
			(xy 219.09123 -130.896801) (xy 219.107127 -130.958715) (xy 219.115138 -131.022133) (xy 219.11564 -131.054094)
			(xy 219.115138 -131.086055) (xy 219.107127 -131.149473) (xy 219.09123 -131.211387) (xy 219.067698 -131.27082)
			(xy 219.036904 -131.326835) (xy 218.999331 -131.37855) (xy 218.955574 -131.425147) (xy 218.906321 -131.465892)
			(xy 218.85235 -131.500143) (xy 218.794511 -131.52736) (xy 218.733718 -131.547113) (xy 218.670928 -131.559091)
			(xy 218.607132 -131.563105) (xy 218.543336 -131.559091) (xy 218.480546 -131.547113) (xy 218.419753 -131.52736)
			(xy 218.361914 -131.500143) (xy 218.307943 -131.465892) (xy 218.25869 -131.425147) (xy 218.214933 -131.37855)
			(xy 218.17736 -131.326835) (xy 218.146566 -131.27082) (xy 218.123034 -131.211387) (xy 218.107137 -131.149473)
			(xy 218.099126 -131.086055) (xy 213.281529 -131.086055) (xy 213.252745 -131.111551) (xy 213.202164 -131.14646)
			(xy 213.147745 -131.175017) (xy 213.090279 -131.196806) (xy 213.030607 -131.21151) (xy 212.969597 -131.218914)
			(xy 212.938868 -131.219448) (xy 212.903178 -131.218825) (xy 212.832502 -131.208815) (xy 212.763915 -131.189036)
			(xy 212.731096 -131.174998) (xy 212.730842 -131.174998) (xy 212.723833 -131.172195) (xy 212.708853 -131.170388)
			(xy 212.701378 -131.171442) (xy 212.700362 -131.171696) (xy 212.692996 -131.172966) (xy 212.6869 -131.176268)
			(xy 212.683645 -131.178103) (xy 212.677648 -131.182561) (xy 212.674962 -131.185158) (xy 211.821057 -132.039063)
			(xy 216.874592 -132.039063) (xy 216.874592 -131.975141) (xy 216.882603 -131.911723) (xy 216.8985 -131.849809)
			(xy 216.922032 -131.790376) (xy 216.952826 -131.734361) (xy 216.990399 -131.682646) (xy 217.034156 -131.636049)
			(xy 217.083409 -131.595304) (xy 217.13738 -131.561053) (xy 217.195219 -131.533836) (xy 217.256012 -131.514083)
			(xy 217.318802 -131.502105) (xy 217.382598 -131.498092) (xy 217.446394 -131.502105) (xy 217.509184 -131.514083)
			(xy 217.569977 -131.533836) (xy 217.627816 -131.561053) (xy 217.681787 -131.595304) (xy 217.73104 -131.636049)
			(xy 217.774797 -131.682646) (xy 217.81237 -131.734361) (xy 217.843164 -131.790376) (xy 217.866696 -131.849809)
			(xy 217.882593 -131.911723) (xy 217.890604 -131.975141) (xy 217.891106 -132.007102) (xy 217.890604 -132.039063)
			(xy 217.882593 -132.102481) (xy 217.866696 -132.164395) (xy 217.843164 -132.223828) (xy 217.81237 -132.279843)
			(xy 217.774797 -132.331558) (xy 217.739152 -132.369517) (xy 251.982218 -132.369517) (xy 251.982218 -132.305595)
			(xy 251.990229 -132.242177) (xy 252.006126 -132.180263) (xy 252.029658 -132.12083) (xy 252.060452 -132.064815)
			(xy 252.098025 -132.0131) (xy 252.141782 -131.966503) (xy 252.191035 -131.925758) (xy 252.245006 -131.891507)
			(xy 252.302845 -131.86429) (xy 252.363638 -131.844537) (xy 252.426428 -131.832559) (xy 252.490224 -131.828546)
			(xy 252.55402 -131.832559) (xy 252.61681 -131.844537) (xy 252.677603 -131.86429) (xy 252.735442 -131.891507)
			(xy 252.789413 -131.925758) (xy 252.838666 -131.966503) (xy 252.882423 -132.0131) (xy 252.919996 -132.064815)
			(xy 252.95079 -132.12083) (xy 252.974322 -132.180263) (xy 252.990219 -132.242177) (xy 252.99823 -132.305595)
			(xy 252.998732 -132.337556) (xy 252.99823 -132.369517) (xy 254.014218 -132.369517) (xy 254.014218 -132.305595)
			(xy 254.022229 -132.242177) (xy 254.038126 -132.180263) (xy 254.061658 -132.12083) (xy 254.092452 -132.064815)
			(xy 254.130025 -132.0131) (xy 254.173782 -131.966503) (xy 254.223035 -131.925758) (xy 254.277006 -131.891507)
			(xy 254.334845 -131.86429) (xy 254.395638 -131.844537) (xy 254.458428 -131.832559) (xy 254.522224 -131.828546)
			(xy 254.58602 -131.832559) (xy 254.64881 -131.844537) (xy 254.709603 -131.86429) (xy 254.767442 -131.891507)
			(xy 254.821413 -131.925758) (xy 254.870666 -131.966503) (xy 254.914423 -132.0131) (xy 254.951996 -132.064815)
			(xy 254.98279 -132.12083) (xy 255.006322 -132.180263) (xy 255.022219 -132.242177) (xy 255.03023 -132.305595)
			(xy 255.030732 -132.337556) (xy 255.03023 -132.369517) (xy 262.95451 -132.369517) (xy 262.95451 -132.305595)
			(xy 262.962521 -132.242177) (xy 262.978418 -132.180263) (xy 263.00195 -132.12083) (xy 263.032744 -132.064815)
			(xy 263.070317 -132.0131) (xy 263.114074 -131.966503) (xy 263.163327 -131.925758) (xy 263.217298 -131.891507)
			(xy 263.275137 -131.86429) (xy 263.33593 -131.844537) (xy 263.39872 -131.832559) (xy 263.462516 -131.828546)
			(xy 263.526312 -131.832559) (xy 263.589102 -131.844537) (xy 263.649895 -131.86429) (xy 263.707734 -131.891507)
			(xy 263.761705 -131.925758) (xy 263.810958 -131.966503) (xy 263.854715 -132.0131) (xy 263.892288 -132.064815)
			(xy 263.923082 -132.12083) (xy 263.946614 -132.180263) (xy 263.962511 -132.242177) (xy 263.970522 -132.305595)
			(xy 263.971024 -132.337556) (xy 263.970785 -132.352796) (xy 265.112498 -132.352796) (xy 265.116569 -132.297174)
			(xy 265.128695 -132.242737) (xy 265.148618 -132.190646) (xy 265.175914 -132.142011) (xy 265.21 -132.097868)
			(xy 265.250149 -132.059159) (xy 265.295507 -132.026708) (xy 265.345107 -132.001207) (xy 265.397891 -131.9832)
			(xy 265.452734 -131.97307) (xy 265.508468 -131.971033) (xy 265.563905 -131.977133) (xy 265.617862 -131.991239)
			(xy 265.669191 -132.013051) (xy 265.716797 -132.042105) (xy 265.759665 -132.07778) (xy 265.796882 -132.119317)
			(xy 265.827655 -132.16583) (xy 265.851327 -132.216327) (xy 265.867395 -132.269734) (xy 265.875515 -132.32491)
			(xy 265.876024 -132.352796) (xy 265.875515 -132.380682) (xy 265.867395 -132.435858) (xy 265.851327 -132.489265)
			(xy 265.827655 -132.539762) (xy 265.796882 -132.586275) (xy 265.759665 -132.627812) (xy 265.716797 -132.663487)
			(xy 265.669191 -132.692541) (xy 265.617862 -132.714353) (xy 265.563905 -132.728459) (xy 265.508468 -132.734559)
			(xy 265.452734 -132.732522) (xy 265.397891 -132.722392) (xy 265.345107 -132.704385) (xy 265.295507 -132.678884)
			(xy 265.250149 -132.646433) (xy 265.21 -132.607724) (xy 265.175914 -132.563581) (xy 265.148618 -132.514946)
			(xy 265.128695 -132.462855) (xy 265.116569 -132.408418) (xy 265.112498 -132.352796) (xy 263.970785 -132.352796)
			(xy 263.970522 -132.369517) (xy 263.962511 -132.432935) (xy 263.946614 -132.494849) (xy 263.923082 -132.554282)
			(xy 263.892288 -132.610297) (xy 263.854715 -132.662012) (xy 263.810958 -132.708609) (xy 263.761705 -132.749354)
			(xy 263.707734 -132.783605) (xy 263.649895 -132.810822) (xy 263.589102 -132.830575) (xy 263.526312 -132.842553)
			(xy 263.462516 -132.846567) (xy 263.39872 -132.842553) (xy 263.33593 -132.830575) (xy 263.275137 -132.810822)
			(xy 263.217298 -132.783605) (xy 263.163327 -132.749354) (xy 263.114074 -132.708609) (xy 263.070317 -132.662012)
			(xy 263.032744 -132.610297) (xy 263.00195 -132.554282) (xy 262.978418 -132.494849) (xy 262.962521 -132.432935)
			(xy 262.95451 -132.369517) (xy 255.03023 -132.369517) (xy 255.022219 -132.432935) (xy 255.006322 -132.494849)
			(xy 254.98279 -132.554282) (xy 254.951996 -132.610297) (xy 254.914423 -132.662012) (xy 254.870666 -132.708609)
			(xy 254.821413 -132.749354) (xy 254.767442 -132.783605) (xy 254.709603 -132.810822) (xy 254.64881 -132.830575)
			(xy 254.58602 -132.842553) (xy 254.522224 -132.846567) (xy 254.458428 -132.842553) (xy 254.395638 -132.830575)
			(xy 254.334845 -132.810822) (xy 254.277006 -132.783605) (xy 254.223035 -132.749354) (xy 254.173782 -132.708609)
			(xy 254.130025 -132.662012) (xy 254.092452 -132.610297) (xy 254.061658 -132.554282) (xy 254.038126 -132.494849)
			(xy 254.022229 -132.432935) (xy 254.014218 -132.369517) (xy 252.99823 -132.369517) (xy 252.990219 -132.432935)
			(xy 252.974322 -132.494849) (xy 252.95079 -132.554282) (xy 252.919996 -132.610297) (xy 252.882423 -132.662012)
			(xy 252.838666 -132.708609) (xy 252.789413 -132.749354) (xy 252.735442 -132.783605) (xy 252.677603 -132.810822)
			(xy 252.61681 -132.830575) (xy 252.55402 -132.842553) (xy 252.490224 -132.846567) (xy 252.426428 -132.842553)
			(xy 252.363638 -132.830575) (xy 252.302845 -132.810822) (xy 252.245006 -132.783605) (xy 252.191035 -132.749354)
			(xy 252.141782 -132.708609) (xy 252.098025 -132.662012) (xy 252.060452 -132.610297) (xy 252.029658 -132.554282)
			(xy 252.006126 -132.494849) (xy 251.990229 -132.432935) (xy 251.982218 -132.369517) (xy 217.739152 -132.369517)
			(xy 217.73104 -132.378155) (xy 217.681787 -132.4189) (xy 217.627816 -132.453151) (xy 217.569977 -132.480368)
			(xy 217.509184 -132.500121) (xy 217.446394 -132.512099) (xy 217.382598 -132.516113) (xy 217.318802 -132.512099)
			(xy 217.256012 -132.500121) (xy 217.195219 -132.480368) (xy 217.13738 -132.453151) (xy 217.083409 -132.4189)
			(xy 217.034156 -132.378155) (xy 216.990399 -132.331558) (xy 216.952826 -132.279843) (xy 216.922032 -132.223828)
			(xy 216.8985 -132.164395) (xy 216.882603 -132.102481) (xy 216.874592 -132.039063) (xy 211.821057 -132.039063)
			(xy 211.053172 -132.806948) (xy 211.050467 -132.809799) (xy 211.045876 -132.816179) (xy 211.044028 -132.819648)
			(xy 211.041444 -132.825075) (xy 211.03862 -132.836754) (xy 211.03844 -132.842762) (xy 211.03844 -133.063996)
			(xy 253.124206 -133.063996) (xy 253.128277 -133.008374) (xy 253.140403 -132.953937) (xy 253.160326 -132.901846)
			(xy 253.187622 -132.853211) (xy 253.221708 -132.809068) (xy 253.261857 -132.770359) (xy 253.307215 -132.737908)
			(xy 253.356815 -132.712407) (xy 253.409599 -132.6944) (xy 253.464442 -132.68427) (xy 253.520176 -132.682233)
			(xy 253.575613 -132.688333) (xy 253.62957 -132.702439) (xy 253.680899 -132.724251) (xy 253.728505 -132.753305)
			(xy 253.771373 -132.78898) (xy 253.80859 -132.830517) (xy 253.839363 -132.87703) (xy 253.863035 -132.927527)
			(xy 253.879103 -132.980934) (xy 253.887223 -133.03611) (xy 253.887732 -133.063996) (xy 264.096498 -133.063996)
			(xy 264.100569 -133.008374) (xy 264.112695 -132.953937) (xy 264.132618 -132.901846) (xy 264.159914 -132.853211)
			(xy 264.194 -132.809068) (xy 264.234149 -132.770359) (xy 264.279507 -132.737908) (xy 264.329107 -132.712407)
			(xy 264.381891 -132.6944) (xy 264.436734 -132.68427) (xy 264.492468 -132.682233) (xy 264.547905 -132.688333)
			(xy 264.601862 -132.702439) (xy 264.653191 -132.724251) (xy 264.700797 -132.753305) (xy 264.743665 -132.78898)
			(xy 264.780882 -132.830517) (xy 264.811655 -132.87703) (xy 264.835327 -132.927527) (xy 264.837399 -132.934413)
			(xy 268.282668 -132.934413) (xy 268.282668 -132.870491) (xy 268.290679 -132.807073) (xy 268.306576 -132.745159)
			(xy 268.330108 -132.685726) (xy 268.360902 -132.629711) (xy 268.398475 -132.577996) (xy 268.442232 -132.531399)
			(xy 268.491485 -132.490654) (xy 268.545456 -132.456403) (xy 268.603295 -132.429186) (xy 268.664088 -132.409433)
			(xy 268.726878 -132.397455) (xy 268.790674 -132.393442) (xy 268.85447 -132.397455) (xy 268.91726 -132.409433)
			(xy 268.978053 -132.429186) (xy 269.035892 -132.456403) (xy 269.089863 -132.490654) (xy 269.139116 -132.531399)
			(xy 269.182873 -132.577996) (xy 269.220446 -132.629711) (xy 269.25124 -132.685726) (xy 269.274772 -132.745159)
			(xy 269.290669 -132.807073) (xy 269.29868 -132.870491) (xy 269.299182 -132.902452) (xy 269.29868 -132.934413)
			(xy 269.290669 -132.997831) (xy 269.274772 -133.059745) (xy 269.257098 -133.104382) (xy 274.430744 -133.104382)
			(xy 274.431223 -133.073987) (xy 274.438475 -133.013632) (xy 274.452874 -132.954572) (xy 274.474214 -132.897651)
			(xy 274.50219 -132.843682) (xy 274.536403 -132.793434) (xy 274.576365 -132.747626) (xy 274.598638 -132.726938)
			(xy 274.606258 -132.72008) (xy 274.61464 -132.7023) (xy 274.61972 -132.610352) (xy 274.612862 -132.591302)
			(xy 274.606258 -132.583936) (xy 274.586068 -132.560602) (xy 274.550917 -132.509885) (xy 274.522157 -132.45529)
			(xy 274.500208 -132.397618) (xy 274.485394 -132.337716) (xy 274.477932 -132.276462) (xy 274.47748 -132.245608)
			(xy 274.477964 -132.214878) (xy 274.485371 -132.153865) (xy 274.500078 -132.09419) (xy 274.521872 -132.036723)
			(xy 274.550433 -131.982301) (xy 274.585346 -131.93172) (xy 274.626101 -131.885715) (xy 274.672104 -131.844958)
			(xy 274.722684 -131.810043) (xy 274.777104 -131.78148) (xy 274.834571 -131.759684) (xy 274.894245 -131.744974)
			(xy 274.955258 -131.737565) (xy 274.985988 -131.7371) (xy 274.986242 -131.7371) (xy 275.016451 -131.737508)
			(xy 275.076444 -131.744652) (xy 275.135167 -131.758859) (xy 275.191791 -131.779929) (xy 275.245518 -131.807563)
			(xy 275.29559 -131.841372) (xy 275.318728 -131.860798) (xy 275.325794 -131.866449) (xy 275.34271 -131.872831)
			(xy 275.351748 -131.873244) (xy 275.382228 -131.873244) (xy 275.391264 -131.872814) (xy 275.408181 -131.866443)
			(xy 275.415248 -131.860798) (xy 275.43839 -131.841379) (xy 275.488471 -131.807592) (xy 275.542201 -131.779972)
			(xy 275.598823 -131.758908) (xy 275.65754 -131.744696) (xy 275.717528 -131.737535) (xy 275.747734 -131.7371)
			(xy 275.747988 -131.7371) (xy 275.77872 -131.737549) (xy 275.839736 -131.744956) (xy 275.899415 -131.759665)
			(xy 275.956885 -131.781459) (xy 276.01131 -131.810023) (xy 276.061894 -131.844938) (xy 276.107901 -131.885696)
			(xy 276.14866 -131.931703) (xy 276.183575 -131.982287) (xy 276.212139 -132.036711) (xy 276.233934 -132.094181)
			(xy 276.248643 -132.15386) (xy 276.256051 -132.214876) (xy 276.256496 -132.245608) (xy 276.25603 -132.276003)
			(xy 276.248778 -132.33636) (xy 276.234379 -132.395421) (xy 276.213037 -132.452342) (xy 276.185058 -132.506312)
			(xy 276.150842 -132.556559) (xy 276.110876 -132.602366) (xy 276.088602 -132.623052) (xy 276.080982 -132.62991)
			(xy 276.0726 -132.64769) (xy 276.06752 -132.739638) (xy 276.074378 -132.758688) (xy 276.080982 -132.766054)
			(xy 276.101158 -132.789401) (xy 276.136312 -132.840114) (xy 276.165076 -132.894706) (xy 276.187027 -132.952375)
			(xy 276.201843 -133.012276) (xy 276.209307 -133.073529) (xy 276.20976 -133.104382) (xy 276.209345 -133.135116)
			(xy 276.201938 -133.196135) (xy 276.187229 -133.255816) (xy 276.165432 -133.313289) (xy 276.136867 -133.367715)
			(xy 276.101949 -133.418301) (xy 276.061188 -133.464309) (xy 276.015177 -133.505068) (xy 275.964589 -133.539983)
			(xy 275.910161 -133.568545) (xy 275.852687 -133.590338) (xy 275.793005 -133.605043) (xy 275.731986 -133.612447)
			(xy 275.701252 -133.61289) (xy 275.700998 -133.61289) (xy 275.67079 -133.612461) (xy 275.610797 -133.605321)
			(xy 275.552075 -133.591118) (xy 275.49545 -133.570053) (xy 275.441723 -133.542422) (xy 275.391651 -133.508616)
			(xy 275.368512 -133.489192) (xy 275.361455 -133.483527) (xy 275.344533 -133.47715) (xy 275.335492 -133.476746)
			(xy 275.305012 -133.476746) (xy 275.295973 -133.47715) (xy 275.279057 -133.483539) (xy 275.271992 -133.489192)
			(xy 275.248834 -133.50859) (xy 275.198756 -133.54238) (xy 275.14503 -133.570003) (xy 275.088411 -133.591071)
			(xy 275.029697 -133.605287) (xy 274.969712 -133.612452) (xy 274.939506 -133.61289) (xy 274.939252 -133.61289)
			(xy 274.908519 -133.612489) (xy 274.847503 -133.605075) (xy 274.787824 -133.59036) (xy 274.730355 -133.56856)
			(xy 274.675932 -133.539991) (xy 274.625349 -133.505071) (xy 274.579344 -133.464309) (xy 274.538588 -133.418299)
			(xy 274.503675 -133.367711) (xy 274.475113 -133.313285) (xy 274.45332 -133.255813) (xy 274.438613 -133.196132)
			(xy 274.431207 -133.135115) (xy 274.430744 -133.104382) (xy 269.257098 -133.104382) (xy 269.25124 -133.119178)
			(xy 269.220446 -133.175193) (xy 269.182873 -133.226908) (xy 269.139116 -133.273505) (xy 269.089863 -133.31425)
			(xy 269.035892 -133.348501) (xy 268.978053 -133.375718) (xy 268.91726 -133.395471) (xy 268.85447 -133.407449)
			(xy 268.790674 -133.411463) (xy 268.726878 -133.407449) (xy 268.664088 -133.395471) (xy 268.603295 -133.375718)
			(xy 268.545456 -133.348501) (xy 268.491485 -133.31425) (xy 268.442232 -133.273505) (xy 268.398475 -133.226908)
			(xy 268.360902 -133.175193) (xy 268.330108 -133.119178) (xy 268.306576 -133.059745) (xy 268.290679 -132.997831)
			(xy 268.282668 -132.934413) (xy 264.837399 -132.934413) (xy 264.851395 -132.980934) (xy 264.859515 -133.03611)
			(xy 264.860024 -133.063996) (xy 264.859515 -133.091882) (xy 264.851395 -133.147058) (xy 264.835327 -133.200465)
			(xy 264.811655 -133.250962) (xy 264.780882 -133.297475) (xy 264.743665 -133.339012) (xy 264.700797 -133.374687)
			(xy 264.653191 -133.403741) (xy 264.601862 -133.425553) (xy 264.547905 -133.439659) (xy 264.492468 -133.445759)
			(xy 264.436734 -133.443722) (xy 264.381891 -133.433592) (xy 264.329107 -133.415585) (xy 264.279507 -133.390084)
			(xy 264.234149 -133.357633) (xy 264.194 -133.318924) (xy 264.159914 -133.274781) (xy 264.132618 -133.226146)
			(xy 264.112695 -133.174055) (xy 264.100569 -133.119618) (xy 264.096498 -133.063996) (xy 253.887732 -133.063996)
			(xy 253.887223 -133.091882) (xy 253.879103 -133.147058) (xy 253.863035 -133.200465) (xy 253.839363 -133.250962)
			(xy 253.80859 -133.297475) (xy 253.771373 -133.339012) (xy 253.728505 -133.374687) (xy 253.680899 -133.403741)
			(xy 253.62957 -133.425553) (xy 253.575613 -133.439659) (xy 253.520176 -133.445759) (xy 253.464442 -133.443722)
			(xy 253.409599 -133.433592) (xy 253.356815 -133.415585) (xy 253.307215 -133.390084) (xy 253.261857 -133.357633)
			(xy 253.221708 -133.318924) (xy 253.187622 -133.274781) (xy 253.160326 -133.226146) (xy 253.140403 -133.174055)
			(xy 253.128277 -133.119618) (xy 253.124206 -133.063996) (xy 211.03844 -133.063996) (xy 211.03844 -133.654757)
			(xy 251.982218 -133.654757) (xy 251.982218 -133.590835) (xy 251.990229 -133.527417) (xy 252.006126 -133.465503)
			(xy 252.029658 -133.40607) (xy 252.060452 -133.350055) (xy 252.098025 -133.29834) (xy 252.141782 -133.251743)
			(xy 252.191035 -133.210998) (xy 252.245006 -133.176747) (xy 252.302845 -133.14953) (xy 252.363638 -133.129777)
			(xy 252.426428 -133.117799) (xy 252.490224 -133.113786) (xy 252.55402 -133.117799) (xy 252.61681 -133.129777)
			(xy 252.677603 -133.14953) (xy 252.735442 -133.176747) (xy 252.789413 -133.210998) (xy 252.838666 -133.251743)
			(xy 252.882423 -133.29834) (xy 252.919996 -133.350055) (xy 252.95079 -133.40607) (xy 252.974322 -133.465503)
			(xy 252.990219 -133.527417) (xy 252.99823 -133.590835) (xy 252.998732 -133.622796) (xy 252.99823 -133.654757)
			(xy 254.014218 -133.654757) (xy 254.014218 -133.590835) (xy 254.022229 -133.527417) (xy 254.038126 -133.465503)
			(xy 254.061658 -133.40607) (xy 254.092452 -133.350055) (xy 254.130025 -133.29834) (xy 254.173782 -133.251743)
			(xy 254.223035 -133.210998) (xy 254.277006 -133.176747) (xy 254.334845 -133.14953) (xy 254.395638 -133.129777)
			(xy 254.458428 -133.117799) (xy 254.522224 -133.113786) (xy 254.58602 -133.117799) (xy 254.64881 -133.129777)
			(xy 254.709603 -133.14953) (xy 254.767442 -133.176747) (xy 254.821413 -133.210998) (xy 254.870666 -133.251743)
			(xy 254.914423 -133.29834) (xy 254.951996 -133.350055) (xy 254.98279 -133.40607) (xy 255.006322 -133.465503)
			(xy 255.022219 -133.527417) (xy 255.03023 -133.590835) (xy 255.030732 -133.622796) (xy 255.03023 -133.654757)
			(xy 255.022219 -133.718175) (xy 255.006322 -133.780089) (xy 254.98279 -133.839522) (xy 254.951996 -133.895537)
			(xy 254.914423 -133.947252) (xy 254.870666 -133.993849) (xy 254.821413 -134.034594) (xy 254.767442 -134.068845)
			(xy 254.709603 -134.096062) (xy 254.64881 -134.115815) (xy 254.58602 -134.127793) (xy 254.522224 -134.131807)
			(xy 254.458428 -134.127793) (xy 254.395638 -134.115815) (xy 254.334845 -134.096062) (xy 254.277006 -134.068845)
			(xy 254.223035 -134.034594) (xy 254.173782 -133.993849) (xy 254.130025 -133.947252) (xy 254.092452 -133.895537)
			(xy 254.061658 -133.839522) (xy 254.038126 -133.780089) (xy 254.022229 -133.718175) (xy 254.014218 -133.654757)
			(xy 252.99823 -133.654757) (xy 252.990219 -133.718175) (xy 252.974322 -133.780089) (xy 252.95079 -133.839522)
			(xy 252.919996 -133.895537) (xy 252.882423 -133.947252) (xy 252.838666 -133.993849) (xy 252.789413 -134.034594)
			(xy 252.735442 -134.068845) (xy 252.677603 -134.096062) (xy 252.61681 -134.115815) (xy 252.55402 -134.127793)
			(xy 252.490224 -134.131807) (xy 252.426428 -134.127793) (xy 252.363638 -134.115815) (xy 252.302845 -134.096062)
			(xy 252.245006 -134.068845) (xy 252.191035 -134.034594) (xy 252.141782 -133.993849) (xy 252.098025 -133.947252)
			(xy 252.060452 -133.895537) (xy 252.029658 -133.839522) (xy 252.006126 -133.780089) (xy 251.990229 -133.718175)
			(xy 251.982218 -133.654757) (xy 211.03844 -133.654757) (xy 211.03844 -134.257796) (xy 251.339856 -134.257796)
			(xy 251.343927 -134.202174) (xy 251.356053 -134.147737) (xy 251.375976 -134.095646) (xy 251.403272 -134.047011)
			(xy 251.437358 -134.002868) (xy 251.477507 -133.964159) (xy 251.522865 -133.931708) (xy 251.572465 -133.906207)
			(xy 251.625249 -133.8882) (xy 251.680092 -133.87807) (xy 251.735826 -133.876033) (xy 251.791263 -133.882133)
			(xy 251.84522 -133.896239) (xy 251.896549 -133.918051) (xy 251.944155 -133.947105) (xy 251.987023 -133.98278)
			(xy 252.02424 -134.024317) (xy 252.055013 -134.07083) (xy 252.078685 -134.121327) (xy 252.094753 -134.174734)
			(xy 252.102873 -134.22991) (xy 252.103382 -134.257796) (xy 253.371856 -134.257796) (xy 253.375927 -134.202174)
			(xy 253.388053 -134.147737) (xy 253.407976 -134.095646) (xy 253.435272 -134.047011) (xy 253.469358 -134.002868)
			(xy 253.509507 -133.964159) (xy 253.554865 -133.931708) (xy 253.604465 -133.906207) (xy 253.657249 -133.8882)
			(xy 253.712092 -133.87807) (xy 253.767826 -133.876033) (xy 253.823263 -133.882133) (xy 253.87722 -133.896239)
			(xy 253.928549 -133.918051) (xy 253.976155 -133.947105) (xy 254.019023 -133.98278) (xy 254.05624 -134.024317)
			(xy 254.087013 -134.07083) (xy 254.110685 -134.121327) (xy 254.126753 -134.174734) (xy 254.134873 -134.22991)
			(xy 254.135382 -134.257796) (xy 254.134873 -134.285682) (xy 254.126753 -134.340858) (xy 254.110685 -134.394265)
			(xy 254.087013 -134.444762) (xy 254.05624 -134.491275) (xy 254.019023 -134.532812) (xy 253.976155 -134.568487)
			(xy 253.928549 -134.597541) (xy 253.87722 -134.619353) (xy 253.823263 -134.633459) (xy 253.767826 -134.639559)
			(xy 253.712092 -134.637522) (xy 253.657249 -134.627392) (xy 253.604465 -134.609385) (xy 253.554865 -134.583884)
			(xy 253.509507 -134.551433) (xy 253.469358 -134.512724) (xy 253.435272 -134.468581) (xy 253.407976 -134.419946)
			(xy 253.388053 -134.367855) (xy 253.375927 -134.313418) (xy 253.371856 -134.257796) (xy 252.103382 -134.257796)
			(xy 252.102873 -134.285682) (xy 252.094753 -134.340858) (xy 252.078685 -134.394265) (xy 252.055013 -134.444762)
			(xy 252.02424 -134.491275) (xy 251.987023 -134.532812) (xy 251.944155 -134.568487) (xy 251.896549 -134.597541)
			(xy 251.84522 -134.619353) (xy 251.791263 -134.633459) (xy 251.735826 -134.639559) (xy 251.680092 -134.637522)
			(xy 251.625249 -134.627392) (xy 251.572465 -134.609385) (xy 251.522865 -134.583884) (xy 251.477507 -134.551433)
			(xy 251.437358 -134.512724) (xy 251.403272 -134.468581) (xy 251.375976 -134.419946) (xy 251.356053 -134.367855)
			(xy 251.343927 -134.313418) (xy 251.339856 -134.257796) (xy 211.03844 -134.257796) (xy 211.03844 -134.655052)
			(xy 214.279986 -134.655052) (xy 214.284057 -134.59943) (xy 214.296183 -134.544993) (xy 214.316106 -134.492902)
			(xy 214.343402 -134.444267) (xy 214.377488 -134.400124) (xy 214.417637 -134.361415) (xy 214.462995 -134.328964)
			(xy 214.512595 -134.303463) (xy 214.565379 -134.285456) (xy 214.620222 -134.275326) (xy 214.675956 -134.273289)
			(xy 214.731393 -134.279389) (xy 214.78535 -134.293495) (xy 214.836679 -134.315307) (xy 214.884285 -134.344361)
			(xy 214.927153 -134.380036) (xy 214.96437 -134.421573) (xy 214.995143 -134.468086) (xy 215.018815 -134.518583)
			(xy 215.034883 -134.57199) (xy 215.043003 -134.627166) (xy 215.043512 -134.655052) (xy 215.295986 -134.655052)
			(xy 215.300057 -134.59943) (xy 215.312183 -134.544993) (xy 215.332106 -134.492902) (xy 215.359402 -134.444267)
			(xy 215.393488 -134.400124) (xy 215.433637 -134.361415) (xy 215.478995 -134.328964) (xy 215.528595 -134.303463)
			(xy 215.581379 -134.285456) (xy 215.636222 -134.275326) (xy 215.691956 -134.273289) (xy 215.747393 -134.279389)
			(xy 215.80135 -134.293495) (xy 215.852679 -134.315307) (xy 215.900285 -134.344361) (xy 215.943153 -134.380036)
			(xy 215.98037 -134.421573) (xy 216.011143 -134.468086) (xy 216.034815 -134.518583) (xy 216.050883 -134.57199)
			(xy 216.059003 -134.627166) (xy 216.059512 -134.655052) (xy 216.059003 -134.682938) (xy 216.050883 -134.738114)
			(xy 216.034815 -134.791521) (xy 216.011143 -134.842018) (xy 215.98037 -134.888531) (xy 215.947912 -134.924757)
			(xy 251.982218 -134.924757) (xy 251.982218 -134.860835) (xy 251.990229 -134.797417) (xy 252.006126 -134.735503)
			(xy 252.029658 -134.67607) (xy 252.060452 -134.620055) (xy 252.098025 -134.56834) (xy 252.141782 -134.521743)
			(xy 252.191035 -134.480998) (xy 252.245006 -134.446747) (xy 252.302845 -134.41953) (xy 252.363638 -134.399777)
			(xy 252.426428 -134.387799) (xy 252.490224 -134.383786) (xy 252.55402 -134.387799) (xy 252.61681 -134.399777)
			(xy 252.677603 -134.41953) (xy 252.735442 -134.446747) (xy 252.789413 -134.480998) (xy 252.838666 -134.521743)
			(xy 252.882423 -134.56834) (xy 252.919996 -134.620055) (xy 252.95079 -134.67607) (xy 252.974322 -134.735503)
			(xy 252.990219 -134.797417) (xy 252.99823 -134.860835) (xy 252.998732 -134.892796) (xy 252.99823 -134.924757)
			(xy 254.014218 -134.924757) (xy 254.014218 -134.860835) (xy 254.022229 -134.797417) (xy 254.038126 -134.735503)
			(xy 254.061658 -134.67607) (xy 254.092452 -134.620055) (xy 254.130025 -134.56834) (xy 254.173782 -134.521743)
			(xy 254.223035 -134.480998) (xy 254.277006 -134.446747) (xy 254.334845 -134.41953) (xy 254.395638 -134.399777)
			(xy 254.458428 -134.387799) (xy 254.522224 -134.383786) (xy 254.58602 -134.387799) (xy 254.64881 -134.399777)
			(xy 254.709603 -134.41953) (xy 254.767442 -134.446747) (xy 254.821413 -134.480998) (xy 254.870666 -134.521743)
			(xy 254.914423 -134.56834) (xy 254.951996 -134.620055) (xy 254.98279 -134.67607) (xy 255.006322 -134.735503)
			(xy 255.022219 -134.797417) (xy 255.03023 -134.860835) (xy 255.030732 -134.892796) (xy 255.03023 -134.924757)
			(xy 255.022219 -134.988175) (xy 255.006322 -135.050089) (xy 254.98279 -135.109522) (xy 254.951996 -135.165537)
			(xy 254.914423 -135.217252) (xy 254.878737 -135.255254) (xy 256.871216 -135.255254) (xy 256.871757 -135.221922)
			(xy 256.880462 -135.155827) (xy 256.897729 -135.091438) (xy 256.923263 -135.029857) (xy 256.956626 -134.972141)
			(xy 256.997245 -134.91928) (xy 257.044424 -134.872181) (xy 257.097353 -134.83165) (xy 257.125978 -134.814564)
			(xy 257.126232 -134.814564) (xy 257.136625 -134.807762) (xy 257.149815 -134.786752) (xy 257.151378 -134.774432)
			(xy 257.159252 -134.678674) (xy 257.149092 -134.65556) (xy 257.13944 -134.647686) (xy 257.117794 -134.629451)
			(xy 257.079584 -134.5877) (xy 257.047959 -134.540764) (xy 257.023614 -134.489671) (xy 257.007083 -134.435543)
			(xy 256.998728 -134.379566) (xy 256.998216 -134.351268) (xy 256.998669 -134.325001) (xy 257.005875 -134.272964)
			(xy 257.020158 -134.222409) (xy 257.041248 -134.174295) (xy 257.068746 -134.129533) (xy 257.102131 -134.088972)
			(xy 257.121152 -134.070852) (xy 257.128478 -134.063296) (xy 257.136878 -134.044024) (xy 257.137408 -134.033514)
			(xy 257.137408 -133.958838) (xy 257.136911 -133.948317) (xy 257.12852 -133.929026) (xy 257.121152 -133.9215)
			(xy 257.102123 -133.903388) (xy 257.06874 -133.862823) (xy 257.041243 -133.818059) (xy 257.020151 -133.769944)
			(xy 257.005864 -133.719389) (xy 256.998654 -133.667351) (xy 256.998216 -133.641084) (xy 256.998702 -133.613833)
			(xy 257.006458 -133.559885) (xy 257.021813 -133.50759) (xy 257.044455 -133.458013) (xy 257.073921 -133.412163)
			(xy 257.109612 -133.370972) (xy 257.150803 -133.335281) (xy 257.196653 -133.305815) (xy 257.24623 -133.283173)
			(xy 257.298525 -133.267818) (xy 257.352473 -133.260062) (xy 257.406975 -133.260062) (xy 257.460923 -133.267818)
			(xy 257.513218 -133.283173) (xy 257.562795 -133.305815) (xy 257.608645 -133.335281) (xy 257.649836 -133.370972)
			(xy 257.685527 -133.412163) (xy 257.714993 -133.458013) (xy 257.737635 -133.50759) (xy 257.75299 -133.559885)
			(xy 257.760746 -133.613833) (xy 257.761232 -133.641084) (xy 257.761006 -133.654757) (xy 262.95451 -133.654757)
			(xy 262.95451 -133.590835) (xy 262.962521 -133.527417) (xy 262.978418 -133.465503) (xy 263.00195 -133.40607)
			(xy 263.032744 -133.350055) (xy 263.070317 -133.29834) (xy 263.114074 -133.251743) (xy 263.163327 -133.210998)
			(xy 263.217298 -133.176747) (xy 263.275137 -133.14953) (xy 263.33593 -133.129777) (xy 263.39872 -133.117799)
			(xy 263.462516 -133.113786) (xy 263.526312 -133.117799) (xy 263.589102 -133.129777) (xy 263.649895 -133.14953)
			(xy 263.707734 -133.176747) (xy 263.761705 -133.210998) (xy 263.810958 -133.251743) (xy 263.854715 -133.29834)
			(xy 263.892288 -133.350055) (xy 263.923082 -133.40607) (xy 263.946614 -133.465503) (xy 263.962511 -133.527417)
			(xy 263.970522 -133.590835) (xy 263.971024 -133.622796) (xy 263.970522 -133.654757) (xy 264.98651 -133.654757)
			(xy 264.98651 -133.590835) (xy 264.994521 -133.527417) (xy 265.010418 -133.465503) (xy 265.03395 -133.40607)
			(xy 265.064744 -133.350055) (xy 265.102317 -133.29834) (xy 265.146074 -133.251743) (xy 265.195327 -133.210998)
			(xy 265.249298 -133.176747) (xy 265.307137 -133.14953) (xy 265.36793 -133.129777) (xy 265.43072 -133.117799)
			(xy 265.494516 -133.113786) (xy 265.558312 -133.117799) (xy 265.621102 -133.129777) (xy 265.681895 -133.14953)
			(xy 265.739734 -133.176747) (xy 265.793705 -133.210998) (xy 265.842958 -133.251743) (xy 265.886715 -133.29834)
			(xy 265.924288 -133.350055) (xy 265.955082 -133.40607) (xy 265.978614 -133.465503) (xy 265.994511 -133.527417)
			(xy 266.002522 -133.590835) (xy 266.003024 -133.622796) (xy 266.002522 -133.654757) (xy 265.994511 -133.718175)
			(xy 265.978614 -133.780089) (xy 265.955082 -133.839522) (xy 265.924288 -133.895537) (xy 265.886715 -133.947252)
			(xy 265.842958 -133.993849) (xy 265.793705 -134.034594) (xy 265.739734 -134.068845) (xy 265.681895 -134.096062)
			(xy 265.621102 -134.115815) (xy 265.558312 -134.127793) (xy 265.494516 -134.131807) (xy 265.43072 -134.127793)
			(xy 265.36793 -134.115815) (xy 265.307137 -134.096062) (xy 265.249298 -134.068845) (xy 265.195327 -134.034594)
			(xy 265.146074 -133.993849) (xy 265.102317 -133.947252) (xy 265.064744 -133.895537) (xy 265.03395 -133.839522)
			(xy 265.010418 -133.780089) (xy 264.994521 -133.718175) (xy 264.98651 -133.654757) (xy 263.970522 -133.654757)
			(xy 263.962511 -133.718175) (xy 263.946614 -133.780089) (xy 263.923082 -133.839522) (xy 263.892288 -133.895537)
			(xy 263.854715 -133.947252) (xy 263.810958 -133.993849) (xy 263.761705 -134.034594) (xy 263.707734 -134.068845)
			(xy 263.649895 -134.096062) (xy 263.589102 -134.115815) (xy 263.526312 -134.127793) (xy 263.462516 -134.131807)
			(xy 263.39872 -134.127793) (xy 263.33593 -134.115815) (xy 263.275137 -134.096062) (xy 263.217298 -134.068845)
			(xy 263.163327 -134.034594) (xy 263.114074 -133.993849) (xy 263.070317 -133.947252) (xy 263.032744 -133.895537)
			(xy 263.00195 -133.839522) (xy 262.978418 -133.780089) (xy 262.962521 -133.718175) (xy 262.95451 -133.654757)
			(xy 257.761006 -133.654757) (xy 257.760798 -133.667351) (xy 257.753587 -133.719389) (xy 257.739299 -133.769943)
			(xy 257.718205 -133.818057) (xy 257.690704 -133.862818) (xy 257.657318 -133.90338) (xy 257.638296 -133.9215)
			(xy 257.630954 -133.929043) (xy 257.622561 -133.948324) (xy 257.62204 -133.958838) (xy 257.62204 -134.033514)
			(xy 257.622495 -134.04404) (xy 257.630914 -134.063332) (xy 257.638296 -134.070852) (xy 257.657311 -134.088978)
			(xy 257.690693 -134.129541) (xy 257.718191 -134.174302) (xy 257.739285 -134.222414) (xy 257.753575 -134.272966)
			(xy 257.760791 -134.325002) (xy 257.761232 -134.351268) (xy 257.760715 -134.379565) (xy 257.752351 -134.435539)
			(xy 257.735817 -134.489665) (xy 257.73326 -134.495032) (xy 263.80262 -134.495032) (xy 263.806691 -134.43941)
			(xy 263.818817 -134.384973) (xy 263.83874 -134.332882) (xy 263.866036 -134.284247) (xy 263.900122 -134.240104)
			(xy 263.940271 -134.201395) (xy 263.985629 -134.168944) (xy 264.035229 -134.143443) (xy 264.088013 -134.125436)
			(xy 264.142856 -134.115306) (xy 264.19859 -134.113269) (xy 264.254027 -134.119369) (xy 264.307984 -134.133475)
			(xy 264.359313 -134.155287) (xy 264.406919 -134.184341) (xy 264.449787 -134.220016) (xy 264.487004 -134.261553)
			(xy 264.517777 -134.308066) (xy 264.541449 -134.358563) (xy 264.557517 -134.41197) (xy 264.565637 -134.467146)
			(xy 264.566146 -134.495032) (xy 264.565637 -134.522918) (xy 264.557517 -134.578094) (xy 264.541449 -134.631501)
			(xy 264.517777 -134.681998) (xy 264.487004 -134.728511) (xy 264.449787 -134.770048) (xy 264.406919 -134.805723)
			(xy 264.359313 -134.834777) (xy 264.307984 -134.856589) (xy 264.254027 -134.870695) (xy 264.19859 -134.876795)
			(xy 264.142856 -134.874758) (xy 264.088013 -134.864628) (xy 264.035229 -134.846621) (xy 263.985629 -134.82112)
			(xy 263.940271 -134.788669) (xy 263.900122 -134.74996) (xy 263.866036 -134.705817) (xy 263.83874 -134.657182)
			(xy 263.818817 -134.605091) (xy 263.806691 -134.550654) (xy 263.80262 -134.495032) (xy 257.73326 -134.495032)
			(xy 257.711474 -134.540758) (xy 257.679857 -134.587697) (xy 257.641657 -134.629456) (xy 257.620008 -134.647686)
			(xy 257.610356 -134.65556) (xy 257.600196 -134.678674) (xy 257.60807 -134.774432) (xy 257.609564 -134.786777)
			(xy 257.622766 -134.80782) (xy 257.633216 -134.814564) (xy 257.63347 -134.814564) (xy 257.662073 -134.831686)
			(xy 257.715002 -134.872212) (xy 257.762182 -134.919307) (xy 257.802804 -134.972163) (xy 257.836172 -135.029873)
			(xy 257.861713 -135.091448) (xy 257.87899 -135.155833) (xy 257.887706 -135.221923) (xy 257.888232 -135.255254)
			(xy 257.88773 -135.287215) (xy 257.879719 -135.350633) (xy 257.863822 -135.412547) (xy 257.84029 -135.47198)
			(xy 257.809496 -135.527995) (xy 257.771923 -135.57971) (xy 257.728166 -135.626307) (xy 257.678913 -135.667052)
			(xy 257.624942 -135.701303) (xy 257.567103 -135.72852) (xy 257.50631 -135.748273) (xy 257.44352 -135.760251)
			(xy 257.379724 -135.764265) (xy 257.315928 -135.760251) (xy 257.253138 -135.748273) (xy 257.192345 -135.72852)
			(xy 257.134506 -135.701303) (xy 257.080535 -135.667052) (xy 257.031282 -135.626307) (xy 256.987525 -135.57971)
			(xy 256.949952 -135.527995) (xy 256.919158 -135.47198) (xy 256.895626 -135.412547) (xy 256.879729 -135.350633)
			(xy 256.871718 -135.287215) (xy 256.871216 -135.255254) (xy 254.878737 -135.255254) (xy 254.870666 -135.263849)
			(xy 254.821413 -135.304594) (xy 254.767442 -135.338845) (xy 254.709603 -135.366062) (xy 254.64881 -135.385815)
			(xy 254.58602 -135.397793) (xy 254.522224 -135.401807) (xy 254.458428 -135.397793) (xy 254.395638 -135.385815)
			(xy 254.334845 -135.366062) (xy 254.277006 -135.338845) (xy 254.223035 -135.304594) (xy 254.173782 -135.263849)
			(xy 254.130025 -135.217252) (xy 254.092452 -135.165537) (xy 254.061658 -135.109522) (xy 254.038126 -135.050089)
			(xy 254.022229 -134.988175) (xy 254.014218 -134.924757) (xy 252.99823 -134.924757) (xy 252.990219 -134.988175)
			(xy 252.974322 -135.050089) (xy 252.95079 -135.109522) (xy 252.919996 -135.165537) (xy 252.882423 -135.217252)
			(xy 252.838666 -135.263849) (xy 252.789413 -135.304594) (xy 252.735442 -135.338845) (xy 252.677603 -135.366062)
			(xy 252.61681 -135.385815) (xy 252.55402 -135.397793) (xy 252.490224 -135.401807) (xy 252.426428 -135.397793)
			(xy 252.363638 -135.385815) (xy 252.302845 -135.366062) (xy 252.245006 -135.338845) (xy 252.191035 -135.304594)
			(xy 252.141782 -135.263849) (xy 252.098025 -135.217252) (xy 252.060452 -135.165537) (xy 252.029658 -135.109522)
			(xy 252.006126 -135.050089) (xy 251.990229 -134.988175) (xy 251.982218 -134.924757) (xy 215.947912 -134.924757)
			(xy 215.943153 -134.930068) (xy 215.900285 -134.965743) (xy 215.852679 -134.994797) (xy 215.80135 -135.016609)
			(xy 215.747393 -135.030715) (xy 215.691956 -135.036815) (xy 215.636222 -135.034778) (xy 215.581379 -135.024648)
			(xy 215.528595 -135.006641) (xy 215.478995 -134.98114) (xy 215.433637 -134.948689) (xy 215.393488 -134.90998)
			(xy 215.359402 -134.865837) (xy 215.332106 -134.817202) (xy 215.312183 -134.765111) (xy 215.300057 -134.710674)
			(xy 215.295986 -134.655052) (xy 215.043512 -134.655052) (xy 215.043003 -134.682938) (xy 215.034883 -134.738114)
			(xy 215.018815 -134.791521) (xy 214.995143 -134.842018) (xy 214.96437 -134.888531) (xy 214.927153 -134.930068)
			(xy 214.884285 -134.965743) (xy 214.836679 -134.994797) (xy 214.78535 -135.016609) (xy 214.731393 -135.030715)
			(xy 214.675956 -135.036815) (xy 214.620222 -135.034778) (xy 214.565379 -135.024648) (xy 214.512595 -135.006641)
			(xy 214.462995 -134.98114) (xy 214.417637 -134.948689) (xy 214.377488 -134.90998) (xy 214.343402 -134.865837)
			(xy 214.316106 -134.817202) (xy 214.296183 -134.765111) (xy 214.284057 -134.710674) (xy 214.279986 -134.655052)
			(xy 211.03844 -134.655052) (xy 211.03844 -135.111998) (xy 211.039456 -135.121396) (xy 211.039456 -135.121904)
			(xy 211.040647 -135.127134) (xy 211.044872 -135.136992) (xy 211.047838 -135.141462) (xy 211.053172 -135.147812)
			(xy 211.83375 -135.92839) (xy 214.145022 -135.92839) (xy 214.147632 -135.865364) (xy 214.158018 -135.803146)
			(xy 214.176021 -135.74269) (xy 214.201363 -135.684925) (xy 214.233656 -135.630738) (xy 214.272403 -135.580962)
			(xy 214.31701 -135.536361) (xy 214.366791 -135.49762) (xy 214.420982 -135.465334) (xy 214.47875 -135.439999)
			(xy 214.539208 -135.422004) (xy 214.601428 -135.411625) (xy 214.664454 -135.409023) (xy 214.727318 -135.414236)
			(xy 214.789054 -135.427185) (xy 214.848714 -135.447672) (xy 214.905382 -135.47538) (xy 214.958188 -135.509885)
			(xy 215.00632 -135.550657) (xy 215.049039 -135.597069) (xy 215.085689 -135.648409) (xy 215.115707 -135.703888)
			(xy 215.138633 -135.762654) (xy 215.154113 -135.823804) (xy 215.161911 -135.8864) (xy 215.162384 -135.91794)
			(xy 215.162361 -135.919421) (xy 262.641328 -135.919421) (xy 262.641328 -135.855499) (xy 262.649339 -135.792081)
			(xy 262.665236 -135.730167) (xy 262.688768 -135.670734) (xy 262.719562 -135.614719) (xy 262.757135 -135.563004)
			(xy 262.800892 -135.516407) (xy 262.850145 -135.475662) (xy 262.904116 -135.441411) (xy 262.961955 -135.414194)
			(xy 263.022748 -135.394441) (xy 263.085538 -135.382463) (xy 263.149334 -135.37845) (xy 263.21313 -135.382463)
			(xy 263.27592 -135.394441) (xy 263.336713 -135.414194) (xy 263.394552 -135.441411) (xy 263.448523 -135.475662)
			(xy 263.497776 -135.516407) (xy 263.541533 -135.563004) (xy 263.579106 -135.614719) (xy 263.6099 -135.670734)
			(xy 263.616244 -135.686757) (xy 264.98651 -135.686757) (xy 264.98651 -135.622835) (xy 264.994521 -135.559417)
			(xy 265.010418 -135.497503) (xy 265.03395 -135.43807) (xy 265.064744 -135.382055) (xy 265.102317 -135.33034)
			(xy 265.146074 -135.283743) (xy 265.195327 -135.242998) (xy 265.249298 -135.208747) (xy 265.307137 -135.18153)
			(xy 265.36793 -135.161777) (xy 265.43072 -135.149799) (xy 265.494516 -135.145786) (xy 265.558312 -135.149799)
			(xy 265.621102 -135.161777) (xy 265.681895 -135.18153) (xy 265.739734 -135.208747) (xy 265.793705 -135.242998)
			(xy 265.842958 -135.283743) (xy 265.886715 -135.33034) (xy 265.924288 -135.382055) (xy 265.955082 -135.43807)
			(xy 265.978614 -135.497503) (xy 265.994511 -135.559417) (xy 266.002522 -135.622835) (xy 266.003024 -135.654796)
			(xy 266.002522 -135.686757) (xy 265.994511 -135.750175) (xy 265.978614 -135.812089) (xy 265.955082 -135.871522)
			(xy 265.924288 -135.927537) (xy 265.886715 -135.979252) (xy 265.842958 -136.025849) (xy 265.793705 -136.066594)
			(xy 265.739734 -136.100845) (xy 265.681895 -136.128062) (xy 265.621102 -136.147815) (xy 265.558312 -136.159793)
			(xy 265.494516 -136.163807) (xy 265.43072 -136.159793) (xy 265.36793 -136.147815) (xy 265.307137 -136.128062)
			(xy 265.249298 -136.100845) (xy 265.195327 -136.066594) (xy 265.146074 -136.025849) (xy 265.102317 -135.979252)
			(xy 265.064744 -135.927537) (xy 265.03395 -135.871522) (xy 265.010418 -135.812089) (xy 264.994521 -135.750175)
			(xy 264.98651 -135.686757) (xy 263.616244 -135.686757) (xy 263.633432 -135.730167) (xy 263.649329 -135.792081)
			(xy 263.65734 -135.855499) (xy 263.657842 -135.88746) (xy 263.65734 -135.919421) (xy 263.649329 -135.982839)
			(xy 263.633432 -136.044753) (xy 263.6099 -136.104186) (xy 263.579106 -136.160201) (xy 263.541533 -136.211916)
			(xy 263.497776 -136.258513) (xy 263.448523 -136.299258) (xy 263.394552 -136.333509) (xy 263.336713 -136.360726)
			(xy 263.27592 -136.380479) (xy 263.21313 -136.392457) (xy 263.149334 -136.396471) (xy 263.085538 -136.392457)
			(xy 263.022748 -136.380479) (xy 262.961955 -136.360726) (xy 262.904116 -136.333509) (xy 262.850145 -136.299258)
			(xy 262.800892 -136.258513) (xy 262.757135 -136.211916) (xy 262.719562 -136.160201) (xy 262.688768 -136.104186)
			(xy 262.665236 -136.044753) (xy 262.649339 -135.982839) (xy 262.641328 -135.919421) (xy 215.162361 -135.919421)
			(xy 215.161887 -135.95027) (xy 215.15368 -136.014407) (xy 215.137391 -136.076982) (xy 215.125808 -136.10717)
			(xy 215.120988 -136.120398) (xy 215.118033 -136.148385) (xy 215.122838 -136.176115) (xy 215.135035 -136.201476)
			(xy 215.153697 -136.222541) (xy 215.177405 -136.237706) (xy 215.204354 -136.245816) (xy 215.232493 -136.246255)
			(xy 215.246204 -136.24306) (xy 215.278132 -136.235136) (xy 215.34336 -136.226597) (xy 215.376252 -136.226042)
			(xy 215.377014 -136.226042) (xy 215.408553 -136.226482) (xy 215.471147 -136.234286) (xy 215.532296 -136.249773)
			(xy 215.591059 -136.272703) (xy 215.646534 -136.302726) (xy 215.69787 -136.33938) (xy 215.744278 -136.382103)
			(xy 215.785046 -136.430237) (xy 215.819547 -136.483044) (xy 215.847251 -136.539714) (xy 215.867733 -136.599374)
			(xy 215.880678 -136.66111) (xy 215.885888 -136.723974) (xy 215.885624 -136.730358) (xy 259.381109 -136.730358)
			(xy 259.381109 -136.675842) (xy 259.388868 -136.62188) (xy 259.404228 -136.569573) (xy 259.426877 -136.519984)
			(xy 259.456352 -136.474123) (xy 259.492055 -136.432924) (xy 259.533258 -136.397226) (xy 259.579122 -136.367756)
			(xy 259.628714 -136.345113) (xy 259.681024 -136.329759) (xy 259.734986 -136.322006) (xy 259.762244 -136.321546)
			(xy 259.789689 -136.322059) (xy 259.844014 -136.329905) (xy 259.896653 -136.345458) (xy 259.94652 -136.368395)
			(xy 259.992583 -136.398244) (xy 260.033892 -136.434387) (xy 260.069593 -136.476079) (xy 260.098949 -136.522458)
			(xy 260.121353 -136.572566) (xy 260.136344 -136.625368) (xy 260.14045 -136.652508) (xy 260.142695 -136.666102)
			(xy 260.153534 -136.691422) (xy 260.170755 -136.712918) (xy 260.1931 -136.729022) (xy 260.21894 -136.738557)
			(xy 260.246389 -136.74083) (xy 260.273445 -136.735673) (xy 260.285992 -136.729978) (xy 260.312217 -136.717573)
			(xy 260.366868 -136.698106) (xy 260.423377 -136.684971) (xy 260.481013 -136.678339) (xy 260.51002 -136.677908)
			(xy 260.510274 -136.677908) (xy 260.541817 -136.67834) (xy 260.604418 -136.68614) (xy 260.665574 -136.701624)
			(xy 260.669239 -136.703054) (xy 261.835898 -136.703054) (xy 261.839969 -136.647432) (xy 261.852095 -136.592995)
			(xy 261.872018 -136.540904) (xy 261.899314 -136.492269) (xy 261.9334 -136.448126) (xy 261.973549 -136.409417)
			(xy 262.018907 -136.376966) (xy 262.068507 -136.351465) (xy 262.121291 -136.333458) (xy 262.176134 -136.323328)
			(xy 262.231868 -136.321291) (xy 262.287305 -136.327391) (xy 262.341262 -136.341497) (xy 262.392591 -136.363309)
			(xy 262.440197 -136.392363) (xy 262.483065 -136.428038) (xy 262.520282 -136.469575) (xy 262.551055 -136.516088)
			(xy 262.574727 -136.566585) (xy 262.590795 -136.619992) (xy 262.598915 -136.675168) (xy 262.599424 -136.703054)
			(xy 262.598915 -136.73094) (xy 262.590795 -136.786116) (xy 262.574727 -136.839523) (xy 262.551055 -136.89002)
			(xy 262.520282 -136.936533) (xy 262.483065 -136.97807) (xy 262.440197 -137.013745) (xy 262.392591 -137.042799)
			(xy 262.341262 -137.064611) (xy 262.287305 -137.078717) (xy 262.231868 -137.084817) (xy 262.176134 -137.08278)
			(xy 262.121291 -137.07265) (xy 262.068507 -137.054643) (xy 262.018907 -137.029142) (xy 261.973549 -136.996691)
			(xy 261.9334 -136.957982) (xy 261.899314 -136.913839) (xy 261.872018 -136.865204) (xy 261.852095 -136.813113)
			(xy 261.839969 -136.758676) (xy 261.835898 -136.703054) (xy 260.669239 -136.703054) (xy 260.724345 -136.724553)
			(xy 260.779829 -136.754576) (xy 260.831173 -136.791231) (xy 260.877588 -136.833955) (xy 260.918363 -136.882093)
			(xy 260.95287 -136.934904) (xy 260.980579 -136.991578) (xy 261.001066 -137.051245) (xy 261.013798 -137.111951)
			(xy 262.966448 -137.111951) (xy 262.966448 -137.048029) (xy 262.974459 -136.984611) (xy 262.990356 -136.922697)
			(xy 263.013888 -136.863264) (xy 263.044682 -136.807249) (xy 263.082255 -136.755534) (xy 263.126012 -136.708937)
			(xy 263.175265 -136.668192) (xy 263.229236 -136.633941) (xy 263.287075 -136.606724) (xy 263.347868 -136.586971)
			(xy 263.410658 -136.574993) (xy 263.474454 -136.57098) (xy 263.53825 -136.574993) (xy 263.60104 -136.586971)
			(xy 263.661833 -136.606724) (xy 263.719672 -136.633941) (xy 263.773643 -136.668192) (xy 263.822896 -136.708937)
			(xy 263.866653 -136.755534) (xy 263.904226 -136.807249) (xy 263.93502 -136.863264) (xy 263.958552 -136.922697)
			(xy 263.974449 -136.984611) (xy 263.98246 -137.048029) (xy 263.982962 -137.07999) (xy 263.98246 -137.111951)
			(xy 263.974449 -137.175369) (xy 263.958552 -137.237283) (xy 263.93502 -137.296716) (xy 263.904226 -137.352731)
			(xy 263.866653 -137.404446) (xy 263.862658 -137.4087) (xy 264.664634 -137.4087) (xy 264.668649 -137.344896)
			(xy 264.680628 -137.282098) (xy 264.700384 -137.221297) (xy 264.727605 -137.163452) (xy 264.761861 -137.109474)
			(xy 264.802612 -137.060216) (xy 264.849215 -137.016453) (xy 264.900937 -136.978877) (xy 264.95696 -136.948079)
			(xy 265.016401 -136.924546) (xy 265.078323 -136.908649) (xy 265.141749 -136.900638) (xy 265.173714 -136.900158)
			(xy 265.205681 -136.900682) (xy 265.269111 -136.908698) (xy 265.331036 -136.924602) (xy 265.390479 -136.948144)
			(xy 265.446502 -136.978951) (xy 265.498221 -137.016538) (xy 265.544821 -137.060311) (xy 265.585565 -137.109581)
			(xy 265.619813 -137.16357) (xy 265.647022 -137.221426) (xy 265.666764 -137.282236) (xy 265.678728 -137.345041)
			(xy 265.681206 -137.376916) (xy 265.682404 -137.390346) (xy 265.691021 -137.415888) (xy 265.70603 -137.43828)
			(xy 265.72638 -137.455958) (xy 265.750651 -137.467686) (xy 265.777147 -137.472646) (xy 265.804017 -137.470491)
			(xy 265.816842 -137.466324) (xy 265.844502 -137.456817) (xy 265.901451 -137.443477) (xy 265.959555 -137.436763)
			(xy 265.9888 -137.436352) (xy 266.020759 -137.436934) (xy 266.084172 -137.444945) (xy 266.146081 -137.46084)
			(xy 266.205509 -137.48437) (xy 266.26152 -137.515162) (xy 266.31323 -137.552731) (xy 266.359824 -137.596486)
			(xy 266.400566 -137.645735) (xy 266.434814 -137.699702) (xy 266.462029 -137.757535) (xy 266.48178 -137.818324)
			(xy 266.493757 -137.881109) (xy 266.497771 -137.9449) (xy 266.493757 -138.008691) (xy 266.48178 -138.071476)
			(xy 266.462029 -138.132265) (xy 266.434814 -138.190098) (xy 266.400566 -138.244065) (xy 266.359824 -138.293314)
			(xy 266.31323 -138.337069) (xy 266.26152 -138.374638) (xy 266.205509 -138.40543) (xy 266.146081 -138.42896)
			(xy 266.084172 -138.444855) (xy 266.020759 -138.452866) (xy 265.9888 -138.453368) (xy 265.956834 -138.452807)
			(xy 265.893406 -138.444793) (xy 265.831483 -138.428891) (xy 265.772042 -138.405353) (xy 265.71602 -138.374549)
			(xy 265.664302 -138.336965) (xy 265.617703 -138.293195) (xy 265.576958 -138.243929) (xy 265.542709 -138.189945)
			(xy 265.515499 -138.132092) (xy 265.495754 -138.071286) (xy 265.483788 -138.008483) (xy 265.481308 -137.97661)
			(xy 265.480072 -137.963184) (xy 265.471462 -137.937645) (xy 265.456461 -137.915253) (xy 265.436117 -137.897575)
			(xy 265.411851 -137.885845) (xy 265.38536 -137.880884) (xy 265.358495 -137.883036) (xy 265.345672 -137.887202)
			(xy 265.318011 -137.896706) (xy 265.261063 -137.910047) (xy 265.202959 -137.916762) (xy 265.173714 -137.917174)
			(xy 265.141749 -137.916762) (xy 265.078323 -137.908751) (xy 265.016401 -137.892854) (xy 264.95696 -137.869321)
			(xy 264.900937 -137.838523) (xy 264.849215 -137.800947) (xy 264.802612 -137.757184) (xy 264.761861 -137.707926)
			(xy 264.727605 -137.653948) (xy 264.700384 -137.596103) (xy 264.680628 -137.535302) (xy 264.668649 -137.472504)
			(xy 264.664634 -137.4087) (xy 263.862658 -137.4087) (xy 263.822896 -137.451043) (xy 263.773643 -137.491788)
			(xy 263.719672 -137.526039) (xy 263.661833 -137.553256) (xy 263.60104 -137.573009) (xy 263.53825 -137.584987)
			(xy 263.474454 -137.589001) (xy 263.410658 -137.584987) (xy 263.347868 -137.573009) (xy 263.287075 -137.553256)
			(xy 263.229236 -137.526039) (xy 263.175265 -137.491788) (xy 263.126012 -137.451043) (xy 263.082255 -137.404446)
			(xy 263.044682 -137.352731) (xy 263.013888 -137.296716) (xy 262.990356 -137.237283) (xy 262.974459 -137.175369)
			(xy 262.966448 -137.111951) (xy 261.013798 -137.111951) (xy 261.014015 -137.112987) (xy 261.019227 -137.175857)
			(xy 261.016623 -137.238889) (xy 261.006242 -137.301114) (xy 260.988244 -137.361578) (xy 260.962906 -137.419351)
			(xy 260.930615 -137.473547) (xy 260.891869 -137.523332) (xy 260.847263 -137.567942) (xy 260.797481 -137.606692)
			(xy 260.743289 -137.638986) (xy 260.685518 -137.66433) (xy 260.625055 -137.682333) (xy 260.562831 -137.692719)
			(xy 260.499799 -137.695328) (xy 260.436929 -137.690121) (xy 260.375185 -137.677177) (xy 260.315517 -137.656695)
			(xy 260.258841 -137.628991) (xy 260.206026 -137.594488) (xy 260.157885 -137.553717) (xy 260.115157 -137.507305)
			(xy 260.078498 -137.455965) (xy 260.048471 -137.400483) (xy 260.025537 -137.341714) (xy 260.010048 -137.28056)
			(xy 260.002243 -137.217959) (xy 260.001766 -137.186416) (xy 260.00202 -137.169398) (xy 260.002082 -137.155623)
			(xy 259.995595 -137.128859) (xy 259.982198 -137.104798) (xy 259.962865 -137.085186) (xy 259.938997 -137.071447)
			(xy 259.912329 -137.064578) (xy 259.884794 -137.065078) (xy 259.871464 -137.06856) (xy 259.844782 -137.076044)
			(xy 259.789952 -137.084071) (xy 259.762244 -137.084562) (xy 259.734986 -137.084194) (xy 259.681024 -137.076441)
			(xy 259.628714 -137.061087) (xy 259.579122 -137.038444) (xy 259.533258 -137.008974) (xy 259.492055 -136.973276)
			(xy 259.456352 -136.932077) (xy 259.426877 -136.886216) (xy 259.404228 -136.836627) (xy 259.388868 -136.78432)
			(xy 259.381109 -136.730358) (xy 215.885624 -136.730358) (xy 215.883282 -136.786998) (xy 215.872901 -136.849217)
			(xy 215.854903 -136.909674) (xy 215.829566 -136.96744) (xy 215.797279 -137.021629) (xy 215.758537 -137.071408)
			(xy 215.713935 -137.116013) (xy 215.664159 -137.154759) (xy 215.609972 -137.18705) (xy 215.552207 -137.212391)
			(xy 215.491752 -137.230393) (xy 215.429534 -137.240778) (xy 215.36651 -137.243388) (xy 215.303646 -137.238183)
			(xy 215.241909 -137.225242) (xy 215.182247 -137.204764) (xy 215.125576 -137.177064) (xy 215.072766 -137.142567)
			(xy 215.024629 -137.101803) (xy 214.981903 -137.055398) (xy 214.945245 -137.004065) (xy 214.915218 -136.948591)
			(xy 214.892284 -136.88983) (xy 214.876793 -136.828683) (xy 214.868985 -136.766089) (xy 214.868506 -136.73455)
			(xy 214.869 -136.70222) (xy 214.877209 -136.638083) (xy 214.893499 -136.575508) (xy 214.905082 -136.54532)
			(xy 214.909925 -136.5321) (xy 214.912879 -136.504109) (xy 214.908072 -136.476376) (xy 214.895872 -136.451012)
			(xy 214.877206 -136.429945) (xy 214.853494 -136.414781) (xy 214.826542 -136.406671) (xy 214.798399 -136.406234)
			(xy 214.784686 -136.40943) (xy 214.752758 -136.417356) (xy 214.68753 -136.425894) (xy 214.654638 -136.426448)
			(xy 214.653876 -136.426448) (xy 214.622336 -136.425907) (xy 214.559742 -136.418101) (xy 214.498593 -136.402613)
			(xy 214.43983 -136.37968) (xy 214.384355 -136.349655) (xy 214.333019 -136.312998) (xy 214.286612 -136.270273)
			(xy 214.245847 -136.222136) (xy 214.211348 -136.169326) (xy 214.183647 -136.112655) (xy 214.163168 -136.052992)
			(xy 214.150227 -135.991254) (xy 214.145022 -135.92839) (xy 211.83375 -135.92839) (xy 213.064852 -137.159492)
			(xy 213.071705 -137.166888) (xy 213.07945 -137.185486) (xy 213.079838 -137.19556) (xy 213.079838 -137.419799)
			(xy 234.881414 -137.419799) (xy 234.881414 -137.355877) (xy 234.889425 -137.292459) (xy 234.905322 -137.230545)
			(xy 234.928854 -137.171112) (xy 234.959648 -137.115097) (xy 234.997221 -137.063382) (xy 235.040978 -137.016785)
			(xy 235.090231 -136.97604) (xy 235.144202 -136.941789) (xy 235.202041 -136.914572) (xy 235.262834 -136.894819)
			(xy 235.325624 -136.882841) (xy 235.38942 -136.878828) (xy 235.453216 -136.882841) (xy 235.516006 -136.894819)
			(xy 235.576799 -136.914572) (xy 235.634638 -136.941789) (xy 235.688609 -136.97604) (xy 235.737862 -137.016785)
			(xy 235.781619 -137.063382) (xy 235.819192 -137.115097) (xy 235.849986 -137.171112) (xy 235.873518 -137.230545)
			(xy 235.889415 -137.292459) (xy 235.897426 -137.355877) (xy 235.897928 -137.387838) (xy 235.897426 -137.419799)
			(xy 235.889415 -137.483217) (xy 235.873518 -137.545131) (xy 235.849986 -137.604564) (xy 235.819192 -137.660579)
			(xy 235.781619 -137.712294) (xy 235.737862 -137.758891) (xy 235.688609 -137.799636) (xy 235.634638 -137.833887)
			(xy 235.576799 -137.861104) (xy 235.516006 -137.880857) (xy 235.453216 -137.892835) (xy 235.38942 -137.896849)
			(xy 235.325624 -137.892835) (xy 235.262834 -137.880857) (xy 235.202041 -137.861104) (xy 235.144202 -137.833887)
			(xy 235.090231 -137.799636) (xy 235.040978 -137.758891) (xy 234.997221 -137.712294) (xy 234.959648 -137.660579)
			(xy 234.928854 -137.604564) (xy 234.905322 -137.545131) (xy 234.889425 -137.483217) (xy 234.881414 -137.419799)
			(xy 213.079838 -137.419799) (xy 213.079838 -138.173417) (xy 214.056208 -138.173417) (xy 214.056208 -138.109495)
			(xy 214.064219 -138.046077) (xy 214.080116 -137.984163) (xy 214.103648 -137.92473) (xy 214.134442 -137.868715)
			(xy 214.172015 -137.817) (xy 214.215772 -137.770403) (xy 214.265025 -137.729658) (xy 214.318996 -137.695407)
			(xy 214.376835 -137.66819) (xy 214.437628 -137.648437) (xy 214.500418 -137.636459) (xy 214.564214 -137.632446)
			(xy 214.62801 -137.636459) (xy 214.6908 -137.648437) (xy 214.751593 -137.66819) (xy 214.809432 -137.695407)
			(xy 214.863403 -137.729658) (xy 214.912656 -137.770403) (xy 214.956413 -137.817) (xy 214.993986 -137.868715)
			(xy 215.02478 -137.92473) (xy 215.048312 -137.984163) (xy 215.064209 -138.046077) (xy 215.07222 -138.109495)
			(xy 215.072722 -138.141456) (xy 215.07222 -138.173417) (xy 215.064209 -138.236835) (xy 215.048312 -138.298749)
			(xy 215.02478 -138.358182) (xy 214.993986 -138.414197) (xy 214.956413 -138.465912) (xy 214.912656 -138.512509)
			(xy 214.863403 -138.553254) (xy 214.809432 -138.587505) (xy 214.751593 -138.614722) (xy 214.6908 -138.634475)
			(xy 214.62801 -138.646453) (xy 214.564214 -138.650467) (xy 214.500418 -138.646453) (xy 214.437628 -138.634475)
			(xy 214.376835 -138.614722) (xy 214.318996 -138.587505) (xy 214.265025 -138.553254) (xy 214.215772 -138.512509)
			(xy 214.172015 -138.465912) (xy 214.134442 -138.414197) (xy 214.103648 -138.358182) (xy 214.080116 -138.298749)
			(xy 214.064219 -138.236835) (xy 214.056208 -138.173417) (xy 213.079838 -138.173417) (xy 213.079838 -138.580368)
			(xy 213.080353 -138.590268) (xy 213.087929 -138.608568) (xy 213.09457 -138.615928) (xy 213.580175 -139.101533)
			(xy 225.138482 -139.101533) (xy 225.138482 -139.037611) (xy 225.146493 -138.974193) (xy 225.16239 -138.912279)
			(xy 225.185922 -138.852846) (xy 225.216716 -138.796831) (xy 225.254289 -138.745116) (xy 225.298046 -138.698519)
			(xy 225.347299 -138.657774) (xy 225.40127 -138.623523) (xy 225.459109 -138.596306) (xy 225.519902 -138.576553)
			(xy 225.582692 -138.564575) (xy 225.646488 -138.560562) (xy 225.710284 -138.564575) (xy 225.773074 -138.576553)
			(xy 225.833867 -138.596306) (xy 225.891706 -138.623523) (xy 225.945677 -138.657774) (xy 225.99493 -138.698519)
			(xy 226.038687 -138.745116) (xy 226.07626 -138.796831) (xy 226.107054 -138.852846) (xy 226.130586 -138.912279)
			(xy 226.146483 -138.974193) (xy 226.154494 -139.037611) (xy 226.154996 -139.069572) (xy 226.154494 -139.101533)
			(xy 226.146483 -139.164951) (xy 226.130586 -139.226865) (xy 226.107054 -139.286298) (xy 226.07626 -139.342313)
			(xy 226.038687 -139.394028) (xy 225.99493 -139.440625) (xy 225.945677 -139.48137) (xy 225.891706 -139.515621)
			(xy 225.833867 -139.542838) (xy 225.773074 -139.562591) (xy 225.710284 -139.574569) (xy 225.646488 -139.578583)
			(xy 225.582692 -139.574569) (xy 225.519902 -139.562591) (xy 225.459109 -139.542838) (xy 225.40127 -139.515621)
			(xy 225.347299 -139.48137) (xy 225.298046 -139.440625) (xy 225.254289 -139.394028) (xy 225.216716 -139.342313)
			(xy 225.185922 -139.286298) (xy 225.16239 -139.226865) (xy 225.146493 -139.164951) (xy 225.138482 -139.101533)
			(xy 213.580175 -139.101533) (xy 214.067942 -139.5893) (xy 232.556724 -139.5893) (xy 232.560739 -139.525494)
			(xy 232.572719 -139.462694) (xy 232.592476 -139.401891) (xy 232.619698 -139.344043) (xy 232.653956 -139.290064)
			(xy 232.694709 -139.240804) (xy 232.741315 -139.197041) (xy 232.793039 -139.159464) (xy 232.849064 -139.128666)
			(xy 232.908508 -139.105133) (xy 232.970433 -139.089237) (xy 233.033862 -139.081227) (xy 233.065828 -139.080748)
			(xy 233.096251 -139.081169) (xy 233.156662 -139.088436) (xy 233.215773 -139.102864) (xy 233.272738 -139.124246)
			(xy 233.326744 -139.152275) (xy 233.377017 -139.186552) (xy 233.422838 -139.226586) (xy 233.443526 -139.248896)
			(xy 233.44378 -139.24915) (xy 233.451866 -139.2571) (xy 233.472827 -139.265673) (xy 233.484166 -139.26566)
			(xy 233.575098 -139.26058) (xy 233.59491 -139.249658) (xy 233.601768 -139.240514) (xy 233.601768 -139.240006)
			(xy 233.619726 -139.215804) (xy 233.660425 -139.171355) (xy 233.706094 -139.132029) (xy 233.75609 -139.098377)
			(xy 233.809713 -139.07087) (xy 233.866212 -139.049894) (xy 233.924794 -139.035744) (xy 233.984639 -139.028617)
			(xy 234.014772 -139.02817) (xy 234.046734 -139.028693) (xy 234.110155 -139.036702) (xy 234.172071 -139.052596)
			(xy 234.231507 -139.076126) (xy 234.287526 -139.106919) (xy 234.339243 -139.144491) (xy 234.385843 -139.188249)
			(xy 234.426591 -139.237503) (xy 234.460844 -139.291475) (xy 234.488063 -139.349315) (xy 234.507817 -139.41011)
			(xy 234.519796 -139.472902) (xy 234.52381 -139.5367) (xy 234.519796 -139.600498) (xy 234.507817 -139.66329)
			(xy 234.493197 -139.708286) (xy 255.932294 -139.708286) (xy 255.937503 -139.645418) (xy 255.950448 -139.583678)
			(xy 255.97093 -139.524014) (xy 255.998635 -139.467341) (xy 256.033137 -139.41453) (xy 256.073907 -139.366392)
			(xy 256.120318 -139.323667) (xy 256.171657 -139.28701) (xy 256.227136 -139.256986) (xy 256.285903 -139.234054)
			(xy 256.347055 -139.218568) (xy 256.409653 -139.210764) (xy 256.441194 -139.210288) (xy 256.441448 -139.210288)
			(xy 256.479496 -139.211002) (xy 256.554741 -139.222358) (xy 256.591308 -139.232894) (xy 256.603754 -139.236704)
			(xy 256.628646 -139.231878) (xy 256.714244 -139.161266) (xy 256.723642 -139.137898) (xy 256.722372 -139.125198)
			(xy 256.722372 -139.12469) (xy 256.721317 -139.114499) (xy 256.720174 -139.094041) (xy 256.720086 -139.083796)
			(xy 256.72017 -139.073488) (xy 256.721315 -139.052902) (xy 256.722372 -139.042648) (xy 256.722946 -139.030044)
			(xy 256.71337 -139.006737) (xy 256.704084 -138.998198) (xy 256.628646 -138.935714) (xy 256.603754 -138.930888)
			(xy 256.591308 -138.934698) (xy 256.554749 -138.945273) (xy 256.479499 -138.956628) (xy 256.441448 -138.957304)
			(xy 256.441194 -138.957304) (xy 256.409653 -138.956826) (xy 256.347057 -138.949023) (xy 256.285906 -138.933536)
			(xy 256.227141 -138.910605) (xy 256.171663 -138.880582) (xy 256.120325 -138.843926) (xy 256.073915 -138.801202)
			(xy 256.033146 -138.753066) (xy 255.998644 -138.700256) (xy 255.97094 -138.643584) (xy 255.950458 -138.583921)
			(xy 255.937513 -138.522182) (xy 255.932304 -138.459317) (xy 255.934911 -138.39629) (xy 255.945294 -138.334069)
			(xy 255.963294 -138.27361) (xy 255.988634 -138.215843) (xy 256.020924 -138.161653) (xy 256.059669 -138.111873)
			(xy 256.104274 -138.067268) (xy 256.154054 -138.028523) (xy 256.208244 -137.996233) (xy 256.266012 -137.970893)
			(xy 256.326471 -137.952894) (xy 256.388692 -137.942511) (xy 256.451719 -137.939904) (xy 256.514584 -137.945113)
			(xy 256.576323 -137.958058) (xy 256.635986 -137.978541) (xy 256.692658 -138.006245) (xy 256.745467 -138.040747)
			(xy 256.793604 -138.081516) (xy 256.836327 -138.127926) (xy 256.872983 -138.179265) (xy 256.903006 -138.234743)
			(xy 256.925937 -138.293508) (xy 256.941423 -138.354659) (xy 256.949226 -138.417255) (xy 256.949702 -138.448796)
			(xy 256.949134 -138.48195) (xy 256.940473 -138.547691) (xy 256.93243 -138.57986) (xy 256.929877 -138.592222)
			(xy 256.935721 -138.616742) (xy 256.943606 -138.626596) (xy 257.000248 -138.689842) (xy 257.009219 -138.698837)
			(xy 257.033063 -138.707506) (xy 257.045714 -138.706352) (xy 257.059415 -138.704463) (xy 257.087002 -138.702432)
			(xy 257.100832 -138.702288) (xy 257.101594 -138.702288) (xy 257.128538 -138.702797) (xy 257.18189 -138.710378)
			(xy 257.233648 -138.725376) (xy 257.282787 -138.747495) (xy 257.328333 -138.776295) (xy 257.369383 -138.811207)
			(xy 257.387598 -138.831066) (xy 257.395099 -138.838909) (xy 257.414855 -138.847848) (xy 257.425698 -138.848338)
			(xy 257.50139 -138.848338) (xy 257.512223 -138.84782) (xy 257.531956 -138.838867) (xy 257.53949 -138.831066)
			(xy 257.557682 -138.811176) (xy 257.598706 -138.776213) (xy 257.644246 -138.747379) (xy 257.693395 -138.72525)
			(xy 257.745172 -138.710265) (xy 257.798543 -138.702726) (xy 257.825494 -138.702288) (xy 257.825748 -138.702288)
			(xy 257.85639 -138.702909) (xy 257.916882 -138.712734) (xy 257.946144 -138.721846) (xy 257.959606 -138.726418)
			(xy 257.987292 -138.720068) (xy 258.072382 -138.63701) (xy 258.079494 -138.609832) (xy 258.07543 -138.596116)
			(xy 258.065215 -138.560146) (xy 258.054246 -138.486182) (xy 258.053586 -138.448796) (xy 258.054072 -138.417255)
			(xy 258.061875 -138.354658) (xy 258.077361 -138.293507) (xy 258.100292 -138.234741) (xy 258.130316 -138.179262)
			(xy 258.166972 -138.127924) (xy 258.209697 -138.081513) (xy 258.257833 -138.040744) (xy 258.310644 -138.006242)
			(xy 258.367316 -137.978538) (xy 258.42698 -137.958056) (xy 258.488719 -137.945111) (xy 258.551585 -137.939902)
			(xy 258.614613 -137.94251) (xy 258.676834 -137.952893) (xy 258.737293 -137.970893) (xy 258.795061 -137.996233)
			(xy 258.849251 -138.028524) (xy 258.899031 -138.06727) (xy 258.943636 -138.111876) (xy 258.982381 -138.161657)
			(xy 259.014671 -138.215848) (xy 259.04001 -138.273616) (xy 259.058009 -138.334076) (xy 259.068391 -138.396297)
			(xy 259.070998 -138.459325) (xy 259.065788 -138.522191) (xy 259.052842 -138.58393) (xy 259.032359 -138.643593)
			(xy 259.004653 -138.700265) (xy 258.97015 -138.753075) (xy 258.92938 -138.801211) (xy 258.882968 -138.843934)
			(xy 258.831629 -138.880589) (xy 258.77615 -138.910612) (xy 258.717384 -138.933542) (xy 258.656232 -138.949027)
			(xy 258.593635 -138.956829) (xy 258.562094 -138.957304) (xy 258.56184 -138.957304) (xy 258.533782 -138.956917)
			(xy 258.478008 -138.950742) (xy 258.423255 -138.938451) (xy 258.370193 -138.920196) (xy 258.34467 -138.908536)
			(xy 258.331716 -138.90244) (xy 258.303522 -138.905234) (xy 258.220464 -138.968734) (xy 258.213281 -138.974672)
			(xy 258.203445 -138.990484) (xy 258.199932 -139.008771) (xy 258.20116 -139.01801) (xy 258.203867 -139.034322)
			(xy 258.206792 -139.067262) (xy 258.207002 -139.083796) (xy 258.206541 -139.111049) (xy 258.205024 -139.1216)
			(xy 263.500431 -139.1216) (xy 263.504445 -139.057811) (xy 263.516421 -138.995028) (xy 263.536171 -138.934241)
			(xy 263.563384 -138.876409) (xy 263.597631 -138.822443) (xy 263.638371 -138.773195) (xy 263.684962 -138.729441)
			(xy 263.736669 -138.691871) (xy 263.792677 -138.661078) (xy 263.852103 -138.637548) (xy 263.91401 -138.62165)
			(xy 263.977421 -138.613637) (xy 264.009378 -138.613134) (xy 264.040344 -138.613639) (xy 264.101818 -138.621158)
			(xy 264.161924 -138.636087) (xy 264.219772 -138.658205) (xy 264.274505 -138.687185) (xy 264.325314 -138.722598)
			(xy 264.371446 -138.76392) (xy 264.412218 -138.810538) (xy 264.430002 -138.835892) (xy 264.438174 -138.847231)
			(xy 264.459543 -138.865236) (xy 264.484989 -138.876781) (xy 264.512611 -138.881003) (xy 264.540345 -138.877587)
			(xy 264.566116 -138.866788) (xy 264.588001 -138.849414) (xy 264.604362 -138.826762) (xy 264.60958 -138.813794)
			(xy 264.620036 -138.786631) (xy 264.648094 -138.735636) (xy 264.683575 -138.689497) (xy 264.725655 -138.649285)
			(xy 264.773357 -138.615935) (xy 264.825572 -138.59022) (xy 264.881089 -138.57274) (xy 264.938618 -138.563898)
			(xy 264.96772 -138.56335) (xy 264.994967 -138.563922) (xy 265.048907 -138.571679) (xy 265.101193 -138.587035)
			(xy 265.150763 -138.609674) (xy 265.196605 -138.639138) (xy 265.237789 -138.674826) (xy 265.273474 -138.716011)
			(xy 265.302935 -138.761855) (xy 265.325572 -138.811425) (xy 265.340925 -138.863713) (xy 265.34868 -138.917653)
			(xy 265.34868 -138.972147) (xy 265.340925 -139.026087) (xy 265.325572 -139.078375) (xy 265.302935 -139.127945)
			(xy 265.273474 -139.173789) (xy 265.237789 -139.214974) (xy 265.196605 -139.250662) (xy 265.150763 -139.280126)
			(xy 265.101193 -139.302765) (xy 265.048907 -139.318121) (xy 264.994967 -139.325878) (xy 264.96772 -139.326366)
			(xy 264.940536 -139.32591) (xy 264.886721 -139.318182) (xy 264.834547 -139.302895) (xy 264.785071 -139.280357)
			(xy 264.739295 -139.251025) (xy 264.698146 -139.215493) (xy 264.679938 -139.195302) (xy 264.670407 -139.18508)
			(xy 264.647067 -139.16973) (xy 264.620443 -139.161272) (xy 264.592524 -139.160339) (xy 264.565395 -139.166999)
			(xy 264.541082 -139.180755) (xy 264.521402 -139.200581) (xy 264.507824 -139.224994) (xy 264.50417 -139.238482)
			(xy 264.496601 -139.2685) (xy 264.475172 -139.326581) (xy 264.446849 -139.38163) (xy 264.412052 -139.432833)
			(xy 264.371295 -139.479433) (xy 264.325182 -139.520738) (xy 264.274394 -139.55614) (xy 264.219684 -139.585113)
			(xy 264.161861 -139.607228) (xy 264.101781 -139.62216) (xy 264.088742 -139.623757) (xy 265.515084 -139.623757)
			(xy 265.515084 -139.559835) (xy 265.523095 -139.496417) (xy 265.538992 -139.434503) (xy 265.562524 -139.37507)
			(xy 265.593318 -139.319055) (xy 265.630891 -139.26734) (xy 265.674648 -139.220743) (xy 265.723901 -139.179998)
			(xy 265.777872 -139.145747) (xy 265.835711 -139.11853) (xy 265.896504 -139.098777) (xy 265.959294 -139.086799)
			(xy 266.02309 -139.082786) (xy 266.086886 -139.086799) (xy 266.149676 -139.098777) (xy 266.210469 -139.11853)
			(xy 266.268308 -139.145747) (xy 266.322279 -139.179998) (xy 266.371532 -139.220743) (xy 266.415289 -139.26734)
			(xy 266.452862 -139.319055) (xy 266.483656 -139.37507) (xy 266.507188 -139.434503) (xy 266.523085 -139.496417)
			(xy 266.531096 -139.559835) (xy 266.531598 -139.591796) (xy 266.531096 -139.623757) (xy 266.523085 -139.687175)
			(xy 266.507188 -139.749089) (xy 266.483656 -139.808522) (xy 266.452862 -139.864537) (xy 266.415289 -139.916252)
			(xy 266.371532 -139.962849) (xy 266.322279 -140.003594) (xy 266.268308 -140.037845) (xy 266.210469 -140.065062)
			(xy 266.149676 -140.084815) (xy 266.086886 -140.096793) (xy 266.02309 -140.100807) (xy 265.959294 -140.096793)
			(xy 265.896504 -140.084815) (xy 265.835711 -140.065062) (xy 265.777872 -140.037845) (xy 265.723901 -140.003594)
			(xy 265.674648 -139.962849) (xy 265.630891 -139.916252) (xy 265.593318 -139.864537) (xy 265.562524 -139.808522)
			(xy 265.538992 -139.749089) (xy 265.523095 -139.687175) (xy 265.515084 -139.623757) (xy 264.088742 -139.623757)
			(xy 264.040332 -139.629686) (xy 264.009378 -139.63015) (xy 263.977421 -139.629563) (xy 263.91401 -139.62155)
			(xy 263.852103 -139.605652) (xy 263.792677 -139.582122) (xy 263.736669 -139.551329) (xy 263.684962 -139.513759)
			(xy 263.638371 -139.470005) (xy 263.597631 -139.420757) (xy 263.563384 -139.366791) (xy 263.536171 -139.308959)
			(xy 263.516421 -139.248172) (xy 263.504445 -139.185389) (xy 263.500431 -139.1216) (xy 258.205024 -139.1216)
			(xy 258.198784 -139.165) (xy 258.183429 -139.217299) (xy 258.160786 -139.266879) (xy 258.131318 -139.312733)
			(xy 258.095624 -139.353925) (xy 258.054431 -139.389619) (xy 258.008577 -139.419087) (xy 257.958997 -139.441729)
			(xy 257.906698 -139.457085) (xy 257.852747 -139.464841) (xy 257.825494 -139.465304) (xy 257.79855 -139.464806)
			(xy 257.745197 -139.457223) (xy 257.693439 -139.442223) (xy 257.6443 -139.420102) (xy 257.598754 -139.3913)
			(xy 257.557705 -139.356386) (xy 257.53949 -139.336526) (xy 257.531955 -139.328722) (xy 257.512225 -139.319761)
			(xy 257.50139 -139.319254) (xy 257.425698 -139.319254) (xy 257.414865 -139.319768) (xy 257.395132 -139.328724)
			(xy 257.387598 -139.336526) (xy 257.36941 -139.356419) (xy 257.328386 -139.391382) (xy 257.282844 -139.420216)
			(xy 257.233695 -139.442345) (xy 257.181917 -139.457328) (xy 257.128545 -139.464866) (xy 257.101594 -139.465304)
			(xy 257.100832 -139.465304) (xy 257.087001 -139.465173) (xy 257.059415 -139.463137) (xy 257.045714 -139.46124)
			(xy 257.037329 -139.460302) (xy 257.020745 -139.463346) (xy 257.006065 -139.47164) (xy 257.000248 -139.47775)
			(xy 256.93497 -139.550648) (xy 256.929128 -139.575032) (xy 256.93243 -139.587478) (xy 256.93243 -139.587986)
			(xy 256.940479 -139.620089) (xy 256.94914 -139.685704) (xy 256.949702 -139.718796) (xy 256.949237 -139.750337)
			(xy 256.941434 -139.812935) (xy 256.925949 -139.874088) (xy 256.903018 -139.932855) (xy 256.872995 -139.988335)
			(xy 256.83634 -140.039675) (xy 256.793615 -140.086086) (xy 256.745478 -140.126857) (xy 256.692668 -140.16136)
			(xy 256.635996 -140.189066) (xy 256.576331 -140.20955) (xy 256.514591 -140.222496) (xy 256.451724 -140.227706)
			(xy 256.388696 -140.225099) (xy 256.326474 -140.214717) (xy 256.266013 -140.196718) (xy 256.208244 -140.171378)
			(xy 256.154052 -140.139088) (xy 256.104271 -140.100342) (xy 256.059664 -140.055737) (xy 256.020918 -140.005956)
			(xy 255.988626 -139.951765) (xy 255.963286 -139.893996) (xy 255.945285 -139.833536) (xy 255.934902 -139.771314)
			(xy 255.932294 -139.708286) (xy 234.493197 -139.708286) (xy 234.488063 -139.724085) (xy 234.460844 -139.781925)
			(xy 234.426591 -139.835897) (xy 234.385843 -139.885151) (xy 234.339243 -139.928909) (xy 234.287526 -139.966481)
			(xy 234.231507 -139.997274) (xy 234.172071 -140.020804) (xy 234.110155 -140.036698) (xy 234.046734 -140.044707)
			(xy 234.014772 -140.045186) (xy 233.984348 -140.044787) (xy 233.923936 -140.037519) (xy 233.864824 -140.023089)
			(xy 233.807857 -140.001704) (xy 233.753852 -139.973671) (xy 233.70358 -139.939389) (xy 233.657761 -139.899351)
			(xy 233.637074 -139.877038) (xy 233.63682 -139.876784) (xy 233.62873 -139.868839) (xy 233.607772 -139.860262)
			(xy 233.596434 -139.860274) (xy 233.505502 -139.865354) (xy 233.48569 -139.876276) (xy 233.478832 -139.88542)
			(xy 233.478832 -139.885928) (xy 233.460884 -139.910138) (xy 233.420182 -139.954585) (xy 233.374512 -139.993909)
			(xy 233.324514 -140.02756) (xy 233.270889 -140.055066) (xy 233.214389 -140.076041) (xy 233.155806 -140.090191)
			(xy 233.095962 -140.097317) (xy 233.065828 -140.097764) (xy 233.033862 -140.097373) (xy 232.970433 -140.089363)
			(xy 232.908508 -140.073467) (xy 232.849064 -140.049934) (xy 232.793039 -140.019136) (xy 232.741315 -139.981559)
			(xy 232.694709 -139.937796) (xy 232.653956 -139.888536) (xy 232.619698 -139.834557) (xy 232.592476 -139.776709)
			(xy 232.572719 -139.715906) (xy 232.560739 -139.653106) (xy 232.556724 -139.5893) (xy 214.067942 -139.5893)
			(xy 215.069928 -140.591286) (xy 215.073497 -140.594691) (xy 215.081681 -140.600195) (xy 215.086184 -140.602208)
			(xy 215.092788 -140.604494) (xy 215.098884 -140.606018) (xy 215.111584 -140.606018) (xy 215.118696 -140.60424)
			(xy 215.148705 -140.596791) (xy 215.209964 -140.588387) (xy 215.24087 -140.587476) (xy 215.252808 -140.587476)
			(xy 215.285918 -140.588289) (xy 215.351514 -140.597444) (xy 215.415367 -140.615037) (xy 215.476395 -140.64077)
			(xy 215.533566 -140.674209) (xy 215.585912 -140.714787) (xy 215.632547 -140.761817) (xy 215.672682 -140.814504)
			(xy 215.705637 -140.871955) (xy 215.71505 -140.894816) (xy 244.376448 -140.894816) (xy 244.376971 -140.864087)
			(xy 244.384377 -140.803077) (xy 244.399082 -140.743404) (xy 244.420873 -140.685939) (xy 244.449431 -140.63152)
			(xy 244.484341 -140.580939) (xy 244.525092 -140.534935) (xy 244.571092 -140.494178) (xy 244.621668 -140.459262)
			(xy 244.676084 -140.430698) (xy 244.733547 -140.4089) (xy 244.793218 -140.394188) (xy 244.854227 -140.386775)
			(xy 244.884956 -140.386308) (xy 244.915846 -140.386837) (xy 244.957261 -140.391896) (xy 260.608572 -140.391896)
			(xy 260.609074 -140.364646) (xy 260.616831 -140.310699) (xy 260.632185 -140.258406) (xy 260.654825 -140.20883)
			(xy 260.68429 -140.162981) (xy 260.71998 -140.121791) (xy 260.761168 -140.0861) (xy 260.807016 -140.056633)
			(xy 260.856591 -140.033991) (xy 260.908884 -140.018634) (xy 260.96283 -140.010875) (xy 260.99008 -140.010388)
			(xy 261.017349 -140.010797) (xy 261.071333 -140.018553) (xy 261.12366 -140.033924) (xy 261.173262 -140.056596)
			(xy 261.219126 -140.086107) (xy 261.260316 -140.121853) (xy 261.29599 -140.163105) (xy 261.325421 -140.20902)
			(xy 261.348007 -140.258662) (xy 261.356094 -140.284708) (xy 261.356094 -140.284962) (xy 261.359383 -140.294257)
			(xy 261.371807 -140.309544) (xy 261.380224 -140.31468) (xy 261.451852 -140.354304) (xy 261.47141 -140.35659)
			(xy 261.481316 -140.353796) (xy 261.515274 -140.344767) (xy 261.584868 -140.335082) (xy 261.62 -140.334492)
			(xy 261.651961 -140.334994) (xy 261.715379 -140.343005) (xy 261.777293 -140.358902) (xy 261.836726 -140.382434)
			(xy 261.892741 -140.413228) (xy 261.944456 -140.450801) (xy 261.991053 -140.494558) (xy 262.031798 -140.543811)
			(xy 262.066049 -140.597782) (xy 262.093266 -140.655621) (xy 262.113019 -140.716414) (xy 262.124997 -140.779204)
			(xy 262.129011 -140.843) (xy 262.124997 -140.906796) (xy 262.113019 -140.969586) (xy 262.112884 -140.97)
			(xy 263.39699 -140.97) (xy 263.401003 -140.906204) (xy 263.412981 -140.843414) (xy 263.432734 -140.782621)
			(xy 263.459951 -140.724782) (xy 263.494202 -140.670811) (xy 263.534947 -140.621558) (xy 263.581544 -140.577801)
			(xy 263.633259 -140.540228) (xy 263.689274 -140.509434) (xy 263.748707 -140.485902) (xy 263.810621 -140.470005)
			(xy 263.874039 -140.461994) (xy 263.906 -140.461492) (xy 263.937396 -140.461954) (xy 263.999711 -140.469685)
			(xy 264.060599 -140.48503) (xy 264.119135 -140.507756) (xy 264.174428 -140.537515) (xy 264.225635 -140.573856)
			(xy 264.271979 -140.616226) (xy 264.312753 -140.663979) (xy 264.347337 -140.716389) (xy 264.375205 -140.772659)
			(xy 264.395932 -140.831931) (xy 264.409204 -140.893305) (xy 264.412476 -140.924534) (xy 264.414283 -140.939131)
			(xy 264.425135 -140.966453) (xy 264.443323 -140.989551) (xy 264.467339 -141.006507) (xy 264.495192 -141.015916)
			(xy 264.524571 -141.016999) (xy 264.55304 -141.009664) (xy 264.565892 -141.002512) (xy 264.595624 -140.985342)
			(xy 264.658731 -140.958297) (xy 264.724899 -140.939975) (xy 264.792929 -140.930707) (xy 264.827258 -140.930122)
			(xy 264.827512 -140.930122) (xy 264.859474 -140.930565) (xy 264.922895 -140.938578) (xy 264.984811 -140.954477)
			(xy 265.044247 -140.97801) (xy 265.100264 -141.008807) (xy 265.15198 -141.046382) (xy 265.198579 -141.090142)
			(xy 265.239325 -141.139397) (xy 265.273577 -141.193371) (xy 265.300795 -141.251212) (xy 265.320549 -141.312009)
			(xy 265.332527 -141.374801) (xy 265.336541 -141.4386) (xy 265.332527 -141.502399) (xy 265.320549 -141.565191)
			(xy 265.300795 -141.625988) (xy 265.273577 -141.683829) (xy 265.239325 -141.737803) (xy 265.198579 -141.787058)
			(xy 265.15198 -141.830818) (xy 265.100264 -141.868393) (xy 265.044247 -141.89919) (xy 264.984811 -141.922723)
			(xy 264.922895 -141.938622) (xy 264.859474 -141.946635) (xy 264.827512 -141.947138) (xy 264.796117 -141.946637)
			(xy 264.733805 -141.938908) (xy 264.672919 -141.923566) (xy 264.614385 -141.900843) (xy 264.559094 -141.871087)
			(xy 264.507887 -141.834749) (xy 264.461544 -141.792384) (xy 264.420769 -141.744634) (xy 264.386184 -141.692228)
			(xy 264.358315 -141.635963) (xy 264.337585 -141.576694) (xy 264.32431 -141.515323) (xy 264.321036 -141.484096)
			(xy 264.319192 -141.469505) (xy 264.308349 -141.442183) (xy 264.290168 -141.419085) (xy 264.266157 -141.402128)
			(xy 264.23831 -141.392717) (xy 264.208935 -141.391633) (xy 264.18047 -141.398967) (xy 264.16762 -141.406118)
			(xy 264.137887 -141.423286) (xy 264.07478 -141.45033) (xy 264.008612 -141.468653) (xy 263.940583 -141.477922)
			(xy 263.906254 -141.478508) (xy 263.906 -141.478508) (xy 263.874039 -141.478006) (xy 263.810621 -141.469995)
			(xy 263.748707 -141.454098) (xy 263.689274 -141.430566) (xy 263.633259 -141.399772) (xy 263.581544 -141.362199)
			(xy 263.534947 -141.318442) (xy 263.494202 -141.269189) (xy 263.459951 -141.215218) (xy 263.432734 -141.157379)
			(xy 263.412981 -141.096586) (xy 263.401003 -141.033796) (xy 263.39699 -140.97) (xy 262.112884 -140.97)
			(xy 262.093266 -141.030379) (xy 262.066049 -141.088218) (xy 262.031798 -141.142189) (xy 261.991053 -141.191442)
			(xy 261.944456 -141.235199) (xy 261.892741 -141.272772) (xy 261.836726 -141.303566) (xy 261.777293 -141.327098)
			(xy 261.715379 -141.342995) (xy 261.651961 -141.351006) (xy 261.62 -141.351508) (xy 261.587814 -141.350936)
			(xy 261.523959 -141.3428) (xy 261.461641 -141.326671) (xy 261.401856 -141.302805) (xy 261.345562 -141.271586)
			(xy 261.293657 -141.233513) (xy 261.246972 -141.189193) (xy 261.206253 -141.139336) (xy 261.172152 -141.084739)
			(xy 261.145214 -141.026275) (xy 261.125869 -140.964879) (xy 261.114427 -140.901532) (xy 261.112254 -140.869416)
			(xy 261.112254 -140.868908) (xy 261.111208 -140.859106) (xy 261.102713 -140.841336) (xy 261.095744 -140.834364)
			(xy 261.035292 -140.7795) (xy 261.016242 -140.772642) (xy 261.006336 -140.77315) (xy 260.990334 -140.773404)
			(xy 260.989826 -140.773404) (xy 260.962586 -140.772923) (xy 260.908665 -140.765135) (xy 260.8564 -140.749755)
			(xy 260.806854 -140.727097) (xy 260.761036 -140.697621) (xy 260.719876 -140.661927) (xy 260.684212 -140.620742)
			(xy 260.65477 -140.574902) (xy 260.632148 -140.525339) (xy 260.616806 -140.473063) (xy 260.609057 -140.419136)
			(xy 260.608572 -140.391896) (xy 244.957261 -140.391896) (xy 244.977171 -140.394328) (xy 245.037136 -140.409194)
			(xy 245.094858 -140.431215) (xy 245.149488 -140.460068) (xy 245.200219 -140.495326) (xy 245.246306 -140.53647)
			(xy 245.287068 -140.582895) (xy 245.321905 -140.633916) (xy 245.350305 -140.688783) (xy 245.371848 -140.746685)
			(xy 245.386218 -140.806771) (xy 245.390162 -140.837412) (xy 245.391497 -140.846341) (xy 245.394805 -140.852949)
			(xy 257.673106 -140.852949) (xy 257.673106 -140.798451) (xy 257.680862 -140.744508) (xy 257.696216 -140.692217)
			(xy 257.718855 -140.642644) (xy 257.748318 -140.596798) (xy 257.784006 -140.555611) (xy 257.825193 -140.519922)
			(xy 257.871039 -140.490458) (xy 257.920612 -140.467818) (xy 257.972902 -140.452463) (xy 258.026845 -140.444707)
			(xy 258.054094 -140.44422) (xy 258.080646 -140.44464) (xy 258.133234 -140.452021) (xy 258.18429 -140.466628)
			(xy 258.232825 -140.488178) (xy 258.2779 -140.516254) (xy 258.318644 -140.550313) (xy 258.336796 -140.569696)
			(xy 258.344414 -140.577216) (xy 258.363954 -140.585889) (xy 258.374642 -140.58646) (xy 258.461256 -140.585952)
			(xy 258.480814 -140.577316) (xy 258.487926 -140.569188) (xy 258.508626 -140.546713) (xy 258.554541 -140.506393)
			(xy 258.604956 -140.471865) (xy 258.659144 -140.443626) (xy 258.716326 -140.422082) (xy 258.775677 -140.407545)
			(xy 258.836341 -140.400223) (xy 258.866894 -140.39977) (xy 258.898855 -140.400295) (xy 258.962274 -140.408305)
			(xy 259.024188 -140.424202) (xy 259.083622 -140.447733) (xy 259.139638 -140.478527) (xy 259.191352 -140.516099)
			(xy 259.23795 -140.559857) (xy 259.278696 -140.60911) (xy 259.312947 -140.663081) (xy 259.340165 -140.72092)
			(xy 259.359918 -140.781714) (xy 259.371896 -140.844504) (xy 259.37591 -140.9083) (xy 259.3739 -140.940239)
			(xy 259.628888 -140.940239) (xy 259.628888 -140.876317) (xy 259.636899 -140.812899) (xy 259.652796 -140.750985)
			(xy 259.676328 -140.691552) (xy 259.707122 -140.635537) (xy 259.744695 -140.583822) (xy 259.788452 -140.537225)
			(xy 259.837705 -140.49648) (xy 259.891676 -140.462229) (xy 259.949515 -140.435012) (xy 260.010308 -140.415259)
			(xy 260.073098 -140.403281) (xy 260.136894 -140.399268) (xy 260.20069 -140.403281) (xy 260.26348 -140.415259)
			(xy 260.324273 -140.435012) (xy 260.382112 -140.462229) (xy 260.436083 -140.49648) (xy 260.485336 -140.537225)
			(xy 260.529093 -140.583822) (xy 260.566666 -140.635537) (xy 260.59746 -140.691552) (xy 260.620992 -140.750985)
			(xy 260.636889 -140.812899) (xy 260.6449 -140.876317) (xy 260.645402 -140.908278) (xy 260.6449 -140.940239)
			(xy 260.636889 -141.003657) (xy 260.620992 -141.065571) (xy 260.59746 -141.125004) (xy 260.566666 -141.181019)
			(xy 260.529093 -141.232734) (xy 260.485336 -141.279331) (xy 260.436083 -141.320076) (xy 260.382112 -141.354327)
			(xy 260.324273 -141.381544) (xy 260.26348 -141.401297) (xy 260.20069 -141.413275) (xy 260.136894 -141.417289)
			(xy 260.073098 -141.413275) (xy 260.010308 -141.401297) (xy 259.949515 -141.381544) (xy 259.891676 -141.354327)
			(xy 259.837705 -141.320076) (xy 259.788452 -141.279331) (xy 259.744695 -141.232734) (xy 259.707122 -141.181019)
			(xy 259.676328 -141.125004) (xy 259.652796 -141.065571) (xy 259.636899 -141.003657) (xy 259.628888 -140.940239)
			(xy 259.3739 -140.940239) (xy 259.371896 -140.972096) (xy 259.359918 -141.034886) (xy 259.340165 -141.09568)
			(xy 259.312947 -141.153519) (xy 259.278696 -141.20749) (xy 259.23795 -141.256743) (xy 259.191352 -141.300501)
			(xy 259.139638 -141.338073) (xy 259.083622 -141.368867) (xy 259.024188 -141.392398) (xy 258.962274 -141.408295)
			(xy 258.898855 -141.416305) (xy 258.866894 -141.416786) (xy 258.833725 -141.416216) (xy 258.767947 -141.407611)
			(xy 258.703847 -141.390524) (xy 258.642514 -141.365243) (xy 258.584992 -141.332198) (xy 258.532256 -141.291952)
			(xy 258.485205 -141.245187) (xy 258.444636 -141.192699) (xy 258.427474 -141.16431) (xy 258.42162 -141.155367)
			(xy 258.404283 -141.142903) (xy 258.393946 -141.14018) (xy 258.309364 -141.1224) (xy 258.288536 -141.126972)
			(xy 258.2799 -141.133322) (xy 258.279392 -141.133322) (xy 258.254761 -141.150733) (xy 258.201127 -141.178332)
			(xy 258.143813 -141.197129) (xy 258.084253 -141.206654) (xy 258.054094 -141.207236) (xy 258.026845 -141.206693)
			(xy 257.972902 -141.198937) (xy 257.920612 -141.183582) (xy 257.871039 -141.160942) (xy 257.825193 -141.131478)
			(xy 257.784006 -141.095789) (xy 257.748318 -141.054602) (xy 257.718855 -141.008756) (xy 257.696216 -140.959183)
			(xy 257.680862 -140.906892) (xy 257.673106 -140.852949) (xy 245.394805 -140.852949) (xy 245.399574 -140.862476)
			(xy 245.40591 -140.868908) (xy 245.428008 -140.889482) (xy 245.434823 -140.895294) (xy 245.451341 -140.902192)
			(xy 245.460266 -140.902944) (xy 245.492428 -140.905063) (xy 245.555874 -140.916435) (xy 245.617375 -140.935733)
			(xy 245.675944 -140.962646) (xy 245.730644 -140.996743) (xy 245.780597 -141.037478) (xy 245.825004 -141.084198)
			(xy 245.863151 -141.136155) (xy 245.894429 -141.192514) (xy 245.918335 -141.252374) (xy 245.934487 -141.314774)
			(xy 245.942625 -141.378715) (xy 245.94312 -141.410944) (xy 245.942686 -141.441675) (xy 245.935272 -141.50269)
			(xy 245.920559 -141.562366) (xy 245.898761 -141.619833) (xy 245.870194 -141.674255) (xy 245.835277 -141.724836)
			(xy 245.794518 -141.770841) (xy 245.748511 -141.811597) (xy 245.697927 -141.846511) (xy 245.643504 -141.875074)
			(xy 245.586035 -141.896869) (xy 245.526358 -141.911578) (xy 245.465344 -141.918988) (xy 245.434612 -141.919452)
			(xy 245.40372 -141.918989) (xy 245.342391 -141.911493) (xy 245.282423 -141.896622) (xy 245.224698 -141.874595)
			(xy 245.170067 -141.845737) (xy 245.119334 -141.810473) (xy 245.073248 -141.769322) (xy 245.032487 -141.722891)
			(xy 244.997651 -141.671863) (xy 244.969254 -141.616991) (xy 244.947714 -141.559083) (xy 244.933348 -141.498991)
			(xy 244.929406 -141.468348) (xy 244.928053 -141.459423) (xy 244.91999 -141.443286) (xy 244.913658 -141.436852)
			(xy 244.89156 -141.416278) (xy 244.884748 -141.410461) (xy 244.868228 -141.403565) (xy 244.859302 -141.402816)
			(xy 244.82714 -141.400677) (xy 244.763693 -141.389311) (xy 244.702191 -141.37002) (xy 244.643619 -141.343111)
			(xy 244.588917 -141.309017) (xy 244.538962 -141.268284) (xy 244.494554 -141.221565) (xy 244.456406 -141.169609)
			(xy 244.425128 -141.113248) (xy 244.401224 -141.053388) (xy 244.385075 -140.990986) (xy 244.37694 -140.927045)
			(xy 244.376448 -140.894816) (xy 215.71505 -140.894816) (xy 215.730855 -140.933198) (xy 215.747908 -140.997197)
			(xy 215.756508 -141.062868) (xy 215.756998 -141.095984) (xy 215.756453 -141.129661) (xy 215.747563 -141.196424)
			(xy 215.729938 -141.26143) (xy 215.703884 -141.32354) (xy 215.669859 -141.381667) (xy 215.628458 -141.434793)
			(xy 215.580406 -141.481989) (xy 215.553798 -141.502638) (xy 215.553544 -141.502892) (xy 215.54974 -141.50589)
			(xy 215.543217 -141.513047) (xy 215.54059 -141.517116) (xy 215.538304 -141.520926) (xy 215.536308 -141.525387)
			(xy 215.533878 -141.534851) (xy 215.533478 -141.539722) (xy 215.5317 -141.565884) (xy 215.5317 -141.566392)
			(xy 215.530684 -141.581124) (xy 215.530684 -141.581632) (xy 215.528144 -141.616176) (xy 215.527851 -141.627144)
			(xy 215.53549 -141.647686) (xy 215.542876 -141.6558) (xy 215.832393 -141.945317) (xy 219.800418 -141.945317)
			(xy 219.800418 -141.881395) (xy 219.808429 -141.817977) (xy 219.824326 -141.756063) (xy 219.847858 -141.69663)
			(xy 219.878652 -141.640615) (xy 219.916225 -141.5889) (xy 219.959982 -141.542303) (xy 220.009235 -141.501558)
			(xy 220.063206 -141.467307) (xy 220.121045 -141.44009) (xy 220.181838 -141.420337) (xy 220.244628 -141.408359)
			(xy 220.308424 -141.404346) (xy 220.37222 -141.408359) (xy 220.43501 -141.420337) (xy 220.495803 -141.44009)
			(xy 220.553642 -141.467307) (xy 220.607613 -141.501558) (xy 220.656866 -141.542303) (xy 220.700623 -141.5889)
			(xy 220.738196 -141.640615) (xy 220.76899 -141.69663) (xy 220.792522 -141.756063) (xy 220.808419 -141.817977)
			(xy 220.81643 -141.881395) (xy 220.816932 -141.913356) (xy 220.81643 -141.945317) (xy 220.808419 -142.008735)
			(xy 220.792522 -142.070649) (xy 220.76899 -142.130082) (xy 220.738196 -142.186097) (xy 220.700623 -142.237812)
			(xy 220.692128 -142.246858) (xy 231.920032 -142.246858) (xy 231.924103 -142.191236) (xy 231.936229 -142.136799)
			(xy 231.956152 -142.084708) (xy 231.983448 -142.036073) (xy 232.017534 -141.99193) (xy 232.057683 -141.953221)
			(xy 232.103041 -141.92077) (xy 232.152641 -141.895269) (xy 232.205425 -141.877262) (xy 232.260268 -141.867132)
			(xy 232.316002 -141.865095) (xy 232.371439 -141.871195) (xy 232.425396 -141.885301) (xy 232.476725 -141.907113)
			(xy 232.524331 -141.936167) (xy 232.567199 -141.971842) (xy 232.604416 -142.013379) (xy 232.635189 -142.059892)
			(xy 232.658861 -142.110389) (xy 232.674929 -142.163796) (xy 232.683049 -142.218972) (xy 232.683558 -142.246858)
			(xy 232.683364 -142.257483) (xy 236.573054 -142.257483) (xy 236.573054 -142.193561) (xy 236.581065 -142.130143)
			(xy 236.596962 -142.068229) (xy 236.620494 -142.008796) (xy 236.651288 -141.952781) (xy 236.688861 -141.901066)
			(xy 236.732618 -141.854469) (xy 236.781871 -141.813724) (xy 236.835842 -141.779473) (xy 236.893681 -141.752256)
			(xy 236.954474 -141.732503) (xy 237.017264 -141.720525) (xy 237.08106 -141.716512) (xy 237.144856 -141.720525)
			(xy 237.207646 -141.732503) (xy 237.268439 -141.752256) (xy 237.326278 -141.779473) (xy 237.380249 -141.813724)
			(xy 237.429502 -141.854469) (xy 237.473259 -141.901066) (xy 237.510832 -141.952781) (xy 237.519599 -141.968728)
			(xy 259.323076 -141.968728) (xy 259.327147 -141.913106) (xy 259.339273 -141.858669) (xy 259.359196 -141.806578)
			(xy 259.386492 -141.757943) (xy 259.420578 -141.7138) (xy 259.460727 -141.675091) (xy 259.506085 -141.64264)
			(xy 259.555685 -141.617139) (xy 259.608469 -141.599132) (xy 259.663312 -141.589002) (xy 259.719046 -141.586965)
			(xy 259.774483 -141.593065) (xy 259.82844 -141.607171) (xy 259.879769 -141.628983) (xy 259.927375 -141.658037)
			(xy 259.970243 -141.693712) (xy 260.00746 -141.735249) (xy 260.038233 -141.781762) (xy 260.061905 -141.832259)
			(xy 260.077973 -141.885666) (xy 260.086093 -141.940842) (xy 260.086602 -141.968728) (xy 260.623048 -141.968728)
			(xy 260.627119 -141.913106) (xy 260.639245 -141.858669) (xy 260.659168 -141.806578) (xy 260.686464 -141.757943)
			(xy 260.72055 -141.7138) (xy 260.760699 -141.675091) (xy 260.806057 -141.64264) (xy 260.855657 -141.617139)
			(xy 260.908441 -141.599132) (xy 260.963284 -141.589002) (xy 261.019018 -141.586965) (xy 261.074455 -141.593065)
			(xy 261.128412 -141.607171) (xy 261.179741 -141.628983) (xy 261.227347 -141.658037) (xy 261.270215 -141.693712)
			(xy 261.307432 -141.735249) (xy 261.338205 -141.781762) (xy 261.361877 -141.832259) (xy 261.377945 -141.885666)
			(xy 261.386065 -141.940842) (xy 261.386574 -141.968728) (xy 261.386065 -141.996614) (xy 261.377945 -142.05179)
			(xy 261.361877 -142.105197) (xy 261.338205 -142.155694) (xy 261.307432 -142.202207) (xy 261.28859 -142.223236)
			(xy 261.893048 -142.223236) (xy 261.897119 -142.167614) (xy 261.909245 -142.113177) (xy 261.929168 -142.061086)
			(xy 261.956464 -142.012451) (xy 261.99055 -141.968308) (xy 262.030699 -141.929599) (xy 262.076057 -141.897148)
			(xy 262.125657 -141.871647) (xy 262.178441 -141.85364) (xy 262.233284 -141.84351) (xy 262.289018 -141.841473)
			(xy 262.344455 -141.847573) (xy 262.398412 -141.861679) (xy 262.449741 -141.883491) (xy 262.497347 -141.912545)
			(xy 262.540215 -141.94822) (xy 262.577432 -141.989757) (xy 262.608205 -142.03627) (xy 262.631877 -142.086767)
			(xy 262.647945 -142.140174) (xy 262.656065 -142.19535) (xy 262.656574 -142.223236) (xy 262.656487 -142.228019)
			(xy 307.352948 -142.228019) (xy 307.352948 -142.164097) (xy 307.360959 -142.100679) (xy 307.376856 -142.038765)
			(xy 307.400388 -141.979332) (xy 307.431182 -141.923317) (xy 307.468755 -141.871602) (xy 307.512512 -141.825005)
			(xy 307.561765 -141.78426) (xy 307.615736 -141.750009) (xy 307.673575 -141.722792) (xy 307.734368 -141.703039)
			(xy 307.797158 -141.691061) (xy 307.860954 -141.687048) (xy 307.92475 -141.691061) (xy 307.98754 -141.703039)
			(xy 308.048333 -141.722792) (xy 308.106172 -141.750009) (xy 308.160143 -141.78426) (xy 308.209396 -141.825005)
			(xy 308.253153 -141.871602) (xy 308.290726 -141.923317) (xy 308.32152 -141.979332) (xy 308.345052 -142.038765)
			(xy 308.360949 -142.100679) (xy 308.36896 -142.164097) (xy 308.369462 -142.196058) (xy 308.36896 -142.228019)
			(xy 308.360949 -142.291437) (xy 308.345052 -142.353351) (xy 308.32152 -142.412784) (xy 308.290726 -142.468799)
			(xy 308.253153 -142.520514) (xy 308.209396 -142.567111) (xy 308.160143 -142.607856) (xy 308.106172 -142.642107)
			(xy 308.048333 -142.669324) (xy 307.98754 -142.689077) (xy 307.92475 -142.701055) (xy 307.860954 -142.705069)
			(xy 307.797158 -142.701055) (xy 307.734368 -142.689077) (xy 307.673575 -142.669324) (xy 307.615736 -142.642107)
			(xy 307.561765 -142.607856) (xy 307.512512 -142.567111) (xy 307.468755 -142.520514) (xy 307.431182 -142.468799)
			(xy 307.400388 -142.412784) (xy 307.376856 -142.353351) (xy 307.360959 -142.291437) (xy 307.352948 -142.228019)
			(xy 262.656487 -142.228019) (xy 262.656065 -142.251122) (xy 262.647945 -142.306298) (xy 262.631877 -142.359705)
			(xy 262.608205 -142.410202) (xy 262.577432 -142.456715) (xy 262.540215 -142.498252) (xy 262.497347 -142.533927)
			(xy 262.449741 -142.562981) (xy 262.398412 -142.584793) (xy 262.344455 -142.598899) (xy 262.289018 -142.604999)
			(xy 262.233284 -142.602962) (xy 262.178441 -142.592832) (xy 262.125657 -142.574825) (xy 262.076057 -142.549324)
			(xy 262.030699 -142.516873) (xy 261.99055 -142.478164) (xy 261.956464 -142.434021) (xy 261.929168 -142.385386)
			(xy 261.909245 -142.333295) (xy 261.897119 -142.278858) (xy 261.893048 -142.223236) (xy 261.28859 -142.223236)
			(xy 261.270215 -142.243744) (xy 261.227347 -142.279419) (xy 261.179741 -142.308473) (xy 261.128412 -142.330285)
			(xy 261.074455 -142.344391) (xy 261.019018 -142.350491) (xy 260.963284 -142.348454) (xy 260.908441 -142.338324)
			(xy 260.855657 -142.320317) (xy 260.806057 -142.294816) (xy 260.760699 -142.262365) (xy 260.72055 -142.223656)
			(xy 260.686464 -142.179513) (xy 260.659168 -142.130878) (xy 260.639245 -142.078787) (xy 260.627119 -142.02435)
			(xy 260.623048 -141.968728) (xy 260.086602 -141.968728) (xy 260.086093 -141.996614) (xy 260.077973 -142.05179)
			(xy 260.061905 -142.105197) (xy 260.038233 -142.155694) (xy 260.00746 -142.202207) (xy 259.970243 -142.243744)
			(xy 259.927375 -142.279419) (xy 259.879769 -142.308473) (xy 259.82844 -142.330285) (xy 259.774483 -142.344391)
			(xy 259.719046 -142.350491) (xy 259.663312 -142.348454) (xy 259.608469 -142.338324) (xy 259.555685 -142.320317)
			(xy 259.506085 -142.294816) (xy 259.460727 -142.262365) (xy 259.420578 -142.223656) (xy 259.386492 -142.179513)
			(xy 259.359196 -142.130878) (xy 259.339273 -142.078787) (xy 259.327147 -142.02435) (xy 259.323076 -141.968728)
			(xy 237.519599 -141.968728) (xy 237.541626 -142.008796) (xy 237.565158 -142.068229) (xy 237.581055 -142.130143)
			(xy 237.589066 -142.193561) (xy 237.589568 -142.225522) (xy 237.589066 -142.257483) (xy 237.581055 -142.320901)
			(xy 237.565158 -142.382815) (xy 237.541626 -142.442248) (xy 237.510832 -142.498263) (xy 237.473259 -142.549978)
			(xy 237.429502 -142.596575) (xy 237.380249 -142.63732) (xy 237.326278 -142.671571) (xy 237.268439 -142.698788)
			(xy 237.207646 -142.718541) (xy 237.144856 -142.730519) (xy 237.08106 -142.734533) (xy 237.017264 -142.730519)
			(xy 236.954474 -142.718541) (xy 236.893681 -142.698788) (xy 236.835842 -142.671571) (xy 236.781871 -142.63732)
			(xy 236.732618 -142.596575) (xy 236.688861 -142.549978) (xy 236.651288 -142.498263) (xy 236.620494 -142.442248)
			(xy 236.596962 -142.382815) (xy 236.581065 -142.320901) (xy 236.573054 -142.257483) (xy 232.683364 -142.257483)
			(xy 232.683049 -142.274744) (xy 232.674929 -142.32992) (xy 232.658861 -142.383327) (xy 232.635189 -142.433824)
			(xy 232.604416 -142.480337) (xy 232.567199 -142.521874) (xy 232.524331 -142.557549) (xy 232.476725 -142.586603)
			(xy 232.425396 -142.608415) (xy 232.371439 -142.622521) (xy 232.316002 -142.628621) (xy 232.260268 -142.626584)
			(xy 232.205425 -142.616454) (xy 232.152641 -142.598447) (xy 232.103041 -142.572946) (xy 232.057683 -142.540495)
			(xy 232.017534 -142.501786) (xy 231.983448 -142.457643) (xy 231.956152 -142.409008) (xy 231.936229 -142.356917)
			(xy 231.924103 -142.30248) (xy 231.920032 -142.246858) (xy 220.692128 -142.246858) (xy 220.656866 -142.284409)
			(xy 220.607613 -142.325154) (xy 220.553642 -142.359405) (xy 220.495803 -142.386622) (xy 220.43501 -142.406375)
			(xy 220.37222 -142.418353) (xy 220.308424 -142.422367) (xy 220.244628 -142.418353) (xy 220.181838 -142.406375)
			(xy 220.121045 -142.386622) (xy 220.063206 -142.359405) (xy 220.009235 -142.325154) (xy 219.959982 -142.284409)
			(xy 219.916225 -142.237812) (xy 219.878652 -142.186097) (xy 219.847858 -142.130082) (xy 219.824326 -142.070649)
			(xy 219.808429 -142.008735) (xy 219.800418 -141.945317) (xy 215.832393 -141.945317) (xy 216.674911 -142.787835)
			(xy 238.153696 -142.787835) (xy 238.153696 -142.723913) (xy 238.161707 -142.660495) (xy 238.177604 -142.598581)
			(xy 238.201136 -142.539148) (xy 238.23193 -142.483133) (xy 238.269503 -142.431418) (xy 238.31326 -142.384821)
			(xy 238.362513 -142.344076) (xy 238.416484 -142.309825) (xy 238.474323 -142.282608) (xy 238.535116 -142.262855)
			(xy 238.597906 -142.250877) (xy 238.661702 -142.246864) (xy 238.725498 -142.250877) (xy 238.788288 -142.262855)
			(xy 238.849081 -142.282608) (xy 238.90692 -142.309825) (xy 238.960891 -142.344076) (xy 239.010144 -142.384821)
			(xy 239.053901 -142.431418) (xy 239.091474 -142.483133) (xy 239.122268 -142.539148) (xy 239.1458 -142.598581)
			(xy 239.161697 -142.660495) (xy 239.169708 -142.723913) (xy 239.17021 -142.755874) (xy 239.169708 -142.787835)
			(xy 239.161697 -142.851253) (xy 239.1458 -142.913167) (xy 239.122268 -142.9726) (xy 239.091474 -143.028615)
			(xy 239.067844 -143.061139) (xy 257.555994 -143.061139) (xy 257.555994 -142.997217) (xy 257.564005 -142.933799)
			(xy 257.579902 -142.871885) (xy 257.603434 -142.812452) (xy 257.634228 -142.756437) (xy 257.671801 -142.704722)
			(xy 257.715558 -142.658125) (xy 257.764811 -142.61738) (xy 257.818782 -142.583129) (xy 257.876621 -142.555912)
			(xy 257.937414 -142.536159) (xy 258.000204 -142.524181) (xy 258.064 -142.520168) (xy 258.127796 -142.524181)
			(xy 258.190586 -142.536159) (xy 258.251379 -142.555912) (xy 258.309218 -142.583129) (xy 258.363189 -142.61738)
			(xy 258.412442 -142.658125) (xy 258.456199 -142.704722) (xy 258.493772 -142.756437) (xy 258.524566 -142.812452)
			(xy 258.548098 -142.871885) (xy 258.563995 -142.933799) (xy 258.572006 -142.997217) (xy 258.572508 -143.029178)
			(xy 258.572433 -143.033961) (xy 259.587994 -143.033961) (xy 259.587994 -142.970039) (xy 259.596005 -142.906621)
			(xy 259.611902 -142.844707) (xy 259.635434 -142.785274) (xy 259.666228 -142.729259) (xy 259.703801 -142.677544)
			(xy 259.747558 -142.630947) (xy 259.796811 -142.590202) (xy 259.850782 -142.555951) (xy 259.908621 -142.528734)
			(xy 259.969414 -142.508981) (xy 260.032204 -142.497003) (xy 260.096 -142.49299) (xy 260.159796 -142.497003)
			(xy 260.222586 -142.508981) (xy 260.283379 -142.528734) (xy 260.341218 -142.555951) (xy 260.395189 -142.590202)
			(xy 260.444442 -142.630947) (xy 260.488199 -142.677544) (xy 260.525772 -142.729259) (xy 260.556566 -142.785274)
			(xy 260.580098 -142.844707) (xy 260.595995 -142.906621) (xy 260.604006 -142.970039) (xy 260.604508 -143.002)
			(xy 260.604006 -143.033961) (xy 260.730994 -143.033961) (xy 260.730994 -142.970039) (xy 260.739005 -142.906621)
			(xy 260.754902 -142.844707) (xy 260.778434 -142.785274) (xy 260.809228 -142.729259) (xy 260.846801 -142.677544)
			(xy 260.890558 -142.630947) (xy 260.939811 -142.590202) (xy 260.993782 -142.555951) (xy 261.051621 -142.528734)
			(xy 261.112414 -142.508981) (xy 261.175204 -142.497003) (xy 261.239 -142.49299) (xy 261.302796 -142.497003)
			(xy 261.365586 -142.508981) (xy 261.426379 -142.528734) (xy 261.484218 -142.555951) (xy 261.538189 -142.590202)
			(xy 261.587442 -142.630947) (xy 261.631199 -142.677544) (xy 261.668772 -142.729259) (xy 261.699566 -142.785274)
			(xy 261.723098 -142.844707) (xy 261.738995 -142.906621) (xy 261.747006 -142.970039) (xy 261.747508 -143.002)
			(xy 261.747006 -143.033961) (xy 261.738995 -143.097379) (xy 261.7378 -143.102033) (xy 263.580366 -143.102033)
			(xy 263.580366 -143.038111) (xy 263.588377 -142.974693) (xy 263.604274 -142.912779) (xy 263.627806 -142.853346)
			(xy 263.6586 -142.797331) (xy 263.696173 -142.745616) (xy 263.73993 -142.699019) (xy 263.789183 -142.658274)
			(xy 263.843154 -142.624023) (xy 263.900993 -142.596806) (xy 263.961786 -142.577053) (xy 264.024576 -142.565075)
			(xy 264.088372 -142.561062) (xy 264.152168 -142.565075) (xy 264.214958 -142.577053) (xy 264.275751 -142.596806)
			(xy 264.33359 -142.624023) (xy 264.387561 -142.658274) (xy 264.436814 -142.699019) (xy 264.480571 -142.745616)
			(xy 264.518144 -142.797331) (xy 264.548938 -142.853346) (xy 264.57247 -142.912779) (xy 264.588367 -142.974693)
			(xy 264.596378 -143.038111) (xy 264.59688 -143.070072) (xy 264.596378 -143.102033) (xy 264.588367 -143.165451)
			(xy 264.57247 -143.227365) (xy 264.548938 -143.286798) (xy 264.518144 -143.342813) (xy 264.480571 -143.394528)
			(xy 264.436814 -143.441125) (xy 264.387561 -143.48187) (xy 264.33359 -143.516121) (xy 264.275751 -143.543338)
			(xy 264.214958 -143.563091) (xy 264.152168 -143.575069) (xy 264.088372 -143.579083) (xy 264.024576 -143.575069)
			(xy 263.961786 -143.563091) (xy 263.900993 -143.543338) (xy 263.843154 -143.516121) (xy 263.789183 -143.48187)
			(xy 263.73993 -143.441125) (xy 263.696173 -143.394528) (xy 263.6586 -143.342813) (xy 263.627806 -143.286798)
			(xy 263.604274 -143.227365) (xy 263.588377 -143.165451) (xy 263.580366 -143.102033) (xy 261.7378 -143.102033)
			(xy 261.723098 -143.159293) (xy 261.699566 -143.218726) (xy 261.668772 -143.274741) (xy 261.631199 -143.326456)
			(xy 261.587442 -143.373053) (xy 261.538189 -143.413798) (xy 261.484218 -143.448049) (xy 261.426379 -143.475266)
			(xy 261.365586 -143.495019) (xy 261.302796 -143.506997) (xy 261.239 -143.511011) (xy 261.175204 -143.506997)
			(xy 261.112414 -143.495019) (xy 261.051621 -143.475266) (xy 260.993782 -143.448049) (xy 260.939811 -143.413798)
			(xy 260.890558 -143.373053) (xy 260.846801 -143.326456) (xy 260.809228 -143.274741) (xy 260.778434 -143.218726)
			(xy 260.754902 -143.159293) (xy 260.739005 -143.097379) (xy 260.730994 -143.033961) (xy 260.604006 -143.033961)
			(xy 260.595995 -143.097379) (xy 260.580098 -143.159293) (xy 260.556566 -143.218726) (xy 260.525772 -143.274741)
			(xy 260.488199 -143.326456) (xy 260.444442 -143.373053) (xy 260.395189 -143.413798) (xy 260.341218 -143.448049)
			(xy 260.283379 -143.475266) (xy 260.222586 -143.495019) (xy 260.159796 -143.506997) (xy 260.096 -143.511011)
			(xy 260.032204 -143.506997) (xy 259.969414 -143.495019) (xy 259.908621 -143.475266) (xy 259.850782 -143.448049)
			(xy 259.796811 -143.413798) (xy 259.747558 -143.373053) (xy 259.703801 -143.326456) (xy 259.666228 -143.274741)
			(xy 259.635434 -143.218726) (xy 259.611902 -143.159293) (xy 259.596005 -143.097379) (xy 259.587994 -143.033961)
			(xy 258.572433 -143.033961) (xy 258.572006 -143.061139) (xy 258.563995 -143.124557) (xy 258.548098 -143.186471)
			(xy 258.524566 -143.245904) (xy 258.493772 -143.301919) (xy 258.456199 -143.353634) (xy 258.412442 -143.400231)
			(xy 258.363189 -143.440976) (xy 258.309218 -143.475227) (xy 258.251379 -143.502444) (xy 258.190586 -143.522197)
			(xy 258.127796 -143.534175) (xy 258.064 -143.538189) (xy 258.000204 -143.534175) (xy 257.937414 -143.522197)
			(xy 257.876621 -143.502444) (xy 257.818782 -143.475227) (xy 257.764811 -143.440976) (xy 257.715558 -143.400231)
			(xy 257.671801 -143.353634) (xy 257.634228 -143.301919) (xy 257.603434 -143.245904) (xy 257.579902 -143.186471)
			(xy 257.564005 -143.124557) (xy 257.555994 -143.061139) (xy 239.067844 -143.061139) (xy 239.053901 -143.08033)
			(xy 239.010144 -143.126927) (xy 238.960891 -143.167672) (xy 238.90692 -143.201923) (xy 238.849081 -143.22914)
			(xy 238.788288 -143.248893) (xy 238.725498 -143.260871) (xy 238.661702 -143.264885) (xy 238.597906 -143.260871)
			(xy 238.535116 -143.248893) (xy 238.474323 -143.22914) (xy 238.416484 -143.201923) (xy 238.362513 -143.167672)
			(xy 238.31326 -143.126927) (xy 238.269503 -143.08033) (xy 238.23193 -143.028615) (xy 238.201136 -142.9726)
			(xy 238.177604 -142.913167) (xy 238.161707 -142.851253) (xy 238.153696 -142.787835) (xy 216.674911 -142.787835)
			(xy 217.33891 -143.451834) (xy 217.34526 -143.457168) (xy 217.349708 -143.460175) (xy 217.359573 -143.464405)
			(xy 217.364818 -143.46555) (xy 217.365326 -143.46555) (xy 217.374724 -143.466566) (xy 217.470482 -143.466566)
			(xy 217.480495 -143.46705) (xy 217.498998 -143.474706) (xy 217.513165 -143.488858) (xy 217.520839 -143.507354)
			(xy 217.521282 -143.517366) (xy 217.521282 -144.424103) (xy 256.438902 -144.424103) (xy 256.438902 -144.360181)
			(xy 256.446913 -144.296763) (xy 256.46281 -144.234849) (xy 256.486342 -144.175416) (xy 256.517136 -144.119401)
			(xy 256.554709 -144.067686) (xy 256.598466 -144.021089) (xy 256.647719 -143.980344) (xy 256.70169 -143.946093)
			(xy 256.759529 -143.918876) (xy 256.820322 -143.899123) (xy 256.883112 -143.887145) (xy 256.946908 -143.883132)
			(xy 257.010704 -143.887145) (xy 257.073494 -143.899123) (xy 257.134287 -143.918876) (xy 257.192126 -143.946093)
			(xy 257.246097 -143.980344) (xy 257.29535 -144.021089) (xy 257.339107 -144.067686) (xy 257.37668 -144.119401)
			(xy 257.407474 -144.175416) (xy 257.431006 -144.234849) (xy 257.446903 -144.296763) (xy 257.454914 -144.360181)
			(xy 257.455416 -144.392142) (xy 257.455308 -144.399) (xy 261.36499 -144.399) (xy 261.369003 -144.335204)
			(xy 261.380981 -144.272414) (xy 261.400734 -144.211621) (xy 261.427951 -144.153782) (xy 261.462202 -144.099811)
			(xy 261.502947 -144.050558) (xy 261.549544 -144.006801) (xy 261.601259 -143.969228) (xy 261.657274 -143.938434)
			(xy 261.716707 -143.914902) (xy 261.778621 -143.899005) (xy 261.842039 -143.890994) (xy 261.874 -143.890492)
			(xy 261.907918 -143.891063) (xy 261.975151 -143.900077) (xy 262.040591 -143.917945) (xy 262.103076 -143.94435)
			(xy 262.132572 -143.961104) (xy 262.142068 -143.966096) (xy 262.163366 -143.96848) (xy 262.17372 -143.965676)
			(xy 262.245856 -143.942816) (xy 262.255875 -143.939041) (xy 262.271892 -143.924875) (xy 262.276844 -143.915384)
			(xy 262.276844 -143.91513) (xy 262.29066 -143.885764) (xy 262.324588 -143.830441) (xy 262.36528 -143.779884)
			(xy 262.412072 -143.734915) (xy 262.464206 -143.696265) (xy 262.520833 -143.664561) (xy 262.581034 -143.64032)
			(xy 262.643829 -143.623934) (xy 262.708199 -143.615671) (xy 262.740648 -143.615156) (xy 262.772605 -143.615733)
			(xy 262.836014 -143.623749) (xy 262.897918 -143.639648) (xy 262.957342 -143.663181) (xy 263.013348 -143.693975)
			(xy 263.065053 -143.731546) (xy 263.111642 -143.7753) (xy 263.15238 -143.824548) (xy 263.186625 -143.878513)
			(xy 263.213837 -143.936345) (xy 263.233586 -143.997131) (xy 263.245562 -144.059912) (xy 263.249575 -144.1237)
			(xy 263.245562 -144.187488) (xy 263.233586 -144.250269) (xy 263.213837 -144.311055) (xy 263.186625 -144.368887)
			(xy 263.15238 -144.422852) (xy 263.111642 -144.4721) (xy 263.065053 -144.515854) (xy 263.013348 -144.553425)
			(xy 262.957342 -144.584219) (xy 262.897918 -144.607752) (xy 262.836014 -144.623651) (xy 262.772605 -144.631667)
			(xy 262.740648 -144.632172) (xy 262.706729 -144.631629) (xy 262.639495 -144.622607) (xy 262.574055 -144.604731)
			(xy 262.511571 -144.578318) (xy 262.482076 -144.56156) (xy 262.472592 -144.556539) (xy 262.451283 -144.554171)
			(xy 262.440928 -144.556988) (xy 262.368792 -144.579848) (xy 262.358769 -144.583615) (xy 262.342752 -144.597785)
			(xy 262.337804 -144.60728) (xy 262.337804 -144.607534) (xy 262.32406 -144.636935) (xy 262.290121 -144.692257)
			(xy 262.249419 -144.742812) (xy 262.202616 -144.787778) (xy 262.195975 -144.7927) (xy 294.655968 -144.7927)
			(xy 294.659983 -144.7289) (xy 294.671961 -144.666106) (xy 294.691716 -144.605309) (xy 294.718935 -144.547467)
			(xy 294.753189 -144.493493) (xy 294.793938 -144.444238) (xy 294.840539 -144.400478) (xy 294.892257 -144.362904)
			(xy 294.948277 -144.332109) (xy 295.007714 -144.308578) (xy 295.069633 -144.292682) (xy 295.133055 -144.284672)
			(xy 295.165018 -144.284192) (xy 295.194813 -144.284621) (xy 295.253995 -144.291584) (xy 295.311958 -144.305413)
			(xy 295.367909 -144.325918) (xy 295.421082 -144.352818) (xy 295.470748 -144.385746) (xy 295.516228 -144.424249)
			(xy 295.536874 -144.445736) (xy 295.547251 -144.456031) (xy 295.572427 -144.470852) (xy 295.600765 -144.477952)
			(xy 295.629955 -144.476752) (xy 295.657614 -144.467349) (xy 295.681488 -144.45051) (xy 295.699627 -144.42761)
			(xy 295.70553 -144.41424) (xy 295.716538 -144.38807) (xy 295.745197 -144.339061) (xy 295.780805 -144.294843)
			(xy 295.822576 -144.256393) (xy 295.869586 -144.22456) (xy 295.920796 -144.200049) (xy 295.975073 -144.183402)
			(xy 296.031219 -144.174986) (xy 296.059606 -144.174464) (xy 296.086855 -144.175007) (xy 296.140798 -144.182763)
			(xy 296.193088 -144.198118) (xy 296.242661 -144.220758) (xy 296.288507 -144.250222) (xy 296.329694 -144.285911)
			(xy 296.365382 -144.327098) (xy 296.394845 -144.372944) (xy 296.417484 -144.422517) (xy 296.432838 -144.474808)
			(xy 296.440594 -144.528751) (xy 296.440594 -144.583249) (xy 296.432838 -144.637192) (xy 296.417484 -144.689483)
			(xy 296.394845 -144.739056) (xy 296.365382 -144.784902) (xy 296.329694 -144.826089) (xy 296.288507 -144.861778)
			(xy 296.242661 -144.891242) (xy 296.193088 -144.913882) (xy 296.140798 -144.929237) (xy 296.086855 -144.936993)
			(xy 296.059606 -144.93748) (xy 296.03393 -144.937082) (xy 295.983043 -144.930198) (xy 295.933538 -144.916554)
			(xy 295.886309 -144.896396) (xy 295.842209 -144.870087) (xy 295.821862 -144.854422) (xy 295.810131 -144.845709)
			(xy 295.783065 -144.83473) (xy 295.753997 -144.831861) (xy 295.725306 -144.837336) (xy 295.699338 -144.850707)
			(xy 295.678215 -144.870881) (xy 295.663666 -144.896208) (xy 295.65981 -144.910302) (xy 295.65227 -144.940298)
			(xy 295.630754 -144.998289) (xy 295.602366 -145.053243) (xy 295.567524 -145.10435) (xy 295.526743 -145.150855)
			(xy 295.480623 -145.192072) (xy 295.429847 -145.227393) (xy 295.375162 -145.256297) (xy 295.317376 -145.278358)
			(xy 295.257342 -145.293248) (xy 295.195945 -145.30075) (xy 295.165018 -145.301208) (xy 295.133055 -145.300728)
			(xy 295.069633 -145.292718) (xy 295.007714 -145.276822) (xy 294.948277 -145.253291) (xy 294.892257 -145.222496)
			(xy 294.840539 -145.184922) (xy 294.793938 -145.141162) (xy 294.753189 -145.091907) (xy 294.718935 -145.037933)
			(xy 294.691716 -144.980091) (xy 294.671961 -144.919294) (xy 294.659983 -144.8565) (xy 294.655968 -144.7927)
			(xy 262.195975 -144.7927) (xy 262.150474 -144.826425) (xy 262.093838 -144.858123) (xy 262.03363 -144.88236)
			(xy 261.970827 -144.898739) (xy 261.906452 -144.906996) (xy 261.874 -144.907508) (xy 261.842039 -144.907006)
			(xy 261.778621 -144.898995) (xy 261.716707 -144.883098) (xy 261.657274 -144.859566) (xy 261.601259 -144.828772)
			(xy 261.549544 -144.791199) (xy 261.502947 -144.747442) (xy 261.462202 -144.698189) (xy 261.427951 -144.644218)
			(xy 261.400734 -144.586379) (xy 261.380981 -144.525586) (xy 261.369003 -144.462796) (xy 261.36499 -144.399)
			(xy 257.455308 -144.399) (xy 257.454914 -144.424103) (xy 257.446903 -144.487521) (xy 257.431006 -144.549435)
			(xy 257.407474 -144.608868) (xy 257.37668 -144.664883) (xy 257.339107 -144.716598) (xy 257.29535 -144.763195)
			(xy 257.246097 -144.80394) (xy 257.192126 -144.838191) (xy 257.134287 -144.865408) (xy 257.073494 -144.885161)
			(xy 257.010704 -144.897139) (xy 256.946908 -144.901153) (xy 256.883112 -144.897139) (xy 256.820322 -144.885161)
			(xy 256.759529 -144.865408) (xy 256.70169 -144.838191) (xy 256.647719 -144.80394) (xy 256.598466 -144.763195)
			(xy 256.554709 -144.716598) (xy 256.517136 -144.664883) (xy 256.486342 -144.608868) (xy 256.46281 -144.549435)
			(xy 256.446913 -144.487521) (xy 256.438902 -144.424103) (xy 217.521282 -144.424103) (xy 217.521282 -145.148257)
			(xy 258.384288 -145.148257) (xy 258.384288 -145.084335) (xy 258.392299 -145.020917) (xy 258.408196 -144.959003)
			(xy 258.431728 -144.89957) (xy 258.462522 -144.843555) (xy 258.500095 -144.79184) (xy 258.543852 -144.745243)
			(xy 258.593105 -144.704498) (xy 258.647076 -144.670247) (xy 258.704915 -144.64303) (xy 258.765708 -144.623277)
			(xy 258.828498 -144.611299) (xy 258.892294 -144.607286) (xy 258.95609 -144.611299) (xy 259.01888 -144.623277)
			(xy 259.079673 -144.64303) (xy 259.137512 -144.670247) (xy 259.191483 -144.704498) (xy 259.240736 -144.745243)
			(xy 259.284493 -144.79184) (xy 259.322066 -144.843555) (xy 259.35286 -144.89957) (xy 259.376392 -144.959003)
			(xy 259.392289 -145.020917) (xy 259.4003 -145.084335) (xy 259.400802 -145.116296) (xy 259.4003 -145.148257)
			(xy 259.392289 -145.211675) (xy 259.376392 -145.273589) (xy 259.35286 -145.333022) (xy 259.322066 -145.389037)
			(xy 259.284493 -145.440752) (xy 259.254333 -145.472869) (xy 298.703994 -145.472869) (xy 298.703994 -145.408947)
			(xy 298.712005 -145.345529) (xy 298.727902 -145.283615) (xy 298.751434 -145.224182) (xy 298.782228 -145.168167)
			(xy 298.819801 -145.116452) (xy 298.863558 -145.069855) (xy 298.912811 -145.02911) (xy 298.966782 -144.994859)
			(xy 299.024621 -144.967642) (xy 299.085414 -144.947889) (xy 299.148204 -144.935911) (xy 299.212 -144.931898)
			(xy 299.275796 -144.935911) (xy 299.338586 -144.947889) (xy 299.399379 -144.967642) (xy 299.457218 -144.994859)
			(xy 299.511189 -145.02911) (xy 299.560442 -145.069855) (xy 299.604199 -145.116452) (xy 299.641772 -145.168167)
			(xy 299.672566 -145.224182) (xy 299.678424 -145.238978) (xy 300.6377 -145.238978) (xy 300.641771 -145.183356)
			(xy 300.653897 -145.128919) (xy 300.67382 -145.076828) (xy 300.701116 -145.028193) (xy 300.735202 -144.98405)
			(xy 300.775351 -144.945341) (xy 300.820709 -144.91289) (xy 300.870309 -144.887389) (xy 300.923093 -144.869382)
			(xy 300.977936 -144.859252) (xy 301.03367 -144.857215) (xy 301.089107 -144.863315) (xy 301.143064 -144.877421)
			(xy 301.194393 -144.899233) (xy 301.241999 -144.928287) (xy 301.284867 -144.963962) (xy 301.322084 -145.005499)
			(xy 301.352857 -145.052012) (xy 301.376529 -145.102509) (xy 301.392597 -145.155916) (xy 301.400717 -145.211092)
			(xy 301.401226 -145.238978) (xy 301.400717 -145.266864) (xy 301.392597 -145.32204) (xy 301.376529 -145.375447)
			(xy 301.352857 -145.425944) (xy 301.322084 -145.472457) (xy 301.284867 -145.513994) (xy 301.241999 -145.549669)
			(xy 301.194393 -145.578723) (xy 301.143064 -145.600535) (xy 301.089107 -145.614641) (xy 301.03367 -145.620741)
			(xy 300.977936 -145.618704) (xy 300.923093 -145.608574) (xy 300.870309 -145.590567) (xy 300.820709 -145.565066)
			(xy 300.775351 -145.532615) (xy 300.735202 -145.493906) (xy 300.701116 -145.449763) (xy 300.67382 -145.401128)
			(xy 300.653897 -145.349037) (xy 300.641771 -145.2946) (xy 300.6377 -145.238978) (xy 299.678424 -145.238978)
			(xy 299.696098 -145.283615) (xy 299.711995 -145.345529) (xy 299.720006 -145.408947) (xy 299.720508 -145.440908)
			(xy 299.720006 -145.472869) (xy 299.711995 -145.536287) (xy 299.696098 -145.598201) (xy 299.672566 -145.657634)
			(xy 299.641772 -145.713649) (xy 299.604199 -145.765364) (xy 299.590974 -145.779447) (xy 302.028092 -145.779447)
			(xy 302.028092 -145.715525) (xy 302.036103 -145.652107) (xy 302.052 -145.590193) (xy 302.075532 -145.53076)
			(xy 302.106326 -145.474745) (xy 302.143899 -145.42303) (xy 302.187656 -145.376433) (xy 302.236909 -145.335688)
			(xy 302.29088 -145.301437) (xy 302.348719 -145.27422) (xy 302.409512 -145.254467) (xy 302.472302 -145.242489)
			(xy 302.536098 -145.238476) (xy 302.599894 -145.242489) (xy 302.662684 -145.254467) (xy 302.723477 -145.27422)
			(xy 302.781316 -145.301437) (xy 302.835287 -145.335688) (xy 302.88454 -145.376433) (xy 302.928297 -145.42303)
			(xy 302.96587 -145.474745) (xy 302.996664 -145.53076) (xy 303.020196 -145.590193) (xy 303.036093 -145.652107)
			(xy 303.044104 -145.715525) (xy 303.044606 -145.747486) (xy 303.044104 -145.779447) (xy 303.036093 -145.842865)
			(xy 303.020196 -145.904779) (xy 302.996664 -145.964212) (xy 302.96587 -146.020227) (xy 302.928297 -146.071942)
			(xy 302.88454 -146.118539) (xy 302.835287 -146.159284) (xy 302.781316 -146.193535) (xy 302.723477 -146.220752)
			(xy 302.662684 -146.240505) (xy 302.599894 -146.252483) (xy 302.536098 -146.256497) (xy 302.472302 -146.252483)
			(xy 302.409512 -146.240505) (xy 302.348719 -146.220752) (xy 302.29088 -146.193535) (xy 302.236909 -146.159284)
			(xy 302.187656 -146.118539) (xy 302.143899 -146.071942) (xy 302.106326 -146.020227) (xy 302.075532 -145.964212)
			(xy 302.052 -145.904779) (xy 302.036103 -145.842865) (xy 302.028092 -145.779447) (xy 299.590974 -145.779447)
			(xy 299.560442 -145.811961) (xy 299.511189 -145.852706) (xy 299.457218 -145.886957) (xy 299.399379 -145.914174)
			(xy 299.338586 -145.933927) (xy 299.275796 -145.945905) (xy 299.212 -145.949919) (xy 299.148204 -145.945905)
			(xy 299.085414 -145.933927) (xy 299.024621 -145.914174) (xy 298.966782 -145.886957) (xy 298.912811 -145.852706)
			(xy 298.863558 -145.811961) (xy 298.819801 -145.765364) (xy 298.782228 -145.713649) (xy 298.751434 -145.657634)
			(xy 298.727902 -145.598201) (xy 298.712005 -145.536287) (xy 298.703994 -145.472869) (xy 259.254333 -145.472869)
			(xy 259.240736 -145.487349) (xy 259.191483 -145.528094) (xy 259.137512 -145.562345) (xy 259.079673 -145.589562)
			(xy 259.01888 -145.609315) (xy 258.95609 -145.621293) (xy 258.892294 -145.625307) (xy 258.828498 -145.621293)
			(xy 258.765708 -145.609315) (xy 258.704915 -145.589562) (xy 258.647076 -145.562345) (xy 258.593105 -145.528094)
			(xy 258.543852 -145.487349) (xy 258.500095 -145.440752) (xy 258.462522 -145.389037) (xy 258.431728 -145.333022)
			(xy 258.408196 -145.273589) (xy 258.392299 -145.211675) (xy 258.384288 -145.148257) (xy 217.521282 -145.148257)
			(xy 217.521282 -145.530316) (xy 217.520856 -145.540385) (xy 217.513135 -145.558983) (xy 217.506296 -145.566384)
			(xy 216.858131 -146.214549) (xy 219.896176 -146.214549) (xy 219.896176 -146.150627) (xy 219.904187 -146.087209)
			(xy 219.920084 -146.025295) (xy 219.943616 -145.965862) (xy 219.97441 -145.909847) (xy 220.011983 -145.858132)
			(xy 220.05574 -145.811535) (xy 220.104993 -145.77079) (xy 220.158964 -145.736539) (xy 220.216803 -145.709322)
			(xy 220.277596 -145.689569) (xy 220.340386 -145.677591) (xy 220.404182 -145.673578) (xy 220.467978 -145.677591)
			(xy 220.530768 -145.689569) (xy 220.591561 -145.709322) (xy 220.6494 -145.736539) (xy 220.703371 -145.77079)
			(xy 220.752624 -145.811535) (xy 220.796381 -145.858132) (xy 220.833954 -145.909847) (xy 220.864748 -145.965862)
			(xy 220.88828 -146.025295) (xy 220.904177 -146.087209) (xy 220.912188 -146.150627) (xy 220.91269 -146.182588)
			(xy 220.912188 -146.214549) (xy 220.904177 -146.277967) (xy 220.88828 -146.339881) (xy 220.864748 -146.399314)
			(xy 220.833954 -146.455329) (xy 220.796381 -146.507044) (xy 220.752624 -146.553641) (xy 220.703371 -146.594386)
			(xy 220.6494 -146.628637) (xy 220.591561 -146.655854) (xy 220.530768 -146.675607) (xy 220.467978 -146.687585)
			(xy 220.404182 -146.691599) (xy 220.340386 -146.687585) (xy 220.277596 -146.675607) (xy 220.216803 -146.655854)
			(xy 220.158964 -146.628637) (xy 220.104993 -146.594386) (xy 220.05574 -146.553641) (xy 220.011983 -146.507044)
			(xy 219.97441 -146.455329) (xy 219.943616 -146.399314) (xy 219.920084 -146.339881) (xy 219.904187 -146.277967)
			(xy 219.896176 -146.214549) (xy 216.858131 -146.214549) (xy 215.802928 -147.269752) (xy 229.894585 -147.269752)
			(xy 229.894585 -147.215248) (xy 229.902343 -147.161298) (xy 229.917699 -147.109001) (xy 229.940343 -147.059422)
			(xy 229.969812 -147.013571) (xy 230.005507 -146.97238) (xy 230.046701 -146.936689) (xy 230.092555 -146.907225)
			(xy 230.142136 -146.884586) (xy 230.194435 -146.869235) (xy 230.248386 -146.861483) (xy 230.275638 -146.861022)
			(xy 230.302571 -146.861507) (xy 230.355902 -146.869093) (xy 230.407634 -146.884107) (xy 230.456738 -146.906252)
			(xy 230.502238 -146.935086) (xy 230.523034 -146.952208) (xy 230.531265 -146.958645) (xy 230.551212 -146.964802)
			(xy 230.561642 -146.964146) (xy 230.635048 -146.955764) (xy 230.645325 -146.954155) (xy 230.663414 -146.943921)
			(xy 230.6701 -146.935952) (xy 230.690767 -146.909506) (xy 230.737916 -146.861738) (xy 230.790943 -146.820591)
			(xy 230.848923 -146.786781) (xy 230.91085 -146.760896) (xy 230.975644 -146.743387) (xy 231.042179 -146.734558)
			(xy 231.075738 -146.734022) (xy 231.107699 -146.734466) (xy 231.171118 -146.742482) (xy 231.233031 -146.758383)
			(xy 231.292464 -146.781918) (xy 231.334163 -146.804845) (xy 233.179868 -146.804845) (xy 233.179868 -146.740923)
			(xy 233.187879 -146.677505) (xy 233.203776 -146.615591) (xy 233.227308 -146.556158) (xy 233.258102 -146.500143)
			(xy 233.295675 -146.448428) (xy 233.339432 -146.401831) (xy 233.388685 -146.361086) (xy 233.442656 -146.326835)
			(xy 233.500495 -146.299618) (xy 233.561288 -146.279865) (xy 233.624078 -146.267887) (xy 233.687874 -146.263874)
			(xy 233.75167 -146.267887) (xy 233.81446 -146.279865) (xy 233.875253 -146.299618) (xy 233.933092 -146.326835)
			(xy 233.987063 -146.361086) (xy 234.036316 -146.401831) (xy 234.080073 -146.448428) (xy 234.117646 -146.500143)
			(xy 234.14844 -146.556158) (xy 234.171972 -146.615591) (xy 234.187869 -146.677505) (xy 234.19588 -146.740923)
			(xy 234.196222 -146.7627) (xy 234.808992 -146.7627) (xy 234.813007 -146.698901) (xy 234.824986 -146.636108)
			(xy 234.844741 -146.575312) (xy 234.87196 -146.517471) (xy 234.906215 -146.463498) (xy 234.946965 -146.414244)
			(xy 234.993566 -146.370487) (xy 235.045285 -146.332915) (xy 235.101305 -146.302122) (xy 235.160743 -146.278594)
			(xy 235.222661 -146.262701) (xy 235.286083 -146.254694) (xy 235.318046 -146.254216) (xy 235.349089 -146.254659)
			(xy 235.410713 -146.262219) (xy 235.470959 -146.277221) (xy 235.528932 -146.299443) (xy 235.58377 -146.328553)
			(xy 235.634659 -146.364121) (xy 235.680841 -146.405615) (xy 235.701586 -146.428714) (xy 235.709968 -146.438366)
			(xy 235.733844 -146.44751) (xy 235.83011 -146.435064) (xy 235.842396 -146.432841) (xy 235.862774 -146.418469)
			(xy 235.868972 -146.407632) (xy 235.883453 -146.37998) (xy 235.918114 -146.328069) (xy 235.958871 -146.280792)
			(xy 236.00511 -146.238862) (xy 236.056136 -146.202911) (xy 236.111181 -146.173478) (xy 236.169416 -146.151008)
			(xy 236.229964 -146.135839) (xy 236.291914 -146.128198) (xy 236.323124 -146.127724) (xy 236.355086 -146.128163)
			(xy 236.418506 -146.136178) (xy 236.480421 -146.152078) (xy 236.539855 -146.175612) (xy 236.595872 -146.206409)
			(xy 236.647586 -146.243985) (xy 236.694184 -146.287745) (xy 236.73493 -146.337) (xy 236.769181 -146.390974)
			(xy 236.796398 -146.448814) (xy 236.816151 -146.50961) (xy 236.828129 -146.572402) (xy 236.832143 -146.6362)
			(xy 236.828129 -146.699998) (xy 236.816151 -146.76279) (xy 236.796398 -146.823586) (xy 236.776645 -146.865563)
			(xy 236.931669 -146.865563) (xy 236.939423 -146.811615) (xy 236.954776 -146.759319) (xy 236.977415 -146.70974)
			(xy 237.00688 -146.663888) (xy 237.04257 -146.622695) (xy 237.083759 -146.587002) (xy 237.129608 -146.557533)
			(xy 237.179185 -146.534889) (xy 237.231479 -146.519531) (xy 237.285427 -146.511771) (xy 237.33993 -146.511768)
			(xy 237.393879 -146.519522) (xy 237.446175 -146.534874) (xy 237.495754 -146.557512) (xy 237.541607 -146.586976)
			(xy 237.553848 -146.597581) (xy 299.961294 -146.597581) (xy 299.961294 -146.533659) (xy 299.969305 -146.470241)
			(xy 299.985202 -146.408327) (xy 300.008734 -146.348894) (xy 300.039528 -146.292879) (xy 300.077101 -146.241164)
			(xy 300.120858 -146.194567) (xy 300.170111 -146.153822) (xy 300.224082 -146.119571) (xy 300.281921 -146.092354)
			(xy 300.342714 -146.072601) (xy 300.405504 -146.060623) (xy 300.4693 -146.05661) (xy 300.533096 -146.060623)
			(xy 300.595886 -146.072601) (xy 300.656679 -146.092354) (xy 300.714518 -146.119571) (xy 300.768489 -146.153822)
			(xy 300.817742 -146.194567) (xy 300.861499 -146.241164) (xy 300.899072 -146.292879) (xy 300.929866 -146.348894)
			(xy 300.953398 -146.408327) (xy 300.969295 -146.470241) (xy 300.977306 -146.533659) (xy 300.977808 -146.56562)
			(xy 300.977306 -146.597581) (xy 300.969295 -146.660999) (xy 300.953398 -146.722913) (xy 300.929866 -146.782346)
			(xy 300.899072 -146.838361) (xy 300.866584 -146.883077) (xy 304.131974 -146.883077) (xy 304.131974 -146.819155)
			(xy 304.139985 -146.755737) (xy 304.155882 -146.693823) (xy 304.179414 -146.63439) (xy 304.210208 -146.578375)
			(xy 304.247781 -146.52666) (xy 304.291538 -146.480063) (xy 304.340791 -146.439318) (xy 304.394762 -146.405067)
			(xy 304.452601 -146.37785) (xy 304.513394 -146.358097) (xy 304.576184 -146.346119) (xy 304.63998 -146.342106)
			(xy 304.703776 -146.346119) (xy 304.766566 -146.358097) (xy 304.827359 -146.37785) (xy 304.885198 -146.405067)
			(xy 304.939169 -146.439318) (xy 304.988422 -146.480063) (xy 305.032179 -146.52666) (xy 305.069752 -146.578375)
			(xy 305.100546 -146.63439) (xy 305.124078 -146.693823) (xy 305.139975 -146.755737) (xy 305.147986 -146.819155)
			(xy 305.148488 -146.851116) (xy 305.147986 -146.883077) (xy 305.139975 -146.946495) (xy 305.124078 -147.008409)
			(xy 305.100546 -147.067842) (xy 305.069752 -147.123857) (xy 305.032179 -147.175572) (xy 304.988422 -147.222169)
			(xy 304.939169 -147.262914) (xy 304.885198 -147.297165) (xy 304.827359 -147.324382) (xy 304.766566 -147.344135)
			(xy 304.703776 -147.356113) (xy 304.63998 -147.360127) (xy 304.576184 -147.356113) (xy 304.513394 -147.344135)
			(xy 304.452601 -147.324382) (xy 304.394762 -147.297165) (xy 304.340791 -147.262914) (xy 304.291538 -147.222169)
			(xy 304.247781 -147.175572) (xy 304.210208 -147.123857) (xy 304.179414 -147.067842) (xy 304.155882 -147.008409)
			(xy 304.139985 -146.946495) (xy 304.131974 -146.883077) (xy 300.866584 -146.883077) (xy 300.861499 -146.890076)
			(xy 300.817742 -146.936673) (xy 300.768489 -146.977418) (xy 300.714518 -147.011669) (xy 300.656679 -147.038886)
			(xy 300.595886 -147.058639) (xy 300.533096 -147.070617) (xy 300.4693 -147.074631) (xy 300.405504 -147.070617)
			(xy 300.342714 -147.058639) (xy 300.281921 -147.038886) (xy 300.224082 -147.011669) (xy 300.170111 -146.977418)
			(xy 300.120858 -146.936673) (xy 300.077101 -146.890076) (xy 300.039528 -146.838361) (xy 300.008734 -146.782346)
			(xy 299.985202 -146.722913) (xy 299.969305 -146.660999) (xy 299.961294 -146.597581) (xy 237.553848 -146.597581)
			(xy 237.5828 -146.622665) (xy 237.618494 -146.663854) (xy 237.647964 -146.709702) (xy 237.670609 -146.759279)
			(xy 237.685968 -146.811573) (xy 237.693728 -146.865521) (xy 237.694216 -146.892772) (xy 237.694216 -146.893534)
			(xy 237.694041 -146.909422) (xy 237.691366 -146.941086) (xy 237.688882 -146.95678) (xy 237.686872 -146.970851)
			(xy 237.689958 -146.999099) (xy 237.700711 -147.025402) (xy 237.718298 -147.047722) (xy 237.741357 -147.064328)
			(xy 237.7681 -147.073934) (xy 237.796455 -147.075796) (xy 237.824225 -147.069769) (xy 237.836964 -147.06346)
			(xy 237.864714 -147.049138) (xy 237.922968 -147.026633) (xy 237.983539 -147.011429) (xy 238.045515 -147.003753)
			(xy 238.07674 -147.003262) (xy 238.108278 -147.00381) (xy 238.17087 -147.011617) (xy 238.232016 -147.027106)
			(xy 238.290776 -147.05004) (xy 238.346248 -147.080065) (xy 238.39758 -147.116722) (xy 238.443984 -147.159446)
			(xy 238.484747 -147.207582) (xy 238.519243 -147.26039) (xy 238.546942 -147.31706) (xy 238.567418 -147.376721)
			(xy 238.580358 -147.438456) (xy 238.585563 -147.501318) (xy 238.582951 -147.564341) (xy 238.572565 -147.626557)
			(xy 238.554562 -147.68701) (xy 238.529221 -147.744772) (xy 238.496929 -147.798956) (xy 238.458183 -147.84873)
			(xy 238.413578 -147.893329) (xy 238.363798 -147.932068) (xy 238.30961 -147.964353) (xy 238.251844 -147.989687)
			(xy 238.191388 -148.007681) (xy 238.129171 -148.018059) (xy 238.066148 -148.020661) (xy 238.003287 -148.015448)
			(xy 237.941553 -148.0025) (xy 237.881895 -147.982015) (xy 237.825229 -147.954308) (xy 237.772426 -147.919805)
			(xy 237.724295 -147.879036) (xy 237.681578 -147.832626) (xy 237.644928 -147.781289) (xy 237.61491 -147.725812)
			(xy 237.591985 -147.667049) (xy 237.576504 -147.605901) (xy 237.568706 -147.543308) (xy 237.568232 -147.51177)
			(xy 237.568232 -147.511262) (xy 237.568854 -147.475467) (xy 237.578925 -147.404589) (xy 237.588298 -147.370038)
			(xy 237.591857 -147.356306) (xy 237.591948 -147.327945) (xy 237.584234 -147.300654) (xy 237.56931 -147.276538)
			(xy 237.548327 -147.257458) (xy 237.522905 -147.244887) (xy 237.495005 -147.239794) (xy 237.466781 -147.242573)
			(xy 237.453424 -147.247356) (xy 237.430954 -147.255881) (xy 237.384415 -147.267871) (xy 237.336737 -147.273914)
			(xy 237.312708 -147.27428) (xy 237.285456 -147.273831) (xy 237.231508 -147.266075) (xy 237.179212 -147.250721)
			(xy 237.129634 -147.228081) (xy 237.083782 -147.198616) (xy 237.042591 -147.162925) (xy 237.006898 -147.121736)
			(xy 236.97743 -147.075886) (xy 236.954787 -147.026309) (xy 236.939429 -146.974014) (xy 236.931671 -146.920066)
			(xy 236.931669 -146.865563) (xy 236.776645 -146.865563) (xy 236.769181 -146.881426) (xy 236.73493 -146.9354)
			(xy 236.694184 -146.984655) (xy 236.647586 -147.028415) (xy 236.595872 -147.065991) (xy 236.539855 -147.096788)
			(xy 236.480421 -147.120322) (xy 236.418506 -147.136222) (xy 236.355086 -147.144237) (xy 236.323124 -147.14474)
			(xy 236.292082 -147.144264) (xy 236.230459 -147.136712) (xy 236.170213 -147.121716) (xy 236.11224 -147.0995)
			(xy 236.057401 -147.070394) (xy 236.006512 -147.034831) (xy 235.960329 -146.993339) (xy 235.939584 -146.970242)
			(xy 235.931202 -146.96059) (xy 235.907326 -146.951446) (xy 235.81106 -146.963892) (xy 235.798776 -146.966119)
			(xy 235.778399 -146.98049) (xy 235.772198 -146.991324) (xy 235.757721 -147.018978) (xy 235.723061 -147.070892)
			(xy 235.682305 -147.11817) (xy 235.636065 -147.160101) (xy 235.585039 -147.196053) (xy 235.529993 -147.225485)
			(xy 235.471757 -147.247954) (xy 235.411207 -147.263122) (xy 235.349256 -147.27076) (xy 235.318046 -147.271232)
			(xy 235.286083 -147.270706) (xy 235.222661 -147.262699) (xy 235.160743 -147.246806) (xy 235.101305 -147.223278)
			(xy 235.045285 -147.192485) (xy 234.993566 -147.154913) (xy 234.946965 -147.111156) (xy 234.906215 -147.061902)
			(xy 234.87196 -147.007929) (xy 234.844741 -146.950088) (xy 234.824986 -146.889292) (xy 234.813007 -146.826499)
			(xy 234.808992 -146.7627) (xy 234.196222 -146.7627) (xy 234.196382 -146.772884) (xy 234.19588 -146.804845)
			(xy 234.187869 -146.868263) (xy 234.171972 -146.930177) (xy 234.14844 -146.98961) (xy 234.117646 -147.045625)
			(xy 234.080073 -147.09734) (xy 234.036316 -147.143937) (xy 233.987063 -147.184682) (xy 233.933092 -147.218933)
			(xy 233.875253 -147.24615) (xy 233.81446 -147.265903) (xy 233.75167 -147.277881) (xy 233.687874 -147.281895)
			(xy 233.624078 -147.277881) (xy 233.561288 -147.265903) (xy 233.500495 -147.24615) (xy 233.442656 -147.218933)
			(xy 233.388685 -147.184682) (xy 233.339432 -147.143937) (xy 233.295675 -147.09734) (xy 233.258102 -147.045625)
			(xy 233.227308 -146.98961) (xy 233.203776 -146.930177) (xy 233.187879 -146.868263) (xy 233.179868 -146.804845)
			(xy 231.334163 -146.804845) (xy 231.348478 -146.812716) (xy 231.400191 -146.850291) (xy 231.446787 -146.894051)
			(xy 231.487531 -146.943306) (xy 231.521781 -146.997279) (xy 231.548997 -147.055118) (xy 231.56875 -147.115913)
			(xy 231.580727 -147.178703) (xy 231.584741 -147.2425) (xy 231.580727 -147.306297) (xy 231.56875 -147.369087)
			(xy 231.548997 -147.429882) (xy 231.521781 -147.487721) (xy 231.487531 -147.541694) (xy 231.446787 -147.590949)
			(xy 231.400191 -147.634709) (xy 231.348478 -147.672284) (xy 231.292464 -147.703082) (xy 231.233031 -147.726617)
			(xy 231.171118 -147.742518) (xy 231.107699 -147.750534) (xy 231.075738 -147.751038) (xy 231.042179 -147.75052)
			(xy 230.975648 -147.741672) (xy 230.910858 -147.724151) (xy 230.848935 -147.698261) (xy 230.790954 -147.664453)
			(xy 230.737923 -147.623313) (xy 230.690764 -147.575556) (xy 230.6701 -147.549108) (xy 230.663459 -147.541089)
			(xy 230.645342 -147.530867) (xy 230.635048 -147.529296) (xy 230.561642 -147.520914) (xy 230.551218 -147.52029)
			(xy 230.531288 -147.526455) (xy 230.523034 -147.532852) (xy 230.502256 -147.549999) (xy 230.456756 -147.578841)
			(xy 230.407648 -147.600989) (xy 230.35591 -147.616001) (xy 230.302574 -147.623578) (xy 230.275638 -147.624038)
			(xy 230.248386 -147.623517) (xy 230.194435 -147.615765) (xy 230.142136 -147.600414) (xy 230.092555 -147.577775)
			(xy 230.046701 -147.548311) (xy 230.005507 -147.51262) (xy 229.969812 -147.471429) (xy 229.940343 -147.425578)
			(xy 229.917699 -147.375999) (xy 229.902343 -147.323702) (xy 229.894585 -147.269752) (xy 215.802928 -147.269752)
			(xy 214.75446 -148.31822) (xy 214.747063 -148.325069) (xy 214.728464 -148.332801) (xy 214.718392 -148.333206)
			(xy 211.574634 -148.333206) (xy 211.568031 -148.333427) (xy 211.555291 -148.336905) (xy 211.549488 -148.340064)
			(xy 211.534502 -148.348446) (xy 211.524342 -148.35632) (xy 211.515452 -148.364702) (xy 211.508086 -148.373846)
			(xy 211.490548 -148.400587) (xy 211.449787 -148.449864) (xy 211.40317 -148.493643) (xy 211.351434 -148.531235)
			(xy 211.295395 -148.562045) (xy 211.235935 -148.585588) (xy 211.173994 -148.601493) (xy 211.110547 -148.609509)
			(xy 211.046597 -148.609509) (xy 210.98315 -148.601493) (xy 210.921209 -148.585588) (xy 210.861749 -148.562045)
			(xy 210.80571 -148.531235) (xy 210.753974 -148.493643) (xy 210.707357 -148.449864) (xy 210.666596 -148.400587)
			(xy 210.649058 -148.373846) (xy 210.641692 -148.364702) (xy 210.632802 -148.35632) (xy 210.622642 -148.348446)
			(xy 210.607656 -148.340064) (xy 210.601836 -148.33695) (xy 210.589105 -148.333484) (xy 210.58251 -148.333206)
			(xy 197.664578 -148.333206) (xy 197.654087 -148.333771) (xy 197.634897 -148.342265) (xy 197.620718 -148.357737)
			(xy 197.616826 -148.367496) (xy 197.587362 -148.461222) (xy 197.585171 -148.46902) (xy 197.585304 -148.485209)
			(xy 197.587616 -148.492972) (xy 197.590156 -148.500592) (xy 197.599808 -148.513292) (xy 197.606666 -148.518118)
			(xy 197.70019 -148.583703) (xy 197.846238 -148.693081) (xy 231.134914 -148.693081) (xy 231.134914 -148.629159)
			(xy 231.142925 -148.565741) (xy 231.158822 -148.503827) (xy 231.182354 -148.444394) (xy 231.213148 -148.388379)
			(xy 231.250721 -148.336664) (xy 231.294478 -148.290067) (xy 231.343731 -148.249322) (xy 231.397702 -148.215071)
			(xy 231.455541 -148.187854) (xy 231.516334 -148.168101) (xy 231.579124 -148.156123) (xy 231.64292 -148.15211)
			(xy 231.706716 -148.156123) (xy 231.769506 -148.168101) (xy 231.830299 -148.187854) (xy 231.888138 -148.215071)
			(xy 231.942109 -148.249322) (xy 231.991362 -148.290067) (xy 232.035119 -148.336664) (xy 232.072692 -148.388379)
			(xy 232.103486 -148.444394) (xy 232.127018 -148.503827) (xy 232.142915 -148.565741) (xy 232.148252 -148.607991)
			(xy 234.123732 -148.607991) (xy 234.123732 -148.544069) (xy 234.131743 -148.480651) (xy 234.14764 -148.418737)
			(xy 234.171172 -148.359304) (xy 234.201966 -148.303289) (xy 234.239539 -148.251574) (xy 234.283296 -148.204977)
			(xy 234.332549 -148.164232) (xy 234.38652 -148.129981) (xy 234.444359 -148.102764) (xy 234.505152 -148.083011)
			(xy 234.567942 -148.071033) (xy 234.631738 -148.06702) (xy 234.695534 -148.071033) (xy 234.758324 -148.083011)
			(xy 234.819117 -148.102764) (xy 234.876956 -148.129981) (xy 234.930927 -148.164232) (xy 234.98018 -148.204977)
			(xy 235.023937 -148.251574) (xy 235.06151 -148.303289) (xy 235.092304 -148.359304) (xy 235.115836 -148.418737)
			(xy 235.131733 -148.480651) (xy 235.139744 -148.544069) (xy 235.140246 -148.57603) (xy 235.139744 -148.607991)
			(xy 235.131733 -148.671409) (xy 235.115836 -148.733323) (xy 235.092304 -148.792756) (xy 235.06151 -148.848771)
			(xy 235.023937 -148.900486) (xy 234.98018 -148.947083) (xy 234.930927 -148.987828) (xy 234.876956 -149.022079)
			(xy 234.819117 -149.049296) (xy 234.758324 -149.069049) (xy 234.695534 -149.081027) (xy 234.631738 -149.085041)
			(xy 234.567942 -149.081027) (xy 234.505152 -149.069049) (xy 234.444359 -149.049296) (xy 234.38652 -149.022079)
			(xy 234.332549 -148.987828) (xy 234.283296 -148.947083) (xy 234.239539 -148.900486) (xy 234.201966 -148.848771)
			(xy 234.171172 -148.792756) (xy 234.14764 -148.733323) (xy 234.131743 -148.671409) (xy 234.123732 -148.607991)
			(xy 232.148252 -148.607991) (xy 232.150926 -148.629159) (xy 232.151428 -148.66112) (xy 232.150926 -148.693081)
			(xy 232.142915 -148.756499) (xy 232.127018 -148.818413) (xy 232.103486 -148.877846) (xy 232.072692 -148.933861)
			(xy 232.035119 -148.985576) (xy 231.991362 -149.032173) (xy 231.942109 -149.072918) (xy 231.888138 -149.107169)
			(xy 231.830299 -149.134386) (xy 231.769506 -149.154139) (xy 231.706716 -149.166117) (xy 231.64292 -149.170131)
			(xy 231.579124 -149.166117) (xy 231.516334 -149.154139) (xy 231.455541 -149.134386) (xy 231.397702 -149.107169)
			(xy 231.343731 -149.072918) (xy 231.294478 -149.032173) (xy 231.250721 -148.985576) (xy 231.213148 -148.933861)
			(xy 231.182354 -148.877846) (xy 231.158822 -148.818413) (xy 231.142925 -148.756499) (xy 231.134914 -148.693081)
			(xy 197.846238 -148.693081) (xy 197.883049 -148.720649) (xy 198.060904 -148.864033) (xy 198.233529 -149.013672)
			(xy 198.400705 -149.169376) (xy 198.505059 -149.273768) (xy 237.176056 -149.273768) (xy 237.176558 -149.241807)
			(xy 237.184569 -149.178389) (xy 237.200466 -149.116475) (xy 237.223998 -149.057042) (xy 237.254792 -149.001027)
			(xy 237.292365 -148.949312) (xy 237.336122 -148.902715) (xy 237.385375 -148.86197) (xy 237.439346 -148.827719)
			(xy 237.497185 -148.800502) (xy 237.557978 -148.780749) (xy 237.620768 -148.768771) (xy 237.684564 -148.764758)
			(xy 237.74836 -148.768771) (xy 237.81115 -148.780749) (xy 237.871943 -148.800502) (xy 237.929782 -148.827719)
			(xy 237.983753 -148.86197) (xy 238.033006 -148.902715) (xy 238.076763 -148.949312) (xy 238.114336 -149.001027)
			(xy 238.14513 -149.057042) (xy 238.168662 -149.116475) (xy 238.184559 -149.178389) (xy 238.19257 -149.241807)
			(xy 238.193072 -149.273768) (xy 238.192528 -149.307873) (xy 238.190553 -149.3225) (xy 238.699125 -149.3225)
			(xy 238.703138 -149.258712) (xy 238.715114 -149.19593) (xy 238.734864 -149.135144) (xy 238.762075 -149.077312)
			(xy 238.796321 -149.023347) (xy 238.837059 -148.974098) (xy 238.883648 -148.930344) (xy 238.935354 -148.892774)
			(xy 238.991361 -148.86198) (xy 239.050785 -148.838447) (xy 239.11269 -148.822548) (xy 239.176099 -148.814532)
			(xy 239.208056 -148.814028) (xy 239.238777 -148.814466) (xy 239.299773 -148.821873) (xy 239.359432 -148.836571)
			(xy 239.416887 -148.858347) (xy 239.471301 -148.886884) (xy 239.496854 -148.903944) (xy 239.505539 -148.909337)
			(xy 239.525556 -148.913398) (xy 239.545573 -148.909337) (xy 239.554258 -148.903944) (xy 239.579822 -148.886902)
			(xy 239.634234 -148.858368) (xy 239.691687 -148.836594) (xy 239.751344 -148.821898) (xy 239.812336 -148.814493)
			(xy 239.843056 -148.814028) (xy 239.875022 -148.814434) (xy 239.938452 -148.822442) (xy 240.000377 -148.838337)
			(xy 240.059822 -148.861868) (xy 240.115848 -148.892665) (xy 240.167573 -148.930241) (xy 240.21418 -148.974004)
			(xy 240.254934 -149.023263) (xy 240.289192 -149.077243) (xy 240.316415 -149.13509) (xy 240.336172 -149.195893)
			(xy 240.348153 -149.258693) (xy 240.352168 -149.3225) (xy 240.348153 -149.386307) (xy 240.336172 -149.449107)
			(xy 240.316415 -149.50991) (xy 240.289192 -149.567757) (xy 240.254934 -149.621737) (xy 240.21418 -149.670996)
			(xy 240.167573 -149.714759) (xy 240.115848 -149.752335) (xy 240.059822 -149.783132) (xy 240.000377 -149.806663)
			(xy 239.938452 -149.822558) (xy 239.875022 -149.830566) (xy 239.843056 -149.831044) (xy 239.812335 -149.830604)
			(xy 239.751339 -149.823199) (xy 239.69168 -149.808502) (xy 239.634225 -149.786726) (xy 239.579811 -149.758189)
			(xy 239.554258 -149.741128) (xy 239.545573 -149.735735) (xy 239.525556 -149.731674) (xy 239.505539 -149.735735)
			(xy 239.496854 -149.741128) (xy 239.471312 -149.758205) (xy 239.416894 -149.786734) (xy 239.359436 -149.808501)
			(xy 239.299774 -149.823189) (xy 239.238778 -149.830584) (xy 239.208056 -149.831044) (xy 239.176099 -149.830468)
			(xy 239.11269 -149.822452) (xy 239.050785 -149.806553) (xy 238.991361 -149.78302) (xy 238.935354 -149.752226)
			(xy 238.883648 -149.714656) (xy 238.837059 -149.670902) (xy 238.796321 -149.621653) (xy 238.762075 -149.567688)
			(xy 238.734864 -149.509856) (xy 238.715114 -149.44907) (xy 238.703138 -149.386288) (xy 238.699125 -149.3225)
			(xy 238.190553 -149.3225) (xy 238.183402 -149.375469) (xy 238.165323 -149.441239) (xy 238.138616 -149.504003)
			(xy 238.103759 -149.562634) (xy 238.061378 -149.616079) (xy 238.012234 -149.663381) (xy 237.985046 -149.683978)
			(xy 237.977167 -149.690231) (xy 237.966694 -149.707387) (xy 237.964726 -149.717252) (xy 237.953804 -149.788118)
			(xy 237.952633 -149.798098) (xy 237.957354 -149.817616) (xy 237.962948 -149.825964) (xy 237.980207 -149.850595)
			(xy 238.00761 -149.904129) (xy 238.026283 -149.961296) (xy 238.035764 -150.020685) (xy 238.036354 -150.050754)
			(xy 238.035868 -150.078005) (xy 238.028112 -150.131953) (xy 238.012757 -150.184248) (xy 237.990115 -150.233825)
			(xy 237.960649 -150.279675) (xy 237.924958 -150.320866) (xy 237.883767 -150.356557) (xy 237.837917 -150.386023)
			(xy 237.78834 -150.408665) (xy 237.736045 -150.42402) (xy 237.682097 -150.431776) (xy 237.627595 -150.431776)
			(xy 237.573647 -150.42402) (xy 237.521352 -150.408665) (xy 237.471775 -150.386023) (xy 237.425925 -150.356557)
			(xy 237.384734 -150.320866) (xy 237.349043 -150.279675) (xy 237.319577 -150.233825) (xy 237.296935 -150.184248)
			(xy 237.28158 -150.131953) (xy 237.273824 -150.078005) (xy 237.273338 -150.050754) (xy 237.273777 -150.02376)
			(xy 237.281389 -149.970311) (xy 237.296454 -149.918468) (xy 237.318673 -149.869263) (xy 237.347602 -149.82368)
			(xy 237.364778 -149.80285) (xy 237.371382 -149.79523) (xy 237.377732 -149.77618) (xy 237.371128 -149.694392)
			(xy 237.369989 -149.684459) (xy 237.360935 -149.666646) (xy 237.353602 -149.659848) (xy 237.33012 -149.639111)
			(xy 237.287928 -149.592798) (xy 237.251746 -149.541654) (xy 237.22212 -149.486451) (xy 237.1995 -149.428028)
			(xy 237.184228 -149.367268) (xy 237.176536 -149.305093) (xy 237.176056 -149.273768) (xy 198.505059 -149.273768)
			(xy 198.562217 -149.330947) (xy 198.717862 -149.498178) (xy 198.867439 -149.670857) (xy 199.010759 -149.848764)
			(xy 199.07578 -149.935649) (xy 228.695498 -149.935649) (xy 228.695498 -149.871727) (xy 228.703509 -149.808309)
			(xy 228.719406 -149.746395) (xy 228.742938 -149.686962) (xy 228.773732 -149.630947) (xy 228.811305 -149.579232)
			(xy 228.855062 -149.532635) (xy 228.904315 -149.49189) (xy 228.958286 -149.457639) (xy 229.016125 -149.430422)
			(xy 229.076918 -149.410669) (xy 229.139708 -149.398691) (xy 229.203504 -149.394678) (xy 229.2673 -149.398691)
			(xy 229.33009 -149.410669) (xy 229.390883 -149.430422) (xy 229.448722 -149.457639) (xy 229.502693 -149.49189)
			(xy 229.551946 -149.532635) (xy 229.595703 -149.579232) (xy 229.633276 -149.630947) (xy 229.66407 -149.686962)
			(xy 229.687602 -149.746395) (xy 229.703499 -149.808309) (xy 229.71151 -149.871727) (xy 229.712012 -149.903688)
			(xy 229.711584 -149.930952) (xy 230.005866 -149.930952) (xy 230.005866 -149.876448) (xy 230.013622 -149.8225)
			(xy 230.028977 -149.770204) (xy 230.051619 -149.720626) (xy 230.081085 -149.674775) (xy 230.116776 -149.633583)
			(xy 230.157967 -149.597891) (xy 230.203817 -149.568423) (xy 230.253395 -149.545781) (xy 230.30569 -149.530424)
			(xy 230.359638 -149.522666) (xy 230.38689 -149.52218) (xy 230.413625 -149.522641) (xy 230.466572 -149.530094)
			(xy 230.51796 -149.544869) (xy 230.56678 -149.566676) (xy 230.612076 -149.595089) (xy 230.65296 -149.629549)
			(xy 230.68863 -149.669382) (xy 230.703882 -149.691344) (xy 230.712708 -149.703448) (xy 230.735851 -149.722438)
			(xy 230.763504 -149.733906) (xy 230.793294 -149.736868) (xy 230.822663 -149.731069) (xy 230.849092 -149.717008)
			(xy 230.870312 -149.695892) (xy 230.877872 -149.682962) (xy 230.892664 -149.656347) (xy 230.927695 -149.606541)
			(xy 230.968424 -149.561275) (xy 231.014268 -149.521197) (xy 231.064571 -149.486882) (xy 231.118612 -149.458821)
			(xy 231.175618 -149.437415) (xy 231.234772 -149.42297) (xy 231.295228 -149.415695) (xy 231.325674 -149.415246)
			(xy 231.357635 -149.415817) (xy 231.421052 -149.423826) (xy 231.482965 -149.43972) (xy 231.542399 -149.463248)
			(xy 231.598414 -149.49404) (xy 231.650128 -149.531611) (xy 231.696726 -149.575366) (xy 231.737472 -149.624617)
			(xy 231.771723 -149.678587) (xy 231.79894 -149.736424) (xy 231.818694 -149.797216) (xy 231.830672 -149.860005)
			(xy 231.834686 -149.9238) (xy 231.830672 -149.987595) (xy 231.818694 -150.050384) (xy 231.79894 -150.111176)
			(xy 231.771723 -150.169013) (xy 231.737472 -150.222983) (xy 231.696726 -150.272234) (xy 231.650128 -150.315989)
			(xy 231.598414 -150.35356) (xy 231.542399 -150.384352) (xy 231.482965 -150.40788) (xy 231.421052 -150.423774)
			(xy 231.357635 -150.431783) (xy 231.325674 -150.432262) (xy 231.294022 -150.431744) (xy 231.231208 -150.423884)
			(xy 231.169855 -150.408287) (xy 231.110912 -150.385196) (xy 231.055292 -150.354968) (xy 231.003853 -150.318069)
			(xy 230.957392 -150.275072) (xy 230.916628 -150.22664) (xy 230.88219 -150.173522) (xy 230.867966 -150.145242)
			(xy 230.860952 -150.131989) (xy 230.840698 -150.109904) (xy 230.814905 -150.094651) (xy 230.785793 -150.087544)
			(xy 230.755873 -150.089196) (xy 230.727721 -150.099464) (xy 230.703763 -150.117464) (xy 230.694484 -150.12924)
			(xy 230.676412 -150.15299) (xy 230.634067 -150.195041) (xy 230.58569 -150.229983) (xy 230.53246 -150.256964)
			(xy 230.475678 -150.275326) (xy 230.416729 -150.284619) (xy 230.38689 -150.285196) (xy 230.359638 -150.284734)
			(xy 230.30569 -150.276976) (xy 230.253395 -150.261619) (xy 230.203817 -150.238977) (xy 230.157967 -150.209509)
			(xy 230.116776 -150.173817) (xy 230.081085 -150.132625) (xy 230.051619 -150.086774) (xy 230.028977 -150.037196)
			(xy 230.013622 -149.9849) (xy 230.005866 -149.930952) (xy 229.711584 -149.930952) (xy 229.71151 -149.935649)
			(xy 229.703499 -149.999067) (xy 229.687602 -150.060981) (xy 229.66407 -150.120414) (xy 229.633276 -150.176429)
			(xy 229.595703 -150.228144) (xy 229.551946 -150.274741) (xy 229.502693 -150.315486) (xy 229.448722 -150.349737)
			(xy 229.390883 -150.376954) (xy 229.33009 -150.396707) (xy 229.2673 -150.408685) (xy 229.203504 -150.412699)
			(xy 229.139708 -150.408685) (xy 229.076918 -150.396707) (xy 229.016125 -150.376954) (xy 228.958286 -150.349737)
			(xy 228.904315 -150.315486) (xy 228.855062 -150.274741) (xy 228.811305 -150.228144) (xy 228.773732 -150.176429)
			(xy 228.742938 -150.120414) (xy 228.719406 -150.060981) (xy 228.703509 -149.999067) (xy 228.695498 -149.935649)
			(xy 199.07578 -149.935649) (xy 199.14764 -150.031672) (xy 199.277906 -150.219348) (xy 199.401392 -150.411552)
			(xy 199.51794 -150.608041) (xy 199.627403 -150.808564) (xy 199.72964 -151.012866) (xy 199.755796 -151.070155)
			(xy 228.822433 -151.070155) (xy 228.822433 -151.015645) (xy 228.83019 -150.961691) (xy 228.845548 -150.90939)
			(xy 228.868192 -150.859806) (xy 228.897662 -150.81395) (xy 228.933358 -150.772755) (xy 228.974554 -150.737059)
			(xy 229.02041 -150.70759) (xy 229.069993 -150.684946) (xy 229.122295 -150.66959) (xy 229.176249 -150.661833)
			(xy 229.203504 -150.66137) (xy 229.230439 -150.661806) (xy 229.283772 -150.669401) (xy 229.335505 -150.684427)
			(xy 229.384609 -150.706583) (xy 229.430106 -150.735428) (xy 229.4509 -150.752556) (xy 229.459147 -150.75897)
			(xy 229.479081 -150.765142) (xy 229.489508 -150.764494) (xy 229.562914 -150.756112) (xy 229.573183 -150.75447)
			(xy 229.591274 -150.744259) (xy 229.597966 -150.7363) (xy 229.61858 -150.709811) (xy 229.66574 -150.662047)
			(xy 229.718777 -150.620905) (xy 229.776766 -150.587102) (xy 229.8387 -150.561224) (xy 229.903502 -150.543723)
			(xy 229.970042 -150.534902) (xy 230.003604 -150.53437) (xy 230.035563 -150.534916) (xy 230.098978 -150.542928)
			(xy 230.160889 -150.558824) (xy 230.220319 -150.582355) (xy 230.276332 -150.613148) (xy 230.328043 -150.650719)
			(xy 230.374638 -150.694475) (xy 230.415381 -150.743725) (xy 230.449631 -150.797694) (xy 230.452577 -150.803955)
			(xy 239.650441 -150.803955) (xy 239.650441 -150.749445) (xy 239.658199 -150.69549) (xy 239.673557 -150.643188)
			(xy 239.696202 -150.593605) (xy 239.725673 -150.547749) (xy 239.761371 -150.506554) (xy 239.802568 -150.470859)
			(xy 239.848426 -150.44139) (xy 239.898011 -150.418748) (xy 239.950313 -150.403394) (xy 240.004269 -150.395639)
			(xy 240.031524 -150.395178) (xy 240.057206 -150.395576) (xy 240.108105 -150.402477) (xy 240.157615 -150.416152)
			(xy 240.204841 -150.436352) (xy 240.248926 -150.462711) (xy 240.289071 -150.494753) (xy 240.307114 -150.513034)
			(xy 240.31448 -150.520654) (xy 240.333784 -150.528782) (xy 240.429542 -150.527766) (xy 240.448592 -150.51913)
			(xy 240.455704 -150.511256) (xy 240.476377 -150.489194) (xy 240.522097 -150.449631) (xy 240.572187 -150.41577)
			(xy 240.62594 -150.38809) (xy 240.682597 -150.366981) (xy 240.741358 -150.352742) (xy 240.801393 -150.345573)
			(xy 240.831624 -150.34514) (xy 240.863587 -150.345547) (xy 240.927009 -150.353562) (xy 240.988926 -150.369462)
			(xy 241.048362 -150.392997) (xy 241.10438 -150.423796) (xy 241.156097 -150.461372) (xy 241.202696 -150.505134)
			(xy 241.243443 -150.55439) (xy 241.277696 -150.608366) (xy 241.304529 -150.665391) (xy 242.000272 -150.665391)
			(xy 242.000272 -150.601469) (xy 242.008283 -150.538051) (xy 242.02418 -150.476137) (xy 242.047712 -150.416704)
			(xy 242.078506 -150.360689) (xy 242.116079 -150.308974) (xy 242.159836 -150.262377) (xy 242.209089 -150.221632)
			(xy 242.26306 -150.187381) (xy 242.320899 -150.160164) (xy 242.381692 -150.140411) (xy 242.444482 -150.128433)
			(xy 242.508278 -150.12442) (xy 242.572074 -150.128433) (xy 242.634864 -150.140411) (xy 242.695657 -150.160164)
			(xy 242.753496 -150.187381) (xy 242.807467 -150.221632) (xy 242.85672 -150.262377) (xy 242.900477 -150.308974)
			(xy 242.93805 -150.360689) (xy 242.968844 -150.416704) (xy 242.992376 -150.476137) (xy 243.008273 -150.538051)
			(xy 243.016284 -150.601469) (xy 243.016786 -150.63343) (xy 243.016284 -150.665391) (xy 243.008273 -150.728809)
			(xy 242.992376 -150.790723) (xy 242.968844 -150.850156) (xy 242.93805 -150.906171) (xy 242.900477 -150.957886)
			(xy 242.85672 -151.004483) (xy 242.807467 -151.045228) (xy 242.753496 -151.079479) (xy 242.695657 -151.106696)
			(xy 242.634864 -151.126449) (xy 242.572074 -151.138427) (xy 242.508278 -151.142441) (xy 242.444482 -151.138427)
			(xy 242.381692 -151.126449) (xy 242.320899 -151.106696) (xy 242.26306 -151.079479) (xy 242.209089 -151.045228)
			(xy 242.159836 -151.004483) (xy 242.116079 -150.957886) (xy 242.078506 -150.906171) (xy 242.047712 -150.850156)
			(xy 242.02418 -150.790723) (xy 242.008283 -150.728809) (xy 242.000272 -150.665391) (xy 241.304529 -150.665391)
			(xy 241.304913 -150.666208) (xy 241.324667 -150.727006) (xy 241.336645 -150.7898) (xy 241.340659 -150.8536)
			(xy 241.336645 -150.9174) (xy 241.324667 -150.980194) (xy 241.304913 -151.040992) (xy 241.277696 -151.098834)
			(xy 241.243443 -151.15281) (xy 241.202696 -151.202066) (xy 241.156097 -151.245828) (xy 241.10438 -151.283404)
			(xy 241.048362 -151.314203) (xy 240.988926 -151.337738) (xy 240.927009 -151.353638) (xy 240.863587 -151.361653)
			(xy 240.831624 -151.362156) (xy 240.79907 -151.36166) (xy 240.734495 -151.353341) (xy 240.67151 -151.336849)
			(xy 240.611145 -151.312452) (xy 240.554387 -151.280552) (xy 240.502165 -151.241668) (xy 240.455332 -151.196437)
			(xy 240.414655 -151.145599) (xy 240.397284 -151.118062) (xy 240.391696 -151.108918) (xy 240.374678 -151.09698)
			(xy 240.29162 -151.079708) (xy 240.28127 -151.078145) (xy 240.260813 -151.082452) (xy 240.251996 -151.08809)
			(xy 240.227675 -151.104611) (xy 240.175043 -151.130811) (xy 240.119017 -151.148632) (xy 240.06092 -151.15765)
			(xy 240.031524 -151.158194) (xy 240.004269 -151.157761) (xy 239.950313 -151.150006) (xy 239.898011 -151.134652)
			(xy 239.848426 -151.11201) (xy 239.802568 -151.082541) (xy 239.761371 -151.046846) (xy 239.725673 -151.005651)
			(xy 239.696202 -150.959795) (xy 239.673557 -150.910212) (xy 239.658199 -150.85791) (xy 239.650441 -150.803955)
			(xy 230.452577 -150.803955) (xy 230.476846 -150.85553) (xy 230.496598 -150.91632) (xy 230.508575 -150.979107)
			(xy 230.512589 -151.0429) (xy 230.508575 -151.106693) (xy 230.496598 -151.16948) (xy 230.476846 -151.23027)
			(xy 230.449631 -151.288106) (xy 230.415381 -151.342075) (xy 230.374638 -151.391325) (xy 230.328043 -151.435081)
			(xy 230.276332 -151.472652) (xy 230.220319 -151.503445) (xy 230.160889 -151.526976) (xy 230.098978 -151.542872)
			(xy 230.035563 -151.550884) (xy 230.003604 -151.551386) (xy 229.970048 -151.5508) (xy 229.90352 -151.541962)
			(xy 229.838732 -151.524451) (xy 229.77681 -151.498572) (xy 229.718829 -151.464774) (xy 229.665796 -151.423645)
			(xy 229.618632 -151.375899) (xy 229.597966 -151.349456) (xy 229.591289 -151.341471) (xy 229.573199 -151.331229)
			(xy 229.562914 -151.329644) (xy 229.489508 -151.321262) (xy 229.479084 -151.320631) (xy 229.459154 -151.326802)
			(xy 229.4509 -151.3332) (xy 229.430104 -151.350324) (xy 229.384608 -151.379168) (xy 229.335504 -151.401319)
			(xy 229.283771 -151.416337) (xy 229.230438 -151.423921) (xy 229.203504 -151.424386) (xy 229.176249 -151.423967)
			(xy 229.122295 -151.41621) (xy 229.069993 -151.400854) (xy 229.02041 -151.37821) (xy 228.974554 -151.348741)
			(xy 228.933358 -151.313045) (xy 228.897662 -151.27185) (xy 228.868192 -151.225994) (xy 228.845548 -151.17641)
			(xy 228.83019 -151.124109) (xy 228.822433 -151.070155) (xy 199.755796 -151.070155) (xy 199.824522 -151.220685)
			(xy 199.911927 -151.431758) (xy 199.991744 -151.645816) (xy 199.995313 -151.656542) (xy 238.127286 -151.656542)
			(xy 238.127788 -151.624581) (xy 238.135799 -151.561163) (xy 238.151696 -151.499249) (xy 238.175228 -151.439816)
			(xy 238.206022 -151.383801) (xy 238.243595 -151.332086) (xy 238.287352 -151.285489) (xy 238.336605 -151.244744)
			(xy 238.390576 -151.210493) (xy 238.448415 -151.183276) (xy 238.509208 -151.163523) (xy 238.571998 -151.151545)
			(xy 238.635794 -151.147532) (xy 238.69959 -151.151545) (xy 238.76238 -151.163523) (xy 238.823173 -151.183276)
			(xy 238.881012 -151.210493) (xy 238.934983 -151.244744) (xy 238.984236 -151.285489) (xy 239.027993 -151.332086)
			(xy 239.065566 -151.383801) (xy 239.09636 -151.439816) (xy 239.119892 -151.499249) (xy 239.135789 -151.561163)
			(xy 239.1438 -151.624581) (xy 239.144302 -151.656542) (xy 239.143714 -151.690326) (xy 239.134761 -151.757299)
			(xy 239.117018 -151.822497) (xy 239.090798 -151.884771) (xy 239.056563 -151.943025) (xy 239.014916 -151.996232)
			(xy 238.966589 -152.043455) (xy 238.912435 -152.083864) (xy 238.88319 -152.100788) (xy 238.882936 -152.100788)
			(xy 238.872718 -152.107296) (xy 238.859337 -152.127455) (xy 238.857282 -152.139396) (xy 238.846106 -152.233122)
			(xy 238.854742 -152.256236) (xy 238.863632 -152.264364) (xy 238.882675 -152.282504) (xy 238.916124 -152.323089)
			(xy 238.943679 -152.367885) (xy 238.964819 -152.416041) (xy 238.979142 -152.466646) (xy 238.986377 -152.518738)
			(xy 238.986822 -152.545034) (xy 238.986336 -152.572285) (xy 238.97858 -152.626233) (xy 238.963225 -152.678528)
			(xy 238.940583 -152.728105) (xy 238.911117 -152.773955) (xy 238.875426 -152.815146) (xy 238.834235 -152.850837)
			(xy 238.788385 -152.880303) (xy 238.738808 -152.902945) (xy 238.686513 -152.9183) (xy 238.632565 -152.926056)
			(xy 238.578063 -152.926056) (xy 238.524115 -152.9183) (xy 238.47182 -152.902945) (xy 238.422243 -152.880303)
			(xy 238.376393 -152.850837) (xy 238.335202 -152.815146) (xy 238.299511 -152.773955) (xy 238.270045 -152.728105)
			(xy 238.247403 -152.678528) (xy 238.232048 -152.626233) (xy 238.224292 -152.572285) (xy 238.223806 -152.545034)
			(xy 238.224334 -152.516556) (xy 238.232791 -152.460232) (xy 238.249536 -152.405795) (xy 238.274197 -152.354455)
			(xy 238.306224 -152.307358) (xy 238.344903 -152.265551) (xy 238.366808 -152.247346) (xy 238.37646 -152.239726)
			(xy 238.386366 -152.217374) (xy 238.381032 -152.11044) (xy 238.369094 -152.089612) (xy 238.358934 -152.082754)
			(xy 238.358426 -152.082754) (xy 238.332227 -152.065084) (xy 238.283939 -152.02432) (xy 238.241074 -151.977886)
			(xy 238.204293 -151.926499) (xy 238.174163 -151.870951) (xy 238.151148 -151.812097) (xy 238.135603 -151.750845)
			(xy 238.127768 -151.688139) (xy 238.127286 -151.656542) (xy 199.995313 -151.656542) (xy 200.063872 -151.862585)
			(xy 200.128218 -152.08179) (xy 200.184702 -152.303152) (xy 200.23325 -152.526389) (xy 200.258237 -152.664922)
			(xy 228.136704 -152.664922) (xy 228.13719 -152.637671) (xy 228.144946 -152.583723) (xy 228.160301 -152.531428)
			(xy 228.182943 -152.481851) (xy 228.212409 -152.436001) (xy 228.2481 -152.39481) (xy 228.289291 -152.359119)
			(xy 228.335141 -152.329653) (xy 228.384718 -152.307011) (xy 228.437013 -152.291656) (xy 228.490961 -152.2839)
			(xy 228.545463 -152.2839) (xy 228.599411 -152.291656) (xy 228.651706 -152.307011) (xy 228.701283 -152.329653)
			(xy 228.747133 -152.359119) (xy 228.788324 -152.39481) (xy 228.824015 -152.436001) (xy 228.853481 -152.481851)
			(xy 228.876123 -152.531428) (xy 228.891478 -152.583723) (xy 228.899234 -152.637671) (xy 228.89972 -152.664922)
			(xy 228.89915 -152.694591) (xy 228.889966 -152.753214) (xy 228.871824 -152.809711) (xy 228.845161 -152.862721)
			(xy 228.828346 -152.887172) (xy 228.822094 -152.896881) (xy 228.818268 -152.919634) (xy 228.82098 -152.93086)
			(xy 228.84638 -153.018744) (xy 228.861874 -153.036016) (xy 228.872796 -153.040334) (xy 228.903673 -153.053411)
			(xy 228.96198 -153.086525) (xy 229.015431 -153.127013) (xy 229.063099 -153.174174) (xy 229.104157 -153.227189)
			(xy 229.137892 -153.28514) (xy 229.163721 -153.34702) (xy 229.181195 -153.411758) (xy 229.190011 -153.478231)
			(xy 229.19055 -153.511758) (xy 229.190048 -153.543719) (xy 229.182085 -153.606754) (xy 235.071664 -153.606754)
			(xy 235.075735 -153.551132) (xy 235.087861 -153.496695) (xy 235.107784 -153.444604) (xy 235.13508 -153.395969)
			(xy 235.169166 -153.351826) (xy 235.209315 -153.313117) (xy 235.254673 -153.280666) (xy 235.304273 -153.255165)
			(xy 235.357057 -153.237158) (xy 235.4119 -153.227028) (xy 235.467634 -153.224991) (xy 235.523071 -153.231091)
			(xy 235.577028 -153.245197) (xy 235.628357 -153.267009) (xy 235.675963 -153.296063) (xy 235.718831 -153.331738)
			(xy 235.756048 -153.373275) (xy 235.786821 -153.419788) (xy 235.810493 -153.470285) (xy 235.826561 -153.523692)
			(xy 235.834681 -153.578868) (xy 235.83519 -153.606754) (xy 235.834681 -153.63464) (xy 235.826561 -153.689816)
			(xy 235.810493 -153.743223) (xy 235.786821 -153.79372) (xy 235.756048 -153.840233) (xy 235.718831 -153.88177)
			(xy 235.675963 -153.917445) (xy 235.628357 -153.946499) (xy 235.577028 -153.968311) (xy 235.523071 -153.982417)
			(xy 235.467634 -153.988517) (xy 235.4119 -153.98648) (xy 235.357057 -153.97635) (xy 235.304273 -153.958343)
			(xy 235.254673 -153.932842) (xy 235.209315 -153.900391) (xy 235.169166 -153.861682) (xy 235.13508 -153.817539)
			(xy 235.107784 -153.768904) (xy 235.087861 -153.716813) (xy 235.075735 -153.662376) (xy 235.071664 -153.606754)
			(xy 229.182085 -153.606754) (xy 229.182037 -153.607137) (xy 229.16614 -153.669051) (xy 229.142608 -153.728484)
			(xy 229.111814 -153.784499) (xy 229.074241 -153.836214) (xy 229.030484 -153.882811) (xy 228.981231 -153.923556)
			(xy 228.92726 -153.957807) (xy 228.869421 -153.985024) (xy 228.808628 -154.004777) (xy 228.745838 -154.016755)
			(xy 228.682042 -154.020769) (xy 228.618246 -154.016755) (xy 228.555456 -154.004777) (xy 228.494663 -153.985024)
			(xy 228.436824 -153.957807) (xy 228.382853 -153.923556) (xy 228.3336 -153.882811) (xy 228.289843 -153.836214)
			(xy 228.25227 -153.784499) (xy 228.221476 -153.728484) (xy 228.197944 -153.669051) (xy 228.182047 -153.607137)
			(xy 228.174036 -153.543719) (xy 228.173534 -153.511758) (xy 228.174085 -153.477669) (xy 228.183206 -153.410103)
			(xy 228.201265 -153.34436) (xy 228.227938 -153.281616) (xy 228.262749 -153.222994) (xy 228.305075 -153.169544)
			(xy 228.329236 -153.14549) (xy 228.337618 -153.137362) (xy 228.345746 -153.115518) (xy 228.335332 -153.012902)
			(xy 228.32314 -152.99309) (xy 228.313234 -152.98674) (xy 228.290399 -152.971653) (xy 228.248924 -152.935944)
			(xy 228.212975 -152.894677) (xy 228.183288 -152.848698) (xy 228.160472 -152.798951) (xy 228.144996 -152.746455)
			(xy 228.137176 -152.692287) (xy 228.136704 -152.664922) (xy 200.258237 -152.664922) (xy 200.273801 -152.751216)
			(xy 200.306303 -152.977346) (xy 200.330715 -153.204493) (xy 200.347005 -153.432366) (xy 200.355154 -153.660675)
			(xy 200.355708 -153.774902) (xy 200.35521 -153.887875) (xy 200.347236 -154.113681) (xy 200.331298 -154.339064)
			(xy 200.307415 -154.563745) (xy 200.275619 -154.787443) (xy 200.235947 -155.009879) (xy 200.18845 -155.230777)
			(xy 200.152952 -155.371503) (xy 237.171478 -155.371503) (xy 237.171478 -155.307581) (xy 237.179489 -155.244163)
			(xy 237.195386 -155.182249) (xy 237.218918 -155.122816) (xy 237.249712 -155.066801) (xy 237.287285 -155.015086)
			(xy 237.331042 -154.968489) (xy 237.380295 -154.927744) (xy 237.434266 -154.893493) (xy 237.492105 -154.866276)
			(xy 237.552898 -154.846523) (xy 237.615688 -154.834545) (xy 237.679484 -154.830532) (xy 237.74328 -154.834545)
			(xy 237.80607 -154.846523) (xy 237.866863 -154.866276) (xy 237.924702 -154.893493) (xy 237.978673 -154.927744)
			(xy 238.027926 -154.968489) (xy 238.071683 -155.015086) (xy 238.109256 -155.066801) (xy 238.14005 -155.122816)
			(xy 238.163582 -155.182249) (xy 238.179479 -155.244163) (xy 238.18749 -155.307581) (xy 238.187992 -155.339542)
			(xy 238.18749 -155.371503) (xy 238.179479 -155.434921) (xy 238.163582 -155.496835) (xy 238.14005 -155.556268)
			(xy 238.109256 -155.612283) (xy 238.071683 -155.663998) (xy 238.027926 -155.710595) (xy 237.978673 -155.75134)
			(xy 237.924702 -155.785591) (xy 237.866863 -155.812808) (xy 237.80607 -155.832561) (xy 237.74328 -155.844539)
			(xy 237.679484 -155.848553) (xy 237.615688 -155.844539) (xy 237.552898 -155.832561) (xy 237.492105 -155.812808)
			(xy 237.434266 -155.785591) (xy 237.380295 -155.75134) (xy 237.331042 -155.710595) (xy 237.287285 -155.663998)
			(xy 237.249712 -155.612283) (xy 237.218918 -155.556268) (xy 237.195386 -155.496835) (xy 237.179489 -155.434921)
			(xy 237.171478 -155.371503) (xy 200.152952 -155.371503) (xy 200.133187 -155.449861) (xy 200.070227 -155.666858)
			(xy 199.999647 -155.881498) (xy 199.956375 -155.998951) (xy 229.122203 -155.998951) (xy 229.122203 -155.944449)
			(xy 229.12996 -155.890503) (xy 229.145315 -155.83821) (xy 229.167957 -155.788635) (xy 229.197423 -155.742786)
			(xy 229.233115 -155.701598) (xy 229.274305 -155.665909) (xy 229.320156 -155.636445) (xy 229.369733 -155.613807)
			(xy 229.422027 -155.598455) (xy 229.475973 -155.590702) (xy 229.503224 -155.59024) (xy 229.530157 -155.590729)
			(xy 229.583488 -155.598313) (xy 229.63522 -155.613326) (xy 229.684324 -155.63547) (xy 229.729824 -155.664304)
			(xy 229.75062 -155.681426) (xy 229.758854 -155.687858) (xy 229.778799 -155.694017) (xy 229.789228 -155.693364)
			(xy 229.862634 -155.684982) (xy 229.872908 -155.68336) (xy 229.890998 -155.673135) (xy 229.897686 -155.66517)
			(xy 229.918366 -155.638735) (xy 229.965513 -155.590965) (xy 230.018537 -155.549817) (xy 230.076515 -155.516005)
			(xy 230.138439 -155.490119) (xy 230.203232 -155.472608) (xy 230.269765 -155.463777) (xy 230.303324 -155.46324)
			(xy 230.335287 -155.463647) (xy 230.398709 -155.471662) (xy 230.460626 -155.487562) (xy 230.520062 -155.511097)
			(xy 230.57608 -155.541896) (xy 230.627797 -155.579472) (xy 230.674396 -155.623234) (xy 230.715143 -155.67249)
			(xy 230.749396 -155.726466) (xy 230.776613 -155.784308) (xy 230.796367 -155.845106) (xy 230.808345 -155.9079)
			(xy 230.812359 -155.9717) (xy 230.808345 -156.0355) (xy 230.796367 -156.098294) (xy 230.776613 -156.159092)
			(xy 230.749396 -156.216934) (xy 230.715143 -156.27091) (xy 230.674396 -156.320166) (xy 230.627797 -156.363928)
			(xy 230.57608 -156.401504) (xy 230.520062 -156.432303) (xy 230.460626 -156.455838) (xy 230.398709 -156.471738)
			(xy 230.335287 -156.479753) (xy 230.303324 -156.480256) (xy 230.269765 -156.479741) (xy 230.203234 -156.470892)
			(xy 230.138444 -156.45337) (xy 230.076521 -156.427479) (xy 230.01854 -156.393671) (xy 229.96551 -156.352531)
			(xy 229.91835 -156.304774) (xy 229.897686 -156.278326) (xy 229.891007 -156.270344) (xy 229.872918 -156.260101)
			(xy 229.862634 -156.258514) (xy 229.789228 -156.250132) (xy 229.778805 -156.249519) (xy 229.758876 -156.255678)
			(xy 229.75062 -156.26207) (xy 229.729813 -156.27918) (xy 229.68432 -156.308027) (xy 229.63522 -156.330181)
			(xy 229.583488 -156.345202) (xy 229.530158 -156.35279) (xy 229.503224 -156.353256) (xy 229.475973 -156.352698)
			(xy 229.422027 -156.344945) (xy 229.369733 -156.329593) (xy 229.320156 -156.306955) (xy 229.274305 -156.277491)
			(xy 229.233115 -156.241802) (xy 229.197423 -156.200614) (xy 229.167957 -156.154765) (xy 229.145315 -156.10519)
			(xy 229.12996 -156.052897) (xy 229.122203 -155.998951) (xy 199.956375 -155.998951) (xy 199.921537 -156.093514)
			(xy 199.835993 -156.30264) (xy 199.743122 -156.508618) (xy 199.643039 -156.711189) (xy 199.608876 -156.774599)
			(xy 199.932284 -156.774599) (xy 199.932284 -156.710677) (xy 199.940295 -156.647259) (xy 199.956192 -156.585345)
			(xy 199.979724 -156.525912) (xy 200.010518 -156.469897) (xy 200.048091 -156.418182) (xy 200.091848 -156.371585)
			(xy 200.141101 -156.33084) (xy 200.195072 -156.296589) (xy 200.252911 -156.269372) (xy 200.313704 -156.249619)
			(xy 200.376494 -156.237641) (xy 200.44029 -156.233628) (xy 200.504086 -156.237641) (xy 200.566876 -156.249619)
			(xy 200.627669 -156.269372) (xy 200.685508 -156.296589) (xy 200.739479 -156.33084) (xy 200.788732 -156.371585)
			(xy 200.832489 -156.418182) (xy 200.870062 -156.469897) (xy 200.900856 -156.525912) (xy 200.924388 -156.585345)
			(xy 200.940285 -156.647259) (xy 200.946392 -156.695605) (xy 217.080332 -156.695605) (xy 217.080332 -156.631683)
			(xy 217.088343 -156.568265) (xy 217.10424 -156.506351) (xy 217.127772 -156.446918) (xy 217.158566 -156.390903)
			(xy 217.196139 -156.339188) (xy 217.239896 -156.292591) (xy 217.289149 -156.251846) (xy 217.34312 -156.217595)
			(xy 217.400959 -156.190378) (xy 217.461752 -156.170625) (xy 217.524542 -156.158647) (xy 217.588338 -156.154634)
			(xy 217.652134 -156.158647) (xy 217.714924 -156.170625) (xy 217.775717 -156.190378) (xy 217.833556 -156.217595)
			(xy 217.887527 -156.251846) (xy 217.93678 -156.292591) (xy 217.980537 -156.339188) (xy 218.01811 -156.390903)
			(xy 218.048904 -156.446918) (xy 218.072436 -156.506351) (xy 218.088333 -156.568265) (xy 218.096344 -156.631683)
			(xy 218.096846 -156.663644) (xy 218.096344 -156.695605) (xy 218.088333 -156.759023) (xy 218.072436 -156.820937)
			(xy 218.048904 -156.88037) (xy 218.01811 -156.936385) (xy 217.980537 -156.9881) (xy 217.93678 -157.034697)
			(xy 217.887527 -157.075442) (xy 217.833556 -157.109693) (xy 217.775717 -157.13691) (xy 217.714924 -157.156663)
			(xy 217.652134 -157.168641) (xy 217.588338 -157.172655) (xy 217.524542 -157.168641) (xy 217.461752 -157.156663)
			(xy 217.400959 -157.13691) (xy 217.34312 -157.109693) (xy 217.289149 -157.075442) (xy 217.239896 -157.034697)
			(xy 217.196139 -156.9881) (xy 217.158566 -156.936385) (xy 217.127772 -156.88037) (xy 217.10424 -156.820937)
			(xy 217.088343 -156.759023) (xy 217.080332 -156.695605) (xy 200.946392 -156.695605) (xy 200.948296 -156.710677)
			(xy 200.948798 -156.742638) (xy 200.948296 -156.774599) (xy 200.940285 -156.838017) (xy 200.924388 -156.899931)
			(xy 200.900856 -156.959364) (xy 200.870062 -157.015379) (xy 200.832489 -157.067094) (xy 200.788732 -157.113691)
			(xy 200.739479 -157.154436) (xy 200.685508 -157.188687) (xy 200.627669 -157.215904) (xy 200.566876 -157.235657)
			(xy 200.504086 -157.247635) (xy 200.44029 -157.251649) (xy 200.376494 -157.247635) (xy 200.313704 -157.235657)
			(xy 200.252911 -157.215904) (xy 200.195072 -157.188687) (xy 200.141101 -157.154436) (xy 200.091848 -157.113691)
			(xy 200.048091 -157.067094) (xy 200.010518 -157.015379) (xy 199.979724 -156.959364) (xy 199.956192 -156.899931)
			(xy 199.940295 -156.838017) (xy 199.932284 -156.774599) (xy 199.608876 -156.774599) (xy 199.53587 -156.910103)
			(xy 199.421748 -157.10511) (xy 199.300814 -157.295968) (xy 199.173221 -157.48244) (xy 199.039125 -157.664292)
			(xy 198.898696 -157.841299) (xy 198.752107 -158.013239) (xy 198.599542 -158.179899) (xy 198.44119 -158.341071)
			(xy 198.277248 -158.496554) (xy 198.107922 -158.646154) (xy 197.933421 -158.789686) (xy 197.753964 -158.926969)
			(xy 197.569773 -159.057834) (xy 197.381079 -159.182117) (xy 197.344489 -159.204406) (xy 203.926694 -159.204406)
			(xy 203.927257 -159.170558) (xy 203.936239 -159.10346) (xy 203.954044 -159.038147) (xy 203.980358 -158.975774)
			(xy 204.014715 -158.917444) (xy 204.056508 -158.864189) (xy 204.080364 -158.84017) (xy 204.086427 -158.833616)
			(xy 204.094103 -158.817514) (xy 204.09535 -158.808674) (xy 204.098398 -158.778702) (xy 204.098811 -158.769768)
			(xy 204.094275 -158.752486) (xy 204.089508 -158.74492) (xy 204.072407 -158.719391) (xy 204.043851 -158.66498)
			(xy 204.022072 -158.60752) (xy 204.007389 -158.547852) (xy 204.000016 -158.486847) (xy 203.999592 -158.456122)
			(xy 204.000017 -158.425996) (xy 204.007149 -158.366167) (xy 204.021303 -158.307601) (xy 204.042282 -158.25112)
			(xy 204.069791 -158.197514) (xy 204.103444 -158.147536) (xy 204.14277 -158.101887) (xy 204.164692 -158.081218)
			(xy 204.172566 -158.074106) (xy 204.180948 -158.05531) (xy 204.182218 -157.96006) (xy 204.174344 -157.940756)
			(xy 204.166724 -157.93339) (xy 204.142723 -157.909347) (xy 204.100662 -157.855996) (xy 204.066077 -157.797522)
			(xy 204.039584 -157.734965) (xy 204.021654 -157.669437) (xy 204.012606 -157.602106) (xy 204.012038 -157.568138)
			(xy 204.01254 -157.536177) (xy 204.020551 -157.472759) (xy 204.036448 -157.410845) (xy 204.05998 -157.351412)
			(xy 204.090774 -157.295397) (xy 204.128347 -157.243682) (xy 204.172104 -157.197085) (xy 204.221357 -157.15634)
			(xy 204.275328 -157.122089) (xy 204.333167 -157.094872) (xy 204.39396 -157.075119) (xy 204.45675 -157.063141)
			(xy 204.520546 -157.059128) (xy 204.584342 -157.063141) (xy 204.647132 -157.075119) (xy 204.707925 -157.094872)
			(xy 204.765764 -157.122089) (xy 204.819735 -157.15634) (xy 204.868988 -157.197085) (xy 204.912745 -157.243682)
			(xy 204.950318 -157.295397) (xy 204.979209 -157.347951) (xy 229.929397 -157.347951) (xy 229.929397 -157.293449)
			(xy 229.937154 -157.2395) (xy 229.952511 -157.187205) (xy 229.975153 -157.137628) (xy 230.004621 -157.091779)
			(xy 230.040315 -157.050589) (xy 230.081507 -157.0149) (xy 230.12736 -156.985436) (xy 230.176939 -156.962798)
			(xy 230.229236 -156.947447) (xy 230.283184 -156.939695) (xy 230.310436 -156.939234) (xy 230.337311 -156.939741)
			(xy 230.39053 -156.947282) (xy 230.442161 -156.962224) (xy 230.491182 -156.984271) (xy 230.53662 -157.012985)
			(xy 230.577574 -157.047796) (xy 230.613233 -157.088015) (xy 230.628444 -157.110176) (xy 230.636463 -157.121351)
			(xy 230.657225 -157.139369) (xy 230.682039 -157.151199) (xy 230.709109 -157.155986) (xy 230.736476 -157.153381)
			(xy 230.762157 -157.143574) (xy 230.784294 -157.127275) (xy 230.801284 -157.105663) (xy 230.807006 -157.093158)
			(xy 230.820312 -157.062768) (xy 230.853685 -157.00543) (xy 230.894234 -156.952922) (xy 230.941271 -156.906137)
			(xy 230.993995 -156.865869) (xy 231.051511 -156.832804) (xy 231.112839 -156.807503) (xy 231.176939 -156.790397)
			(xy 231.242719 -156.781777) (xy 231.27589 -156.781246) (xy 231.30785 -156.781818) (xy 231.371266 -156.789828)
			(xy 231.433178 -156.805724) (xy 231.492609 -156.829253) (xy 231.548623 -156.860046) (xy 231.595039 -156.893768)
			(xy 233.422698 -156.893768) (xy 233.423148 -156.863433) (xy 233.430351 -156.803192) (xy 233.444673 -156.744237)
			(xy 233.465911 -156.687406) (xy 233.493764 -156.633507) (xy 233.527835 -156.583307) (xy 233.56764 -156.53752)
			(xy 233.58983 -156.516832) (xy 233.597704 -156.50972) (xy 233.60634 -156.490162) (xy 233.60634 -156.393134)
			(xy 233.597704 -156.373576) (xy 233.58983 -156.366464) (xy 233.567642 -156.345774) (xy 233.527849 -156.29998)
			(xy 233.493785 -156.249777) (xy 233.465934 -156.195879) (xy 233.444691 -156.139051) (xy 233.430358 -156.0801)
			(xy 233.423139 -156.019862) (xy 233.422698 -155.989528) (xy 233.4232 -155.957567) (xy 233.431211 -155.894149)
			(xy 233.447108 -155.832235) (xy 233.47064 -155.772802) (xy 233.501434 -155.716787) (xy 233.539007 -155.665072)
			(xy 233.582764 -155.618475) (xy 233.632017 -155.57773) (xy 233.685988 -155.543479) (xy 233.743827 -155.516262)
			(xy 233.80462 -155.496509) (xy 233.86741 -155.484531) (xy 233.931206 -155.480518) (xy 233.995002 -155.484531)
			(xy 234.057792 -155.496509) (xy 234.118585 -155.516262) (xy 234.176424 -155.543479) (xy 234.230395 -155.57773)
			(xy 234.279648 -155.618475) (xy 234.323405 -155.665072) (xy 234.360978 -155.716787) (xy 234.391772 -155.772802)
			(xy 234.415304 -155.832235) (xy 234.431201 -155.894149) (xy 234.439212 -155.957567) (xy 234.439506 -155.9763)
			(xy 241.425188 -155.9763) (xy 241.429203 -155.912501) (xy 241.441182 -155.849708) (xy 241.460936 -155.788912)
			(xy 241.488156 -155.731071) (xy 241.52241 -155.677098) (xy 241.563159 -155.627844) (xy 241.60976 -155.584086)
			(xy 241.661479 -155.546514) (xy 241.717498 -155.515721) (xy 241.776936 -155.492192) (xy 241.838854 -155.476298)
			(xy 241.902275 -155.468291) (xy 241.934238 -155.467812) (xy 241.965934 -155.468291) (xy 242.028835 -155.476178)
			(xy 242.090266 -155.491826) (xy 242.149275 -155.514992) (xy 242.204945 -155.545316) (xy 242.256412 -155.582327)
			(xy 242.302877 -155.625451) (xy 242.32362 -155.649422) (xy 242.323874 -155.649676) (xy 242.330525 -155.656787)
			(xy 242.347767 -155.665797) (xy 242.357402 -155.667202) (xy 242.438428 -155.675076) (xy 242.457478 -155.669488)
			(xy 242.465098 -155.663138) (xy 242.485525 -155.647256) (xy 242.529849 -155.620559) (xy 242.577373 -155.600094)
			(xy 242.627227 -155.586238) (xy 242.678495 -155.579243) (xy 242.704366 -155.57881) (xy 242.731622 -155.579235)
			(xy 242.785579 -155.586988) (xy 242.837883 -155.602342) (xy 242.88747 -155.624983) (xy 242.93333 -155.654452)
			(xy 242.974529 -155.690147) (xy 243.010228 -155.731343) (xy 243.0397 -155.7772) (xy 243.062346 -155.826785)
			(xy 243.077705 -155.879088) (xy 243.085463 -155.933044) (xy 243.085463 -155.987556) (xy 243.077705 -156.041512)
			(xy 243.062346 -156.093815) (xy 243.0397 -156.1434) (xy 243.010228 -156.189257) (xy 242.974529 -156.230453)
			(xy 242.93333 -156.266148) (xy 242.88747 -156.295617) (xy 242.837883 -156.318258) (xy 242.785579 -156.333612)
			(xy 242.731622 -156.341365) (xy 242.704366 -156.341826) (xy 242.674019 -156.341226) (xy 242.614093 -156.331612)
			(xy 242.556449 -156.312617) (xy 242.502547 -156.284721) (xy 242.477798 -156.26715) (xy 242.477544 -156.266896)
			(xy 242.469374 -156.261541) (xy 242.450437 -156.256826) (xy 242.440714 -156.257752) (xy 242.370102 -156.267658)
			(xy 242.360365 -156.269481) (xy 242.343247 -156.279416) (xy 242.336828 -156.286962) (xy 242.316109 -156.312903)
			(xy 242.269056 -156.359741) (xy 242.216309 -156.400057) (xy 242.158764 -156.433166) (xy 242.097399 -156.458505)
			(xy 242.033258 -156.475643) (xy 241.967433 -156.484288) (xy 241.934238 -156.484828) (xy 241.902275 -156.484309)
			(xy 241.838854 -156.476302) (xy 241.776936 -156.460408) (xy 241.717498 -156.436879) (xy 241.661479 -156.406086)
			(xy 241.60976 -156.368514) (xy 241.563159 -156.324756) (xy 241.52241 -156.275502) (xy 241.488156 -156.221529)
			(xy 241.460936 -156.163688) (xy 241.441182 -156.102892) (xy 241.429203 -156.040099) (xy 241.425188 -155.9763)
			(xy 234.439506 -155.9763) (xy 234.439714 -155.989528) (xy 234.439257 -156.019863) (xy 234.432055 -156.080103)
			(xy 234.417734 -156.139058) (xy 234.396496 -156.195889) (xy 234.368645 -156.249788) (xy 234.334575 -156.299988)
			(xy 234.294772 -156.345776) (xy 234.272582 -156.366464) (xy 234.264708 -156.373576) (xy 234.256072 -156.393134)
			(xy 234.256072 -156.490162) (xy 234.264708 -156.50972) (xy 234.272582 -156.516832) (xy 234.29477 -156.537521)
			(xy 234.334563 -156.583316) (xy 234.360458 -156.62148) (xy 234.604814 -156.62148) (xy 234.605316 -156.589519)
			(xy 234.613327 -156.526101) (xy 234.629224 -156.464187) (xy 234.652756 -156.404754) (xy 234.68355 -156.348739)
			(xy 234.721123 -156.297024) (xy 234.76488 -156.250427) (xy 234.814133 -156.209682) (xy 234.868104 -156.175431)
			(xy 234.925943 -156.148214) (xy 234.986736 -156.128461) (xy 235.049526 -156.116483) (xy 235.113322 -156.11247)
			(xy 235.177118 -156.116483) (xy 235.239908 -156.128461) (xy 235.300701 -156.148214) (xy 235.35854 -156.175431)
			(xy 235.412511 -156.209682) (xy 235.461764 -156.250427) (xy 235.505521 -156.297024) (xy 235.543094 -156.348739)
			(xy 235.573888 -156.404754) (xy 235.59742 -156.464187) (xy 235.613317 -156.526101) (xy 235.621328 -156.589519)
			(xy 235.62183 -156.62148) (xy 235.62183 -156.621734) (xy 235.621353 -156.653608) (xy 235.613373 -156.716854)
			(xy 235.597532 -156.778602) (xy 235.58627 -156.808424) (xy 235.582714 -156.817568) (xy 235.582714 -156.83738)
			(xy 235.617766 -156.921454) (xy 235.631482 -156.93517) (xy 235.640626 -156.939234) (xy 235.665991 -156.950627)
			(xy 235.713372 -156.979728) (xy 235.756025 -157.015399) (xy 235.793048 -157.056885) (xy 235.823656 -157.103307)
			(xy 235.847199 -157.15368) (xy 235.86318 -157.206938) (xy 235.87126 -157.261952) (xy 235.871766 -157.289754)
			(xy 235.87128 -157.317005) (xy 235.863524 -157.370953) (xy 235.848169 -157.423248) (xy 235.825527 -157.472825)
			(xy 235.796061 -157.518675) (xy 235.76037 -157.559866) (xy 235.719179 -157.595557) (xy 235.673329 -157.625023)
			(xy 235.623752 -157.647665) (xy 235.571457 -157.66302) (xy 235.517509 -157.670776) (xy 235.463007 -157.670776)
			(xy 235.409059 -157.66302) (xy 235.356764 -157.647665) (xy 235.307187 -157.625023) (xy 235.261337 -157.595557)
			(xy 235.220146 -157.559866) (xy 235.184455 -157.518675) (xy 235.154989 -157.472825) (xy 235.132347 -157.423248)
			(xy 235.116992 -157.370953) (xy 235.109236 -157.317005) (xy 235.10875 -157.289754) (xy 235.108841 -157.276567)
			(xy 235.110617 -157.250254) (xy 235.112306 -157.237176) (xy 235.11383 -157.22727) (xy 235.109004 -157.207966)
			(xy 235.061252 -157.142942) (xy 235.055121 -157.135329) (xy 235.038532 -157.125019) (xy 235.028994 -157.122876)
			(xy 235.028486 -157.122876) (xy 234.996568 -157.117023) (xy 234.934484 -157.098136) (xy 234.875307 -157.071505)
			(xy 234.819998 -157.037562) (xy 234.769456 -156.99686) (xy 234.724502 -156.950059) (xy 234.685867 -156.897919)
			(xy 234.654178 -156.841289) (xy 234.62995 -156.781088) (xy 234.613577 -156.718294) (xy 234.605324 -156.653927)
			(xy 234.604814 -156.62148) (xy 234.360458 -156.62148) (xy 234.368627 -156.633519) (xy 234.396478 -156.687417)
			(xy 234.41772 -156.744245) (xy 234.432053 -156.803196) (xy 234.439273 -156.863434) (xy 234.439714 -156.893768)
			(xy 234.439212 -156.925729) (xy 234.431201 -156.989147) (xy 234.415304 -157.051061) (xy 234.391772 -157.110494)
			(xy 234.360978 -157.166509) (xy 234.323405 -157.218224) (xy 234.279648 -157.264821) (xy 234.230395 -157.305566)
			(xy 234.176424 -157.339817) (xy 234.118585 -157.367034) (xy 234.057792 -157.386787) (xy 233.995002 -157.398765)
			(xy 233.931206 -157.402779) (xy 233.86741 -157.398765) (xy 233.80462 -157.386787) (xy 233.743827 -157.367034)
			(xy 233.685988 -157.339817) (xy 233.632017 -157.305566) (xy 233.582764 -157.264821) (xy 233.539007 -157.218224)
			(xy 233.501434 -157.166509) (xy 233.47064 -157.110494) (xy 233.447108 -157.051061) (xy 233.431211 -156.989147)
			(xy 233.4232 -156.925729) (xy 233.422698 -156.893768) (xy 231.595039 -156.893768) (xy 231.600335 -156.897616)
			(xy 231.646931 -156.941372) (xy 231.687676 -156.990623) (xy 231.721926 -157.044592) (xy 231.749142 -157.102428)
			(xy 231.768894 -157.163219) (xy 231.780872 -157.226006) (xy 231.784886 -157.2898) (xy 231.780872 -157.353594)
			(xy 231.768894 -157.416381) (xy 231.749142 -157.477172) (xy 231.721926 -157.535008) (xy 231.687676 -157.588977)
			(xy 231.646931 -157.638228) (xy 231.600335 -157.681984) (xy 231.548623 -157.719554) (xy 231.492609 -157.750347)
			(xy 231.433178 -157.773876) (xy 231.371266 -157.789772) (xy 231.30785 -157.797782) (xy 231.27589 -157.798262)
			(xy 231.244528 -157.797849) (xy 231.182279 -157.790144) (xy 231.121451 -157.77484) (xy 231.062968 -157.752169)
			(xy 231.007718 -157.722476) (xy 230.95654 -157.686212) (xy 230.910212 -157.643928) (xy 230.869437 -157.596265)
			(xy 230.834836 -157.543949) (xy 230.820468 -157.516068) (xy 230.813919 -157.503978) (xy 230.795637 -157.483465)
			(xy 230.772539 -157.468582) (xy 230.746303 -157.460412) (xy 230.718839 -157.459549) (xy 230.692143 -157.466056)
			(xy 230.668155 -157.479459) (xy 230.648621 -157.498784) (xy 230.641398 -157.51048) (xy 230.626678 -157.535046)
			(xy 230.591098 -157.579917) (xy 230.54921 -157.618966) (xy 230.501955 -157.651314) (xy 230.450396 -157.676235)
			(xy 230.395691 -157.693168) (xy 230.339069 -157.701734) (xy 230.310436 -157.70225) (xy 230.283184 -157.701705)
			(xy 230.229236 -157.693953) (xy 230.176939 -157.678602) (xy 230.12736 -157.655964) (xy 230.081507 -157.6265)
			(xy 230.040315 -157.590811) (xy 230.004621 -157.549621) (xy 229.975153 -157.503772) (xy 229.952511 -157.454195)
			(xy 229.937154 -157.4019) (xy 229.929397 -157.347951) (xy 204.979209 -157.347951) (xy 204.981112 -157.351412)
			(xy 205.004644 -157.410845) (xy 205.020541 -157.472759) (xy 205.028552 -157.536177) (xy 205.029054 -157.568138)
			(xy 205.028587 -157.598263) (xy 205.021461 -157.658089) (xy 205.007312 -157.716654) (xy 204.98634 -157.773135)
			(xy 204.958837 -157.826741) (xy 204.925191 -157.87672) (xy 204.885873 -157.922372) (xy 204.863954 -157.943042)
			(xy 204.85608 -157.950154) (xy 204.847698 -157.96895) (xy 204.846428 -158.0642) (xy 204.854302 -158.083504)
			(xy 204.861922 -158.09087) (xy 204.885943 -158.114895) (xy 204.915827 -158.152803) (xy 234.438692 -158.152803)
			(xy 234.438692 -158.088881) (xy 234.446703 -158.025463) (xy 234.4626 -157.963549) (xy 234.486132 -157.904116)
			(xy 234.516926 -157.848101) (xy 234.554499 -157.796386) (xy 234.598256 -157.749789) (xy 234.647509 -157.709044)
			(xy 234.70148 -157.674793) (xy 234.759319 -157.647576) (xy 234.820112 -157.627823) (xy 234.882902 -157.615845)
			(xy 234.946698 -157.611832) (xy 235.010494 -157.615845) (xy 235.073284 -157.627823) (xy 235.134077 -157.647576)
			(xy 235.191916 -157.674793) (xy 235.245887 -157.709044) (xy 235.29514 -157.749789) (xy 235.338897 -157.796386)
			(xy 235.37647 -157.848101) (xy 235.407264 -157.904116) (xy 235.430796 -157.963549) (xy 235.446693 -158.025463)
			(xy 235.454704 -158.088881) (xy 235.455206 -158.120842) (xy 235.454704 -158.152803) (xy 235.446693 -158.216221)
			(xy 235.430796 -158.278135) (xy 235.407264 -158.337568) (xy 235.37647 -158.393583) (xy 235.338897 -158.445298)
			(xy 235.29514 -158.491895) (xy 235.245887 -158.53264) (xy 235.191916 -158.566891) (xy 235.134077 -158.594108)
			(xy 235.073284 -158.613861) (xy 235.010494 -158.625839) (xy 234.946698 -158.629853) (xy 234.882902 -158.625839)
			(xy 234.820112 -158.613861) (xy 234.759319 -158.594108) (xy 234.70148 -158.566891) (xy 234.647509 -158.53264)
			(xy 234.598256 -158.491895) (xy 234.554499 -158.445298) (xy 234.516926 -158.393583) (xy 234.486132 -158.337568)
			(xy 234.4626 -158.278135) (xy 234.446703 -158.216221) (xy 234.438692 -158.152803) (xy 204.915827 -158.152803)
			(xy 204.928003 -158.168248) (xy 204.962586 -158.226726) (xy 204.989077 -158.289287) (xy 205.007002 -158.354818)
			(xy 205.016044 -158.422153) (xy 205.016608 -158.456122) (xy 205.016062 -158.489971) (xy 205.007077 -158.557069)
			(xy 204.989268 -158.622383) (xy 204.962951 -158.684755) (xy 204.928591 -158.743085) (xy 204.886795 -158.79634)
			(xy 204.862938 -158.820358) (xy 204.856865 -158.826904) (xy 204.849194 -158.843012) (xy 204.847952 -158.851854)
			(xy 204.844904 -158.881826) (xy 204.844477 -158.89076) (xy 204.849023 -158.908043) (xy 204.853794 -158.915608)
			(xy 204.870863 -158.941157) (xy 204.899425 -158.995562) (xy 204.92121 -159.053017) (xy 204.935901 -159.112681)
			(xy 204.943281 -159.173683) (xy 204.94371 -159.204406) (xy 204.943208 -159.236367) (xy 204.935197 -159.299785)
			(xy 204.9193 -159.361699) (xy 204.895768 -159.421132) (xy 204.864974 -159.477147) (xy 204.827401 -159.528862)
			(xy 204.783644 -159.575459) (xy 204.734391 -159.616204) (xy 204.68042 -159.650455) (xy 204.622581 -159.677672)
			(xy 204.561788 -159.697425) (xy 204.498998 -159.709403) (xy 204.435202 -159.713417) (xy 204.371406 -159.709403)
			(xy 204.308616 -159.697425) (xy 204.247823 -159.677672) (xy 204.189984 -159.650455) (xy 204.136013 -159.616204)
			(xy 204.08676 -159.575459) (xy 204.043003 -159.528862) (xy 204.00543 -159.477147) (xy 203.974636 -159.421132)
			(xy 203.951104 -159.361699) (xy 203.935207 -159.299785) (xy 203.927196 -159.236367) (xy 203.926694 -159.204406)
			(xy 197.344489 -159.204406) (xy 197.188116 -159.299663) (xy 196.991125 -159.410327) (xy 196.790351 -159.513969)
			(xy 196.586045 -159.61046) (xy 196.37846 -159.699682) (xy 196.167856 -159.781522) (xy 196.133076 -159.793643)
			(xy 202.626462 -159.793643) (xy 202.626462 -159.729721) (xy 202.634473 -159.666303) (xy 202.65037 -159.604389)
			(xy 202.673902 -159.544956) (xy 202.704696 -159.488941) (xy 202.742269 -159.437226) (xy 202.786026 -159.390629)
			(xy 202.835279 -159.349884) (xy 202.88925 -159.315633) (xy 202.947089 -159.288416) (xy 203.007882 -159.268663)
			(xy 203.070672 -159.256685) (xy 203.134468 -159.252672) (xy 203.198264 -159.256685) (xy 203.261054 -159.268663)
			(xy 203.321847 -159.288416) (xy 203.379686 -159.315633) (xy 203.433657 -159.349884) (xy 203.48291 -159.390629)
			(xy 203.526667 -159.437226) (xy 203.56424 -159.488941) (xy 203.595034 -159.544956) (xy 203.618566 -159.604389)
			(xy 203.634463 -159.666303) (xy 203.642474 -159.729721) (xy 203.642976 -159.761682) (xy 203.642474 -159.793643)
			(xy 203.635576 -159.848253) (xy 206.941922 -159.848253) (xy 206.941922 -159.784331) (xy 206.949933 -159.720913)
			(xy 206.96583 -159.658999) (xy 206.989362 -159.599566) (xy 207.020156 -159.543551) (xy 207.057729 -159.491836)
			(xy 207.101486 -159.445239) (xy 207.150739 -159.404494) (xy 207.20471 -159.370243) (xy 207.262549 -159.343026)
			(xy 207.323342 -159.323273) (xy 207.386132 -159.311295) (xy 207.449928 -159.307282) (xy 207.513724 -159.311295)
			(xy 207.576514 -159.323273) (xy 207.637307 -159.343026) (xy 207.695146 -159.370243) (xy 207.749117 -159.404494)
			(xy 207.79837 -159.445239) (xy 207.842127 -159.491836) (xy 207.8797 -159.543551) (xy 207.910494 -159.599566)
			(xy 207.929455 -159.647454) (xy 229.894559 -159.647454) (xy 229.894559 -159.592946) (xy 229.902317 -159.538992)
			(xy 229.917675 -159.486692) (xy 229.94032 -159.43711) (xy 229.969791 -159.391255) (xy 230.005489 -159.350062)
			(xy 230.046686 -159.314369) (xy 230.092543 -159.284902) (xy 230.142127 -159.262262) (xy 230.194429 -159.246909)
			(xy 230.248384 -159.239157) (xy 230.275638 -159.238696) (xy 230.302572 -159.239164) (xy 230.355904 -159.246751)
			(xy 230.407637 -159.261768) (xy 230.456741 -159.283917) (xy 230.50224 -159.312757) (xy 230.523034 -159.329882)
			(xy 230.531267 -159.336316) (xy 230.551213 -159.342476) (xy 230.561642 -159.34182) (xy 230.635048 -159.333438)
			(xy 230.645319 -159.331804) (xy 230.663408 -159.321586) (xy 230.6701 -159.313626) (xy 230.69076 -159.287174)
			(xy 230.737911 -159.239408) (xy 230.790939 -159.198262) (xy 230.848921 -159.164453) (xy 230.910848 -159.138569)
			(xy 230.975643 -159.121061) (xy 231.042179 -159.112232) (xy 231.075738 -159.111696) (xy 231.107698 -159.112192)
			(xy 231.171113 -159.120208) (xy 231.233023 -159.136108) (xy 231.292453 -159.159642) (xy 231.348464 -159.190438)
			(xy 231.400174 -159.228011) (xy 231.446768 -159.271769) (xy 231.48751 -159.321021) (xy 231.521759 -159.374991)
			(xy 231.548973 -159.432828) (xy 231.568724 -159.493619) (xy 231.580701 -159.556407) (xy 231.584715 -159.6202)
			(xy 231.580701 -159.683993) (xy 231.568724 -159.746781) (xy 231.548973 -159.807572) (xy 231.521759 -159.865409)
			(xy 231.48751 -159.919379) (xy 231.446768 -159.968631) (xy 231.400174 -160.012389) (xy 231.348464 -160.049962)
			(xy 231.292453 -160.080758) (xy 231.233023 -160.104292) (xy 231.171113 -160.120192) (xy 231.107698 -160.128208)
			(xy 231.075738 -160.128712) (xy 231.042181 -160.128165) (xy 230.975651 -160.119318) (xy 230.910863 -160.1018)
			(xy 230.848941 -160.075915) (xy 230.79096 -160.042111) (xy 230.737928 -160.000977) (xy 230.690766 -159.953227)
			(xy 230.6701 -159.926782) (xy 230.663464 -159.918759) (xy 230.645343 -159.90854) (xy 230.635048 -159.90697)
			(xy 230.561642 -159.898588) (xy 230.551218 -159.89797) (xy 230.531289 -159.904131) (xy 230.523034 -159.910526)
			(xy 230.502253 -159.927669) (xy 230.456754 -159.956513) (xy 230.407647 -159.978661) (xy 230.355909 -159.993674)
			(xy 230.302574 -160.001252) (xy 230.275638 -160.001712) (xy 230.248384 -160.001243) (xy 230.194429 -159.993491)
			(xy 230.142127 -159.978138) (xy 230.092543 -159.955498) (xy 230.046686 -159.926031) (xy 230.005489 -159.890338)
			(xy 229.969791 -159.849145) (xy 229.94032 -159.80329) (xy 229.917675 -159.753708) (xy 229.902317 -159.701408)
			(xy 229.894559 -159.647454) (xy 207.929455 -159.647454) (xy 207.934026 -159.658999) (xy 207.949923 -159.720913)
			(xy 207.957934 -159.784331) (xy 207.958436 -159.816292) (xy 207.957934 -159.848253) (xy 207.949923 -159.911671)
			(xy 207.934026 -159.973585) (xy 207.910494 -160.033018) (xy 207.8797 -160.089033) (xy 207.842127 -160.140748)
			(xy 207.79837 -160.187345) (xy 207.749117 -160.22809) (xy 207.695146 -160.262341) (xy 207.637307 -160.289558)
			(xy 207.576514 -160.309311) (xy 207.513724 -160.321289) (xy 207.490218 -160.322768) (xy 237.180374 -160.322768)
			(xy 237.180876 -160.290807) (xy 237.188887 -160.227389) (xy 237.204784 -160.165475) (xy 237.228316 -160.106042)
			(xy 237.25911 -160.050027) (xy 237.296683 -159.998312) (xy 237.34044 -159.951715) (xy 237.389693 -159.91097)
			(xy 237.443664 -159.876719) (xy 237.501503 -159.849502) (xy 237.562296 -159.829749) (xy 237.625086 -159.817771)
			(xy 237.688882 -159.813758) (xy 237.752678 -159.817771) (xy 237.815468 -159.829749) (xy 237.876261 -159.849502)
			(xy 237.9341 -159.876719) (xy 237.988071 -159.91097) (xy 238.037324 -159.951715) (xy 238.081081 -159.998312)
			(xy 238.118654 -160.050027) (xy 238.149448 -160.106042) (xy 238.17298 -160.165475) (xy 238.188877 -160.227389)
			(xy 238.196888 -160.290807) (xy 238.19739 -160.322768) (xy 238.196952 -160.35368) (xy 238.189439 -160.415045)
			(xy 238.174545 -160.475047) (xy 238.152489 -160.532802) (xy 238.123597 -160.587459) (xy 238.088294 -160.638212)
			(xy 238.0471 -160.684311) (xy 238.024162 -160.705038) (xy 238.023908 -160.705292) (xy 238.017432 -160.711544)
			(xy 238.008969 -160.727417) (xy 238.007398 -160.73628) (xy 237.997238 -160.811972) (xy 238.001556 -160.830006)
			(xy 238.006636 -160.837626) (xy 238.021734 -160.861183) (xy 238.045565 -160.911807) (xy 238.061738 -160.965371)
			(xy 238.069905 -161.020724) (xy 238.07039 -161.0487) (xy 238.07039 -161.048954) (xy 238.069904 -161.076205)
			(xy 238.062148 -161.130153) (xy 238.046793 -161.182448) (xy 238.024151 -161.232025) (xy 237.994685 -161.277875)
			(xy 237.958994 -161.319066) (xy 237.917803 -161.354757) (xy 237.871953 -161.384223) (xy 237.822376 -161.406865)
			(xy 237.770081 -161.42222) (xy 237.716133 -161.429976) (xy 237.661631 -161.429976) (xy 237.607683 -161.42222)
			(xy 237.555388 -161.406865) (xy 237.505811 -161.384223) (xy 237.459961 -161.354757) (xy 237.41877 -161.319066)
			(xy 237.383079 -161.277875) (xy 237.353613 -161.232025) (xy 237.330971 -161.182448) (xy 237.315616 -161.130153)
			(xy 237.30786 -161.076205) (xy 237.307374 -161.048954) (xy 237.307374 -161.0487) (xy 237.307874 -161.020727)
			(xy 237.316065 -160.965382) (xy 237.332243 -160.911825) (xy 237.356061 -160.8612) (xy 237.371128 -160.837626)
			(xy 237.376208 -160.830006) (xy 237.380526 -160.811972) (xy 237.370366 -160.73628) (xy 237.368794 -160.727418)
			(xy 237.360329 -160.711546) (xy 237.353856 -160.705292) (xy 237.353348 -160.704784) (xy 237.330451 -160.684051)
			(xy 237.289312 -160.637974) (xy 237.254058 -160.587253) (xy 237.225209 -160.532633) (xy 237.20319 -160.474921)
			(xy 237.188325 -160.414967) (xy 237.180833 -160.353653) (xy 237.180374 -160.322768) (xy 207.490218 -160.322768)
			(xy 207.449928 -160.325303) (xy 207.386132 -160.321289) (xy 207.323342 -160.309311) (xy 207.262549 -160.289558)
			(xy 207.20471 -160.262341) (xy 207.150739 -160.22809) (xy 207.101486 -160.187345) (xy 207.057729 -160.140748)
			(xy 207.020156 -160.089033) (xy 206.989362 -160.033018) (xy 206.96583 -159.973585) (xy 206.949933 -159.911671)
			(xy 206.941922 -159.848253) (xy 203.635576 -159.848253) (xy 203.634463 -159.857061) (xy 203.618566 -159.918975)
			(xy 203.595034 -159.978408) (xy 203.56424 -160.034423) (xy 203.526667 -160.086138) (xy 203.48291 -160.132735)
			(xy 203.433657 -160.17348) (xy 203.379686 -160.207731) (xy 203.321847 -160.234948) (xy 203.261054 -160.254701)
			(xy 203.198264 -160.266679) (xy 203.134468 -160.270693) (xy 203.070672 -160.266679) (xy 203.007882 -160.254701)
			(xy 202.947089 -160.234948) (xy 202.88925 -160.207731) (xy 202.835279 -160.17348) (xy 202.786026 -160.132735)
			(xy 202.742269 -160.086138) (xy 202.704696 -160.034423) (xy 202.673902 -159.978408) (xy 202.65037 -159.918975)
			(xy 202.634473 -159.857061) (xy 202.626462 -159.793643) (xy 196.133076 -159.793643) (xy 195.954496 -159.855878)
			(xy 195.738643 -159.922659) (xy 195.520569 -159.98178) (xy 195.300544 -160.033167) (xy 195.078842 -160.076758)
			(xy 194.85574 -160.112498) (xy 194.631516 -160.140342) (xy 194.406449 -160.160255) (xy 194.180819 -160.172213)
			(xy 193.954908 -160.176201) (xy 193.728997 -160.172213) (xy 193.503367 -160.160255) (xy 193.2783 -160.140342)
			(xy 193.054076 -160.112498) (xy 192.830974 -160.076758) (xy 192.609272 -160.033167) (xy 192.389247 -159.98178)
			(xy 192.171173 -159.922659) (xy 191.95532 -159.855878) (xy 191.74196 -159.781522) (xy 191.531356 -159.699682)
			(xy 191.323771 -159.61046) (xy 191.119465 -159.513969) (xy 190.918691 -159.410327) (xy 190.7217 -159.299663)
			(xy 190.528737 -159.182117) (xy 190.340043 -159.057834) (xy 190.155852 -158.926969) (xy 189.976395 -158.789686)
			(xy 189.801894 -158.646154) (xy 189.632568 -158.496554) (xy 189.468626 -158.341071) (xy 189.310274 -158.179899)
			(xy 189.157709 -158.013239) (xy 189.01112 -157.841299) (xy 188.870691 -157.664292) (xy 188.736595 -157.48244)
			(xy 188.609002 -157.295968) (xy 188.488068 -157.10511) (xy 188.373946 -156.910103) (xy 188.266777 -156.711189)
			(xy 188.166694 -156.508618) (xy 188.073823 -156.30264) (xy 187.988279 -156.093514) (xy 187.910169 -155.881498)
			(xy 187.839589 -155.666858) (xy 187.776629 -155.449861) (xy 187.721366 -155.230777) (xy 187.673869 -155.009879)
			(xy 187.634197 -154.787443) (xy 187.602401 -154.563745) (xy 187.578518 -154.339064) (xy 187.56258 -154.113681)
			(xy 187.554606 -153.887875) (xy 187.554108 -153.774902) (xy 187.554617 -153.660674) (xy 187.562769 -153.432365)
			(xy 187.579063 -153.204492) (xy 187.603479 -152.977345) (xy 187.635984 -152.751214) (xy 187.676538 -152.526388)
			(xy 187.725088 -152.303151) (xy 187.781574 -152.081789) (xy 187.845923 -151.862584) (xy 187.918053 -151.645815)
			(xy 187.997873 -151.431758) (xy 188.08528 -151.220685) (xy 188.180163 -151.012866) (xy 188.282402 -150.808565)
			(xy 188.391866 -150.608042) (xy 188.508416 -150.411554) (xy 188.631903 -150.219349) (xy 188.762171 -150.031673)
			(xy 188.899052 -149.848766) (xy 189.042373 -149.670859) (xy 189.191951 -149.49818) (xy 189.347596 -149.330949)
			(xy 189.50911 -149.169378) (xy 189.676286 -149.013674) (xy 189.848911 -148.864034) (xy 190.026767 -148.720649)
			(xy 190.209626 -148.583703) (xy 190.30315 -148.518118) (xy 190.309754 -148.513546) (xy 190.31966 -148.500592)
			(xy 190.323216 -148.490178) (xy 190.324708 -148.483858) (xy 190.324826 -148.470876) (xy 190.32347 -148.464524)
			(xy 190.293498 -148.368766) (xy 190.29058 -148.360603) (xy 190.280182 -148.346745) (xy 190.265751 -148.337159)
			(xy 190.25743 -148.33473) (xy 190.256922 -148.33473) (xy 190.255144 -148.334222) (xy 190.244984 -148.333206)
			(xy 185.092848 -148.333206) (xy 185.082782 -148.332774) (xy 185.06419 -148.325047) (xy 185.05678 -148.31822)
			(xy 184.065164 -147.326604) (xy 184.055923 -147.318462) (xy 184.032437 -147.311178) (xy 184.020206 -147.312634)
			(xy 183.938164 -147.327366) (xy 183.926265 -147.330193) (xy 183.906887 -147.345051) (xy 183.90108 -147.355814)
			(xy 183.90108 -147.356068) (xy 183.887175 -147.385133) (xy 183.853088 -147.439811) (xy 183.812368 -147.489745)
			(xy 183.765666 -147.534136) (xy 183.713731 -147.572271) (xy 183.657395 -147.603542) (xy 183.597561 -147.627445)
			(xy 183.535186 -147.643599) (xy 183.47127 -147.651745) (xy 183.439054 -147.652232) (xy 183.408324 -147.651765)
			(xy 183.347313 -147.644352) (xy 183.287641 -147.62964) (xy 183.230177 -147.607843) (xy 183.175758 -147.579278)
			(xy 183.125179 -147.544364) (xy 183.079177 -147.503607) (xy 183.038423 -147.457603) (xy 183.00351 -147.407023)
			(xy 182.974948 -147.352603) (xy 182.953154 -147.295138) (xy 182.938444 -147.235465) (xy 182.931033 -147.174454)
			(xy 182.930546 -147.143724) (xy 182.931042 -147.111507) (xy 182.939179 -147.047589) (xy 182.955327 -146.985211)
			(xy 182.979227 -146.925373) (xy 183.010495 -146.869035) (xy 183.04863 -146.817098) (xy 183.093021 -146.770395)
			(xy 183.142957 -146.729675) (xy 183.197638 -146.69559) (xy 183.22671 -146.681698) (xy 183.226964 -146.681698)
			(xy 183.237714 -146.675873) (xy 183.25258 -146.656507) (xy 183.255412 -146.644614) (xy 183.270144 -146.562572)
			(xy 183.271648 -146.550338) (xy 183.26435 -146.526837) (xy 183.256174 -146.517614) (xy 182.591964 -145.853658)
			(xy 182.584566 -145.846811) (xy 182.565968 -145.839081) (xy 182.555896 -145.838672) (xy 181.200298 -145.838672)
			(xy 181.188539 -145.839259) (xy 181.167474 -145.849715) (xy 181.159912 -145.858738) (xy 181.11089 -145.923254)
			(xy 181.107384 -145.928095) (xy 181.102511 -145.939004) (xy 181.101238 -145.944844) (xy 181.099206 -145.95602)
			(xy 181.100984 -145.961862) (xy 181.108329 -145.988309) (xy 181.116235 -146.042623) (xy 181.116732 -146.070066)
			(xy 181.116732 -146.070574) (xy 181.116271 -146.097829) (xy 181.108517 -146.151784) (xy 181.093164 -146.204086)
			(xy 181.070523 -146.253671) (xy 181.041056 -146.299529) (xy 181.005363 -146.340727) (xy 180.964169 -146.376426)
			(xy 180.918315 -146.405899) (xy 180.868733 -146.428546) (xy 180.816433 -146.443906) (xy 180.762479 -146.451667)
			(xy 180.735224 -146.452082) (xy 180.707844 -146.451611) (xy 180.653648 -146.443783) (xy 180.601128 -146.428284)
			(xy 180.551365 -146.405433) (xy 180.505381 -146.3757) (xy 180.464123 -146.339696) (xy 180.445918 -146.31924)
			(xy 180.44287 -146.315684) (xy 180.439736 -146.31284) (xy 180.432719 -146.30811) (xy 180.4289 -146.306286)
			(xy 180.42636 -146.30527) (xy 180.426106 -146.30527) (xy 180.42063 -146.303223) (xy 180.409084 -146.30142)
			(xy 180.403246 -146.301714) (xy 180.321204 -146.308572) (xy 180.315142 -146.309219) (xy 180.30358 -146.31307)
			(xy 180.298344 -146.316192) (xy 180.294026 -146.318986) (xy 180.29301 -146.319494) (xy 180.285136 -146.327622)
			(xy 180.281834 -146.332956) (xy 180.264525 -146.36071) (xy 180.223867 -146.411949) (xy 180.176973 -146.457551)
			(xy 180.124619 -146.496762) (xy 180.067668 -146.528936) (xy 180.007062 -146.55354) (xy 179.943801 -146.570169)
			(xy 179.878929 -146.578548) (xy 179.846224 -146.579082) (xy 179.813196 -146.57855) (xy 179.747697 -146.569988)
			(xy 179.683858 -146.553018) (xy 179.622754 -146.527925) (xy 179.565412 -146.495133) (xy 179.512799 -146.455192)
			(xy 179.4658 -146.408776) (xy 179.425206 -146.356665) (xy 179.3917 -146.299738) (xy 179.365847 -146.238951)
			(xy 179.348081 -146.175329) (xy 179.338703 -146.109942) (xy 179.337716 -146.076924) (xy 179.337716 -146.069812)
			(xy 179.338098 -146.042609) (xy 179.343953 -145.988517) (xy 179.3494 -145.961862) (xy 179.3494 -145.961608)
			(xy 179.351121 -145.950407) (xy 179.345851 -145.928394) (xy 179.33924 -145.91919) (xy 179.28971 -145.857722)
			(xy 179.282077 -145.849211) (xy 179.2615 -145.839321) (xy 179.250086 -145.838672) (xy 177.125122 -145.838672)
			(xy 177.113681 -145.839199) (xy 177.093064 -145.849123) (xy 177.085498 -145.857722) (xy 177.035968 -145.91919)
			(xy 177.0292 -145.92832) (xy 177.023918 -145.950401) (xy 177.025808 -145.961608) (xy 177.025808 -145.961862)
			(xy 177.031189 -145.988142) (xy 177.037039 -146.041467) (xy 177.037492 -146.068288) (xy 177.037492 -146.076924)
			(xy 177.036554 -146.109945) (xy 177.027184 -146.175338) (xy 177.009423 -146.238966) (xy 176.983571 -146.299758)
			(xy 176.950063 -146.35669) (xy 176.909464 -146.408802) (xy 176.862457 -146.455217) (xy 176.809835 -146.495153)
			(xy 176.752483 -146.527937) (xy 176.691369 -146.553017) (xy 176.62752 -146.56997) (xy 176.562014 -146.578511)
			(xy 176.528984 -146.579082) (xy 176.494852 -146.57853) (xy 176.427201 -146.569399) (xy 176.36138 -146.551301)
			(xy 176.29857 -146.524564) (xy 176.2399 -146.489666) (xy 176.186425 -146.447235) (xy 176.139104 -146.398034)
			(xy 176.11852 -146.370802) (xy 176.118266 -146.370548) (xy 176.115403 -146.366757) (xy 176.108503 -146.360229)
			(xy 176.10455 -146.357594) (xy 176.092612 -146.35099) (xy 176.082706 -146.350228) (xy 176.002442 -146.344132)
			(xy 175.991941 -146.344225) (xy 175.972392 -146.351829) (xy 175.964596 -146.358864) (xy 175.886618 -146.436842)
			(xy 175.883915 -146.439695) (xy 175.879328 -146.446076) (xy 175.877474 -146.449542) (xy 175.874892 -146.454969)
			(xy 175.872069 -146.466649) (xy 175.871886 -146.472656) (xy 175.871886 -146.751294) (xy 175.87341 -146.763486)
			(xy 175.876204 -146.774154) (xy 175.87712 -146.77761) (xy 175.879796 -146.78424) (xy 175.881538 -146.787362)
			(xy 175.898022 -146.816672) (xy 175.92398 -146.878706) (xy 175.941541 -146.943619) (xy 175.950398 -147.010279)
			(xy 175.950398 -147.077525) (xy 175.94154 -147.144185) (xy 175.923979 -147.209097) (xy 175.89802 -147.271131)
			(xy 175.881538 -147.300442) (xy 175.876204 -147.31365) (xy 175.87341 -147.324318) (xy 175.871886 -147.33651)
			(xy 175.871886 -148.092099) (xy 177.036072 -148.092099) (xy 177.041279 -148.029229) (xy 177.054223 -147.967485)
			(xy 177.074705 -147.907817) (xy 177.102409 -147.851141) (xy 177.136912 -147.798326) (xy 177.177683 -147.750185)
			(xy 177.224095 -147.707457) (xy 177.275435 -147.670798) (xy 177.330917 -147.640771) (xy 177.389686 -147.617837)
			(xy 177.45084 -147.602348) (xy 177.513441 -147.594543) (xy 177.544984 -147.594066) (xy 177.545492 -147.594066)
			(xy 177.577923 -147.594587) (xy 177.642255 -147.602871) (xy 177.673762 -147.610576) (xy 177.685946 -147.613151)
			(xy 177.710183 -147.607579) (xy 177.71999 -147.599908) (xy 177.792888 -147.537424) (xy 177.802032 -147.513802)
			(xy 177.800508 -147.50161) (xy 177.799534 -147.491542) (xy 177.798516 -147.471339) (xy 177.798476 -147.461224)
			(xy 177.798962 -147.433973) (xy 177.806718 -147.380025) (xy 177.822073 -147.32773) (xy 177.844715 -147.278153)
			(xy 177.874181 -147.232303) (xy 177.909872 -147.191112) (xy 177.951063 -147.155421) (xy 177.996913 -147.125955)
			(xy 178.04649 -147.103313) (xy 178.098785 -147.087958) (xy 178.152733 -147.080202) (xy 178.207235 -147.080202)
			(xy 178.261183 -147.087958) (xy 178.313478 -147.103313) (xy 178.363055 -147.125955) (xy 178.408905 -147.155421)
			(xy 178.450096 -147.191112) (xy 178.485787 -147.232303) (xy 178.515253 -147.278153) (xy 178.537895 -147.32773)
			(xy 178.55325 -147.380025) (xy 178.561006 -147.433973) (xy 178.561492 -147.461224) (xy 178.561418 -147.472235)
			(xy 178.560145 -147.49422) (xy 178.558952 -147.505166) (xy 178.557428 -147.517866) (xy 178.566826 -147.541234)
			(xy 178.651154 -147.612608) (xy 178.676046 -147.617942) (xy 178.688238 -147.614386) (xy 178.722967 -147.604904)
			(xy 178.79423 -147.594707) (xy 178.830224 -147.594066) (xy 178.861764 -147.594593) (xy 178.924358 -147.602398)
			(xy 178.985506 -147.617886) (xy 179.044269 -147.640819) (xy 179.099744 -147.670844) (xy 179.151079 -147.7075)
			(xy 179.197486 -147.750225) (xy 179.238252 -147.798361) (xy 179.27275 -147.851171) (xy 179.300452 -147.907842)
			(xy 179.32093 -147.967504) (xy 179.333872 -148.029242) (xy 179.339078 -148.092106) (xy 179.336468 -148.155131)
			(xy 179.326083 -148.217349) (xy 179.308081 -148.277805) (xy 179.28274 -148.33557) (xy 179.250448 -148.389757)
			(xy 179.211701 -148.439533) (xy 179.167096 -148.484135) (xy 179.117315 -148.522876) (xy 179.063125 -148.555163)
			(xy 179.005358 -148.580498) (xy 178.9449 -148.598494) (xy 178.882681 -148.608874) (xy 178.819655 -148.611477)
			(xy 178.756792 -148.606265) (xy 178.695056 -148.593317) (xy 178.635396 -148.572832) (xy 178.578727 -148.545125)
			(xy 178.525921 -148.510622) (xy 178.477789 -148.469851) (xy 178.435069 -148.42344) (xy 178.398417 -148.372102)
			(xy 178.368398 -148.316624) (xy 178.345471 -148.257858) (xy 178.329989 -148.196709) (xy 178.32219 -148.134114)
			(xy 178.321716 -148.102574) (xy 178.322278 -148.068367) (xy 178.331449 -148.000571) (xy 178.340004 -147.967446)
			(xy 178.342711 -147.955087) (xy 178.337107 -147.930442) (xy 178.329336 -147.920456) (xy 178.265328 -147.84705)
			(xy 178.241452 -147.837906) (xy 178.229006 -147.839684) (xy 178.216802 -147.841128) (xy 178.192273 -147.842655)
			(xy 178.179984 -147.842732) (xy 178.143408 -147.840954) (xy 178.143154 -147.840954) (xy 178.130792 -147.840338)
			(xy 178.107892 -147.849666) (xy 178.099466 -147.858734) (xy 178.03749 -147.932394) (xy 178.032156 -147.956524)
			(xy 178.035458 -147.968462) (xy 178.035458 -147.96897) (xy 178.04385 -148.001734) (xy 178.052902 -148.068758)
			(xy 178.053492 -148.102574) (xy 178.05306 -148.134117) (xy 178.04526 -148.196718) (xy 178.029776 -148.257874)
			(xy 178.006847 -148.316645) (xy 177.976824 -148.372129) (xy 177.940169 -148.423473) (xy 177.897445 -148.469888)
			(xy 177.849307 -148.510663) (xy 177.796496 -148.54517) (xy 177.739822 -148.572879) (xy 177.680155 -148.593366)
			(xy 177.618413 -148.606315) (xy 177.555543 -148.611527) (xy 177.492511 -148.608923) (xy 177.430286 -148.598542)
			(xy 177.369822 -148.580544) (xy 177.312049 -148.555206) (xy 177.257853 -148.522915) (xy 177.208068 -148.484169)
			(xy 177.163458 -148.439563) (xy 177.124708 -148.389781) (xy 177.092414 -148.335589) (xy 177.06707 -148.277818)
			(xy 177.049067 -148.217355) (xy 177.038681 -148.155131) (xy 177.036072 -148.092099) (xy 175.871886 -148.092099)
			(xy 175.871886 -149.261068) (xy 181.122574 -149.261068) (xy 181.123036 -149.232592) (xy 181.1315 -149.176273)
			(xy 181.148248 -149.121841) (xy 181.172908 -149.070505) (xy 181.204931 -149.02341) (xy 181.243605 -148.981604)
			(xy 181.288068 -148.946016) (xy 181.337331 -148.91744) (xy 181.36362 -148.906484) (xy 181.371581 -148.902963)
			(xy 181.384696 -148.891536) (xy 181.389274 -148.884132) (xy 181.404006 -148.857716) (xy 181.407972 -148.849899)
			(xy 181.41082 -148.832614) (xy 181.409594 -148.823934) (xy 181.405804 -148.80152) (xy 181.401732 -148.756241)
			(xy 181.401466 -148.73351) (xy 181.401466 -148.732748) (xy 181.401968 -148.700787) (xy 181.409979 -148.637369)
			(xy 181.425876 -148.575455) (xy 181.449408 -148.516022) (xy 181.480202 -148.460007) (xy 181.517775 -148.408292)
			(xy 181.561532 -148.361695) (xy 181.610785 -148.32095) (xy 181.664756 -148.286699) (xy 181.722595 -148.259482)
			(xy 181.783388 -148.239729) (xy 181.846178 -148.227751) (xy 181.909974 -148.223738) (xy 181.97377 -148.227751)
			(xy 182.03656 -148.239729) (xy 182.097353 -148.259482) (xy 182.155192 -148.286699) (xy 182.209163 -148.32095)
			(xy 182.258416 -148.361695) (xy 182.302173 -148.408292) (xy 182.339746 -148.460007) (xy 182.37054 -148.516022)
			(xy 182.394072 -148.575455) (xy 182.409969 -148.637369) (xy 182.41798 -148.700787) (xy 182.418482 -148.732748)
			(xy 182.418015 -148.764335) (xy 182.410165 -148.82702) (xy 182.394617 -148.888251) (xy 182.371609 -148.947086)
			(xy 182.341496 -149.002622) (xy 182.30474 -149.054003) (xy 182.261907 -149.100439) (xy 182.213656 -149.141217)
			(xy 182.160729 -149.175709) (xy 182.103939 -149.203384) (xy 182.04416 -149.223818) (xy 181.982312 -149.236695)
			(xy 181.950868 -149.239732) (xy 181.942155 -149.240841) (xy 181.92618 -149.248109) (xy 181.919626 -149.253956)
			(xy 181.898036 -149.275038) (xy 181.892065 -149.281351) (xy 181.884403 -149.296934) (xy 181.88305 -149.305518)
			(xy 181.87924 -149.333008) (xy 181.864851 -149.386604) (xy 181.842851 -149.437551) (xy 181.813703 -149.484773)
			(xy 181.778021 -149.527275) (xy 181.73656 -149.56416) (xy 181.690192 -149.59465) (xy 181.639897 -149.618102)
			(xy 181.586736 -149.634021) (xy 181.531829 -149.642072) (xy 181.504082 -149.642576) (xy 181.476827 -149.642162)
			(xy 181.422873 -149.634402) (xy 181.370572 -149.619042) (xy 181.32099 -149.596395) (xy 181.275135 -149.566922)
			(xy 181.233942 -149.531223) (xy 181.198248 -149.490025) (xy 181.168781 -149.444166) (xy 181.146141 -149.394581)
			(xy 181.130788 -149.342278) (xy 181.123035 -149.288323) (xy 181.122574 -149.261068) (xy 175.871886 -149.261068)
			(xy 175.871886 -152.828244) (xy 176.75555 -152.828244) (xy 176.759621 -152.772622) (xy 176.771747 -152.718185)
			(xy 176.79167 -152.666094) (xy 176.818966 -152.617459) (xy 176.853052 -152.573316) (xy 176.893201 -152.534607)
			(xy 176.938559 -152.502156) (xy 176.988159 -152.476655) (xy 177.040943 -152.458648) (xy 177.095786 -152.448518)
			(xy 177.15152 -152.446481) (xy 177.206957 -152.452581) (xy 177.260914 -152.466687) (xy 177.312243 -152.488499)
			(xy 177.359849 -152.517553) (xy 177.402717 -152.553228) (xy 177.439934 -152.594765) (xy 177.470707 -152.641278)
			(xy 177.494379 -152.691775) (xy 177.510447 -152.745182) (xy 177.518567 -152.800358) (xy 177.519076 -152.828244)
			(xy 177.518567 -152.85613) (xy 177.510447 -152.911306) (xy 177.494379 -152.964713) (xy 177.470707 -153.01521)
			(xy 177.439934 -153.061723) (xy 177.402717 -153.10326) (xy 177.359849 -153.138935) (xy 177.312243 -153.167989)
			(xy 177.260914 -153.189801) (xy 177.206957 -153.203907) (xy 177.15152 -153.210007) (xy 177.095786 -153.20797)
			(xy 177.040943 -153.19784) (xy 176.988159 -153.179833) (xy 176.938559 -153.154332) (xy 176.893201 -153.121881)
			(xy 176.853052 -153.083172) (xy 176.818966 -153.039029) (xy 176.79167 -152.990394) (xy 176.771747 -152.938303)
			(xy 176.759621 -152.883866) (xy 176.75555 -152.828244) (xy 175.871886 -152.828244) (xy 175.871886 -154.032712)
			(xy 181.11089 -154.032712) (xy 181.111417 -153.999154) (xy 181.120267 -153.932624) (xy 181.137789 -153.867835)
			(xy 181.163678 -153.805913) (xy 181.197484 -153.747932) (xy 181.238621 -153.694901) (xy 181.286374 -153.647739)
			(xy 181.31282 -153.627074) (xy 181.320815 -153.620409) (xy 181.331049 -153.602309) (xy 181.332632 -153.592022)
			(xy 181.341014 -153.518616) (xy 181.341646 -153.508192) (xy 181.335475 -153.488262) (xy 181.329076 -153.480008)
			(xy 181.311968 -153.4592) (xy 181.283119 -153.413708) (xy 181.260963 -153.364608) (xy 181.245942 -153.312877)
			(xy 181.238356 -153.259546) (xy 181.23789 -153.232612) (xy 181.238376 -153.205361) (xy 181.246132 -153.151413)
			(xy 181.261487 -153.099118) (xy 181.284129 -153.049541) (xy 181.313595 -153.003691) (xy 181.349286 -152.9625)
			(xy 181.390477 -152.926809) (xy 181.436327 -152.897343) (xy 181.485904 -152.874701) (xy 181.538199 -152.859346)
			(xy 181.592147 -152.85159) (xy 181.646649 -152.85159) (xy 181.700597 -152.859346) (xy 181.752892 -152.874701)
			(xy 181.802469 -152.897343) (xy 181.848319 -152.926809) (xy 181.88951 -152.9625) (xy 181.925201 -153.003691)
			(xy 181.954667 -153.049541) (xy 181.977309 -153.099118) (xy 181.992664 -153.151413) (xy 182.00042 -153.205361)
			(xy 182.000906 -153.232612) (xy 182.000423 -153.259546) (xy 181.992839 -153.312877) (xy 181.977825 -153.364609)
			(xy 181.95568 -153.413714) (xy 181.926843 -153.459213) (xy 181.90972 -153.480008) (xy 181.903299 -153.48825)
			(xy 181.897132 -153.508188) (xy 181.897782 -153.518616) (xy 181.906164 -153.592022) (xy 181.90781 -153.60229)
			(xy 181.918019 -153.620381) (xy 181.925976 -153.627074) (xy 181.952416 -153.647749) (xy 182.000183 -153.694898)
			(xy 182.04133 -153.747923) (xy 182.07514 -153.805902) (xy 182.101026 -153.867827) (xy 182.118537 -153.93262)
			(xy 182.127368 -153.999153) (xy 182.127906 -154.032712) (xy 182.127453 -154.0644) (xy 182.119574 -154.127285)
			(xy 182.103942 -154.188703) (xy 182.080797 -154.247702) (xy 182.050499 -154.303367) (xy 182.032402 -154.329384)
			(xy 182.025909 -154.33973) (xy 182.022448 -154.363868) (xy 182.025798 -154.375612) (xy 182.056786 -154.465782)
			(xy 182.074566 -154.482546) (xy 182.086504 -154.486102) (xy 182.117749 -154.495766) (xy 182.17764 -154.522047)
			(xy 182.233666 -154.555792) (xy 182.284902 -154.596443) (xy 182.330501 -154.643329) (xy 182.369712 -154.695676)
			(xy 182.401886 -154.752618) (xy 182.426492 -154.813217) (xy 182.443123 -154.87647) (xy 182.451506 -154.941334)
			(xy 182.45201 -154.974036) (xy 182.45201 -154.974544) (xy 182.451599 -155.003245) (xy 182.445108 -155.060278)
			(xy 182.439056 -155.088336) (xy 182.435754 -155.102814) (xy 182.445152 -155.130246) (xy 182.466194 -155.146967)
			(xy 184.214256 -155.146967) (xy 184.214256 -155.083045) (xy 184.222267 -155.019627) (xy 184.238164 -154.957713)
			(xy 184.261696 -154.89828) (xy 184.29249 -154.842265) (xy 184.330063 -154.79055) (xy 184.37382 -154.743953)
			(xy 184.423073 -154.703208) (xy 184.477044 -154.668957) (xy 184.534883 -154.64174) (xy 184.595676 -154.621987)
			(xy 184.658466 -154.610009) (xy 184.722262 -154.605996) (xy 184.786058 -154.610009) (xy 184.848848 -154.621987)
			(xy 184.909641 -154.64174) (xy 184.96748 -154.668957) (xy 185.021451 -154.703208) (xy 185.070704 -154.743953)
			(xy 185.114461 -154.79055) (xy 185.152034 -154.842265) (xy 185.182828 -154.89828) (xy 185.20636 -154.957713)
			(xy 185.222257 -155.019627) (xy 185.230268 -155.083045) (xy 185.23077 -155.115006) (xy 185.230268 -155.146967)
			(xy 185.222257 -155.210385) (xy 185.20636 -155.272299) (xy 185.182828 -155.331732) (xy 185.152034 -155.387747)
			(xy 185.114461 -155.439462) (xy 185.070704 -155.486059) (xy 185.021451 -155.526804) (xy 184.96748 -155.561055)
			(xy 184.909641 -155.588272) (xy 184.848848 -155.608025) (xy 184.786058 -155.620003) (xy 184.722262 -155.624017)
			(xy 184.658466 -155.620003) (xy 184.595676 -155.608025) (xy 184.534883 -155.588272) (xy 184.477044 -155.561055)
			(xy 184.423073 -155.526804) (xy 184.37382 -155.486059) (xy 184.330063 -155.439462) (xy 184.29249 -155.387747)
			(xy 184.261696 -155.331732) (xy 184.238164 -155.272299) (xy 184.222267 -155.210385) (xy 184.214256 -155.146967)
			(xy 182.466194 -155.146967) (xy 182.540402 -155.205938) (xy 182.569358 -155.208986) (xy 182.582566 -155.202382)
			(xy 182.608735 -155.190021) (xy 182.663263 -155.170619) (xy 182.719645 -155.157546) (xy 182.777147 -155.150972)
			(xy 182.806086 -155.150566) (xy 182.80634 -155.150566) (xy 182.837878 -155.15111) (xy 182.90047 -155.158917)
			(xy 182.961615 -155.174406) (xy 183.020375 -155.19734) (xy 183.075848 -155.227365) (xy 183.12718 -155.264021)
			(xy 183.173584 -155.306745) (xy 183.214347 -155.354881) (xy 183.248842 -155.40769) (xy 183.276541 -155.464359)
			(xy 183.297018 -155.52402) (xy 183.309958 -155.585755) (xy 183.315163 -155.648617) (xy 183.312552 -155.711639)
			(xy 183.302165 -155.773855) (xy 183.284163 -155.834308) (xy 183.258821 -155.892071) (xy 183.22653 -155.946255)
			(xy 183.187784 -155.996029) (xy 183.143179 -156.040628) (xy 183.0934 -156.079367) (xy 183.039212 -156.111652)
			(xy 182.981446 -156.136986) (xy 182.920991 -156.15498) (xy 182.858774 -156.165358) (xy 182.795751 -156.167961)
			(xy 182.73289 -156.162749) (xy 182.671156 -156.149801) (xy 182.611498 -156.129316) (xy 182.554832 -156.10161)
			(xy 182.502028 -156.067107) (xy 182.453898 -156.026338) (xy 182.41118 -155.979928) (xy 182.37453 -155.928592)
			(xy 182.344512 -155.873116) (xy 182.321586 -155.814353) (xy 182.306105 -155.753205) (xy 182.298306 -155.690612)
			(xy 182.297832 -155.659074) (xy 182.297832 -155.658566) (xy 182.298243 -155.629865) (xy 182.304734 -155.572832)
			(xy 182.310786 -155.544774) (xy 182.314088 -155.530296) (xy 182.30469 -155.502864) (xy 182.20944 -155.427172)
			(xy 182.180484 -155.424124) (xy 182.167276 -155.430728) (xy 182.141117 -155.443111) (xy 182.086585 -155.462507)
			(xy 182.0302 -155.475574) (xy 181.972695 -155.482142) (xy 181.943756 -155.482544) (xy 181.943502 -155.482544)
			(xy 181.912772 -155.482042) (xy 181.851761 -155.474635) (xy 181.792088 -155.459927) (xy 181.734622 -155.438135)
			(xy 181.680202 -155.409575) (xy 181.629621 -155.374663) (xy 181.583617 -155.33391) (xy 181.54286 -155.287909)
			(xy 181.507945 -155.23733) (xy 181.479381 -155.182913) (xy 181.457584 -155.125448) (xy 181.442872 -155.065776)
			(xy 181.43546 -155.004766) (xy 181.434994 -154.974036) (xy 181.435472 -154.942349) (xy 181.443345 -154.879465)
			(xy 181.458972 -154.818047) (xy 181.482111 -154.759048) (xy 181.512404 -154.703382) (xy 181.530498 -154.677364)
			(xy 181.537024 -154.667035) (xy 181.540465 -154.642883) (xy 181.537102 -154.631136) (xy 181.506114 -154.540966)
			(xy 181.488334 -154.524202) (xy 181.476396 -154.520646) (xy 181.445135 -154.511028) (xy 181.385242 -154.484743)
			(xy 181.329215 -154.450994) (xy 181.277978 -154.410338) (xy 181.232378 -154.363447) (xy 181.193169 -154.311095)
			(xy 181.160997 -154.254147) (xy 181.136395 -154.193543) (xy 181.119768 -154.130284) (xy 181.111391 -154.065416)
			(xy 181.11089 -154.032712) (xy 175.871886 -154.032712) (xy 175.871886 -155.786539) (xy 176.511706 -155.786539)
			(xy 176.511706 -155.722617) (xy 176.519717 -155.659199) (xy 176.535614 -155.597285) (xy 176.559146 -155.537852)
			(xy 176.58994 -155.481837) (xy 176.627513 -155.430122) (xy 176.67127 -155.383525) (xy 176.720523 -155.34278)
			(xy 176.774494 -155.308529) (xy 176.832333 -155.281312) (xy 176.893126 -155.261559) (xy 176.955916 -155.249581)
			(xy 177.019712 -155.245568) (xy 177.083508 -155.249581) (xy 177.146298 -155.261559) (xy 177.207091 -155.281312)
			(xy 177.26493 -155.308529) (xy 177.318901 -155.34278) (xy 177.368154 -155.383525) (xy 177.411911 -155.430122)
			(xy 177.449484 -155.481837) (xy 177.480278 -155.537852) (xy 177.50381 -155.597285) (xy 177.519707 -155.659199)
			(xy 177.527718 -155.722617) (xy 177.52822 -155.754578) (xy 177.527718 -155.786539) (xy 177.525889 -155.801017)
			(xy 178.004718 -155.801017) (xy 178.004718 -155.737095) (xy 178.012729 -155.673677) (xy 178.028626 -155.611763)
			(xy 178.052158 -155.55233) (xy 178.082952 -155.496315) (xy 178.120525 -155.4446) (xy 178.164282 -155.398003)
			(xy 178.213535 -155.357258) (xy 178.267506 -155.323007) (xy 178.325345 -155.29579) (xy 178.386138 -155.276037)
			(xy 178.448928 -155.264059) (xy 178.512724 -155.260046) (xy 178.57652 -155.264059) (xy 178.63931 -155.276037)
			(xy 178.700103 -155.29579) (xy 178.757942 -155.323007) (xy 178.811913 -155.357258) (xy 178.861166 -155.398003)
			(xy 178.904923 -155.4446) (xy 178.942496 -155.496315) (xy 178.97329 -155.55233) (xy 178.996822 -155.611763)
			(xy 179.012719 -155.673677) (xy 179.02073 -155.737095) (xy 179.021232 -155.769056) (xy 179.02073 -155.801017)
			(xy 179.012719 -155.864435) (xy 178.996822 -155.926349) (xy 178.97329 -155.985782) (xy 178.942496 -156.041797)
			(xy 178.904923 -156.093512) (xy 178.861166 -156.140109) (xy 178.811913 -156.180854) (xy 178.757942 -156.215105)
			(xy 178.700103 -156.242322) (xy 178.63931 -156.262075) (xy 178.57652 -156.274053) (xy 178.512724 -156.278067)
			(xy 178.448928 -156.274053) (xy 178.386138 -156.262075) (xy 178.325345 -156.242322) (xy 178.267506 -156.215105)
			(xy 178.213535 -156.180854) (xy 178.164282 -156.140109) (xy 178.120525 -156.093512) (xy 178.082952 -156.041797)
			(xy 178.052158 -155.985782) (xy 178.028626 -155.926349) (xy 178.012729 -155.864435) (xy 178.004718 -155.801017)
			(xy 177.525889 -155.801017) (xy 177.519707 -155.849957) (xy 177.50381 -155.911871) (xy 177.480278 -155.971304)
			(xy 177.449484 -156.027319) (xy 177.411911 -156.079034) (xy 177.368154 -156.125631) (xy 177.318901 -156.166376)
			(xy 177.26493 -156.200627) (xy 177.207091 -156.227844) (xy 177.146298 -156.247597) (xy 177.083508 -156.259575)
			(xy 177.019712 -156.263589) (xy 176.955916 -156.259575) (xy 176.893126 -156.247597) (xy 176.832333 -156.227844)
			(xy 176.774494 -156.200627) (xy 176.720523 -156.166376) (xy 176.67127 -156.125631) (xy 176.627513 -156.079034)
			(xy 176.58994 -156.027319) (xy 176.559146 -155.971304) (xy 176.535614 -155.911871) (xy 176.519717 -155.849957)
			(xy 176.511706 -155.786539) (xy 175.871886 -155.786539) (xy 175.871886 -157.940205) (xy 178.914292 -157.940205)
			(xy 178.914292 -157.876283) (xy 178.922303 -157.812865) (xy 178.9382 -157.750951) (xy 178.961732 -157.691518)
			(xy 178.992526 -157.635503) (xy 179.030099 -157.583788) (xy 179.073856 -157.537191) (xy 179.123109 -157.496446)
			(xy 179.17708 -157.462195) (xy 179.234919 -157.434978) (xy 179.295712 -157.415225) (xy 179.358502 -157.403247)
			(xy 179.422298 -157.399234) (xy 179.486094 -157.403247) (xy 179.548884 -157.415225) (xy 179.609677 -157.434978)
			(xy 179.667516 -157.462195) (xy 179.721487 -157.496446) (xy 179.77074 -157.537191) (xy 179.814497 -157.583788)
			(xy 179.85207 -157.635503) (xy 179.882864 -157.691518) (xy 179.906396 -157.750951) (xy 179.922293 -157.812865)
			(xy 179.930304 -157.876283) (xy 179.930806 -157.908244) (xy 179.930304 -157.940205) (xy 179.922293 -158.003623)
			(xy 179.906396 -158.065537) (xy 179.882864 -158.12497) (xy 179.85207 -158.180985) (xy 179.814497 -158.2327)
			(xy 179.77074 -158.279297) (xy 179.721487 -158.320042) (xy 179.667516 -158.354293) (xy 179.609677 -158.38151)
			(xy 179.548884 -158.401263) (xy 179.486094 -158.413241) (xy 179.422298 -158.417255) (xy 179.358502 -158.413241)
			(xy 179.295712 -158.401263) (xy 179.234919 -158.38151) (xy 179.17708 -158.354293) (xy 179.123109 -158.320042)
			(xy 179.073856 -158.279297) (xy 179.030099 -158.2327) (xy 178.992526 -158.180985) (xy 178.961732 -158.12497)
			(xy 178.9382 -158.065537) (xy 178.922303 -158.003623) (xy 178.914292 -157.940205) (xy 175.871886 -157.940205)
			(xy 175.871886 -159.4884) (xy 181.538046 -159.4884) (xy 181.542061 -159.424596) (xy 181.554041 -159.361798)
			(xy 181.573797 -159.300997) (xy 181.601018 -159.243152) (xy 181.635275 -159.189175) (xy 181.676027 -159.139917)
			(xy 181.722632 -159.096155) (xy 181.774354 -159.05858) (xy 181.830378 -159.027784) (xy 181.88982 -159.004253)
			(xy 181.951742 -158.988358) (xy 182.015169 -158.980349) (xy 182.047134 -158.97987) (xy 182.079228 -158.980316)
			(xy 182.142906 -158.988405) (xy 182.20506 -159.004438) (xy 182.264705 -159.02816) (xy 182.320893 -159.059194)
			(xy 182.372732 -159.097048) (xy 182.4194 -159.141121) (xy 182.460154 -159.190712) (xy 182.477664 -159.217614)
			(xy 182.482513 -159.224659) (xy 182.495904 -159.235282) (xy 182.512044 -159.240908) (xy 182.52059 -159.241236)
			(xy 182.606442 -159.241236) (xy 182.614989 -159.240904) (xy 182.631133 -159.235287) (xy 182.644522 -159.224661)
			(xy 182.649368 -159.217614) (xy 182.6669 -159.190728) (xy 182.707646 -159.141133) (xy 182.754307 -159.097058)
			(xy 182.806143 -159.059205) (xy 182.86233 -159.028173) (xy 182.921974 -159.004458) (xy 182.984129 -158.988435)
			(xy 183.047805 -158.980359) (xy 183.079898 -158.97987) (xy 183.11436 -158.980449) (xy 183.18265 -158.98977)
			(xy 183.249056 -159.008227) (xy 183.312361 -159.035482) (xy 183.371406 -159.071036) (xy 183.425109 -159.114239)
			(xy 183.449214 -159.138874) (xy 183.449468 -159.139128) (xy 183.456867 -159.146174) (xy 183.47559 -159.154306)
			(xy 183.48579 -159.154876) (xy 183.569356 -159.155638) (xy 183.588406 -159.147764) (xy 183.595518 -159.140398)
			(xy 183.619519 -159.116738) (xy 183.672654 -159.075278) (xy 183.730801 -159.041203) (xy 183.79294 -159.015109)
			(xy 183.857982 -158.997454) (xy 183.924786 -158.988547) (xy 183.958484 -158.987998) (xy 183.990447 -158.988466)
			(xy 184.05387 -158.996476) (xy 184.115789 -159.012373) (xy 184.175227 -159.035904) (xy 184.231247 -159.0667)
			(xy 184.282966 -159.104274) (xy 184.329567 -159.148034) (xy 184.370316 -159.19729) (xy 184.40457 -159.251265)
			(xy 184.43179 -159.309107) (xy 184.451545 -159.369905) (xy 184.463523 -159.432699) (xy 184.467538 -159.4965)
			(xy 184.463523 -159.560301) (xy 184.451545 -159.623095) (xy 184.43179 -159.683893) (xy 184.40457 -159.741735)
			(xy 184.370316 -159.79571) (xy 184.329567 -159.844966) (xy 184.282966 -159.888726) (xy 184.231247 -159.9263)
			(xy 184.175227 -159.957096) (xy 184.115789 -159.980627) (xy 184.05387 -159.996524) (xy 183.990447 -160.004534)
			(xy 183.958484 -160.005014) (xy 183.924023 -160.004421) (xy 183.855735 -159.9951) (xy 183.78933 -159.976643)
			(xy 183.726025 -159.949391) (xy 183.666979 -159.91384) (xy 183.613274 -159.870643) (xy 183.589168 -159.84601)
			(xy 183.588914 -159.845756) (xy 183.581523 -159.8387) (xy 183.562794 -159.830574) (xy 183.552592 -159.830008)
			(xy 183.469026 -159.829246) (xy 183.449976 -159.83712) (xy 183.442864 -159.844486) (xy 183.418868 -159.868152)
			(xy 183.365733 -159.909611) (xy 183.307585 -159.943686) (xy 183.245445 -159.96978) (xy 183.180402 -159.987433)
			(xy 183.113596 -159.996338) (xy 183.079898 -159.996886) (xy 183.047805 -159.996389) (xy 182.984131 -159.988305)
			(xy 182.921979 -159.972278) (xy 182.862336 -159.948562) (xy 182.806148 -159.917535) (xy 182.754308 -159.879689)
			(xy 182.707638 -159.835624) (xy 182.66688 -159.78604) (xy 182.649368 -159.759142) (xy 182.644485 -159.752123)
			(xy 182.631112 -159.741491) (xy 182.614984 -159.735854) (xy 182.606442 -159.73552) (xy 182.52059 -159.73552)
			(xy 182.512041 -159.735824) (xy 182.495898 -159.741457) (xy 182.48251 -159.752092) (xy 182.477664 -159.759142)
			(xy 182.460197 -159.786072) (xy 182.41944 -159.835665) (xy 182.372768 -159.879735) (xy 182.320922 -159.917584)
			(xy 182.264726 -159.948609) (xy 182.205074 -159.972318) (xy 182.142912 -159.988333) (xy 182.07923 -159.996401)
			(xy 182.047134 -159.996886) (xy 182.015169 -159.996451) (xy 181.951742 -159.988442) (xy 181.88982 -159.972547)
			(xy 181.830378 -159.949016) (xy 181.774354 -159.91822) (xy 181.722632 -159.880645) (xy 181.676027 -159.836883)
			(xy 181.635275 -159.787625) (xy 181.601018 -159.733648) (xy 181.573797 -159.675803) (xy 181.554041 -159.615002)
			(xy 181.542061 -159.552204) (xy 181.538046 -159.4884) (xy 175.871886 -159.4884) (xy 175.871886 -160.995868)
			(xy 180.680614 -160.995868) (xy 180.681116 -160.963907) (xy 180.689127 -160.900489) (xy 180.705024 -160.838575)
			(xy 180.728556 -160.779142) (xy 180.75935 -160.723127) (xy 180.796923 -160.671412) (xy 180.84068 -160.624815)
			(xy 180.889933 -160.58407) (xy 180.943904 -160.549819) (xy 181.001743 -160.522602) (xy 181.062536 -160.502849)
			(xy 181.125326 -160.490871) (xy 181.189122 -160.486858) (xy 181.252918 -160.490871) (xy 181.315708 -160.502849)
			(xy 181.376501 -160.522602) (xy 181.43434 -160.549819) (xy 181.488311 -160.58407) (xy 181.537564 -160.624815)
			(xy 181.581321 -160.671412) (xy 181.618894 -160.723127) (xy 181.649688 -160.779142) (xy 181.67322 -160.838575)
			(xy 181.689117 -160.900489) (xy 181.697128 -160.963907) (xy 181.69763 -160.995868) (xy 181.697384 -161.012124)
			(xy 183.387492 -161.012124) (xy 183.387994 -160.980163) (xy 183.396005 -160.916745) (xy 183.411902 -160.854831)
			(xy 183.435434 -160.795398) (xy 183.466228 -160.739383) (xy 183.503801 -160.687668) (xy 183.547558 -160.641071)
			(xy 183.596811 -160.600326) (xy 183.650782 -160.566075) (xy 183.708621 -160.538858) (xy 183.769414 -160.519105)
			(xy 183.832204 -160.507127) (xy 183.896 -160.503114) (xy 183.959796 -160.507127) (xy 184.022586 -160.519105)
			(xy 184.083379 -160.538858) (xy 184.141218 -160.566075) (xy 184.195189 -160.600326) (xy 184.244442 -160.641071)
			(xy 184.288199 -160.687668) (xy 184.325772 -160.739383) (xy 184.356566 -160.795398) (xy 184.380098 -160.854831)
			(xy 184.395995 -160.916745) (xy 184.401428 -160.959757) (xy 185.771022 -160.959757) (xy 185.771022 -160.895835)
			(xy 185.779033 -160.832417) (xy 185.79493 -160.770503) (xy 185.818462 -160.71107) (xy 185.849256 -160.655055)
			(xy 185.886829 -160.60334) (xy 185.930586 -160.556743) (xy 185.979839 -160.515998) (xy 186.03381 -160.481747)
			(xy 186.091649 -160.45453) (xy 186.152442 -160.434777) (xy 186.215232 -160.422799) (xy 186.279028 -160.418786)
			(xy 186.342824 -160.422799) (xy 186.405614 -160.434777) (xy 186.466407 -160.45453) (xy 186.524246 -160.481747)
			(xy 186.578217 -160.515998) (xy 186.62747 -160.556743) (xy 186.671227 -160.60334) (xy 186.708397 -160.6545)
			(xy 197.470781 -160.6545) (xy 197.474795 -160.590704) (xy 197.486773 -160.527913) (xy 197.506526 -160.46712)
			(xy 197.533742 -160.409281) (xy 197.567994 -160.355309) (xy 197.608739 -160.306056) (xy 197.655336 -160.262297)
			(xy 197.70705 -160.224724) (xy 197.763065 -160.193929) (xy 197.822499 -160.170397) (xy 197.884413 -160.154499)
			(xy 197.947831 -160.146486) (xy 197.979792 -160.145984) (xy 198.012781 -160.146523) (xy 198.078204 -160.155056)
			(xy 198.141975 -160.171978) (xy 198.203021 -160.197006) (xy 198.260317 -160.22972) (xy 198.312901 -160.269569)
			(xy 198.359889 -160.315885) (xy 198.380604 -160.341564) (xy 198.389494 -160.352994) (xy 198.416164 -160.3629)
			(xy 198.533512 -160.339786) (xy 198.554594 -160.320228) (xy 198.558404 -160.306512) (xy 198.567852 -160.274924)
			(xy 198.593792 -160.214308) (xy 198.627348 -160.157552) (xy 198.667958 -160.105609) (xy 198.71494 -160.05935)
			(xy 198.767506 -160.019551) (xy 198.824775 -159.986878) (xy 198.885786 -159.96188) (xy 198.949516 -159.944977)
			(xy 199.014895 -159.936451) (xy 199.047862 -159.935926) (xy 199.079345 -159.936387) (xy 199.14183 -159.944168)
			(xy 199.202876 -159.959603) (xy 199.261549 -159.982455) (xy 199.316953 -160.012377) (xy 199.368239 -160.048908)
			(xy 199.414623 -160.091492) (xy 199.455395 -160.139476) (xy 199.473058 -160.165542) (xy 199.479916 -160.17621)
			(xy 199.501506 -160.188402) (xy 199.609964 -160.191196) (xy 199.632316 -160.180528) (xy 199.639682 -160.170368)
			(xy 199.660355 -160.143516) (xy 199.707605 -160.094939) (xy 199.760889 -160.053068) (xy 199.819261 -160.018645)
			(xy 199.881688 -159.99228) (xy 199.947064 -159.97444) (xy 200.014231 -159.965441) (xy 200.048114 -159.964882)
			(xy 200.080074 -159.965405) (xy 200.143489 -159.973418) (xy 200.2054 -159.989315) (xy 200.264831 -160.012847)
			(xy 200.320844 -160.043641) (xy 200.372555 -160.081213) (xy 200.41915 -160.12497) (xy 200.459893 -160.174222)
			(xy 200.494143 -160.228191) (xy 200.521358 -160.286028) (xy 200.54111 -160.346819) (xy 200.553087 -160.409606)
			(xy 200.557101 -160.4734) (xy 200.553087 -160.537194) (xy 200.54111 -160.599981) (xy 200.521358 -160.660772)
			(xy 200.494143 -160.718609) (xy 200.459893 -160.772578) (xy 200.41915 -160.82183) (xy 200.372555 -160.865587)
			(xy 200.320844 -160.903159) (xy 200.264831 -160.933953) (xy 200.2054 -160.957485) (xy 200.143489 -160.973382)
			(xy 200.080074 -160.981395) (xy 200.048114 -160.981898) (xy 200.016631 -160.981412) (xy 199.954147 -160.973639)
			(xy 199.8931 -160.95821) (xy 199.834425 -160.935362) (xy 199.779021 -160.905445) (xy 199.727734 -160.868915)
			(xy 199.681351 -160.826332) (xy 199.64058 -160.778348) (xy 199.622918 -160.752282) (xy 199.61606 -160.741614)
			(xy 199.59447 -160.729422) (xy 199.486012 -160.726628) (xy 199.46366 -160.737296) (xy 199.456294 -160.747456)
			(xy 199.435642 -160.774325) (xy 199.388387 -160.8229) (xy 199.3351 -160.864769) (xy 199.276724 -160.89919)
			(xy 199.214293 -160.925552) (xy 199.148915 -160.943389) (xy 199.081746 -160.952385) (xy 199.047862 -160.952942)
			(xy 199.014873 -160.952426) (xy 198.949449 -160.943888) (xy 198.885678 -160.926961) (xy 198.824632 -160.901929)
			(xy 198.767336 -160.869212) (xy 198.714753 -160.82936) (xy 198.667765 -160.783042) (xy 198.64705 -160.757362)
			(xy 198.63816 -160.745932) (xy 198.61149 -160.736026) (xy 198.494142 -160.75914) (xy 198.47306 -160.778698)
			(xy 198.46925 -160.792414) (xy 198.459797 -160.824001) (xy 198.433862 -160.88462) (xy 198.400309 -160.941379)
			(xy 198.359701 -160.993325) (xy 198.31272 -161.039586) (xy 198.260154 -161.079387) (xy 198.202884 -161.11206)
			(xy 198.141872 -161.137056) (xy 198.07814 -161.153956) (xy 198.012759 -161.162477) (xy 197.979792 -161.163)
			(xy 197.947831 -161.162514) (xy 197.884413 -161.154501) (xy 197.822499 -161.138603) (xy 197.763065 -161.115071)
			(xy 197.70705 -161.084276) (xy 197.655336 -161.046703) (xy 197.608739 -161.002944) (xy 197.567994 -160.953691)
			(xy 197.533742 -160.899719) (xy 197.506526 -160.84188) (xy 197.486773 -160.781087) (xy 197.474795 -160.718296)
			(xy 197.470781 -160.6545) (xy 186.708397 -160.6545) (xy 186.7088 -160.655055) (xy 186.739594 -160.71107)
			(xy 186.763126 -160.770503) (xy 186.779023 -160.832417) (xy 186.787034 -160.895835) (xy 186.787536 -160.927796)
			(xy 186.787034 -160.959757) (xy 186.779023 -161.023175) (xy 186.763126 -161.085089) (xy 186.739594 -161.144522)
			(xy 186.7088 -161.200537) (xy 186.671227 -161.252252) (xy 186.62747 -161.298849) (xy 186.578217 -161.339594)
			(xy 186.524246 -161.373845) (xy 186.466407 -161.401062) (xy 186.405614 -161.420815) (xy 186.342824 -161.432793)
			(xy 186.279028 -161.436807) (xy 186.215232 -161.432793) (xy 186.152442 -161.420815) (xy 186.091649 -161.401062)
			(xy 186.03381 -161.373845) (xy 185.979839 -161.339594) (xy 185.930586 -161.298849) (xy 185.886829 -161.252252)
			(xy 185.849256 -161.200537) (xy 185.818462 -161.144522) (xy 185.79493 -161.085089) (xy 185.779033 -161.023175)
			(xy 185.771022 -160.959757) (xy 184.401428 -160.959757) (xy 184.404006 -160.980163) (xy 184.404508 -161.012124)
			(xy 184.404059 -161.043229) (xy 184.396457 -161.104972) (xy 184.381381 -161.165327) (xy 184.359057 -161.223393)
			(xy 184.329817 -161.278303) (xy 184.294099 -161.329236) (xy 184.252435 -161.375433) (xy 184.229248 -161.396172)
			(xy 184.222483 -161.402598) (xy 184.213615 -161.418993) (xy 184.211976 -161.428176) (xy 184.20207 -161.504376)
			(xy 184.206388 -161.52241) (xy 184.211722 -161.53003) (xy 184.2273 -161.553907) (xy 184.251982 -161.605295)
			(xy 184.26875 -161.659782) (xy 184.277231 -161.716156) (xy 184.277762 -161.74466) (xy 184.277276 -161.771911)
			(xy 184.274262 -161.792877) (xy 186.527942 -161.792877) (xy 186.527942 -161.728955) (xy 186.535953 -161.665537)
			(xy 186.55185 -161.603623) (xy 186.575382 -161.54419) (xy 186.606176 -161.488175) (xy 186.643749 -161.43646)
			(xy 186.687506 -161.389863) (xy 186.736759 -161.349118) (xy 186.79073 -161.314867) (xy 186.848569 -161.28765)
			(xy 186.909362 -161.267897) (xy 186.972152 -161.255919) (xy 187.035948 -161.251906) (xy 187.099744 -161.255919)
			(xy 187.162534 -161.267897) (xy 187.223327 -161.28765) (xy 187.281166 -161.314867) (xy 187.335137 -161.349118)
			(xy 187.38439 -161.389863) (xy 187.428147 -161.43646) (xy 187.46572 -161.488175) (xy 187.496514 -161.54419)
			(xy 187.520046 -161.603623) (xy 187.535943 -161.665537) (xy 187.543954 -161.728955) (xy 187.544456 -161.760916)
			(xy 187.543954 -161.792877) (xy 187.535943 -161.856295) (xy 187.520046 -161.918209) (xy 187.496514 -161.977642)
			(xy 187.46572 -162.033657) (xy 187.428147 -162.085372) (xy 187.38439 -162.131969) (xy 187.335137 -162.172714)
			(xy 187.281166 -162.206965) (xy 187.223327 -162.234182) (xy 187.162534 -162.253935) (xy 187.099744 -162.265913)
			(xy 187.035948 -162.269927) (xy 186.972152 -162.265913) (xy 186.909362 -162.253935) (xy 186.848569 -162.234182)
			(xy 186.79073 -162.206965) (xy 186.736759 -162.172714) (xy 186.687506 -162.131969) (xy 186.643749 -162.085372)
			(xy 186.606176 -162.033657) (xy 186.575382 -161.977642) (xy 186.55185 -161.918209) (xy 186.535953 -161.856295)
			(xy 186.527942 -161.792877) (xy 184.274262 -161.792877) (xy 184.26952 -161.825859) (xy 184.254165 -161.878154)
			(xy 184.231523 -161.927731) (xy 184.202057 -161.973581) (xy 184.166366 -162.014772) (xy 184.125175 -162.050463)
			(xy 184.079325 -162.079929) (xy 184.029748 -162.102571) (xy 183.977453 -162.117926) (xy 183.923505 -162.125682)
			(xy 183.869003 -162.125682) (xy 183.815055 -162.117926) (xy 183.76276 -162.102571) (xy 183.713183 -162.079929)
			(xy 183.667333 -162.050463) (xy 183.626142 -162.014772) (xy 183.590451 -161.973581) (xy 183.560985 -161.927731)
			(xy 183.538343 -161.878154) (xy 183.522988 -161.825859) (xy 183.515232 -161.771911) (xy 183.514746 -161.74466)
			(xy 183.514746 -161.744406) (xy 183.515292 -161.715975) (xy 183.523741 -161.659744) (xy 183.540437 -161.605388)
			(xy 183.565011 -161.554111) (xy 183.580532 -161.530284) (xy 183.585433 -161.522366) (xy 183.589719 -161.504256)
			(xy 183.588914 -161.494978) (xy 183.580278 -161.42843) (xy 183.578751 -161.419207) (xy 183.569874 -161.402769)
			(xy 183.563006 -161.396426) (xy 183.539793 -161.375677) (xy 183.498068 -161.329467) (xy 183.462297 -161.278508)
			(xy 183.433015 -161.223563) (xy 183.41066 -161.165453) (xy 183.395568 -161.105049) (xy 183.387963 -161.043254)
			(xy 183.387492 -161.012124) (xy 181.697384 -161.012124) (xy 181.697125 -161.029274) (xy 181.688379 -161.095511)
			(xy 181.671033 -161.160031) (xy 181.645385 -161.221725) (xy 181.611879 -161.279527) (xy 181.571091 -161.332443)
			(xy 181.523723 -161.379562) (xy 181.497478 -161.400236) (xy 181.48935 -161.406332) (xy 181.47919 -161.423858)
			(xy 181.466744 -161.514536) (xy 181.471824 -161.534094) (xy 181.47792 -161.542222) (xy 181.495975 -161.56716)
			(xy 181.524634 -161.621648) (xy 181.54416 -161.680035) (xy 181.554044 -161.740801) (xy 181.554628 -161.771584)
			(xy 181.554628 -161.771838) (xy 181.554142 -161.799089) (xy 181.546386 -161.853037) (xy 181.531031 -161.905332)
			(xy 181.508389 -161.954909) (xy 181.478923 -162.000759) (xy 181.443232 -162.04195) (xy 181.402041 -162.077641)
			(xy 181.356191 -162.107107) (xy 181.306614 -162.129749) (xy 181.254319 -162.145104) (xy 181.200371 -162.15286)
			(xy 181.145869 -162.15286) (xy 181.091921 -162.145104) (xy 181.039626 -162.129749) (xy 180.990049 -162.107107)
			(xy 180.944199 -162.077641) (xy 180.903008 -162.04195) (xy 180.867317 -162.000759) (xy 180.837851 -161.954909)
			(xy 180.815209 -161.905332) (xy 180.799854 -161.853037) (xy 180.792098 -161.799089) (xy 180.791612 -161.771838)
			(xy 180.792032 -161.745604) (xy 180.799219 -161.693629) (xy 180.813463 -161.643131) (xy 180.834494 -161.595062)
			(xy 180.861916 -161.550329) (xy 180.878226 -161.529776) (xy 180.884576 -161.522156) (xy 180.890418 -161.502852)
			(xy 180.882544 -161.421318) (xy 180.881173 -161.41152) (xy 180.872023 -161.394003) (xy 180.864764 -161.387282)
			(xy 180.864256 -161.387282) (xy 180.840012 -161.366529) (xy 180.796397 -161.319939) (xy 180.758957 -161.268256)
			(xy 180.728281 -161.212293) (xy 180.704853 -161.15293) (xy 180.68904 -161.0911) (xy 180.681092 -161.027778)
			(xy 180.680614 -160.995868) (xy 175.871886 -160.995868) (xy 175.871886 -162.278779) (xy 178.553104 -162.278779)
			(xy 178.553104 -162.214857) (xy 178.561115 -162.151439) (xy 178.577012 -162.089525) (xy 178.600544 -162.030092)
			(xy 178.631338 -161.974077) (xy 178.668911 -161.922362) (xy 178.712668 -161.875765) (xy 178.761921 -161.83502)
			(xy 178.815892 -161.800769) (xy 178.873731 -161.773552) (xy 178.934524 -161.753799) (xy 178.997314 -161.741821)
			(xy 179.06111 -161.737808) (xy 179.124906 -161.741821) (xy 179.187696 -161.753799) (xy 179.248489 -161.773552)
			(xy 179.306328 -161.800769) (xy 179.360299 -161.83502) (xy 179.409552 -161.875765) (xy 179.453309 -161.922362)
			(xy 179.490882 -161.974077) (xy 179.521676 -162.030092) (xy 179.545208 -162.089525) (xy 179.561105 -162.151439)
			(xy 179.569116 -162.214857) (xy 179.569618 -162.246818) (xy 179.569116 -162.278779) (xy 179.561105 -162.342197)
			(xy 179.545208 -162.404111) (xy 179.521676 -162.463544) (xy 179.490882 -162.519559) (xy 179.453309 -162.571274)
			(xy 179.409552 -162.617871) (xy 179.360299 -162.658616) (xy 179.306328 -162.692867) (xy 179.248489 -162.720084)
			(xy 179.187696 -162.739837) (xy 179.124906 -162.751815) (xy 179.06111 -162.755829) (xy 178.997314 -162.751815)
			(xy 178.934524 -162.739837) (xy 178.873731 -162.720084) (xy 178.815892 -162.692867) (xy 178.761921 -162.658616)
			(xy 178.712668 -162.617871) (xy 178.668911 -162.571274) (xy 178.631338 -162.519559) (xy 178.600544 -162.463544)
			(xy 178.577012 -162.404111) (xy 178.561115 -162.342197) (xy 178.553104 -162.278779) (xy 175.871886 -162.278779)
			(xy 175.871886 -162.915303) (xy 207.928712 -162.915303) (xy 207.928712 -162.851381) (xy 207.936723 -162.787963)
			(xy 207.95262 -162.726049) (xy 207.976152 -162.666616) (xy 208.006946 -162.610601) (xy 208.044519 -162.558886)
			(xy 208.088276 -162.512289) (xy 208.137529 -162.471544) (xy 208.1915 -162.437293) (xy 208.249339 -162.410076)
			(xy 208.310132 -162.390323) (xy 208.372922 -162.378345) (xy 208.436718 -162.374332) (xy 208.500514 -162.378345)
			(xy 208.509845 -162.380125) (xy 231.98683 -162.380125) (xy 231.98683 -162.316203) (xy 231.994841 -162.252785)
			(xy 232.010738 -162.190871) (xy 232.03427 -162.131438) (xy 232.065064 -162.075423) (xy 232.102637 -162.023708)
			(xy 232.146394 -161.977111) (xy 232.195647 -161.936366) (xy 232.249618 -161.902115) (xy 232.307457 -161.874898)
			(xy 232.36825 -161.855145) (xy 232.43104 -161.843167) (xy 232.494836 -161.839154) (xy 232.558632 -161.843167)
			(xy 232.621422 -161.855145) (xy 232.682215 -161.874898) (xy 232.740054 -161.902115) (xy 232.794025 -161.936366)
			(xy 232.843278 -161.977111) (xy 232.887035 -162.023708) (xy 232.924608 -162.075423) (xy 232.955402 -162.131438)
			(xy 232.978934 -162.190871) (xy 232.994831 -162.252785) (xy 233.002842 -162.316203) (xy 233.003344 -162.348164)
			(xy 233.002842 -162.380125) (xy 232.994831 -162.443543) (xy 232.978934 -162.505457) (xy 232.955402 -162.56489)
			(xy 232.924608 -162.620905) (xy 232.887035 -162.67262) (xy 232.843278 -162.719217) (xy 232.794025 -162.759962)
			(xy 232.740054 -162.794213) (xy 232.682215 -162.82143) (xy 232.621422 -162.841183) (xy 232.558632 -162.853161)
			(xy 232.494836 -162.857175) (xy 232.43104 -162.853161) (xy 232.36825 -162.841183) (xy 232.307457 -162.82143)
			(xy 232.249618 -162.794213) (xy 232.195647 -162.759962) (xy 232.146394 -162.719217) (xy 232.102637 -162.67262)
			(xy 232.065064 -162.620905) (xy 232.03427 -162.56489) (xy 232.010738 -162.505457) (xy 231.994841 -162.443543)
			(xy 231.98683 -162.380125) (xy 208.509845 -162.380125) (xy 208.563304 -162.390323) (xy 208.624097 -162.410076)
			(xy 208.681936 -162.437293) (xy 208.735907 -162.471544) (xy 208.78516 -162.512289) (xy 208.828917 -162.558886)
			(xy 208.86649 -162.610601) (xy 208.897284 -162.666616) (xy 208.920816 -162.726049) (xy 208.936713 -162.787963)
			(xy 208.944724 -162.851381) (xy 208.945226 -162.883342) (xy 208.944724 -162.915303) (xy 208.936713 -162.978721)
			(xy 208.920816 -163.040635) (xy 208.897284 -163.100068) (xy 208.86649 -163.156083) (xy 208.852964 -163.1747)
			(xy 219.096869 -163.1747) (xy 219.100883 -163.110905) (xy 219.11286 -163.048115) (xy 219.132612 -162.987322)
			(xy 219.159827 -162.929484) (xy 219.194076 -162.875512) (xy 219.23482 -162.826259) (xy 219.281414 -162.7825)
			(xy 219.333126 -162.744925) (xy 219.389139 -162.714128) (xy 219.44857 -162.690593) (xy 219.510483 -162.674692)
			(xy 219.573899 -162.666676) (xy 219.60586 -162.666172) (xy 219.638011 -162.666639) (xy 219.701802 -162.674736)
			(xy 219.764061 -162.690817) (xy 219.823793 -162.714625) (xy 219.880043 -162.745781) (xy 219.931913 -162.783785)
			(xy 219.978572 -162.828031) (xy 219.999306 -162.852608) (xy 220.005784 -162.859847) (xy 220.022752 -162.869262)
			(xy 220.032326 -162.870896) (xy 220.102176 -162.879278) (xy 220.111902 -162.879968) (xy 220.130708 -162.874882)
			(xy 220.138752 -162.869372) (xy 220.139006 -162.869372) (xy 220.16112 -162.853389) (xy 220.209003 -162.827232)
			(xy 220.260123 -162.808158) (xy 220.313437 -162.796555) (xy 220.36786 -162.792661) (xy 220.422283 -162.796555)
			(xy 220.475597 -162.808158) (xy 220.526717 -162.827232) (xy 220.5746 -162.853389) (xy 220.596714 -162.869372)
			(xy 220.596968 -162.869372) (xy 220.604989 -162.874931) (xy 220.623812 -162.880021) (xy 220.633544 -162.879278)
			(xy 220.703394 -162.870896) (xy 220.712966 -162.869257) (xy 220.729937 -162.859845) (xy 220.736414 -162.852608)
			(xy 220.757139 -162.828026) (xy 220.803814 -162.783802) (xy 220.855691 -162.745814) (xy 220.911943 -162.714669)
			(xy 220.971672 -162.690864) (xy 221.033926 -162.674778) (xy 221.097711 -162.666667) (xy 221.12986 -162.666172)
			(xy 221.161823 -162.666691) (xy 221.225245 -162.674698) (xy 221.287163 -162.690591) (xy 221.3466 -162.71412)
			(xy 221.40262 -162.744914) (xy 221.454339 -162.782486) (xy 221.50094 -162.826244) (xy 221.54169 -162.875498)
			(xy 221.575944 -162.929471) (xy 221.603163 -162.987311) (xy 221.622918 -163.048108) (xy 221.634897 -163.110901)
			(xy 221.638912 -163.1747) (xy 221.634897 -163.238499) (xy 221.622918 -163.301292) (xy 221.603163 -163.362089)
			(xy 221.575944 -163.419929) (xy 221.54169 -163.473902) (xy 221.50094 -163.523156) (xy 221.454339 -163.566914)
			(xy 221.40262 -163.604486) (xy 221.3466 -163.63528) (xy 221.287163 -163.658809) (xy 221.225245 -163.674702)
			(xy 221.161823 -163.682709) (xy 221.12986 -163.683188) (xy 221.09771 -163.682685) (xy 221.033922 -163.674592)
			(xy 220.971665 -163.658515) (xy 220.911933 -163.634712) (xy 220.855683 -163.603563) (xy 220.803812 -163.565565)
			(xy 220.75715 -163.521326) (xy 220.736414 -163.496752) (xy 220.729936 -163.489514) (xy 220.712967 -163.4801)
			(xy 220.703394 -163.478464) (xy 220.633544 -163.470082) (xy 220.623818 -163.46941) (xy 220.605014 -163.474485)
			(xy 220.596968 -163.479988) (xy 220.596714 -163.479988) (xy 220.5746 -163.495971) (xy 220.526717 -163.522128)
			(xy 220.475597 -163.541202) (xy 220.422283 -163.552805) (xy 220.36786 -163.556699) (xy 220.313437 -163.552805)
			(xy 220.260123 -163.541202) (xy 220.209003 -163.522128) (xy 220.16112 -163.495971) (xy 220.139006 -163.479988)
			(xy 220.138752 -163.479988) (xy 220.130721 -163.474444) (xy 220.111906 -163.469344) (xy 220.102176 -163.470082)
			(xy 220.032326 -163.478464) (xy 220.022759 -163.480124) (xy 220.005787 -163.489522) (xy 219.999306 -163.496752)
			(xy 219.97856 -163.521316) (xy 219.93189 -163.565542) (xy 219.880017 -163.603533) (xy 219.823769 -163.634681)
			(xy 219.764042 -163.658489) (xy 219.701791 -163.674578) (xy 219.638008 -163.682691) (xy 219.60586 -163.683188)
			(xy 219.573899 -163.682724) (xy 219.510483 -163.674708) (xy 219.44857 -163.658807) (xy 219.389139 -163.635272)
			(xy 219.333126 -163.604475) (xy 219.281414 -163.5669) (xy 219.23482 -163.523141) (xy 219.194076 -163.473888)
			(xy 219.159827 -163.419916) (xy 219.132612 -163.362078) (xy 219.11286 -163.301285) (xy 219.100883 -163.238495)
			(xy 219.096869 -163.1747) (xy 208.852964 -163.1747) (xy 208.828917 -163.207798) (xy 208.78516 -163.254395)
			(xy 208.735907 -163.29514) (xy 208.681936 -163.329391) (xy 208.624097 -163.356608) (xy 208.563304 -163.376361)
			(xy 208.500514 -163.388339) (xy 208.436718 -163.392353) (xy 208.372922 -163.388339) (xy 208.310132 -163.376361)
			(xy 208.249339 -163.356608) (xy 208.1915 -163.329391) (xy 208.137529 -163.29514) (xy 208.088276 -163.254395)
			(xy 208.044519 -163.207798) (xy 208.006946 -163.156083) (xy 207.976152 -163.100068) (xy 207.95262 -163.040635)
			(xy 207.936723 -162.978721) (xy 207.928712 -162.915303) (xy 175.871886 -162.915303) (xy 175.871886 -163.138866)
			(xy 175.872902 -163.148264) (xy 175.872902 -163.148772) (xy 175.874091 -163.154003) (xy 175.878315 -163.163862)
			(xy 175.881284 -163.16833) (xy 175.886618 -163.17468) (xy 176.664577 -163.952639) (xy 178.602126 -163.952639)
			(xy 178.602126 -163.888717) (xy 178.610137 -163.825299) (xy 178.626034 -163.763385) (xy 178.649566 -163.703952)
			(xy 178.68036 -163.647937) (xy 178.717933 -163.596222) (xy 178.76169 -163.549625) (xy 178.810943 -163.50888)
			(xy 178.864914 -163.474629) (xy 178.922753 -163.447412) (xy 178.983546 -163.427659) (xy 179.046336 -163.415681)
			(xy 179.110132 -163.411668) (xy 179.173928 -163.415681) (xy 179.236718 -163.427659) (xy 179.297511 -163.447412)
			(xy 179.35535 -163.474629) (xy 179.409321 -163.50888) (xy 179.458574 -163.549625) (xy 179.502331 -163.596222)
			(xy 179.539904 -163.647937) (xy 179.548368 -163.663333) (xy 185.107574 -163.663333) (xy 185.107574 -163.599411)
			(xy 185.115585 -163.535993) (xy 185.131482 -163.474079) (xy 185.155014 -163.414646) (xy 185.185808 -163.358631)
			(xy 185.223381 -163.306916) (xy 185.267138 -163.260319) (xy 185.316391 -163.219574) (xy 185.370362 -163.185323)
			(xy 185.428201 -163.158106) (xy 185.488994 -163.138353) (xy 185.551784 -163.126375) (xy 185.61558 -163.122362)
			(xy 185.679376 -163.126375) (xy 185.742166 -163.138353) (xy 185.802959 -163.158106) (xy 185.860798 -163.185323)
			(xy 185.914769 -163.219574) (xy 185.964022 -163.260319) (xy 186.007779 -163.306916) (xy 186.045352 -163.358631)
			(xy 186.076146 -163.414646) (xy 186.099678 -163.474079) (xy 186.115575 -163.535993) (xy 186.123586 -163.599411)
			(xy 186.124088 -163.631372) (xy 186.123586 -163.663333) (xy 186.123554 -163.663587) (xy 206.693256 -163.663587)
			(xy 206.693256 -163.599665) (xy 206.701267 -163.536247) (xy 206.717164 -163.474333) (xy 206.740696 -163.4149)
			(xy 206.77149 -163.358885) (xy 206.809063 -163.30717) (xy 206.85282 -163.260573) (xy 206.902073 -163.219828)
			(xy 206.956044 -163.185577) (xy 207.013883 -163.15836) (xy 207.074676 -163.138607) (xy 207.137466 -163.126629)
			(xy 207.201262 -163.122616) (xy 207.265058 -163.126629) (xy 207.327848 -163.138607) (xy 207.388641 -163.15836)
			(xy 207.44648 -163.185577) (xy 207.500451 -163.219828) (xy 207.549704 -163.260573) (xy 207.593461 -163.30717)
			(xy 207.631034 -163.358885) (xy 207.661828 -163.4149) (xy 207.68536 -163.474333) (xy 207.701257 -163.536247)
			(xy 207.709268 -163.599665) (xy 207.70977 -163.631626) (xy 207.709268 -163.663587) (xy 207.701257 -163.727005)
			(xy 207.68536 -163.788919) (xy 207.661828 -163.848352) (xy 207.655045 -163.860691) (xy 215.13774 -163.860691)
			(xy 215.13774 -163.796769) (xy 215.145751 -163.733351) (xy 215.161648 -163.671437) (xy 215.18518 -163.612004)
			(xy 215.215974 -163.555989) (xy 215.253547 -163.504274) (xy 215.297304 -163.457677) (xy 215.346557 -163.416932)
			(xy 215.400528 -163.382681) (xy 215.458367 -163.355464) (xy 215.51916 -163.335711) (xy 215.58195 -163.323733)
			(xy 215.645746 -163.31972) (xy 215.709542 -163.323733) (xy 215.772332 -163.335711) (xy 215.833125 -163.355464)
			(xy 215.890964 -163.382681) (xy 215.944935 -163.416932) (xy 215.994188 -163.457677) (xy 216.037945 -163.504274)
			(xy 216.075518 -163.555989) (xy 216.106312 -163.612004) (xy 216.129844 -163.671437) (xy 216.145741 -163.733351)
			(xy 216.153752 -163.796769) (xy 216.154254 -163.82873) (xy 216.153752 -163.860691) (xy 216.145741 -163.924109)
			(xy 216.129844 -163.986023) (xy 216.106312 -164.045456) (xy 216.075518 -164.101471) (xy 216.037945 -164.153186)
			(xy 215.994188 -164.199783) (xy 215.944935 -164.240528) (xy 215.890964 -164.274779) (xy 215.833125 -164.301996)
			(xy 215.772332 -164.321749) (xy 215.709542 -164.333727) (xy 215.645746 -164.337741) (xy 215.58195 -164.333727)
			(xy 215.51916 -164.321749) (xy 215.458367 -164.301996) (xy 215.400528 -164.274779) (xy 215.346557 -164.240528)
			(xy 215.297304 -164.199783) (xy 215.253547 -164.153186) (xy 215.215974 -164.101471) (xy 215.18518 -164.045456)
			(xy 215.161648 -163.986023) (xy 215.145751 -163.924109) (xy 215.13774 -163.860691) (xy 207.655045 -163.860691)
			(xy 207.631034 -163.904367) (xy 207.593461 -163.956082) (xy 207.549704 -164.002679) (xy 207.500451 -164.043424)
			(xy 207.44648 -164.077675) (xy 207.388641 -164.104892) (xy 207.327848 -164.124645) (xy 207.265058 -164.136623)
			(xy 207.201262 -164.140637) (xy 207.137466 -164.136623) (xy 207.074676 -164.124645) (xy 207.013883 -164.104892)
			(xy 206.956044 -164.077675) (xy 206.902073 -164.043424) (xy 206.85282 -164.002679) (xy 206.809063 -163.956082)
			(xy 206.77149 -163.904367) (xy 206.740696 -163.848352) (xy 206.717164 -163.788919) (xy 206.701267 -163.727005)
			(xy 206.693256 -163.663587) (xy 186.123554 -163.663587) (xy 186.115575 -163.726751) (xy 186.099678 -163.788665)
			(xy 186.076146 -163.848098) (xy 186.045352 -163.904113) (xy 186.007779 -163.955828) (xy 185.964022 -164.002425)
			(xy 185.914769 -164.04317) (xy 185.860798 -164.077421) (xy 185.802959 -164.104638) (xy 185.742166 -164.124391)
			(xy 185.679376 -164.136369) (xy 185.61558 -164.140383) (xy 185.551784 -164.136369) (xy 185.488994 -164.124391)
			(xy 185.428201 -164.104638) (xy 185.370362 -164.077421) (xy 185.316391 -164.04317) (xy 185.267138 -164.002425)
			(xy 185.223381 -163.955828) (xy 185.185808 -163.904113) (xy 185.155014 -163.848098) (xy 185.131482 -163.788665)
			(xy 185.115585 -163.726751) (xy 185.107574 -163.663333) (xy 179.548368 -163.663333) (xy 179.570698 -163.703952)
			(xy 179.59423 -163.763385) (xy 179.610127 -163.825299) (xy 179.618138 -163.888717) (xy 179.61864 -163.920678)
			(xy 179.618138 -163.952639) (xy 179.610127 -164.016057) (xy 179.59423 -164.077971) (xy 179.570698 -164.137404)
			(xy 179.539904 -164.193419) (xy 179.502331 -164.245134) (xy 179.458574 -164.291731) (xy 179.409321 -164.332476)
			(xy 179.35535 -164.366727) (xy 179.297511 -164.393944) (xy 179.236718 -164.413697) (xy 179.173928 -164.425675)
			(xy 179.110132 -164.429689) (xy 179.046336 -164.425675) (xy 178.983546 -164.413697) (xy 178.922753 -164.393944)
			(xy 178.864914 -164.366727) (xy 178.810943 -164.332476) (xy 178.76169 -164.291731) (xy 178.717933 -164.245134)
			(xy 178.68036 -164.193419) (xy 178.649566 -164.137404) (xy 178.626034 -164.077971) (xy 178.610137 -164.016057)
			(xy 178.602126 -163.952639) (xy 176.664577 -163.952639) (xy 178.675284 -165.963346) (xy 178.682695 -165.970028)
			(xy 178.70113 -165.977609) (xy 178.711098 -165.978078) (xy 178.727608 -165.974268) (xy 178.736752 -165.97122)
			(xy 178.762409 -165.959438) (xy 178.815769 -165.940982) (xy 178.870846 -165.928558) (xy 178.926961 -165.922318)
			(xy 178.955192 -165.921944) (xy 178.965606 -165.921944) (xy 178.995265 -165.922974) (xy 179.054055 -165.931093)
			(xy 179.111501 -165.945996) (xy 179.166823 -165.967481) (xy 179.219271 -165.995255) (xy 179.268131 -166.028941)
			(xy 179.290726 -166.048182) (xy 179.298346 -166.054786) (xy 179.309268 -166.058596) (xy 179.322984 -166.060882)
			(xy 179.358798 -166.059612) (xy 179.395374 -166.058342) (xy 179.400223 -166.058064) (xy 179.409687 -166.055892)
			(xy 179.41417 -166.054024) (xy 179.422552 -166.050468) (xy 179.429664 -166.04361) (xy 179.453376 -166.020559)
			(xy 179.505737 -165.980166) (xy 179.534058 -165.963092) (xy 179.543202 -165.957758) (xy 179.550822 -165.947598)
			(xy 179.552819 -165.944577) (xy 179.556001 -165.938071) (xy 179.557172 -165.934644) (xy 179.57165 -165.875716)
			(xy 179.57546 -165.860476) (xy 179.576467 -165.856107) (xy 179.577108 -165.847164) (xy 179.57673 -165.842696)
			(xy 179.576222 -165.838886) (xy 179.575714 -165.835838) (xy 179.574952 -165.831012) (xy 179.569364 -165.821868)
			(xy 179.551332 -165.791602) (xy 179.522869 -165.727157) (xy 179.503572 -165.659401) (xy 179.493809 -165.589631)
			(xy 179.493164 -165.554406) (xy 179.493164 -165.553898) (xy 179.493374 -165.533936) (xy 179.496552 -165.494138)
			(xy 179.499514 -165.474396) (xy 179.49992 -165.466795) (xy 179.496698 -165.451926) (xy 179.493164 -165.445186)
			(xy 179.493164 -165.444932) (xy 179.478073 -165.416639) (xy 179.454344 -165.357068) (xy 179.438298 -165.294985)
			(xy 179.430191 -165.231375) (xy 179.429664 -165.199314) (xy 179.429664 -165.198806) (xy 179.430166 -165.166845)
			(xy 179.438177 -165.103427) (xy 179.454074 -165.041513) (xy 179.477606 -164.98208) (xy 179.5084 -164.926065)
			(xy 179.545973 -164.87435) (xy 179.58973 -164.827753) (xy 179.638983 -164.787008) (xy 179.692954 -164.752757)
			(xy 179.750793 -164.72554) (xy 179.811586 -164.705787) (xy 179.874376 -164.693809) (xy 179.938172 -164.689796)
			(xy 180.001968 -164.693809) (xy 180.064758 -164.705787) (xy 180.125551 -164.72554) (xy 180.18339 -164.752757)
			(xy 180.197038 -164.761418) (xy 184.26379 -164.761418) (xy 184.267861 -164.705796) (xy 184.279987 -164.651359)
			(xy 184.29991 -164.599268) (xy 184.327206 -164.550633) (xy 184.361292 -164.50649) (xy 184.401441 -164.467781)
			(xy 184.446799 -164.43533) (xy 184.496399 -164.409829) (xy 184.549183 -164.391822) (xy 184.604026 -164.381692)
			(xy 184.65976 -164.379655) (xy 184.715197 -164.385755) (xy 184.769154 -164.399861) (xy 184.820483 -164.421673)
			(xy 184.868089 -164.450727) (xy 184.910957 -164.486402) (xy 184.948174 -164.527939) (xy 184.978947 -164.574452)
			(xy 185.002619 -164.624949) (xy 185.018687 -164.678356) (xy 185.026807 -164.733532) (xy 185.027316 -164.761418)
			(xy 185.026982 -164.7797) (xy 190.009795 -164.7797) (xy 190.013809 -164.715905) (xy 190.025787 -164.653116)
			(xy 190.045539 -164.592324) (xy 190.072755 -164.534486) (xy 190.107006 -164.480516) (xy 190.14775 -164.431264)
			(xy 190.194347 -164.387507) (xy 190.24606 -164.349935) (xy 190.302074 -164.31914) (xy 190.361506 -164.295609)
			(xy 190.423419 -164.279712) (xy 190.486836 -164.2717) (xy 190.518796 -164.271198) (xy 190.552373 -164.271767)
			(xy 190.61894 -164.280616) (xy 190.683765 -164.298147) (xy 190.745719 -164.324055) (xy 190.803726 -164.35789)
			(xy 190.856777 -164.399063) (xy 190.880746 -164.422582) (xy 190.887858 -164.429694) (xy 190.9064 -164.437568)
			(xy 190.99911 -164.437822) (xy 191.017652 -164.429948) (xy 191.024764 -164.422836) (xy 191.048693 -164.399659)
			(xy 191.101518 -164.359071) (xy 191.159193 -164.325733) (xy 191.22073 -164.300217) (xy 191.285073 -164.28296)
			(xy 191.351119 -164.274259) (xy 191.384428 -164.273738) (xy 191.384682 -164.273738) (xy 191.416648 -164.274126)
			(xy 191.480076 -164.282137) (xy 191.542 -164.298034) (xy 191.601443 -164.321567) (xy 191.657468 -164.352365)
			(xy 191.70919 -164.389943) (xy 191.755796 -164.433706) (xy 191.796548 -164.482966) (xy 191.830805 -164.536945)
			(xy 191.858027 -164.594792) (xy 191.877783 -164.655595) (xy 191.889763 -164.718394) (xy 191.893778 -164.7822)
			(xy 191.889763 -164.846006) (xy 191.883086 -164.881009) (xy 207.238594 -164.881009) (xy 207.238594 -164.817087)
			(xy 207.246605 -164.753669) (xy 207.262502 -164.691755) (xy 207.286034 -164.632322) (xy 207.316828 -164.576307)
			(xy 207.354401 -164.524592) (xy 207.398158 -164.477995) (xy 207.447411 -164.43725) (xy 207.501382 -164.402999)
			(xy 207.559221 -164.375782) (xy 207.620014 -164.356029) (xy 207.682804 -164.344051) (xy 207.7466 -164.340038)
			(xy 207.810396 -164.344051) (xy 207.873186 -164.356029) (xy 207.933979 -164.375782) (xy 207.991818 -164.402999)
			(xy 208.045789 -164.43725) (xy 208.095042 -164.477995) (xy 208.097587 -164.480705) (xy 216.53093 -164.480705)
			(xy 216.53093 -164.416783) (xy 216.538941 -164.353365) (xy 216.554838 -164.291451) (xy 216.57837 -164.232018)
			(xy 216.609164 -164.176003) (xy 216.646737 -164.124288) (xy 216.690494 -164.077691) (xy 216.739747 -164.036946)
			(xy 216.793718 -164.002695) (xy 216.851557 -163.975478) (xy 216.91235 -163.955725) (xy 216.97514 -163.943747)
			(xy 217.038936 -163.939734) (xy 217.102732 -163.943747) (xy 217.165522 -163.955725) (xy 217.226315 -163.975478)
			(xy 217.284154 -164.002695) (xy 217.338125 -164.036946) (xy 217.387378 -164.077691) (xy 217.431135 -164.124288)
			(xy 217.468708 -164.176003) (xy 217.499502 -164.232018) (xy 217.523034 -164.291451) (xy 217.538931 -164.353365)
			(xy 217.546942 -164.416783) (xy 217.547444 -164.448744) (xy 217.546942 -164.480705) (xy 217.538931 -164.544123)
			(xy 217.523034 -164.606037) (xy 217.499502 -164.66547) (xy 217.468708 -164.721485) (xy 217.431135 -164.7732)
			(xy 217.387378 -164.819797) (xy 217.338125 -164.860542) (xy 217.284154 -164.894793) (xy 217.226315 -164.92201)
			(xy 217.165522 -164.941763) (xy 217.102732 -164.953741) (xy 217.038936 -164.957755) (xy 216.97514 -164.953741)
			(xy 216.91235 -164.941763) (xy 216.851557 -164.92201) (xy 216.793718 -164.894793) (xy 216.739747 -164.860542)
			(xy 216.690494 -164.819797) (xy 216.646737 -164.7732) (xy 216.609164 -164.721485) (xy 216.57837 -164.66547)
			(xy 216.554838 -164.606037) (xy 216.538941 -164.544123) (xy 216.53093 -164.480705) (xy 208.097587 -164.480705)
			(xy 208.138799 -164.524592) (xy 208.176372 -164.576307) (xy 208.207166 -164.632322) (xy 208.230698 -164.691755)
			(xy 208.246595 -164.753669) (xy 208.254606 -164.817087) (xy 208.255108 -164.849048) (xy 208.254606 -164.881009)
			(xy 208.246595 -164.944427) (xy 208.230698 -165.006341) (xy 208.207166 -165.065774) (xy 208.176372 -165.121789)
			(xy 208.138799 -165.173504) (xy 208.095042 -165.220101) (xy 208.045789 -165.260846) (xy 207.991818 -165.295097)
			(xy 207.933979 -165.322314) (xy 207.873186 -165.342067) (xy 207.810396 -165.354045) (xy 207.7466 -165.358059)
			(xy 207.682804 -165.354045) (xy 207.620014 -165.342067) (xy 207.559221 -165.322314) (xy 207.501382 -165.295097)
			(xy 207.447411 -165.260846) (xy 207.398158 -165.220101) (xy 207.354401 -165.173504) (xy 207.316828 -165.121789)
			(xy 207.286034 -165.065774) (xy 207.262502 -165.006341) (xy 207.246605 -164.944427) (xy 207.238594 -164.881009)
			(xy 191.883086 -164.881009) (xy 191.877783 -164.908805) (xy 191.858027 -164.969608) (xy 191.830805 -165.027455)
			(xy 191.796548 -165.081434) (xy 191.755796 -165.130694) (xy 191.70919 -165.174457) (xy 191.657468 -165.212035)
			(xy 191.601443 -165.242833) (xy 191.542 -165.266366) (xy 191.480076 -165.282263) (xy 191.416648 -165.290274)
			(xy 191.384682 -165.290754) (xy 191.351104 -165.290213) (xy 191.284535 -165.281361) (xy 191.219709 -165.263825)
			(xy 191.157754 -165.237912) (xy 191.099748 -165.204071) (xy 191.0467 -165.162892) (xy 191.022732 -165.13937)
			(xy 191.01562 -165.132258) (xy 190.997078 -165.124384) (xy 190.904368 -165.12413) (xy 190.885826 -165.132004)
			(xy 190.878714 -165.139116) (xy 190.854803 -165.162313) (xy 190.801974 -165.202897) (xy 190.744294 -165.236231)
			(xy 190.682754 -165.261744) (xy 190.618408 -165.278997) (xy 190.552359 -165.287694) (xy 190.51905 -165.288214)
			(xy 190.518796 -165.288214) (xy 190.486836 -165.2877) (xy 190.423419 -165.279688) (xy 190.361506 -165.263791)
			(xy 190.302074 -165.24026) (xy 190.24606 -165.209465) (xy 190.194347 -165.171893) (xy 190.14775 -165.128136)
			(xy 190.107006 -165.078884) (xy 190.072755 -165.024914) (xy 190.045539 -164.967076) (xy 190.025787 -164.906284)
			(xy 190.013809 -164.843495) (xy 190.009795 -164.7797) (xy 185.026982 -164.7797) (xy 185.026807 -164.789304)
			(xy 185.018687 -164.84448) (xy 185.002619 -164.897887) (xy 184.978947 -164.948384) (xy 184.948174 -164.994897)
			(xy 184.910957 -165.036434) (xy 184.868089 -165.072109) (xy 184.820483 -165.101163) (xy 184.769154 -165.122975)
			(xy 184.715197 -165.137081) (xy 184.65976 -165.143181) (xy 184.604026 -165.141144) (xy 184.549183 -165.131014)
			(xy 184.496399 -165.113007) (xy 184.446799 -165.087506) (xy 184.401441 -165.055055) (xy 184.361292 -165.016346)
			(xy 184.327206 -164.972203) (xy 184.29991 -164.923568) (xy 184.279987 -164.871477) (xy 184.267861 -164.81704)
			(xy 184.26379 -164.761418) (xy 180.197038 -164.761418) (xy 180.237361 -164.787008) (xy 180.286614 -164.827753)
			(xy 180.330371 -164.87435) (xy 180.367944 -164.926065) (xy 180.398738 -164.98208) (xy 180.42227 -165.041513)
			(xy 180.438167 -165.103427) (xy 180.446178 -165.166845) (xy 180.44668 -165.198806) (xy 180.44668 -165.199568)
			(xy 180.446455 -165.218567) (xy 180.44353 -165.256452) (xy 180.440838 -165.27526) (xy 180.440838 -165.289738)
			(xy 180.441552 -165.294395) (xy 180.444493 -165.303345) (xy 180.44668 -165.307518) (xy 180.461789 -165.335838)
			(xy 180.481873 -165.386258) (xy 215.177622 -165.386258) (xy 215.181693 -165.330636) (xy 215.193819 -165.276199)
			(xy 215.213742 -165.224108) (xy 215.241038 -165.175473) (xy 215.275124 -165.13133) (xy 215.315273 -165.092621)
			(xy 215.360631 -165.06017) (xy 215.410231 -165.034669) (xy 215.463015 -165.016662) (xy 215.517858 -165.006532)
			(xy 215.573592 -165.004495) (xy 215.629029 -165.010595) (xy 215.682986 -165.024701) (xy 215.734315 -165.046513)
			(xy 215.781921 -165.075567) (xy 215.824789 -165.111242) (xy 215.862006 -165.152779) (xy 215.892779 -165.199292)
			(xy 215.916451 -165.249789) (xy 215.932519 -165.303196) (xy 215.934943 -165.319667) (xy 219.640652 -165.319667)
			(xy 219.640652 -165.255745) (xy 219.648663 -165.192327) (xy 219.66456 -165.130413) (xy 219.688092 -165.07098)
			(xy 219.718886 -165.014965) (xy 219.756459 -164.96325) (xy 219.800216 -164.916653) (xy 219.849469 -164.875908)
			(xy 219.90344 -164.841657) (xy 219.961279 -164.81444) (xy 220.022072 -164.794687) (xy 220.084862 -164.782709)
			(xy 220.148658 -164.778696) (xy 220.212454 -164.782709) (xy 220.275244 -164.794687) (xy 220.336037 -164.81444)
			(xy 220.393876 -164.841657) (xy 220.447847 -164.875908) (xy 220.4971 -164.916653) (xy 220.540857 -164.96325)
			(xy 220.57843 -165.014965) (xy 220.609224 -165.07098) (xy 220.632756 -165.130413) (xy 220.648653 -165.192327)
			(xy 220.656664 -165.255745) (xy 220.657166 -165.287706) (xy 220.656664 -165.319667) (xy 220.648653 -165.383085)
			(xy 220.632756 -165.444999) (xy 220.609224 -165.504432) (xy 220.595575 -165.52926) (xy 223.959166 -165.52926)
			(xy 223.959668 -165.497299) (xy 223.967679 -165.433881) (xy 223.983576 -165.371967) (xy 224.007108 -165.312534)
			(xy 224.037902 -165.256519) (xy 224.075475 -165.204804) (xy 224.119232 -165.158207) (xy 224.168485 -165.117462)
			(xy 224.222456 -165.083211) (xy 224.280295 -165.055994) (xy 224.341088 -165.036241) (xy 224.403878 -165.024263)
			(xy 224.467674 -165.02025) (xy 224.53147 -165.024263) (xy 224.59426 -165.036241) (xy 224.655053 -165.055994)
			(xy 224.712892 -165.083211) (xy 224.766863 -165.117462) (xy 224.816116 -165.158207) (xy 224.859873 -165.204804)
			(xy 224.897446 -165.256519) (xy 224.92824 -165.312534) (xy 224.951772 -165.371967) (xy 224.967669 -165.433881)
			(xy 224.97568 -165.497299) (xy 224.976182 -165.52926) (xy 224.976182 -165.533832) (xy 225.011996 -165.570408)
			(xy 225.018988 -165.576974) (xy 225.036477 -165.584811) (xy 225.046032 -165.585648) (xy 225.078292 -165.58766)
			(xy 225.141963 -165.598795) (xy 225.20371 -165.617909) (xy 225.262537 -165.644692) (xy 225.317497 -165.678713)
			(xy 225.367702 -165.719424) (xy 225.412345 -165.766168) (xy 225.450705 -165.818192) (xy 225.482163 -165.874657)
			(xy 225.506214 -165.934654) (xy 225.522469 -165.997214) (xy 225.530665 -166.061329) (xy 225.531172 -166.093648)
			(xy 225.53067 -166.125609) (xy 225.522659 -166.189027) (xy 225.506762 -166.250941) (xy 225.48323 -166.310374)
			(xy 225.461501 -166.3499) (xy 229.684623 -166.3499) (xy 229.688637 -166.286109) (xy 229.700614 -166.223323)
			(xy 229.720365 -166.162534) (xy 229.74758 -166.1047) (xy 229.781828 -166.050732) (xy 229.822571 -166.001483)
			(xy 229.869164 -165.957728) (xy 229.920875 -165.920158) (xy 229.976886 -165.889366) (xy 230.036315 -165.865836)
			(xy 230.098224 -165.84994) (xy 230.161637 -165.841928) (xy 230.193596 -165.841426) (xy 230.223082 -165.841828)
			(xy 230.281658 -165.848641) (xy 230.339052 -165.862186) (xy 230.394494 -165.882283) (xy 230.447237 -165.90866)
			(xy 230.496573 -165.940964) (xy 230.519478 -165.959536) (xy 230.527934 -165.965858) (xy 230.548177 -165.971761)
			(xy 230.569092 -165.969076) (xy 230.578406 -165.964108) (xy 230.608247 -165.946757) (xy 230.671636 -165.919426)
			(xy 230.738136 -165.90091) (xy 230.806528 -165.891548) (xy 230.841042 -165.890956) (xy 230.872999 -165.891532)
			(xy 230.936409 -165.899548) (xy 230.998314 -165.915447) (xy 231.057738 -165.938979) (xy 231.113745 -165.969773)
			(xy 231.165451 -166.007343) (xy 231.21204 -166.051098) (xy 231.252779 -166.100346) (xy 231.287024 -166.154311)
			(xy 231.314236 -166.212143) (xy 231.333986 -166.27293) (xy 231.345962 -166.335712) (xy 231.349975 -166.3995)
			(xy 231.345962 -166.463288) (xy 231.333986 -166.52607) (xy 231.314236 -166.586857) (xy 231.287024 -166.644689)
			(xy 231.252779 -166.698654) (xy 231.21204 -166.747902) (xy 231.165451 -166.791657) (xy 231.113745 -166.829227)
			(xy 231.057738 -166.860021) (xy 230.998314 -166.883553) (xy 230.936409 -166.899452) (xy 230.872999 -166.907468)
			(xy 230.841042 -166.907972) (xy 230.811557 -166.907548) (xy 230.752981 -166.90074) (xy 230.695587 -166.887199)
			(xy 230.640146 -166.867106) (xy 230.587403 -166.840733) (xy 230.538066 -166.808432) (xy 230.51516 -166.789862)
			(xy 230.506738 -166.783488) (xy 230.486474 -166.777601) (xy 230.465547 -166.780309) (xy 230.456232 -166.78529)
			(xy 230.426382 -166.802626) (xy 230.362997 -166.829961) (xy 230.2965 -166.848481) (xy 230.22811 -166.857847)
			(xy 230.193596 -166.858442) (xy 230.161637 -166.857872) (xy 230.098224 -166.84986) (xy 230.036315 -166.833964)
			(xy 229.976886 -166.810434) (xy 229.920875 -166.779642) (xy 229.869164 -166.742072) (xy 229.822571 -166.698317)
			(xy 229.781828 -166.649068) (xy 229.74758 -166.5951) (xy 229.720365 -166.537266) (xy 229.700614 -166.476477)
			(xy 229.688637 -166.413691) (xy 229.684623 -166.3499) (xy 225.461501 -166.3499) (xy 225.452436 -166.366389)
			(xy 225.414863 -166.418104) (xy 225.371106 -166.464701) (xy 225.321853 -166.505446) (xy 225.267882 -166.539697)
			(xy 225.210043 -166.566914) (xy 225.14925 -166.586667) (xy 225.08646 -166.598645) (xy 225.022664 -166.602659)
			(xy 224.958868 -166.598645) (xy 224.896078 -166.586667) (xy 224.835285 -166.566914) (xy 224.777446 -166.539697)
			(xy 224.723475 -166.505446) (xy 224.674222 -166.464701) (xy 224.630465 -166.418104) (xy 224.592892 -166.366389)
			(xy 224.562098 -166.310374) (xy 224.538566 -166.250941) (xy 224.522669 -166.189027) (xy 224.514658 -166.125609)
			(xy 224.514156 -166.093648) (xy 224.514156 -166.089076) (xy 224.478342 -166.0525) (xy 224.471369 -166.04591)
			(xy 224.453866 -166.038086) (xy 224.444306 -166.03726) (xy 224.412049 -166.035206) (xy 224.348379 -166.024076)
			(xy 224.286634 -166.004967) (xy 224.227807 -165.978189) (xy 224.172847 -165.944172) (xy 224.122641 -165.903465)
			(xy 224.077998 -165.856724) (xy 224.039638 -165.804704) (xy 224.008178 -165.748241) (xy 223.984127 -165.688248)
			(xy 223.967871 -165.625691) (xy 223.959673 -165.561577) (xy 223.959166 -165.52926) (xy 220.595575 -165.52926)
			(xy 220.57843 -165.560447) (xy 220.540857 -165.612162) (xy 220.4971 -165.658759) (xy 220.447847 -165.699504)
			(xy 220.393876 -165.733755) (xy 220.336037 -165.760972) (xy 220.275244 -165.780725) (xy 220.212454 -165.792703)
			(xy 220.148658 -165.796717) (xy 220.084862 -165.792703) (xy 220.022072 -165.780725) (xy 219.961279 -165.760972)
			(xy 219.90344 -165.733755) (xy 219.849469 -165.699504) (xy 219.800216 -165.658759) (xy 219.756459 -165.612162)
			(xy 219.718886 -165.560447) (xy 219.688092 -165.504432) (xy 219.66456 -165.444999) (xy 219.648663 -165.383085)
			(xy 219.640652 -165.319667) (xy 215.934943 -165.319667) (xy 215.940639 -165.358372) (xy 215.941148 -165.386258)
			(xy 215.940639 -165.414144) (xy 215.932519 -165.46932) (xy 215.916451 -165.522727) (xy 215.892779 -165.573224)
			(xy 215.862006 -165.619737) (xy 215.824789 -165.661274) (xy 215.781921 -165.696949) (xy 215.734315 -165.726003)
			(xy 215.682986 -165.747815) (xy 215.629029 -165.761921) (xy 215.573592 -165.768021) (xy 215.517858 -165.765984)
			(xy 215.463015 -165.755854) (xy 215.410231 -165.737847) (xy 215.360631 -165.712346) (xy 215.315273 -165.679895)
			(xy 215.275124 -165.641186) (xy 215.241038 -165.597043) (xy 215.213742 -165.548408) (xy 215.193819 -165.496317)
			(xy 215.181693 -165.44188) (xy 215.177622 -165.386258) (xy 180.481873 -165.386258) (xy 180.485543 -165.39547)
			(xy 180.501597 -165.457619) (xy 180.509695 -165.521296) (xy 180.51018 -165.55339) (xy 180.51018 -165.553898)
			(xy 180.509642 -165.587102) (xy 180.500999 -165.652945) (xy 180.483859 -165.717102) (xy 180.458515 -165.778483)
			(xy 180.425397 -165.836044) (xy 180.385069 -165.888804) (xy 180.338217 -165.935866) (xy 180.285637 -165.97643)
			(xy 180.257196 -165.993572) (xy 180.248052 -165.998906) (xy 180.240432 -166.009066) (xy 180.238431 -166.012085)
			(xy 180.235241 -166.018588) (xy 180.234082 -166.02202) (xy 180.219604 -166.080948) (xy 180.215794 -166.096188)
			(xy 180.214785 -166.100557) (xy 180.214138 -166.109501) (xy 180.214524 -166.113968) (xy 180.215794 -166.122604)
			(xy 180.216302 -166.125652) (xy 180.22189 -166.134796) (xy 180.239926 -166.165061) (xy 180.268396 -166.229504)
			(xy 180.287699 -166.297261) (xy 180.297469 -166.367032) (xy 180.297796 -166.385553) (xy 180.547971 -166.385553)
			(xy 180.547971 -166.331047) (xy 180.555729 -166.277096) (xy 180.571085 -166.224798) (xy 180.593729 -166.175219)
			(xy 180.623198 -166.129366) (xy 180.658893 -166.088175) (xy 180.700087 -166.052482) (xy 180.745942 -166.023016)
			(xy 180.795523 -166.000376) (xy 180.847822 -165.985023) (xy 180.901773 -165.97727) (xy 180.929026 -165.976808)
			(xy 180.957345 -165.977322) (xy 181.013359 -165.985694) (xy 181.067518 -166.002263) (xy 181.118628 -166.026666)
			(xy 181.142386 -166.042086) (xy 181.14264 -166.04234) (xy 181.151106 -166.047428) (xy 181.17045 -166.051338)
			(xy 181.180232 -166.04996) (xy 181.261004 -166.034466) (xy 181.277768 -166.02329) (xy 181.283356 -166.014908)
			(xy 181.301136 -165.98952) (xy 181.341916 -165.942841) (xy 181.388067 -165.901464) (xy 181.438904 -165.866003)
			(xy 181.493674 -165.836983) (xy 181.551565 -165.814833) (xy 181.611718 -165.799884) (xy 181.673242 -165.792355)
			(xy 181.704234 -165.791896) (xy 181.736194 -165.792392) (xy 181.799609 -165.800407) (xy 181.86152 -165.816307)
			(xy 181.92095 -165.83984) (xy 181.976962 -165.870637) (xy 182.028673 -165.90821) (xy 182.075267 -165.951968)
			(xy 182.116009 -166.00122) (xy 182.150258 -166.05519) (xy 182.177473 -166.113027) (xy 182.197224 -166.173819)
			(xy 182.209201 -166.236606) (xy 182.213215 -166.3004) (xy 182.211411 -166.329063) (xy 183.848242 -166.329063)
			(xy 183.848242 -166.265141) (xy 183.856253 -166.201723) (xy 183.87215 -166.139809) (xy 183.895682 -166.080376)
			(xy 183.926476 -166.024361) (xy 183.964049 -165.972646) (xy 184.007806 -165.926049) (xy 184.057059 -165.885304)
			(xy 184.11103 -165.851053) (xy 184.168869 -165.823836) (xy 184.229662 -165.804083) (xy 184.292452 -165.792105)
			(xy 184.356248 -165.788092) (xy 184.420044 -165.792105) (xy 184.482834 -165.804083) (xy 184.543627 -165.823836)
			(xy 184.601466 -165.851053) (xy 184.655437 -165.885304) (xy 184.70469 -165.926049) (xy 184.748447 -165.972646)
			(xy 184.78602 -166.024361) (xy 184.816814 -166.080376) (xy 184.840346 -166.139809) (xy 184.856243 -166.201723)
			(xy 184.864254 -166.265141) (xy 184.864756 -166.297102) (xy 184.864254 -166.329063) (xy 184.856243 -166.392481)
			(xy 184.840346 -166.454395) (xy 184.832029 -166.4754) (xy 190.006678 -166.4754) (xy 190.010693 -166.411599)
			(xy 190.022672 -166.348804) (xy 190.042428 -166.288006) (xy 190.069648 -166.230164) (xy 190.103904 -166.176189)
			(xy 190.144655 -166.126934) (xy 190.191258 -166.083175) (xy 190.242979 -166.045602) (xy 190.299 -166.014809)
			(xy 190.35844 -165.99128) (xy 190.42036 -165.975387) (xy 190.483784 -165.96738) (xy 190.515748 -165.966902)
			(xy 190.548547 -165.967421) (xy 190.613601 -165.975861) (xy 190.67703 -165.992596) (xy 190.73778 -166.017347)
			(xy 190.794844 -166.049704) (xy 190.847273 -166.089129) (xy 190.871094 -166.111682) (xy 190.877698 -166.118286)
			(xy 190.895224 -166.125652) (xy 190.973456 -166.128192) (xy 190.982955 -166.128067) (xy 191.000829 -166.121671)
			(xy 191.008254 -166.115746) (xy 191.031396 -166.096373) (xy 191.081448 -166.062647) (xy 191.135139 -166.035079)
			(xy 191.191714 -166.014056) (xy 191.250378 -165.999875) (xy 191.310309 -165.992733) (xy 191.340486 -165.992302)
			(xy 191.37245 -165.992762) (xy 191.435873 -166.000773) (xy 191.497792 -166.016669) (xy 191.55723 -166.040201)
			(xy 191.613251 -166.070997) (xy 191.664969 -166.108572) (xy 191.711571 -166.152332) (xy 191.75232 -166.201588)
			(xy 191.786574 -166.255563) (xy 191.813794 -166.313406) (xy 191.833548 -166.374204) (xy 191.845527 -166.436999)
			(xy 191.848964 -166.491623) (xy 191.959224 -166.491623) (xy 191.959224 -166.427701) (xy 191.967235 -166.364283)
			(xy 191.983132 -166.302369) (xy 192.006664 -166.242936) (xy 192.037458 -166.186921) (xy 192.075031 -166.135206)
			(xy 192.118788 -166.088609) (xy 192.168041 -166.047864) (xy 192.222012 -166.013613) (xy 192.279851 -165.986396)
			(xy 192.340644 -165.966643) (xy 192.403434 -165.954665) (xy 192.46723 -165.950652) (xy 192.531026 -165.954665)
			(xy 192.593816 -165.966643) (xy 192.654609 -165.986396) (xy 192.712448 -166.013613) (xy 192.766419 -166.047864)
			(xy 192.815672 -166.088609) (xy 192.859429 -166.135206) (xy 192.897002 -166.186921) (xy 192.927796 -166.242936)
			(xy 192.951328 -166.302369) (xy 192.967225 -166.364283) (xy 192.975236 -166.427701) (xy 192.975738 -166.459662)
			(xy 192.975487 -166.475621) (xy 195.69658 -166.475621) (xy 195.69658 -166.411699) (xy 195.704591 -166.348281)
			(xy 195.720488 -166.286367) (xy 195.74402 -166.226934) (xy 195.774814 -166.170919) (xy 195.812387 -166.119204)
			(xy 195.856144 -166.072607) (xy 195.905397 -166.031862) (xy 195.959368 -165.997611) (xy 196.017207 -165.970394)
			(xy 196.078 -165.950641) (xy 196.14079 -165.938663) (xy 196.204586 -165.93465) (xy 196.268382 -165.938663)
			(xy 196.331172 -165.950641) (xy 196.391965 -165.970394) (xy 196.449804 -165.997611) (xy 196.503775 -166.031862)
			(xy 196.553028 -166.072607) (xy 196.596785 -166.119204) (xy 196.634358 -166.170919) (xy 196.665152 -166.226934)
			(xy 196.688684 -166.286367) (xy 196.704581 -166.348281) (xy 196.712592 -166.411699) (xy 196.713094 -166.44366)
			(xy 196.712592 -166.475621) (xy 196.704581 -166.539039) (xy 196.688684 -166.600953) (xy 196.665152 -166.660386)
			(xy 196.634358 -166.716401) (xy 196.596785 -166.768116) (xy 196.553028 -166.814713) (xy 196.503775 -166.855458)
			(xy 196.449804 -166.889709) (xy 196.391965 -166.916926) (xy 196.331172 -166.936679) (xy 196.268382 -166.948657)
			(xy 196.204586 -166.952671) (xy 196.14079 -166.948657) (xy 196.078 -166.936679) (xy 196.017207 -166.916926)
			(xy 195.959368 -166.889709) (xy 195.905397 -166.855458) (xy 195.856144 -166.814713) (xy 195.812387 -166.768116)
			(xy 195.774814 -166.716401) (xy 195.74402 -166.660386) (xy 195.720488 -166.600953) (xy 195.704591 -166.539039)
			(xy 195.69658 -166.475621) (xy 192.975487 -166.475621) (xy 192.975236 -166.491623) (xy 192.967225 -166.555041)
			(xy 192.951328 -166.616955) (xy 192.927796 -166.676388) (xy 192.897002 -166.732403) (xy 192.859429 -166.784118)
			(xy 192.815672 -166.830715) (xy 192.766419 -166.87146) (xy 192.712448 -166.905711) (xy 192.654609 -166.932928)
			(xy 192.593816 -166.952681) (xy 192.531026 -166.964659) (xy 192.46723 -166.968673) (xy 192.403434 -166.964659)
			(xy 192.340644 -166.952681) (xy 192.279851 -166.932928) (xy 192.222012 -166.905711) (xy 192.168041 -166.87146)
			(xy 192.118788 -166.830715) (xy 192.075031 -166.784118) (xy 192.037458 -166.732403) (xy 192.006664 -166.676388)
			(xy 191.983132 -166.616955) (xy 191.967235 -166.555041) (xy 191.959224 -166.491623) (xy 191.848964 -166.491623)
			(xy 191.849542 -166.5008) (xy 191.845527 -166.564601) (xy 191.833548 -166.627396) (xy 191.813794 -166.688194)
			(xy 191.786574 -166.746037) (xy 191.75232 -166.800012) (xy 191.711571 -166.849268) (xy 191.664969 -166.893028)
			(xy 191.613251 -166.930603) (xy 191.55723 -166.961399) (xy 191.497792 -166.984931) (xy 191.435873 -167.000827)
			(xy 191.37245 -167.008838) (xy 191.340486 -167.009318) (xy 191.307688 -167.008772) (xy 191.242635 -167.000336)
			(xy 191.179207 -166.983607) (xy 191.118457 -166.95886) (xy 191.061393 -166.926509) (xy 191.008962 -166.887089)
			(xy 190.98514 -166.864538) (xy 190.978536 -166.857934) (xy 190.96101 -166.850568) (xy 190.882778 -166.848028)
			(xy 190.87328 -166.848166) (xy 190.855406 -166.854552) (xy 190.84798 -166.860474) (xy 190.824827 -166.879834)
			(xy 190.774777 -166.913561) (xy 190.721089 -166.941131) (xy 190.664516 -166.962155) (xy 190.605853 -166.97634)
			(xy 190.545925 -166.983485) (xy 190.515748 -166.983918) (xy 190.483784 -166.98342) (xy 190.42036 -166.975413)
			(xy 190.35844 -166.95952) (xy 190.299 -166.935991) (xy 190.242979 -166.905198) (xy 190.191258 -166.867625)
			(xy 190.144655 -166.823866) (xy 190.103904 -166.774611) (xy 190.069648 -166.720636) (xy 190.042428 -166.662794)
			(xy 190.022672 -166.601996) (xy 190.010693 -166.539201) (xy 190.006678 -166.4754) (xy 184.832029 -166.4754)
			(xy 184.816814 -166.513828) (xy 184.78602 -166.569843) (xy 184.748447 -166.621558) (xy 184.70469 -166.668155)
			(xy 184.655437 -166.7089) (xy 184.601466 -166.743151) (xy 184.543627 -166.770368) (xy 184.482834 -166.790121)
			(xy 184.420044 -166.802099) (xy 184.356248 -166.806113) (xy 184.292452 -166.802099) (xy 184.229662 -166.790121)
			(xy 184.168869 -166.770368) (xy 184.11103 -166.743151) (xy 184.057059 -166.7089) (xy 184.007806 -166.668155)
			(xy 183.964049 -166.621558) (xy 183.926476 -166.569843) (xy 183.895682 -166.513828) (xy 183.87215 -166.454395)
			(xy 183.856253 -166.392481) (xy 183.848242 -166.329063) (xy 182.211411 -166.329063) (xy 182.209201 -166.364194)
			(xy 182.197224 -166.426981) (xy 182.177473 -166.487773) (xy 182.150258 -166.54561) (xy 182.116009 -166.59958)
			(xy 182.075267 -166.648832) (xy 182.028673 -166.69259) (xy 181.976962 -166.730163) (xy 181.92095 -166.76096)
			(xy 181.86152 -166.784493) (xy 181.799609 -166.800393) (xy 181.736194 -166.808408) (xy 181.704234 -166.808912)
			(xy 181.674248 -166.808451) (xy 181.614693 -166.801401) (xy 181.556381 -166.787393) (xy 181.500121 -166.766624)
			(xy 181.446695 -166.739381) (xy 181.396844 -166.706042) (xy 181.351262 -166.667071) (xy 181.3306 -166.645336)
			(xy 181.330346 -166.645082) (xy 181.323206 -166.638191) (xy 181.305178 -166.629951) (xy 181.295294 -166.62908)
			(xy 181.213506 -166.625524) (xy 181.194456 -166.632382) (xy 181.18709 -166.63924) (xy 181.16586 -166.658049)
			(xy 181.118876 -166.689821) (xy 181.067706 -166.714284) (xy 181.013477 -166.7309) (xy 180.957385 -166.739303)
			(xy 180.929026 -166.739824) (xy 180.901773 -166.73933) (xy 180.847822 -166.731577) (xy 180.795523 -166.716224)
			(xy 180.745942 -166.693584) (xy 180.700087 -166.664118) (xy 180.658893 -166.628425) (xy 180.623198 -166.587234)
			(xy 180.593729 -166.541381) (xy 180.571085 -166.491802) (xy 180.555729 -166.439504) (xy 180.547971 -166.385553)
			(xy 180.297796 -166.385553) (xy 180.29809 -166.402258) (xy 180.29809 -166.402766) (xy 180.297582 -166.425626)
			(xy 180.297582 -166.42969) (xy 180.29809 -166.452296) (xy 180.29809 -166.45255) (xy 180.297622 -166.483935)
			(xy 180.289891 -166.546228) (xy 180.274553 -166.607095) (xy 180.251841 -166.665612) (xy 180.2221 -166.72089)
			(xy 180.185782 -166.772087) (xy 180.14344 -166.818426) (xy 180.095718 -166.859202) (xy 180.04334 -166.893795)
			(xy 179.987103 -166.921679) (xy 179.927862 -166.94243) (xy 179.866518 -166.955734) (xy 179.835302 -166.959026)
			(xy 179.825626 -166.960347) (xy 179.80826 -166.969245) (xy 179.795475 -166.983986) (xy 179.791868 -166.993062)
			(xy 179.791614 -166.993824) (xy 179.779676 -167.028622) (xy 179.776847 -167.039121) (xy 179.779359 -167.060697)
			(xy 179.784502 -167.070278) (xy 179.786788 -167.073834) (xy 179.791868 -167.07993) (xy 180.590738 -167.8788)
			(xy 211.595949 -167.8788) (xy 211.599963 -167.815) (xy 211.611942 -167.752206) (xy 211.631696 -167.691409)
			(xy 211.658913 -167.633567) (xy 211.693166 -167.579592) (xy 211.733914 -167.530336) (xy 211.780513 -167.486575)
			(xy 211.83223 -167.448999) (xy 211.888248 -167.418202) (xy 211.947684 -167.394668) (xy 212.009601 -167.378768)
			(xy 212.073023 -167.370755) (xy 212.104986 -167.370252) (xy 212.12785 -167.370553) (xy 212.173385 -167.374747)
			(xy 212.195918 -167.378634) (xy 212.206526 -167.380033) (xy 212.227289 -167.374943) (xy 212.244203 -167.36187)
			(xy 212.249766 -167.352726) (xy 212.264628 -167.326198) (xy 212.299697 -167.276523) (xy 212.340437 -167.231382)
			(xy 212.386268 -167.191419) (xy 212.436536 -167.157204) (xy 212.490524 -167.129226) (xy 212.547462 -167.107883)
			(xy 212.606538 -167.093479) (xy 212.666911 -167.086221) (xy 212.697314 -167.085772) (xy 212.729273 -167.086315)
			(xy 212.792687 -167.094327) (xy 212.854597 -167.110225) (xy 212.914027 -167.133756) (xy 212.970038 -167.16455)
			(xy 213.021749 -167.202121) (xy 213.068343 -167.245877) (xy 213.109085 -167.295127) (xy 213.143334 -167.349096)
			(xy 213.170549 -167.406931) (xy 213.1903 -167.467721) (xy 213.202277 -167.530508) (xy 213.206291 -167.5943)
			(xy 213.202277 -167.658092) (xy 213.1903 -167.720879) (xy 213.170549 -167.781669) (xy 213.143334 -167.839504)
			(xy 213.109085 -167.893473) (xy 213.068343 -167.942723) (xy 213.021749 -167.986479) (xy 212.970038 -168.02405)
			(xy 212.914027 -168.054844) (xy 212.854597 -168.078375) (xy 212.792687 -168.094273) (xy 212.729273 -168.102285)
			(xy 212.697314 -168.102788) (xy 212.67445 -168.102486) (xy 212.628915 -168.098293) (xy 212.606382 -168.094406)
			(xy 212.595773 -168.093038) (xy 212.575017 -168.098121) (xy 212.558103 -168.111179) (xy 212.552534 -168.120314)
			(xy 212.537689 -168.146851) (xy 212.502616 -168.196525) (xy 212.461873 -168.241665) (xy 212.416039 -168.281626)
			(xy 212.36577 -168.315839) (xy 212.31178 -168.343816) (xy 212.25484 -168.365158) (xy 212.195763 -168.379561)
			(xy 212.13539 -168.386819) (xy 212.104986 -168.387268) (xy 212.073023 -168.386845) (xy 212.009601 -168.378832)
			(xy 211.947684 -168.362932) (xy 211.888248 -168.339398) (xy 211.83223 -168.308601) (xy 211.780513 -168.271025)
			(xy 211.733914 -168.227264) (xy 211.693166 -168.178008) (xy 211.658913 -168.124033) (xy 211.631696 -168.066191)
			(xy 211.611942 -168.005394) (xy 211.599963 -167.9426) (xy 211.595949 -167.8788) (xy 180.590738 -167.8788)
			(xy 181.837076 -169.125138) (xy 181.846276 -169.133367) (xy 181.869773 -169.140796) (xy 181.882034 -169.139362)
			(xy 181.888671 -169.137897) (xy 181.9009 -169.131977) (xy 181.906164 -169.127678) (xy 182.045356 -168.98874)
			(xy 182.069255 -168.965573) (xy 182.122059 -168.925048) (xy 182.179702 -168.891766) (xy 182.241197 -168.866294)
			(xy 182.305492 -168.849069) (xy 182.371485 -168.840387) (xy 182.404766 -168.839896) (xy 183.425846 -168.839896)
			(xy 183.457458 -168.840696) (xy 183.520123 -168.849171) (xy 183.581255 -168.865351) (xy 183.639908 -168.888985)
			(xy 183.695179 -168.91971) (xy 183.746214 -168.95705) (xy 183.792225 -169.000429) (xy 183.832502 -169.049179)
			(xy 183.866425 -169.102547) (xy 183.893468 -169.159709) (xy 183.913216 -169.219782) (xy 183.925362 -169.281841)
			(xy 183.928004 -169.313352) (xy 183.928004 -169.313606) (xy 183.929005 -169.32323) (xy 183.937244 -169.340719)
			(xy 183.944006 -169.347642) (xy 183.944768 -169.348404) (xy 183.94867 -169.351694) (xy 183.957501 -169.356809)
			(xy 183.962294 -169.358564) (xy 183.966302 -169.359846) (xy 183.974598 -169.361246) (xy 183.978804 -169.361358)
			(xy 184.730898 -169.361358) (xy 184.740916 -169.360938) (xy 184.759427 -169.353267) (xy 184.773589 -169.339093)
			(xy 184.781246 -169.320577) (xy 184.781698 -169.310558) (xy 184.781698 -169.302938) (xy 184.782141 -169.272205)
			(xy 184.789546 -169.211185) (xy 184.804253 -169.151504) (xy 184.826046 -169.09403) (xy 184.854608 -169.039602)
			(xy 184.889523 -168.989015) (xy 184.930282 -168.943005) (xy 184.976289 -168.902243) (xy 185.026875 -168.867325)
			(xy 185.081301 -168.838759) (xy 185.138773 -168.816962) (xy 185.198454 -168.802252) (xy 185.259473 -168.794843)
			(xy 185.290206 -168.79443) (xy 185.323226 -168.794957) (xy 185.38871 -168.803506) (xy 185.452537 -168.82046)
			(xy 185.513633 -168.845533) (xy 185.570968 -168.878303) (xy 185.62358 -168.918219) (xy 185.670582 -168.96461)
			(xy 185.711184 -169.016694) (xy 185.744702 -169.073596) (xy 185.770573 -169.134357) (xy 185.788361 -169.197957)
			(xy 185.797767 -169.263324) (xy 185.798714 -169.296334) (xy 185.799285 -169.306258) (xy 185.806992 -169.324559)
			(xy 185.8137 -169.331894) (xy 185.820812 -169.338752) (xy 185.829702 -169.342562) (xy 185.834389 -169.344361)
			(xy 185.844241 -169.34628) (xy 185.84926 -169.346372) (xy 187.68187 -169.346372) (xy 187.685351 -169.349657)
			(xy 187.693278 -169.35502) (xy 187.697618 -169.35704) (xy 187.698888 -169.357548) (xy 187.703455 -169.359305)
			(xy 187.713047 -169.361226) (xy 187.717938 -169.361358) (xy 190.420752 -169.361358) (xy 190.428626 -169.36085)
			(xy 190.436125 -169.359418) (xy 190.449823 -169.352692) (xy 190.45555 -169.347642) (xy 190.462408 -169.341038)
			(xy 190.47079 -169.323512) (xy 190.471298 -169.31386) (xy 190.473943 -169.282091) (xy 190.486156 -169.219522)
			(xy 190.50609 -169.158969) (xy 190.53343 -169.101379) (xy 190.56775 -169.047656) (xy 190.608512 -168.998641)
			(xy 190.655077 -168.955101) (xy 190.706716 -168.917718) (xy 190.762621 -168.887079) (xy 190.821914 -168.863662)
			(xy 190.883668 -168.847836) (xy 190.946915 -168.839846) (xy 190.97879 -168.839388) (xy 191.010206 -168.839854)
			(xy 191.072561 -168.84759) (xy 191.133489 -168.862944) (xy 191.192063 -168.885684) (xy 191.247391 -168.915464)
			(xy 191.298631 -168.951829) (xy 191.345003 -168.994227) (xy 191.385802 -169.042012) (xy 191.403478 -169.067988)
			(xy 191.41067 -169.077676) (xy 191.431609 -169.089599) (xy 191.44361 -169.090848) (xy 191.525398 -169.094658)
			(xy 191.527938 -169.094658) (xy 191.552576 -169.08272) (xy 191.56172 -169.077132) (xy 191.570102 -169.070528)
			(xy 191.577722 -169.063416) (xy 191.598454 -169.039847) (xy 191.644779 -168.997484) (xy 191.695967 -168.961149)
			(xy 191.751241 -168.931395) (xy 191.809758 -168.908674) (xy 191.870628 -168.893331) (xy 191.932923 -168.885602)
			(xy 191.96431 -168.885108) (xy 191.99719 -168.885626) (xy 192.0624 -168.894103) (xy 192.125974 -168.910914)
			(xy 192.186851 -168.935779) (xy 192.244015 -168.968282) (xy 192.296514 -169.007883) (xy 192.34347 -169.053919)
			(xy 192.384101 -169.105624) (xy 192.417729 -169.162134) (xy 192.443794 -169.222507) (xy 192.461859 -169.285736)
			(xy 192.46723 -169.318178) (xy 192.4685 -169.327068) (xy 192.47739 -169.34307) (xy 192.484248 -169.348912)
			(xy 192.491371 -169.354589) (xy 192.508421 -169.360961) (xy 192.517522 -169.361358) (xy 193.242946 -169.361358)
			(xy 193.245994 -169.361358) (xy 193.251367 -169.360873) (xy 193.261742 -169.357927) (xy 193.266568 -169.355516)
			(xy 193.281046 -169.347896) (xy 193.290952 -169.341292) (xy 193.299334 -169.333672) (xy 193.306954 -169.325798)
			(xy 193.326206 -169.300819) (xy 193.369904 -169.255346) (xy 193.418887 -169.215621) (xy 193.472403 -169.182254)
			(xy 193.529633 -169.155756) (xy 193.589698 -169.136533) (xy 193.651679 -169.12488) (xy 193.714624 -169.120976)
			(xy 193.777569 -169.12488) (xy 193.83955 -169.136533) (xy 193.899615 -169.155756) (xy 193.956845 -169.182254)
			(xy 194.010361 -169.215621) (xy 194.059344 -169.255346) (xy 194.103042 -169.300819) (xy 194.122294 -169.325798)
			(xy 194.129914 -169.333672) (xy 194.138296 -169.341292) (xy 194.148202 -169.347896) (xy 194.16268 -169.355516)
			(xy 194.167506 -169.357928) (xy 194.177881 -169.360878) (xy 194.183254 -169.361358) (xy 229.927658 -169.361358)
			(xy 229.934402 -169.361113) (xy 229.9474 -169.357502) (xy 229.953312 -169.354246) (xy 229.968552 -169.345356)
			(xy 229.978712 -169.337482) (xy 229.987602 -169.328592) (xy 229.995222 -169.31894) (xy 230.013935 -169.289167)
			(xy 230.058298 -169.234607) (xy 230.109772 -169.186697) (xy 230.138224 -169.166032) (xy 230.147632 -169.158646)
			(xy 230.158878 -169.137572) (xy 230.159814 -169.125646) (xy 230.15956 -169.119296) (xy 230.150416 -169.03065)
			(xy 230.150162 -169.028618) (xy 230.146352 -169.015156) (xy 230.14051 -169.005504) (xy 230.132382 -168.994582)
			(xy 230.13035 -168.99382) (xy 230.116995 -168.988469) (xy 230.091058 -168.97601) (xy 230.078534 -168.968928)
			(xy 230.061008 -168.95826) (xy 230.055166 -168.95445) (xy 230.050848 -168.952926) (xy 230.027226 -168.945814)
			(xy 230.02113 -168.946322) (xy 230.020368 -168.946322) (xy 229.990142 -168.950132) (xy 229.985316 -168.950894)
			(xy 229.977338 -168.953027) (xy 229.963223 -168.961581) (xy 229.95763 -168.967658) (xy 229.936887 -168.991325)
			(xy 229.890513 -169.033872) (xy 229.839243 -169.070371) (xy 229.783862 -169.100266) (xy 229.725216 -169.123099)
			(xy 229.6642 -169.13852) (xy 229.601747 -169.146296) (xy 229.57028 -169.146728) (xy 229.538319 -169.146225)
			(xy 229.4749 -169.138211) (xy 229.412986 -169.122312) (xy 229.353552 -169.098778) (xy 229.297537 -169.067982)
			(xy 229.245823 -169.030408) (xy 229.199226 -168.986648) (xy 229.158481 -168.937394) (xy 229.12423 -168.883422)
			(xy 229.097014 -168.825582) (xy 229.077261 -168.764788) (xy 229.065283 -168.701997) (xy 229.061269 -168.6382)
			(xy 229.065283 -168.574403) (xy 229.077261 -168.511612) (xy 229.097014 -168.450818) (xy 229.12423 -168.392978)
			(xy 229.158481 -168.339006) (xy 229.199226 -168.289752) (xy 229.245823 -168.245992) (xy 229.297537 -168.208418)
			(xy 229.353552 -168.177622) (xy 229.412986 -168.154088) (xy 229.4749 -168.138189) (xy 229.538319 -168.130175)
			(xy 229.57028 -168.129712) (xy 229.601747 -168.130182) (xy 229.6642 -168.137946) (xy 229.725217 -168.153358)
			(xy 229.783866 -168.176182) (xy 229.83925 -168.206069) (xy 229.890523 -168.242563) (xy 229.936899 -168.285105)
			(xy 229.95763 -168.308782) (xy 229.963199 -168.314885) (xy 229.97733 -168.323424) (xy 229.985316 -168.325546)
			(xy 229.990142 -168.326308) (xy 230.020368 -168.330118) (xy 230.02113 -168.330118) (xy 230.027226 -168.330626)
			(xy 230.050848 -168.323514) (xy 230.055166 -168.32199) (xy 230.061008 -168.31818) (xy 230.084311 -168.303612)
			(xy 230.134217 -168.280604) (xy 230.186912 -168.265008) (xy 230.241302 -168.257149) (xy 230.26878 -168.256712)
			(xy 230.296254 -168.257193) (xy 230.350635 -168.265072) (xy 230.403328 -168.280656) (xy 230.453247 -168.303623)
			(xy 230.476552 -168.31818) (xy 230.482394 -168.32199) (xy 230.486712 -168.323514) (xy 230.510334 -168.330626)
			(xy 230.517192 -168.330118) (xy 230.547672 -168.326308) (xy 230.548942 -168.326054) (xy 230.54945 -168.326054)
			(xy 230.558218 -168.324172) (xy 230.573804 -168.315332) (xy 230.57993 -168.308782) (xy 230.600676 -168.28512)
			(xy 230.647053 -168.242584) (xy 230.698325 -168.206094) (xy 230.753706 -168.17621) (xy 230.812352 -168.153387)
			(xy 230.873366 -168.137974) (xy 230.935815 -168.130207) (xy 230.96728 -168.129712) (xy 230.999128 -168.130206)
			(xy 231.062325 -168.138162) (xy 231.124032 -168.153952) (xy 231.183283 -168.177328) (xy 231.23915 -168.207924)
			(xy 231.290755 -168.24526) (xy 231.337291 -168.288752) (xy 231.378029 -168.337717) (xy 231.412329 -168.391389)
			(xy 231.439654 -168.448925) (xy 231.459577 -168.509425) (xy 231.471784 -168.57194) (xy 231.474518 -168.603676)
			(xy 231.474772 -168.607232) (xy 231.475801 -168.613225) (xy 231.480293 -168.624521) (xy 231.483662 -168.629584)
			(xy 231.488996 -168.636696) (xy 231.49433 -168.64076) (xy 231.497281 -168.64286) (xy 231.503656 -168.6463)
			(xy 231.50703 -168.647618) (xy 231.524556 -168.654222) (xy 231.525064 -168.654222) (xy 231.594152 -168.680384)
			(xy 231.60228 -168.68267) (xy 231.603296 -168.68267) (xy 231.61063 -168.683715) (xy 231.625341 -168.682035)
			(xy 231.632252 -168.679368) (xy 231.636537 -168.677354) (xy 231.64433 -168.671979) (xy 231.647746 -168.6687)
			(xy 251.47143 -148.845016) (xy 251.478829 -148.838173) (xy 251.497428 -148.830446) (xy 251.507498 -148.83003)
			(xy 261.09041 -148.83003) (xy 261.093458 -148.83003) (xy 261.102367 -148.829153) (xy 261.118763 -148.821997)
			(xy 261.125462 -148.81606) (xy 261.14914 -148.794255) (xy 261.201038 -148.756175) (xy 261.25733 -148.724955)
			(xy 261.317114 -148.701093) (xy 261.379433 -148.684973) (xy 261.443289 -148.676853) (xy 261.475474 -148.67636)
			(xy 261.475728 -148.67636) (xy 261.506239 -148.67683) (xy 261.566818 -148.684168) (xy 261.626085 -148.698701)
			(xy 261.683187 -148.720219) (xy 261.737305 -148.748413) (xy 261.762748 -148.76526) (xy 261.773162 -148.769578)
			(xy 261.795006 -148.776436) (xy 261.803388 -148.775674) (xy 261.808593 -148.774604) (xy 261.818448 -148.77063)
			(xy 261.822946 -148.7678) (xy 261.82828 -148.763736) (xy 261.855244 -148.743324) (xy 261.913543 -148.709051)
			(xy 261.975869 -148.682804) (xy 262.041124 -148.665048) (xy 262.108156 -148.656096) (xy 262.14197 -148.655532)
			(xy 262.171661 -148.655955) (xy 262.230637 -148.662877) (xy 262.288406 -148.67662) (xy 262.344182 -148.696995)
			(xy 262.397207 -148.723726) (xy 262.446758 -148.75645) (xy 262.492162 -148.79472) (xy 262.51281 -148.81606)
			(xy 262.513318 -148.816568) (xy 262.543544 -148.829776) (xy 262.547862 -148.83003) (xy 273.802856 -148.83003)
			(xy 273.81454 -148.828506) (xy 273.815048 -148.828506) (xy 273.820636 -148.826728) (xy 273.823948 -148.825405)
			(xy 273.830192 -148.82196) (xy 273.833082 -148.81987) (xy 273.91671 -148.751783) (xy 274.08791 -148.620602)
			(xy 274.263431 -148.495265) (xy 274.443076 -148.375911) (xy 274.62664 -148.262678) (xy 274.813914 -148.155693)
			(xy 275.004687 -148.055079) (xy 275.198741 -147.960949) (xy 275.395856 -147.87341) (xy 275.595808 -147.792561)
			(xy 275.696934 -147.755102) (xy 275.802471 -147.71703) (xy 276.01578 -147.647398) (xy 276.231398 -147.585283)
			(xy 276.44906 -147.530764) (xy 276.6685 -147.483905) (xy 276.889446 -147.444765) (xy 277.111629 -147.413392)
			(xy 277.334774 -147.389825) (xy 277.558609 -147.374092) (xy 277.782857 -147.366213) (xy 277.89505 -147.36572)
			(xy 278.007244 -147.366213) (xy 278.231493 -147.374083) (xy 278.455328 -147.389809) (xy 278.678475 -147.413372)
			(xy 278.900658 -147.444741) (xy 279.121606 -147.483879) (xy 279.219902 -147.504869) (xy 295.689268 -147.504869)
			(xy 295.689268 -147.440947) (xy 295.697279 -147.377529) (xy 295.713176 -147.315615) (xy 295.736708 -147.256182)
			(xy 295.767502 -147.200167) (xy 295.805075 -147.148452) (xy 295.848832 -147.101855) (xy 295.898085 -147.06111)
			(xy 295.952056 -147.026859) (xy 296.009895 -146.999642) (xy 296.070688 -146.979889) (xy 296.133478 -146.967911)
			(xy 296.197274 -146.963898) (xy 296.26107 -146.967911) (xy 296.32386 -146.979889) (xy 296.384653 -146.999642)
			(xy 296.442492 -147.026859) (xy 296.496463 -147.06111) (xy 296.545716 -147.101855) (xy 296.589473 -147.148452)
			(xy 296.627046 -147.200167) (xy 296.65784 -147.256182) (xy 296.681372 -147.315615) (xy 296.697269 -147.377529)
			(xy 296.70528 -147.440947) (xy 296.705782 -147.472908) (xy 296.70528 -147.504869) (xy 296.697269 -147.568287)
			(xy 296.681372 -147.630201) (xy 296.65784 -147.689634) (xy 296.647007 -147.709339) (xy 303.081938 -147.709339)
			(xy 303.081938 -147.645417) (xy 303.089949 -147.581999) (xy 303.105846 -147.520085) (xy 303.129378 -147.460652)
			(xy 303.160172 -147.404637) (xy 303.197745 -147.352922) (xy 303.241502 -147.306325) (xy 303.290755 -147.26558)
			(xy 303.344726 -147.231329) (xy 303.402565 -147.204112) (xy 303.463358 -147.184359) (xy 303.526148 -147.172381)
			(xy 303.589944 -147.168368) (xy 303.65374 -147.172381) (xy 303.71653 -147.184359) (xy 303.777323 -147.204112)
			(xy 303.835162 -147.231329) (xy 303.889133 -147.26558) (xy 303.938386 -147.306325) (xy 303.982143 -147.352922)
			(xy 304.019716 -147.404637) (xy 304.05051 -147.460652) (xy 304.074042 -147.520085) (xy 304.089939 -147.581999)
			(xy 304.09795 -147.645417) (xy 304.098452 -147.677378) (xy 304.09795 -147.709339) (xy 304.089939 -147.772757)
			(xy 304.074042 -147.834671) (xy 304.05051 -147.894104) (xy 304.019716 -147.950119) (xy 304.003468 -147.972483)
			(xy 305.790594 -147.972483) (xy 305.790594 -147.908561) (xy 305.798605 -147.845143) (xy 305.814502 -147.783229)
			(xy 305.838034 -147.723796) (xy 305.868828 -147.667781) (xy 305.906401 -147.616066) (xy 305.950158 -147.569469)
			(xy 305.999411 -147.528724) (xy 306.053382 -147.494473) (xy 306.111221 -147.467256) (xy 306.172014 -147.447503)
			(xy 306.234804 -147.435525) (xy 306.2986 -147.431512) (xy 306.362396 -147.435525) (xy 306.425186 -147.447503)
			(xy 306.485979 -147.467256) (xy 306.543818 -147.494473) (xy 306.597789 -147.528724) (xy 306.647042 -147.569469)
			(xy 306.690799 -147.616066) (xy 306.728372 -147.667781) (xy 306.759166 -147.723796) (xy 306.782698 -147.783229)
			(xy 306.798595 -147.845143) (xy 306.806606 -147.908561) (xy 306.807108 -147.940522) (xy 306.806606 -147.972483)
			(xy 306.798595 -148.035901) (xy 306.782698 -148.097815) (xy 306.759166 -148.157248) (xy 306.728372 -148.213263)
			(xy 306.690799 -148.264978) (xy 306.647042 -148.311575) (xy 306.597789 -148.35232) (xy 306.543818 -148.386571)
			(xy 306.485979 -148.413788) (xy 306.425186 -148.433541) (xy 306.362396 -148.445519) (xy 306.2986 -148.449533)
			(xy 306.234804 -148.445519) (xy 306.172014 -148.433541) (xy 306.111221 -148.413788) (xy 306.053382 -148.386571)
			(xy 305.999411 -148.35232) (xy 305.950158 -148.311575) (xy 305.906401 -148.264978) (xy 305.868828 -148.213263)
			(xy 305.838034 -148.157248) (xy 305.814502 -148.097815) (xy 305.798605 -148.035901) (xy 305.790594 -147.972483)
			(xy 304.003468 -147.972483) (xy 303.982143 -148.001834) (xy 303.938386 -148.048431) (xy 303.889133 -148.089176)
			(xy 303.835162 -148.123427) (xy 303.777323 -148.150644) (xy 303.71653 -148.170397) (xy 303.65374 -148.182375)
			(xy 303.589944 -148.186389) (xy 303.526148 -148.182375) (xy 303.463358 -148.170397) (xy 303.402565 -148.150644)
			(xy 303.344726 -148.123427) (xy 303.290755 -148.089176) (xy 303.241502 -148.048431) (xy 303.197745 -148.001834)
			(xy 303.160172 -147.950119) (xy 303.129378 -147.894104) (xy 303.105846 -147.834671) (xy 303.089949 -147.772757)
			(xy 303.081938 -147.709339) (xy 296.647007 -147.709339) (xy 296.627046 -147.745649) (xy 296.589473 -147.797364)
			(xy 296.545716 -147.843961) (xy 296.496463 -147.884706) (xy 296.442492 -147.918957) (xy 296.384653 -147.946174)
			(xy 296.32386 -147.965927) (xy 296.26107 -147.977905) (xy 296.197274 -147.981919) (xy 296.133478 -147.977905)
			(xy 296.070688 -147.965927) (xy 296.009895 -147.946174) (xy 295.952056 -147.918957) (xy 295.898085 -147.884706)
			(xy 295.848832 -147.843961) (xy 295.805075 -147.797364) (xy 295.767502 -147.745649) (xy 295.736708 -147.689634)
			(xy 295.713176 -147.630201) (xy 295.697279 -147.568287) (xy 295.689268 -147.504869) (xy 279.219902 -147.504869)
			(xy 279.341046 -147.530738) (xy 279.558708 -147.58526) (xy 279.774326 -147.647378) (xy 279.987634 -147.717015)
			(xy 280.093166 -147.755102) (xy 280.194292 -147.79256) (xy 280.394244 -147.87341) (xy 280.591359 -147.96095)
			(xy 280.785413 -148.05508) (xy 280.976185 -148.155694) (xy 281.16346 -148.262678) (xy 281.347025 -148.37591)
			(xy 281.526671 -148.495262) (xy 281.702194 -148.620598) (xy 281.873395 -148.751776) (xy 281.957018 -148.81987)
			(xy 281.969464 -148.826728) (xy 281.975052 -148.828506) (xy 281.97556 -148.828506) (xy 281.987244 -148.83003)
			(xy 292.61435 -148.83003) (xy 292.622629 -148.829705) (xy 292.638308 -148.824384) (xy 292.645084 -148.819616)
			(xy 292.645338 -148.819616) (xy 292.651942 -148.814282) (xy 292.660832 -148.801074) (xy 292.663118 -148.792946)
			(xy 292.66946 -148.77127) (xy 292.68549 -148.729045) (xy 292.695122 -148.708618) (xy 292.710077 -148.678852)
			(xy 292.746643 -148.623168) (xy 292.76802 -148.59762) (xy 292.77056 -148.594572) (xy 292.775084 -148.587987)
			(xy 292.780127 -148.572836) (xy 292.780466 -148.564854) (xy 292.780466 -148.533358) (xy 292.780068 -148.525388)
			(xy 292.775016 -148.510261) (xy 292.77056 -148.50364) (xy 292.76802 -148.500592) (xy 292.748605 -148.477447)
			(xy 292.714813 -148.427367) (xy 292.687188 -148.373639) (xy 292.666119 -148.317018) (xy 292.651901 -148.258301)
			(xy 292.644736 -148.198313) (xy 292.644322 -148.168106) (xy 292.644767 -148.137374) (xy 292.652175 -148.076359)
			(xy 292.666885 -148.016682) (xy 292.68868 -147.959213) (xy 292.717244 -147.90479) (xy 292.75216 -147.854207)
			(xy 292.792919 -147.808202) (xy 292.838926 -147.767445) (xy 292.88951 -147.732532) (xy 292.943934 -147.70397)
			(xy 293.001405 -147.682177) (xy 293.061083 -147.667471) (xy 293.122098 -147.660066) (xy 293.15283 -147.659598)
			(xy 293.153084 -147.659598) (xy 293.186806 -147.660141) (xy 293.25366 -147.669046) (xy 293.318748 -147.686717)
			(xy 293.380927 -147.712841) (xy 293.439105 -147.74696) (xy 293.466012 -147.767294) (xy 293.468044 -147.768818)
			(xy 293.49065 -147.776692) (xy 293.494955 -147.778099) (xy 293.503901 -147.779502) (xy 293.50843 -147.779486)
			(xy 293.51478 -147.779486) (xy 293.523924 -147.779232) (xy 293.537894 -147.776184) (xy 293.561262 -147.767548)
			(xy 293.564818 -147.764754) (xy 293.592231 -147.743004) (xy 293.651892 -147.706435) (xy 293.716001 -147.678385)
			(xy 293.783348 -147.659384) (xy 293.852664 -147.64979) (xy 293.887652 -147.649184) (xy 293.918386 -147.649627)
			(xy 293.979407 -147.657031) (xy 294.03909 -147.671736) (xy 294.096566 -147.693529) (xy 294.150995 -147.722091)
			(xy 294.201585 -147.757005) (xy 294.247597 -147.797764) (xy 294.28836 -147.843771) (xy 294.323281 -147.894357)
			(xy 294.351848 -147.948783) (xy 294.373647 -148.006256) (xy 294.388359 -148.065938) (xy 294.39577 -148.126958)
			(xy 294.39616 -148.157692) (xy 294.395729 -148.187899) (xy 294.388573 -148.247887) (xy 294.374363 -148.306606)
			(xy 294.353297 -148.363228) (xy 294.325672 -148.416956) (xy 294.291878 -148.467033) (xy 294.272462 -148.490178)
			(xy 294.269922 -148.493226) (xy 294.265399 -148.499811) (xy 294.260358 -148.514962) (xy 294.260016 -148.522944)
			(xy 294.260016 -148.55444) (xy 294.260416 -148.562409) (xy 294.265473 -148.577533) (xy 294.269922 -148.584158)
			(xy 294.272462 -148.587206) (xy 294.290517 -148.608669) (xy 294.322297 -148.654885) (xy 294.348799 -148.704318)
			(xy 294.359584 -148.730208) (xy 294.365517 -148.74528) (xy 294.375683 -148.776038) (xy 294.379904 -148.791676)
			(xy 294.379904 -148.792184) (xy 294.380158 -148.792438) (xy 294.38256 -148.800321) (xy 294.391623 -148.81407)
			(xy 294.397938 -148.819362) (xy 294.40124 -148.821902) (xy 294.404796 -148.824696) (xy 294.41267 -148.827236)
			(xy 294.416617 -148.828498) (xy 294.424784 -148.829899) (xy 294.428926 -148.83003) (xy 300.163484 -148.83003)
			(xy 300.17339 -148.825712) (xy 300.205891 -148.811992) (xy 300.273735 -148.792653) (xy 300.343603 -148.782894)
			(xy 300.378876 -148.782278) (xy 300.414147 -148.782903) (xy 300.484009 -148.792686) (xy 300.551854 -148.812013)
			(xy 300.584362 -148.825712) (xy 300.594268 -148.83003) (xy 301.469552 -148.83003) (xy 301.479617 -148.830463)
			(xy 301.498205 -148.838194) (xy 301.50562 -148.845016) (xy 301.690489 -149.029885) (xy 303.107338 -149.029885)
			(xy 303.107338 -148.965963) (xy 303.115349 -148.902545) (xy 303.131246 -148.840631) (xy 303.154778 -148.781198)
			(xy 303.185572 -148.725183) (xy 303.223145 -148.673468) (xy 303.266902 -148.626871) (xy 303.316155 -148.586126)
			(xy 303.370126 -148.551875) (xy 303.427965 -148.524658) (xy 303.488758 -148.504905) (xy 303.551548 -148.492927)
			(xy 303.615344 -148.488914) (xy 303.67914 -148.492927) (xy 303.74193 -148.504905) (xy 303.802723 -148.524658)
			(xy 303.860562 -148.551875) (xy 303.914533 -148.586126) (xy 303.963786 -148.626871) (xy 304.007543 -148.673468)
			(xy 304.045116 -148.725183) (xy 304.07591 -148.781198) (xy 304.099442 -148.840631) (xy 304.115339 -148.902545)
			(xy 304.12335 -148.965963) (xy 304.123852 -148.997924) (xy 304.12335 -149.029885) (xy 304.115339 -149.093303)
			(xy 304.099442 -149.155217) (xy 304.07591 -149.21465) (xy 304.045116 -149.270665) (xy 304.007543 -149.32238)
			(xy 303.963786 -149.368977) (xy 303.914533 -149.409722) (xy 303.860562 -149.443973) (xy 303.802723 -149.47119)
			(xy 303.74193 -149.490943) (xy 303.67914 -149.502921) (xy 303.615344 -149.506935) (xy 303.551548 -149.502921)
			(xy 303.488758 -149.490943) (xy 303.427965 -149.47119) (xy 303.370126 -149.443973) (xy 303.316155 -149.409722)
			(xy 303.266902 -149.368977) (xy 303.223145 -149.32238) (xy 303.185572 -149.270665) (xy 303.154778 -149.21465)
			(xy 303.131246 -149.155217) (xy 303.115349 -149.093303) (xy 303.107338 -149.029885) (xy 301.690489 -149.029885)
			(xy 302.024034 -149.36343) (xy 302.027082 -149.365716) (xy 302.04986 -149.38315) (xy 302.090414 -149.423714)
			(xy 302.107854 -149.446488) (xy 302.11014 -149.449536) (xy 302.208438 -149.547834) (xy 302.216734 -149.555273)
			(xy 302.237689 -149.562771) (xy 302.248824 -149.562312) (xy 302.327056 -149.5552) (xy 302.332467 -149.554539)
			(xy 302.342843 -149.551204) (xy 302.34763 -149.548596) (xy 302.352456 -149.545802) (xy 302.360838 -149.538182)
			(xy 302.363886 -149.53361) (xy 302.379217 -149.512135) (xy 302.414845 -149.473219) (xy 302.455497 -149.439583)
			(xy 302.500396 -149.41187) (xy 302.548685 -149.390608) (xy 302.599443 -149.376203) (xy 302.651703 -149.36893)
			(xy 302.678084 -149.36851) (xy 302.70476 -149.368955) (xy 302.757592 -149.376388) (xy 302.808873 -149.391112)
			(xy 302.8576 -149.41284) (xy 302.902825 -149.441146) (xy 302.943662 -149.475479) (xy 302.979316 -149.515169)
			(xy 303.009091 -149.55944) (xy 303.032405 -149.607429) (xy 303.04105 -149.63267) (xy 303.04105 -149.632924)
			(xy 303.044683 -149.642512) (xy 303.058153 -149.657948) (xy 303.076569 -149.666922) (xy 303.08677 -149.667976)
			(xy 304.215038 -149.667976) (xy 304.220415 -149.667818) (xy 304.230921 -149.665519) (xy 304.235866 -149.663404)
			(xy 304.249836 -149.657054) (xy 304.258472 -149.651974) (xy 304.266854 -149.646132) (xy 304.27422 -149.639528)
			(xy 304.296463 -149.616468) (xy 304.345769 -149.575552) (xy 304.399823 -149.541154) (xy 304.45777 -149.513818)
			(xy 304.518692 -149.493977) (xy 304.581624 -149.481945) (xy 304.645568 -149.477913) (xy 304.709512 -149.481945)
			(xy 304.772444 -149.493977) (xy 304.833366 -149.513818) (xy 304.891313 -149.541154) (xy 304.945367 -149.575552)
			(xy 304.994673 -149.616468) (xy 305.016916 -149.639528) (xy 305.024282 -149.646132) (xy 305.032664 -149.651974)
			(xy 305.0413 -149.657054) (xy 305.05527 -149.663404) (xy 305.060218 -149.665512) (xy 305.070722 -149.667816)
			(xy 305.076098 -149.667976) (xy 305.77282 -149.667976) (xy 305.782726 -149.66696) (xy 305.79023 -149.665151)
			(xy 305.803783 -149.657782) (xy 305.809396 -149.652482) (xy 305.811936 -149.649688) (xy 305.861974 -149.58949)
			(xy 305.865495 -149.585032) (xy 305.870626 -149.574901) (xy 305.872134 -149.569424) (xy 305.874928 -149.558756)
			(xy 305.872896 -149.54758) (xy 305.868754 -149.524305) (xy 305.864296 -149.477238) (xy 305.864006 -149.4536)
			(xy 305.864435 -149.424244) (xy 305.871224 -149.365924) (xy 305.884689 -149.308776) (xy 305.90465 -149.25356)
			(xy 305.930841 -149.201013) (xy 305.962914 -149.151834) (xy 305.981354 -149.128988) (xy 305.98618 -149.121876)
			(xy 306.001131 -149.095698) (xy 306.03629 -149.046727) (xy 306.076994 -149.002256) (xy 306.12267 -148.96291)
			(xy 306.172678 -148.929242) (xy 306.226317 -148.901723) (xy 306.282834 -148.88074) (xy 306.341435 -148.866587)
			(xy 306.401299 -148.859463) (xy 306.431442 -148.858986) (xy 306.437538 -148.858986) (xy 306.447092 -148.858792)
			(xy 306.464989 -148.852141) (xy 306.472336 -148.846032) (xy 306.495196 -148.825458) (xy 306.501064 -148.819871)
			(xy 306.509228 -148.805885) (xy 306.511198 -148.798026) (xy 306.51196 -148.792692) (xy 306.51196 -148.792184)
			(xy 306.515403 -148.76109) (xy 306.52893 -148.700009) (xy 306.549847 -148.641048) (xy 306.57784 -148.5851)
			(xy 306.612485 -148.533007) (xy 306.653258 -148.485558) (xy 306.699544 -148.443469) (xy 306.750644 -148.407377)
			(xy 306.805786 -148.377825) (xy 306.864136 -148.355261) (xy 306.924813 -148.340026) (xy 306.986902 -148.332349)
			(xy 307.018182 -148.331936) (xy 307.050142 -148.332416) (xy 307.113559 -148.340425) (xy 307.175472 -148.35632)
			(xy 307.234905 -148.379849) (xy 307.290919 -148.410641) (xy 307.342633 -148.448212) (xy 307.38923 -148.491968)
			(xy 307.429975 -148.541219) (xy 307.464226 -148.595188) (xy 307.491443 -148.653025) (xy 307.511196 -148.713817)
			(xy 307.523174 -148.776606) (xy 307.527188 -148.8404) (xy 307.523174 -148.904194) (xy 307.511196 -148.966983)
			(xy 307.491443 -149.027775) (xy 307.464226 -149.085612) (xy 307.429975 -149.139581) (xy 307.38923 -149.188832)
			(xy 307.342633 -149.232588) (xy 307.290919 -149.270159) (xy 307.234905 -149.300951) (xy 307.175472 -149.32448)
			(xy 307.113559 -149.340375) (xy 307.050142 -149.348384) (xy 307.018182 -149.348952) (xy 307.012086 -149.348952)
			(xy 307.002537 -149.349158) (xy 306.984653 -149.355823) (xy 306.977288 -149.361906) (xy 306.954428 -149.38248)
			(xy 306.947955 -149.388734) (xy 306.93949 -149.404606) (xy 306.937918 -149.413468) (xy 306.934693 -149.444036)
			(xy 306.921833 -149.504145) (xy 306.912264 -149.533356) (xy 306.912264 -149.53361) (xy 306.910475 -149.539335)
			(xy 306.909325 -149.55127) (xy 306.909978 -149.557232) (xy 306.911502 -149.56917) (xy 306.966874 -149.64664)
			(xy 306.974495 -149.656138) (xy 306.996117 -149.667262) (xy 307.008276 -149.667976) (xy 309.923942 -149.667976)
			(xy 309.929952 -149.66781) (xy 309.941634 -149.664986) (xy 309.947056 -149.662388) (xy 309.950528 -149.660546)
			(xy 309.956903 -149.655948) (xy 309.959756 -149.653244) (xy 330.439014 -129.173986) (xy 330.446409 -129.167132)
			(xy 330.465008 -129.15939) (xy 330.475082 -129.159) (xy 343.572846 -129.159) (xy 343.582912 -129.159432)
			(xy 343.601505 -129.167158) (xy 343.608914 -129.173986) (xy 344.540332 -130.105404) (xy 344.543185 -130.108107)
			(xy 344.549567 -130.112693) (xy 344.553032 -130.114548) (xy 344.558458 -130.117135) (xy 344.570138 -130.119964)
			(xy 344.576146 -130.120136) (xy 348.388686 -130.120136) (xy 348.394782 -130.119628) (xy 348.39529 -130.119628)
			(xy 348.404822 -130.117901) (xy 348.421672 -130.108372) (xy 348.428056 -130.101086) (xy 348.428564 -130.100578)
			(xy 348.430342 -130.098292) (xy 348.47784 -130.029712) (xy 348.482053 -130.023155) (xy 348.486713 -130.008291)
			(xy 348.486984 -130.000502) (xy 348.484698 -129.987548) (xy 348.482412 -129.979166) (xy 348.47291 -129.951505)
			(xy 348.459576 -129.894555) (xy 348.452859 -129.836453) (xy 348.45244 -129.807208) (xy 348.452942 -129.775247)
			(xy 348.460953 -129.711829) (xy 348.47685 -129.649915) (xy 348.500382 -129.590482) (xy 348.531176 -129.534467)
			(xy 348.568749 -129.482752) (xy 348.612506 -129.436155) (xy 348.661759 -129.39541) (xy 348.71573 -129.361159)
			(xy 348.773569 -129.333942) (xy 348.834362 -129.314189) (xy 348.897152 -129.302211) (xy 348.960948 -129.298198)
			(xy 349.024744 -129.302211) (xy 349.087534 -129.314189) (xy 349.148327 -129.333942) (xy 349.206166 -129.361159)
			(xy 349.260137 -129.39541) (xy 349.30939 -129.436155) (xy 349.353147 -129.482752) (xy 349.39072 -129.534467)
			(xy 349.421514 -129.590482) (xy 349.445046 -129.649915) (xy 349.460943 -129.711829) (xy 349.468954 -129.775247)
			(xy 349.469456 -129.807208) (xy 349.469044 -129.836453) (xy 349.462327 -129.894556) (xy 349.448981 -129.951503)
			(xy 349.439484 -129.979166) (xy 349.437198 -129.987548) (xy 349.434912 -130.000502) (xy 349.435145 -130.008299)
			(xy 349.439791 -130.023181) (xy 349.444056 -130.029712) (xy 349.491554 -130.098292) (xy 349.493332 -130.100578)
			(xy 349.49384 -130.101086) (xy 349.501426 -130.109548) (xy 349.521866 -130.119413) (xy 349.53321 -130.120136)
			(xy 349.542608 -130.120136) (xy 349.551174 -130.119762) (xy 349.567327 -130.114046) (xy 349.580714 -130.103349)
			(xy 349.585534 -130.09626) (xy 349.631254 -130.023362) (xy 349.634786 -130.017199) (xy 349.638663 -130.003538)
			(xy 349.638874 -129.996438) (xy 349.635064 -129.979674) (xy 349.631508 -129.96926) (xy 349.620108 -129.943829)
			(xy 349.604041 -129.890465) (xy 349.59593 -129.835327) (xy 349.59544 -129.807462) (xy 349.59544 -129.807208)
			(xy 349.595903 -129.779956) (xy 349.603659 -129.726007) (xy 349.619015 -129.673711) (xy 349.641658 -129.624133)
			(xy 349.671126 -129.578282) (xy 349.706821 -129.537092) (xy 349.748014 -129.501402) (xy 349.793868 -129.471938)
			(xy 349.843448 -129.449301) (xy 349.895746 -129.433951) (xy 349.949696 -129.4262) (xy 349.976948 -129.4257)
			(xy 350.005791 -129.426224) (xy 350.062822 -129.434897) (xy 350.117899 -129.452053) (xy 350.169767 -129.477302)
			(xy 350.217244 -129.510068) (xy 350.259251 -129.549605) (xy 350.27743 -129.572004) (xy 350.281494 -129.577084)
			(xy 350.291146 -129.584704) (xy 350.296734 -129.587244) (xy 350.302535 -129.589587) (xy 350.314871 -129.591654)
			(xy 350.321118 -129.591308) (xy 350.4057 -129.584704) (xy 350.411902 -129.584026) (xy 350.423726 -129.580052)
			(xy 350.429068 -129.57683) (xy 350.434402 -129.573528) (xy 350.443038 -129.56413) (xy 350.446086 -129.558796)
			(xy 350.463021 -129.529595) (xy 350.503437 -129.475527) (xy 350.550652 -129.427281) (xy 350.603834 -129.385706)
			(xy 350.66205 -129.351533) (xy 350.724275 -129.325362) (xy 350.789415 -129.307654) (xy 350.856326 -129.298721)
			(xy 350.890078 -129.298192) (xy 350.920811 -129.298636) (xy 350.981829 -129.306043) (xy 351.041509 -129.32075)
			(xy 351.098982 -129.342545) (xy 351.153408 -129.371108) (xy 351.203994 -129.406023) (xy 351.250003 -129.446781)
			(xy 351.290764 -129.492788) (xy 351.325681 -129.543373) (xy 351.354246 -129.597798) (xy 351.376043 -129.65527)
			(xy 351.390753 -129.714949) (xy 351.398162 -129.775967) (xy 351.398586 -129.8067) (xy 351.398154 -129.836036)
			(xy 351.391369 -129.894316) (xy 351.377923 -129.951429) (xy 351.36836 -129.979166) (xy 351.366074 -129.987802)
			(xy 351.363788 -130.00101) (xy 351.364042 -130.007106) (xy 351.365566 -130.019552) (xy 351.42043 -130.098292)
			(xy 351.42692 -130.1067) (xy 351.445031 -130.117748) (xy 351.455482 -130.119628) (xy 351.45599 -130.119628)
			(xy 351.462086 -130.120136) (xy 359.977182 -130.120136) (xy 359.987245 -130.120575) (xy 360.005824 -130.128314)
			(xy 360.01325 -130.135122) (xy 360.203961 -130.325833) (xy 444.897758 -130.325833) (xy 444.897758 -130.261911)
			(xy 444.905769 -130.198493) (xy 444.921666 -130.136579) (xy 444.945198 -130.077146) (xy 444.975992 -130.021131)
			(xy 445.013565 -129.969416) (xy 445.057322 -129.922819) (xy 445.106575 -129.882074) (xy 445.160546 -129.847823)
			(xy 445.218385 -129.820606) (xy 445.279178 -129.800853) (xy 445.341968 -129.788875) (xy 445.405764 -129.784862)
			(xy 445.46956 -129.788875) (xy 445.53235 -129.800853) (xy 445.593143 -129.820606) (xy 445.650982 -129.847823)
			(xy 445.704953 -129.882074) (xy 445.754206 -129.922819) (xy 445.797963 -129.969416) (xy 445.835536 -130.021131)
			(xy 445.86633 -130.077146) (xy 445.889862 -130.136579) (xy 445.905759 -130.198493) (xy 445.91377 -130.261911)
			(xy 445.914272 -130.293872) (xy 445.91377 -130.325833) (xy 445.905759 -130.389251) (xy 445.889862 -130.451165)
			(xy 445.86633 -130.510598) (xy 445.835536 -130.566613) (xy 445.797963 -130.618328) (xy 445.754206 -130.664925)
			(xy 445.704953 -130.70567) (xy 445.650982 -130.739921) (xy 445.593143 -130.767138) (xy 445.53235 -130.786891)
			(xy 445.46956 -130.798869) (xy 445.405764 -130.802883) (xy 445.341968 -130.798869) (xy 445.279178 -130.786891)
			(xy 445.218385 -130.767138) (xy 445.160546 -130.739921) (xy 445.106575 -130.70567) (xy 445.057322 -130.664925)
			(xy 445.013565 -130.618328) (xy 444.975992 -130.566613) (xy 444.945198 -130.510598) (xy 444.921666 -130.451165)
			(xy 444.905769 -130.389251) (xy 444.897758 -130.325833) (xy 360.203961 -130.325833) (xy 362.214668 -132.33654)
			(xy 362.217517 -132.339248) (xy 362.223893 -132.343847) (xy 362.227368 -132.345684) (xy 362.232795 -132.348265)
			(xy 362.244475 -132.351084) (xy 362.250482 -132.351272) (xy 402.841968 -132.351272) (xy 402.851959 -132.351803)
			(xy 402.870402 -132.359505) (xy 402.877782 -132.366258) (xy 403.052237 -132.540713) (xy 406.125166 -132.540713)
			(xy 406.125166 -132.476791) (xy 406.133177 -132.413373) (xy 406.149074 -132.351459) (xy 406.172606 -132.292026)
			(xy 406.2034 -132.236011) (xy 406.240973 -132.184296) (xy 406.28473 -132.137699) (xy 406.333983 -132.096954)
			(xy 406.387954 -132.062703) (xy 406.445793 -132.035486) (xy 406.506586 -132.015733) (xy 406.569376 -132.003755)
			(xy 406.633172 -131.999742) (xy 406.696968 -132.003755) (xy 406.759758 -132.015733) (xy 406.820551 -132.035486)
			(xy 406.87839 -132.062703) (xy 406.932361 -132.096954) (xy 406.981614 -132.137699) (xy 407.025371 -132.184296)
			(xy 407.062944 -132.236011) (xy 407.093738 -132.292026) (xy 407.11727 -132.351459) (xy 407.133167 -132.413373)
			(xy 407.141178 -132.476791) (xy 407.14168 -132.508752) (xy 407.141178 -132.540713) (xy 407.133167 -132.604131)
			(xy 407.11727 -132.666045) (xy 407.093738 -132.725478) (xy 407.062944 -132.781493) (xy 407.025371 -132.833208)
			(xy 406.981614 -132.879805) (xy 406.932361 -132.92055) (xy 406.87839 -132.954801) (xy 406.820551 -132.982018)
			(xy 406.759758 -133.001771) (xy 406.696968 -133.013749) (xy 406.633172 -133.017763) (xy 406.569376 -133.013749)
			(xy 406.506586 -133.001771) (xy 406.445793 -132.982018) (xy 406.387954 -132.954801) (xy 406.333983 -132.92055)
			(xy 406.28473 -132.879805) (xy 406.240973 -132.833208) (xy 406.2034 -132.781493) (xy 406.172606 -132.725478)
			(xy 406.149074 -132.666045) (xy 406.133177 -132.604131) (xy 406.125166 -132.540713) (xy 403.052237 -132.540713)
			(xy 404.445724 -133.9342) (xy 407.838656 -133.9342) (xy 407.838656 -133.933946) (xy 407.8391 -133.894068)
			(xy 407.846251 -133.814632) (xy 407.860492 -133.736157) (xy 407.881707 -133.659274) (xy 407.895298 -133.62178)
			(xy 407.898138 -133.613113) (xy 407.898138 -133.594887) (xy 407.895298 -133.58622) (xy 407.881725 -133.548721)
			(xy 407.860522 -133.471836) (xy 407.846281 -133.393363) (xy 407.839116 -133.313931) (xy 407.838656 -133.274054)
			(xy 407.838656 -133.2738) (xy 407.839167 -133.232699) (xy 407.846751 -133.150846) (xy 407.861855 -133.070043)
			(xy 407.884351 -132.990978) (xy 407.914045 -132.914326) (xy 407.950685 -132.84074) (xy 407.993958 -132.77085)
			(xy 408.043496 -132.705249) (xy 408.098874 -132.6445) (xy 408.159622 -132.589119) (xy 408.22522 -132.539579)
			(xy 408.295109 -132.496303) (xy 408.368693 -132.45966) (xy 408.445344 -132.429962) (xy 408.524408 -132.407464)
			(xy 408.605211 -132.392356) (xy 408.687063 -132.384768) (xy 408.728164 -132.384292) (xy 408.768213 -132.384742)
			(xy 408.847984 -132.391967) (xy 408.926782 -132.406335) (xy 409.003969 -132.42773) (xy 409.0416 -132.441442)
			(xy 409.050269 -132.444272) (xy 409.068491 -132.444272) (xy 409.07716 -132.441442) (xy 409.114787 -132.427719)
			(xy 409.191976 -132.406327) (xy 409.270775 -132.391962) (xy 409.350547 -132.384741) (xy 409.390596 -132.384292)
			(xy 409.39085 -132.384292) (xy 409.431953 -132.384719) (xy 409.513809 -132.392308) (xy 409.594615 -132.407418)
			(xy 409.673683 -132.429918) (xy 409.740793 -132.45592) (xy 414.117788 -132.45592) (xy 414.121859 -132.400298)
			(xy 414.133985 -132.345861) (xy 414.153908 -132.29377) (xy 414.181204 -132.245135) (xy 414.21529 -132.200992)
			(xy 414.255439 -132.162283) (xy 414.300797 -132.129832) (xy 414.350397 -132.104331) (xy 414.403181 -132.086324)
			(xy 414.458024 -132.076194) (xy 414.513758 -132.074157) (xy 414.569195 -132.080257) (xy 414.623152 -132.094363)
			(xy 414.674481 -132.116175) (xy 414.722087 -132.145229) (xy 414.764955 -132.180904) (xy 414.802172 -132.222441)
			(xy 414.832945 -132.268954) (xy 414.856617 -132.319451) (xy 414.872685 -132.372858) (xy 414.880805 -132.428034)
			(xy 414.881314 -132.45592) (xy 414.880805 -132.483806) (xy 414.872685 -132.538982) (xy 414.856617 -132.592389)
			(xy 414.832945 -132.642886) (xy 414.802172 -132.689399) (xy 414.764955 -132.730936) (xy 414.722087 -132.766611)
			(xy 414.674481 -132.795665) (xy 414.623152 -132.817477) (xy 414.569195 -132.831583) (xy 414.513758 -132.837683)
			(xy 414.458024 -132.835646) (xy 414.403181 -132.825516) (xy 414.350397 -132.807509) (xy 414.300797 -132.782008)
			(xy 414.255439 -132.749557) (xy 414.21529 -132.710848) (xy 414.181204 -132.666705) (xy 414.153908 -132.61807)
			(xy 414.133985 -132.565979) (xy 414.121859 -132.511542) (xy 414.117788 -132.45592) (xy 409.740793 -132.45592)
			(xy 409.750337 -132.459618) (xy 409.823924 -132.496264) (xy 409.893816 -132.539542) (xy 409.959416 -132.589085)
			(xy 410.020166 -132.644469) (xy 410.075547 -132.705222) (xy 410.125086 -132.770826) (xy 410.168361 -132.84072)
			(xy 410.205002 -132.914309) (xy 410.234698 -132.990965) (xy 410.257194 -133.070034) (xy 410.272299 -133.150841)
			(xy 410.279883 -133.232697) (xy 410.280329 -133.27126) (xy 415.397948 -133.27126) (xy 415.402019 -133.215638)
			(xy 415.414145 -133.161201) (xy 415.434068 -133.10911) (xy 415.461364 -133.060475) (xy 415.49545 -133.016332)
			(xy 415.535599 -132.977623) (xy 415.580957 -132.945172) (xy 415.630557 -132.919671) (xy 415.683341 -132.901664)
			(xy 415.738184 -132.891534) (xy 415.793918 -132.889497) (xy 415.849355 -132.895597) (xy 415.903312 -132.909703)
			(xy 415.954641 -132.931515) (xy 416.002247 -132.960569) (xy 416.045115 -132.996244) (xy 416.082332 -133.037781)
			(xy 416.113105 -133.084294) (xy 416.136777 -133.134791) (xy 416.152845 -133.188198) (xy 416.160965 -133.243374)
			(xy 416.161474 -133.27126) (xy 416.160965 -133.299146) (xy 416.152845 -133.354322) (xy 416.136777 -133.407729)
			(xy 416.113105 -133.458226) (xy 416.082332 -133.504739) (xy 416.045115 -133.546276) (xy 416.002247 -133.581951)
			(xy 415.954641 -133.611005) (xy 415.903312 -133.632817) (xy 415.849355 -133.646923) (xy 415.793918 -133.653023)
			(xy 415.738184 -133.650986) (xy 415.683341 -133.640856) (xy 415.630557 -133.622849) (xy 415.580957 -133.597348)
			(xy 415.535599 -133.564897) (xy 415.49545 -133.526188) (xy 415.461364 -133.482045) (xy 415.434068 -133.43341)
			(xy 415.414145 -133.381319) (xy 415.402019 -133.326882) (xy 415.397948 -133.27126) (xy 410.280329 -133.27126)
			(xy 410.280358 -133.2738) (xy 410.280358 -133.274054) (xy 410.279913 -133.313932) (xy 410.272762 -133.393368)
			(xy 410.258522 -133.471843) (xy 410.237307 -133.548726) (xy 410.223716 -133.58622) (xy 410.220876 -133.594887)
			(xy 410.220876 -133.613113) (xy 410.223716 -133.62178) (xy 410.23729 -133.659279) (xy 410.258492 -133.736164)
			(xy 410.272733 -133.814637) (xy 410.279898 -133.894069) (xy 410.280358 -133.933946) (xy 410.280358 -133.9342)
			(xy 410.279855 -133.977974) (xy 410.271244 -134.065096) (xy 410.254106 -134.15095) (xy 410.251271 -134.16026)
			(xy 415.397948 -134.16026) (xy 415.402019 -134.104638) (xy 415.414145 -134.050201) (xy 415.434068 -133.99811)
			(xy 415.461364 -133.949475) (xy 415.49545 -133.905332) (xy 415.535599 -133.866623) (xy 415.580957 -133.834172)
			(xy 415.630557 -133.808671) (xy 415.683341 -133.790664) (xy 415.738184 -133.780534) (xy 415.793918 -133.778497)
			(xy 415.849355 -133.784597) (xy 415.903312 -133.798703) (xy 415.954641 -133.820515) (xy 416.002247 -133.849569)
			(xy 416.045115 -133.885244) (xy 416.082332 -133.926781) (xy 416.113105 -133.973294) (xy 416.136777 -134.023791)
			(xy 416.152845 -134.077198) (xy 416.160965 -134.132374) (xy 416.161474 -134.16026) (xy 416.160965 -134.188146)
			(xy 416.152845 -134.243322) (xy 416.136777 -134.296729) (xy 416.113105 -134.347226) (xy 416.082332 -134.393739)
			(xy 416.045115 -134.435276) (xy 416.002247 -134.470951) (xy 415.954641 -134.500005) (xy 415.903312 -134.521817)
			(xy 415.849355 -134.535923) (xy 415.793918 -134.542023) (xy 415.738184 -134.539986) (xy 415.683341 -134.529856)
			(xy 415.630557 -134.511849) (xy 415.580957 -134.486348) (xy 415.535599 -134.453897) (xy 415.49545 -134.415188)
			(xy 415.461364 -134.371045) (xy 415.434068 -134.32241) (xy 415.414145 -134.270319) (xy 415.402019 -134.215882)
			(xy 415.397948 -134.16026) (xy 410.251271 -134.16026) (xy 410.228607 -134.234702) (xy 410.212286 -134.275322)
			(xy 410.208332 -134.286436) (xy 410.209963 -134.309946) (xy 410.221834 -134.330305) (xy 410.231336 -134.337298)
			(xy 410.268016 -134.361857) (xy 410.336779 -134.417218) (xy 410.39972 -134.479118) (xy 410.456219 -134.546948)
			(xy 410.505722 -134.620041) (xy 410.547741 -134.697679) (xy 410.581862 -134.779097) (xy 410.607751 -134.863495)
			(xy 410.625152 -134.950042) (xy 410.633894 -135.037887) (xy 410.634033 -135.04926) (xy 415.397948 -135.04926)
			(xy 415.402019 -134.993638) (xy 415.414145 -134.939201) (xy 415.434068 -134.88711) (xy 415.461364 -134.838475)
			(xy 415.49545 -134.794332) (xy 415.535599 -134.755623) (xy 415.580957 -134.723172) (xy 415.630557 -134.697671)
			(xy 415.683341 -134.679664) (xy 415.738184 -134.669534) (xy 415.793918 -134.667497) (xy 415.849355 -134.673597)
			(xy 415.903312 -134.687703) (xy 415.954641 -134.709515) (xy 416.002247 -134.738569) (xy 416.045115 -134.774244)
			(xy 416.082332 -134.815781) (xy 416.113105 -134.862294) (xy 416.136777 -134.912791) (xy 416.152845 -134.966198)
			(xy 416.160965 -135.021374) (xy 416.161474 -135.04926) (xy 416.160965 -135.077146) (xy 416.152845 -135.132322)
			(xy 416.136777 -135.185729) (xy 416.113105 -135.236226) (xy 416.082332 -135.282739) (xy 416.045115 -135.324276)
			(xy 416.002247 -135.359951) (xy 415.954641 -135.389005) (xy 415.903312 -135.410817) (xy 415.849355 -135.424923)
			(xy 415.793918 -135.431023) (xy 415.738184 -135.428986) (xy 415.683341 -135.418856) (xy 415.630557 -135.400849)
			(xy 415.580957 -135.375348) (xy 415.535599 -135.342897) (xy 415.49545 -135.304188) (xy 415.461364 -135.260045)
			(xy 415.434068 -135.21141) (xy 415.414145 -135.159319) (xy 415.402019 -135.104882) (xy 415.397948 -135.04926)
			(xy 410.634033 -135.04926) (xy 410.634434 -135.082026) (xy 410.63393 -135.124374) (xy 410.625879 -135.208688)
			(xy 410.60985 -135.291854) (xy 410.585989 -135.373121) (xy 410.55451 -135.451751) (xy 410.539662 -135.480552)
			(xy 410.814518 -135.480552) (xy 410.818589 -135.42493) (xy 410.830715 -135.370493) (xy 410.850638 -135.318402)
			(xy 410.877934 -135.269767) (xy 410.91202 -135.225624) (xy 410.952169 -135.186915) (xy 410.997527 -135.154464)
			(xy 411.047127 -135.128963) (xy 411.099911 -135.110956) (xy 411.154754 -135.100826) (xy 411.210488 -135.098789)
			(xy 411.265925 -135.104889) (xy 411.319882 -135.118995) (xy 411.371211 -135.140807) (xy 411.418817 -135.169861)
			(xy 411.461685 -135.205536) (xy 411.498902 -135.247073) (xy 411.529675 -135.293586) (xy 411.553347 -135.344083)
			(xy 411.569415 -135.39749) (xy 411.577535 -135.452666) (xy 411.578044 -135.480552) (xy 411.577535 -135.508438)
			(xy 411.569415 -135.563614) (xy 411.553347 -135.617021) (xy 411.529675 -135.667518) (xy 411.498902 -135.714031)
			(xy 411.461685 -135.755568) (xy 411.418817 -135.791243) (xy 411.371211 -135.820297) (xy 411.319882 -135.842109)
			(xy 411.265925 -135.856215) (xy 411.210488 -135.862315) (xy 411.154754 -135.860278) (xy 411.099911 -135.850148)
			(xy 411.047127 -135.832141) (xy 410.997527 -135.80664) (xy 410.952169 -135.774189) (xy 410.91202 -135.73548)
			(xy 410.877934 -135.691337) (xy 410.850638 -135.642702) (xy 410.830715 -135.590611) (xy 410.818589 -135.536174)
			(xy 410.814518 -135.480552) (xy 410.539662 -135.480552) (xy 410.515699 -135.527032) (xy 410.469909 -135.598284)
			(xy 410.417553 -135.66486) (xy 410.359105 -135.726158) (xy 410.295095 -135.781623) (xy 410.226103 -135.830752)
			(xy 410.152753 -135.873101) (xy 410.07571 -135.908285) (xy 409.995671 -135.935987) (xy 409.986302 -135.93826)
			(xy 415.397948 -135.93826) (xy 415.402019 -135.882638) (xy 415.414145 -135.828201) (xy 415.434068 -135.77611)
			(xy 415.461364 -135.727475) (xy 415.49545 -135.683332) (xy 415.535599 -135.644623) (xy 415.580957 -135.612172)
			(xy 415.630557 -135.586671) (xy 415.683341 -135.568664) (xy 415.738184 -135.558534) (xy 415.793918 -135.556497)
			(xy 415.849355 -135.562597) (xy 415.903312 -135.576703) (xy 415.954641 -135.598515) (xy 416.002247 -135.627569)
			(xy 416.045115 -135.663244) (xy 416.082332 -135.704781) (xy 416.113105 -135.751294) (xy 416.136777 -135.801791)
			(xy 416.152845 -135.855198) (xy 416.160965 -135.910374) (xy 416.161474 -135.93826) (xy 416.160965 -135.966146)
			(xy 416.152845 -136.021322) (xy 416.136777 -136.074729) (xy 416.113105 -136.125226) (xy 416.082332 -136.171739)
			(xy 416.045115 -136.213276) (xy 416.002247 -136.248951) (xy 415.954641 -136.278005) (xy 415.903312 -136.299817)
			(xy 415.849355 -136.313923) (xy 415.793918 -136.320023) (xy 415.738184 -136.317986) (xy 415.683341 -136.307856)
			(xy 415.630557 -136.289849) (xy 415.580957 -136.264348) (xy 415.535599 -136.231897) (xy 415.49545 -136.193188)
			(xy 415.461364 -136.149045) (xy 415.434068 -136.10041) (xy 415.414145 -136.048319) (xy 415.402019 -135.993882)
			(xy 415.397948 -135.93826) (xy 409.986302 -135.93826) (xy 409.913362 -135.955955) (xy 409.829527 -135.968008)
			(xy 409.744926 -135.972039) (xy 409.660325 -135.968008) (xy 409.57649 -135.955955) (xy 409.494181 -135.935987)
			(xy 409.414142 -135.908285) (xy 409.337099 -135.873101) (xy 409.263749 -135.830752) (xy 409.194757 -135.781623)
			(xy 409.130747 -135.726158) (xy 409.072299 -135.66486) (xy 409.019943 -135.598284) (xy 408.974153 -135.527032)
			(xy 408.935342 -135.451751) (xy 408.903863 -135.373121) (xy 408.880002 -135.291854) (xy 408.863973 -135.208688)
			(xy 408.855922 -135.124374) (xy 408.855418 -135.082026) (xy 408.855418 -135.080756) (xy 408.855783 -135.045615)
			(xy 408.861381 -134.975556) (xy 408.866594 -134.940802) (xy 408.868626 -134.929372) (xy 408.862276 -134.907528)
			(xy 408.802332 -134.839964) (xy 408.794489 -134.831955) (xy 408.773917 -134.823123) (xy 408.762708 -134.822946)
			(xy 408.7622 -134.822946) (xy 408.728164 -134.823708) (xy 408.687061 -134.823268) (xy 408.605206 -134.81568)
			(xy 408.5244 -134.800571) (xy 408.445332 -134.778072) (xy 408.368678 -134.748373) (xy 408.295091 -134.711729)
			(xy 408.225199 -134.668451) (xy 408.159599 -134.618909) (xy 408.098849 -134.563526) (xy 408.043468 -134.502774)
			(xy 407.993929 -134.437171) (xy 407.950654 -134.367277) (xy 407.914012 -134.293689) (xy 407.884317 -134.217033)
			(xy 407.86182 -134.137965) (xy 407.846715 -134.057159) (xy 407.839131 -133.975303) (xy 407.838656 -133.9342)
			(xy 404.445724 -133.9342) (xy 405.442928 -134.931404) (xy 407.260042 -134.931404) (xy 407.264113 -134.875782)
			(xy 407.276239 -134.821345) (xy 407.296162 -134.769254) (xy 407.323458 -134.720619) (xy 407.357544 -134.676476)
			(xy 407.397693 -134.637767) (xy 407.443051 -134.605316) (xy 407.492651 -134.579815) (xy 407.545435 -134.561808)
			(xy 407.600278 -134.551678) (xy 407.656012 -134.549641) (xy 407.711449 -134.555741) (xy 407.765406 -134.569847)
			(xy 407.816735 -134.591659) (xy 407.864341 -134.620713) (xy 407.907209 -134.656388) (xy 407.944426 -134.697925)
			(xy 407.975199 -134.744438) (xy 407.998871 -134.794935) (xy 408.014939 -134.848342) (xy 408.023059 -134.903518)
			(xy 408.023568 -134.931404) (xy 408.023059 -134.95929) (xy 408.014939 -135.014466) (xy 407.998871 -135.067873)
			(xy 407.975199 -135.11837) (xy 407.944426 -135.164883) (xy 407.907209 -135.20642) (xy 407.864341 -135.242095)
			(xy 407.816735 -135.271149) (xy 407.765406 -135.292961) (xy 407.711449 -135.307067) (xy 407.656012 -135.313167)
			(xy 407.600278 -135.31113) (xy 407.545435 -135.301) (xy 407.492651 -135.282993) (xy 407.443051 -135.257492)
			(xy 407.397693 -135.225041) (xy 407.357544 -135.186332) (xy 407.323458 -135.142189) (xy 407.296162 -135.093554)
			(xy 407.276239 -135.041463) (xy 407.264113 -134.987026) (xy 407.260042 -134.931404) (xy 405.442928 -134.931404)
			(xy 407.338784 -136.82726) (xy 415.397948 -136.82726) (xy 415.402019 -136.771638) (xy 415.414145 -136.717201)
			(xy 415.434068 -136.66511) (xy 415.461364 -136.616475) (xy 415.49545 -136.572332) (xy 415.535599 -136.533623)
			(xy 415.580957 -136.501172) (xy 415.630557 -136.475671) (xy 415.683341 -136.457664) (xy 415.738184 -136.447534)
			(xy 415.793918 -136.445497) (xy 415.849355 -136.451597) (xy 415.903312 -136.465703) (xy 415.954641 -136.487515)
			(xy 416.002247 -136.516569) (xy 416.045115 -136.552244) (xy 416.082332 -136.593781) (xy 416.113105 -136.640294)
			(xy 416.136777 -136.690791) (xy 416.152845 -136.744198) (xy 416.160965 -136.799374) (xy 416.161474 -136.82726)
			(xy 416.160965 -136.855146) (xy 416.152845 -136.910322) (xy 416.136777 -136.963729) (xy 416.113105 -137.014226)
			(xy 416.082332 -137.060739) (xy 416.045115 -137.102276) (xy 416.002247 -137.137951) (xy 415.954641 -137.167005)
			(xy 415.903312 -137.188817) (xy 415.849355 -137.202923) (xy 415.793918 -137.209023) (xy 415.738184 -137.206986)
			(xy 415.683341 -137.196856) (xy 415.630557 -137.178849) (xy 415.580957 -137.153348) (xy 415.535599 -137.120897)
			(xy 415.49545 -137.082188) (xy 415.461364 -137.038045) (xy 415.434068 -136.98941) (xy 415.414145 -136.937319)
			(xy 415.402019 -136.882882) (xy 415.397948 -136.82726) (xy 407.338784 -136.82726) (xy 408.419765 -137.908241)
			(xy 410.68218 -137.908241) (xy 410.68218 -137.844319) (xy 410.690191 -137.780901) (xy 410.706088 -137.718987)
			(xy 410.72962 -137.659554) (xy 410.760414 -137.603539) (xy 410.797987 -137.551824) (xy 410.841744 -137.505227)
			(xy 410.890997 -137.464482) (xy 410.944968 -137.430231) (xy 411.002807 -137.403014) (xy 411.0636 -137.383261)
			(xy 411.12639 -137.371283) (xy 411.190186 -137.36727) (xy 411.253982 -137.371283) (xy 411.316772 -137.383261)
			(xy 411.377565 -137.403014) (xy 411.435404 -137.430231) (xy 411.489375 -137.464482) (xy 411.538628 -137.505227)
			(xy 411.582385 -137.551824) (xy 411.619958 -137.603539) (xy 411.650752 -137.659554) (xy 411.674284 -137.718987)
			(xy 411.690181 -137.780901) (xy 411.698192 -137.844319) (xy 411.698694 -137.87628) (xy 411.698192 -137.908241)
			(xy 411.690181 -137.971659) (xy 411.674284 -138.033573) (xy 411.650752 -138.093006) (xy 411.619958 -138.149021)
			(xy 411.582385 -138.200736) (xy 411.538628 -138.247333) (xy 411.489375 -138.288078) (xy 411.435404 -138.322329)
			(xy 411.383923 -138.346554) (xy 414.349634 -138.346554) (xy 414.349634 -138.292046) (xy 414.357391 -138.238093)
			(xy 414.372748 -138.185793) (xy 414.395391 -138.13621) (xy 414.42486 -138.090355) (xy 414.460554 -138.04916)
			(xy 414.501748 -138.013464) (xy 414.547603 -137.983995) (xy 414.597185 -137.96135) (xy 414.649485 -137.945993)
			(xy 414.703438 -137.938234) (xy 414.730692 -137.937748) (xy 414.758331 -137.938217) (xy 414.813027 -137.946215)
			(xy 414.865998 -137.962014) (xy 414.916138 -137.985286) (xy 414.962399 -138.015544) (xy 415.003815 -138.052156)
			(xy 415.039518 -138.094356) (xy 415.068765 -138.141263) (xy 415.090943 -138.191897) (xy 415.098738 -138.218418)
			(xy 415.10204 -138.230864) (xy 415.119312 -138.249152) (xy 415.223706 -138.28395) (xy 415.248852 -138.279632)
			(xy 415.258758 -138.271758) (xy 415.277667 -138.257567) (xy 415.318335 -138.233455) (xy 415.361667 -138.214545)
			(xy 415.384234 -138.207496) (xy 415.384488 -138.207496) (xy 415.395956 -138.203294) (xy 415.413464 -138.186317)
			(xy 415.418016 -138.174984) (xy 415.444432 -138.095736) (xy 415.447634 -138.083848) (xy 415.443787 -138.059569)
			(xy 415.437066 -138.049254) (xy 415.419268 -138.024421) (xy 415.391019 -137.97025) (xy 415.371764 -137.91227)
			(xy 415.361994 -137.851963) (xy 415.361374 -137.821416) (xy 415.361893 -137.794166) (xy 415.369647 -137.74022)
			(xy 415.384999 -137.687927) (xy 415.407637 -137.638352) (xy 415.4371 -137.592502) (xy 415.472788 -137.551312)
			(xy 415.513975 -137.51562) (xy 415.559822 -137.486153) (xy 415.609396 -137.463511) (xy 415.661687 -137.448154)
			(xy 415.715632 -137.440396) (xy 415.742882 -137.439908) (xy 415.771389 -137.440431) (xy 415.827766 -137.448926)
			(xy 415.882253 -137.465714) (xy 415.933635 -137.490421) (xy 415.980769 -137.522499) (xy 416.022606 -137.561232)
			(xy 416.040824 -137.583164) (xy 416.048444 -137.592816) (xy 416.070796 -137.602722) (xy 416.17773 -137.597134)
			(xy 416.198812 -137.584942) (xy 416.205416 -137.574528) (xy 416.220542 -137.551845) (xy 416.256253 -137.510649)
			(xy 416.297463 -137.474954) (xy 416.343334 -137.445487) (xy 416.392931 -137.422848) (xy 416.445246 -137.407498)
			(xy 416.499212 -137.399749) (xy 416.526472 -137.399268) (xy 416.553723 -137.399781) (xy 416.607671 -137.407534)
			(xy 416.659966 -137.422885) (xy 416.709545 -137.445523) (xy 416.755397 -137.474985) (xy 416.796589 -137.510674)
			(xy 416.832283 -137.551861) (xy 416.861752 -137.597709) (xy 416.884397 -137.647285) (xy 416.899755 -137.699578)
			(xy 416.907515 -137.753525) (xy 416.90798 -137.780776) (xy 416.907598 -137.807116) (xy 416.900366 -137.859297)
			(xy 416.886021 -137.909987) (xy 416.864837 -137.95822) (xy 416.837217 -138.003079) (xy 416.803687 -138.043711)
			(xy 416.764885 -138.079341) (xy 416.721548 -138.109293) (xy 416.674502 -138.132997) (xy 416.624641 -138.15)
			(xy 416.598862 -138.155426) (xy 416.5854 -138.157966) (xy 416.56508 -138.175746) (xy 416.527488 -138.284966)
			(xy 416.532822 -138.31189) (xy 416.541712 -138.32205) (xy 416.559451 -138.342991) (xy 416.589326 -138.389029)
			(xy 416.612287 -138.438875) (xy 416.627861 -138.4915) (xy 416.635726 -138.545815) (xy 416.6362 -138.573256)
			(xy 416.635775 -138.599636) (xy 416.628515 -138.651894) (xy 416.614127 -138.702655) (xy 416.592885 -138.75095)
			(xy 416.565195 -138.79586) (xy 416.531583 -138.836528) (xy 416.492691 -138.87218) (xy 416.44926 -138.902135)
			(xy 416.425888 -138.914378) (xy 416.412934 -138.920728) (xy 416.397694 -138.945366) (xy 416.397694 -139.064746)
			(xy 416.412934 -139.089384) (xy 416.425888 -139.095734) (xy 416.449237 -139.108014) (xy 416.492661 -139.137971)
			(xy 416.531548 -139.17362) (xy 416.565156 -139.214283) (xy 416.592845 -139.259187) (xy 416.614089 -139.307475)
			(xy 416.628483 -139.358228) (xy 416.635752 -139.410479) (xy 416.6362 -139.436856) (xy 416.635749 -139.464101)
			(xy 416.627985 -139.518035) (xy 416.612623 -139.570314) (xy 416.589975 -139.619875) (xy 416.560503 -139.665707)
			(xy 416.524807 -139.706877) (xy 416.483615 -139.742547) (xy 416.46094 -139.757658) (xy 416.453942 -139.762539)
			(xy 416.443391 -139.775932) (xy 416.437853 -139.792057) (xy 416.437572 -139.800584) (xy 416.437572 -139.885928)
			(xy 416.4379 -139.894447) (xy 416.443447 -139.910557) (xy 416.453955 -139.923968) (xy 416.46094 -139.928854)
			(xy 416.483547 -139.944051) (xy 416.52471 -139.979724) (xy 416.560378 -140.020892) (xy 416.589825 -140.066716)
			(xy 416.612453 -140.116263) (xy 416.627799 -140.168526) (xy 416.635553 -140.222441) (xy 416.635557 -140.276911)
			(xy 416.627809 -140.330827) (xy 416.612469 -140.383092) (xy 416.589848 -140.432643) (xy 416.560407 -140.47847)
			(xy 416.54938 -140.4912) (xy 429.506399 -140.4912) (xy 429.510413 -140.427406) (xy 429.522391 -140.364617)
			(xy 429.542143 -140.303825) (xy 429.569359 -140.245988) (xy 429.603609 -140.192018) (xy 429.644353 -140.142767)
			(xy 429.690949 -140.09901) (xy 429.742662 -140.061438) (xy 429.798676 -140.030644) (xy 429.858107 -140.007113)
			(xy 429.920019 -139.991216) (xy 429.983436 -139.983204) (xy 430.015396 -139.982702) (xy 430.046683 -139.983216)
			(xy 430.108783 -139.990886) (xy 430.169473 -140.006124) (xy 430.227832 -140.028698) (xy 430.282977 -140.058267)
			(xy 430.334075 -140.094383) (xy 430.380351 -140.1365) (xy 430.421106 -140.183981) (xy 430.438814 -140.209778)
			(xy 430.446347 -140.21992) (xy 430.468613 -140.231785) (xy 430.481232 -140.232384) (xy 430.56556 -140.232384)
			(xy 430.578162 -140.231717) (xy 430.600409 -140.219874) (xy 430.607978 -140.209778) (xy 430.625694 -140.18399)
			(xy 430.66646 -140.136527) (xy 430.712742 -140.094426) (xy 430.763841 -140.058322) (xy 430.818983 -140.028761)
			(xy 430.877337 -140.00619) (xy 430.938019 -139.990951) (xy 431.000113 -139.983273) (xy 431.062679 -139.983273)
			(xy 431.124773 -139.990951) (xy 431.185455 -140.00619) (xy 431.243809 -140.028761) (xy 431.298951 -140.058322)
			(xy 431.35005 -140.094426) (xy 431.396332 -140.136527) (xy 431.437098 -140.18399) (xy 431.454814 -140.209778)
			(xy 431.462347 -140.21992) (xy 431.484613 -140.231785) (xy 431.497232 -140.232384) (xy 431.58156 -140.232384)
			(xy 431.594162 -140.231717) (xy 431.616409 -140.219874) (xy 431.623978 -140.209778) (xy 431.641694 -140.18399)
			(xy 431.68246 -140.136527) (xy 431.728742 -140.094426) (xy 431.779841 -140.058322) (xy 431.834983 -140.028761)
			(xy 431.893337 -140.00619) (xy 431.954019 -139.990951) (xy 432.016113 -139.983273) (xy 432.078679 -139.983273)
			(xy 432.140773 -139.990951) (xy 432.201455 -140.00619) (xy 432.259809 -140.028761) (xy 432.314951 -140.058322)
			(xy 432.36605 -140.094426) (xy 432.412332 -140.136527) (xy 432.453098 -140.18399) (xy 432.470814 -140.209778)
			(xy 432.478347 -140.21992) (xy 432.500613 -140.231785) (xy 432.513232 -140.232384) (xy 432.59756 -140.232384)
			(xy 432.610162 -140.231717) (xy 432.632409 -140.219874) (xy 432.639978 -140.209778) (xy 432.657692 -140.183984)
			(xy 432.698448 -140.136503) (xy 432.744724 -140.094385) (xy 432.79582 -140.058265) (xy 432.850964 -140.028692)
			(xy 432.909321 -140.006111) (xy 432.970009 -139.990864) (xy 433.032109 -139.983182) (xy 433.063396 -139.982702)
			(xy 433.095359 -139.983163) (xy 433.158781 -139.991174) (xy 433.220699 -140.007072) (xy 433.280137 -140.030604)
			(xy 433.336156 -140.061401) (xy 433.387874 -140.098975) (xy 433.434474 -140.142736) (xy 433.475222 -140.191992)
			(xy 433.509476 -140.245966) (xy 433.536694 -140.303808) (xy 433.556449 -140.364606) (xy 433.568428 -140.4274)
			(xy 433.572442 -140.4912) (xy 433.568428 -140.555) (xy 433.556449 -140.617794) (xy 433.536694 -140.678592)
			(xy 433.509476 -140.736434) (xy 433.475222 -140.790408) (xy 433.434474 -140.839664) (xy 433.387874 -140.883425)
			(xy 433.336156 -140.920999) (xy 433.280137 -140.951796) (xy 433.220699 -140.975328) (xy 433.158781 -140.991226)
			(xy 433.095359 -140.999237) (xy 433.063396 -140.999718) (xy 433.03211 -140.999201) (xy 432.970009 -140.99153)
			(xy 432.90932 -140.976293) (xy 432.850962 -140.953719) (xy 432.795816 -140.92415) (xy 432.744719 -140.888034)
			(xy 432.698442 -140.845918) (xy 432.657687 -140.798439) (xy 432.639978 -140.772642) (xy 432.632445 -140.7625)
			(xy 432.610179 -140.750634) (xy 432.59756 -140.750036) (xy 432.513232 -140.750036) (xy 432.500628 -140.75069)
			(xy 432.47838 -140.762541) (xy 432.470814 -140.772642) (xy 432.453098 -140.79843) (xy 432.412332 -140.845893)
			(xy 432.36605 -140.887994) (xy 432.314951 -140.924098) (xy 432.259809 -140.953659) (xy 432.201455 -140.97623)
			(xy 432.140773 -140.991469) (xy 432.078679 -140.999147) (xy 432.016113 -140.999147) (xy 431.954019 -140.991469)
			(xy 431.893337 -140.97623) (xy 431.834983 -140.953659) (xy 431.779841 -140.924098) (xy 431.728742 -140.887994)
			(xy 431.68246 -140.845893) (xy 431.641694 -140.79843) (xy 431.623978 -140.772642) (xy 431.616445 -140.7625)
			(xy 431.594179 -140.750634) (xy 431.58156 -140.750036) (xy 431.497232 -140.750036) (xy 431.484628 -140.75069)
			(xy 431.46238 -140.762541) (xy 431.454814 -140.772642) (xy 431.437098 -140.79843) (xy 431.396332 -140.845893)
			(xy 431.35005 -140.887994) (xy 431.298951 -140.924098) (xy 431.243809 -140.953659) (xy 431.185455 -140.97623)
			(xy 431.124773 -140.991469) (xy 431.062679 -140.999147) (xy 431.000113 -140.999147) (xy 430.938019 -140.991469)
			(xy 430.877337 -140.97623) (xy 430.818983 -140.953659) (xy 430.763841 -140.924098) (xy 430.712742 -140.887994)
			(xy 430.66646 -140.845893) (xy 430.625694 -140.79843) (xy 430.607978 -140.772642) (xy 430.600445 -140.7625)
			(xy 430.578179 -140.750634) (xy 430.56556 -140.750036) (xy 430.481232 -140.750036) (xy 430.468628 -140.75069)
			(xy 430.44638 -140.762541) (xy 430.438814 -140.772642) (xy 430.421112 -140.798444) (xy 430.380354 -140.845924)
			(xy 430.334076 -140.888041) (xy 430.282977 -140.92416) (xy 430.227832 -140.953732) (xy 430.169473 -140.976312)
			(xy 430.108785 -140.991558) (xy 430.046683 -140.999238) (xy 430.015396 -140.999718) (xy 429.983436 -140.999196)
			(xy 429.920019 -140.991184) (xy 429.858107 -140.975287) (xy 429.798676 -140.951756) (xy 429.742662 -140.920962)
			(xy 429.690949 -140.88339) (xy 429.644353 -140.839633) (xy 429.603609 -140.790382) (xy 429.569359 -140.736412)
			(xy 429.542143 -140.678575) (xy 429.522391 -140.617783) (xy 429.510413 -140.554994) (xy 429.506399 -140.4912)
			(xy 416.54938 -140.4912) (xy 416.524744 -140.519642) (xy 416.483586 -140.55532) (xy 416.46094 -140.570458)
			(xy 416.453942 -140.575339) (xy 416.443391 -140.588732) (xy 416.437853 -140.604857) (xy 416.437572 -140.613384)
			(xy 416.437572 -140.698728) (xy 416.4379 -140.707247) (xy 416.443447 -140.723357) (xy 416.453955 -140.736768)
			(xy 416.46094 -140.741654) (xy 416.483634 -140.756738) (xy 416.524829 -140.792409) (xy 416.560525 -140.833583)
			(xy 416.589994 -140.87942) (xy 416.612636 -140.928986) (xy 416.627989 -140.981271) (xy 416.63574 -141.03521)
			(xy 416.6362 -141.062456) (xy 416.635704 -141.089708) (xy 416.627953 -141.143658) (xy 416.612602 -141.195956)
			(xy 416.589964 -141.245537) (xy 416.5605 -141.29139) (xy 416.524809 -141.332584) (xy 416.49271 -141.3604)
			(xy 448.573366 -141.3604) (xy 448.577381 -141.2966) (xy 448.589359 -141.233806) (xy 448.609114 -141.173009)
			(xy 448.636333 -141.115167) (xy 448.670587 -141.061193) (xy 448.711335 -141.011938) (xy 448.757936 -140.968178)
			(xy 448.809654 -140.930604) (xy 448.865673 -140.899808) (xy 448.925111 -140.876277) (xy 448.987029 -140.860381)
			(xy 449.050451 -140.85237) (xy 449.082414 -140.85189) (xy 449.115433 -140.85243) (xy 449.180914 -140.860981)
			(xy 449.244738 -140.877936) (xy 449.305829 -140.903012) (xy 449.36316 -140.935785) (xy 449.415766 -140.975703)
			(xy 449.462762 -141.022097) (xy 449.503357 -141.074183) (xy 449.536867 -141.131087) (xy 449.550282 -141.161262)
			(xy 449.55507 -141.17112) (xy 449.571263 -141.185859) (xy 449.581524 -141.18971) (xy 449.66509 -141.216888)
			(xy 449.68668 -141.214348) (xy 449.696332 -141.208506) (xy 449.718794 -141.195459) (xy 449.766473 -141.174842)
			(xy 449.816507 -141.160879) (xy 449.867971 -141.153829) (xy 449.893944 -141.153388) (xy 449.920878 -141.153854)
			(xy 449.97421 -141.161442) (xy 450.025943 -141.17646) (xy 450.075047 -141.198609) (xy 450.120545 -141.227449)
			(xy 450.14134 -141.244574) (xy 450.148605 -141.25024) (xy 450.165914 -141.256503) (xy 450.175122 -141.256766)
			(xy 450.20611 -141.256004) (xy 450.215433 -141.255481) (xy 450.232765 -141.248576) (xy 450.239892 -141.242542)
			(xy 450.263489 -141.221207) (xy 450.31505 -141.183945) (xy 450.370859 -141.153411) (xy 450.430043 -141.130082)
			(xy 450.491676 -141.114324) (xy 450.554794 -141.106383) (xy 450.586602 -141.10589) (xy 450.618563 -141.106396)
			(xy 450.68198 -141.114408) (xy 450.743894 -141.130305) (xy 450.803327 -141.153836) (xy 450.859341 -141.184631)
			(xy 450.911055 -141.222203) (xy 450.957652 -141.26596) (xy 450.998397 -141.315213) (xy 451.032648 -141.369184)
			(xy 451.059864 -141.427022) (xy 451.079617 -141.487815) (xy 451.091595 -141.550604) (xy 451.095609 -141.6144)
			(xy 451.091595 -141.678196) (xy 451.079617 -141.740985) (xy 451.059864 -141.801778) (xy 451.053972 -141.8143)
			(xy 451.452464 -141.8143) (xy 451.456478 -141.750501) (xy 451.468457 -141.687707) (xy 451.488211 -141.626911)
			(xy 451.515429 -141.569069) (xy 451.549683 -141.515095) (xy 451.59043 -141.46584) (xy 451.63703 -141.42208)
			(xy 451.688747 -141.384506) (xy 451.744766 -141.35371) (xy 451.804202 -141.330177) (xy 451.86612 -141.31428)
			(xy 451.929541 -141.306269) (xy 451.961504 -141.305788) (xy 451.961758 -141.305788) (xy 451.991967 -141.306189)
			(xy 452.05196 -141.313335) (xy 452.110683 -141.327544) (xy 452.167307 -141.348614) (xy 452.221034 -141.37625)
			(xy 452.271106 -141.41006) (xy 452.294244 -141.429486) (xy 452.301306 -141.435142) (xy 452.318225 -141.441522)
			(xy 452.327264 -141.441932) (xy 452.357744 -141.441932) (xy 452.366781 -141.441512) (xy 452.383698 -141.435135)
			(xy 452.390764 -141.429486) (xy 452.413928 -141.410061) (xy 452.464045 -141.376251) (xy 452.517815 -141.348618)
			(xy 452.574481 -141.327552) (xy 452.633244 -141.313349) (xy 452.693276 -141.306209) (xy 452.723504 -141.305788)
			(xy 452.753734 -141.306175) (xy 452.813773 -141.313302) (xy 452.872541 -141.327501) (xy 452.929211 -141.348572)
			(xy 452.98298 -141.376217) (xy 453.033089 -141.410047) (xy 453.056244 -141.429486) (xy 453.063306 -141.435142)
			(xy 453.080225 -141.441522) (xy 453.089264 -141.441932) (xy 453.119744 -141.441932) (xy 453.128781 -141.441512)
			(xy 453.145698 -141.435135) (xy 453.152764 -141.429486) (xy 453.175928 -141.410061) (xy 453.226045 -141.376251)
			(xy 453.279815 -141.348618) (xy 453.336481 -141.327552) (xy 453.395244 -141.313349) (xy 453.455276 -141.306209)
			(xy 453.485504 -141.305788) (xy 453.515734 -141.306175) (xy 453.575773 -141.313302) (xy 453.634541 -141.327501)
			(xy 453.691211 -141.348572) (xy 453.74498 -141.376217) (xy 453.795089 -141.410047) (xy 453.818244 -141.429486)
			(xy 453.825306 -141.435142) (xy 453.842225 -141.441522) (xy 453.851264 -141.441932) (xy 453.881744 -141.441932)
			(xy 453.890781 -141.441512) (xy 453.907698 -141.435135) (xy 453.914764 -141.429486) (xy 453.937898 -141.410058)
			(xy 453.987981 -141.376272) (xy 454.041713 -141.348654) (xy 454.098336 -141.327591) (xy 454.157055 -141.313381)
			(xy 454.217043 -141.306222) (xy 454.24725 -141.305788) (xy 454.247504 -141.305788) (xy 454.279465 -141.306298)
			(xy 454.342882 -141.31431) (xy 454.404795 -141.330207) (xy 454.464227 -141.353738) (xy 454.520241 -141.384533)
			(xy 454.571955 -141.422105) (xy 454.618551 -141.465862) (xy 454.659296 -141.515115) (xy 454.693546 -141.569085)
			(xy 454.720763 -141.626923) (xy 454.740515 -141.687716) (xy 454.752493 -141.750505) (xy 454.756507 -141.8143)
			(xy 454.752493 -141.878095) (xy 454.740515 -141.940884) (xy 454.720763 -142.001677) (xy 454.693546 -142.059515)
			(xy 454.659296 -142.113485) (xy 454.618551 -142.162738) (xy 454.571955 -142.206495) (xy 454.520241 -142.244067)
			(xy 454.464227 -142.274862) (xy 454.404795 -142.298393) (xy 454.342882 -142.31429) (xy 454.279465 -142.322302)
			(xy 454.247504 -142.322804) (xy 454.24725 -142.322804) (xy 454.217041 -142.3224) (xy 454.157048 -142.315255)
			(xy 454.098325 -142.301047) (xy 454.041701 -142.279977) (xy 453.987974 -142.252342) (xy 453.937902 -142.218532)
			(xy 453.914764 -142.199106) (xy 453.9077 -142.193452) (xy 453.890782 -142.187071) (xy 453.881744 -142.18666)
			(xy 453.851264 -142.18666) (xy 453.842228 -142.187086) (xy 453.825311 -142.193459) (xy 453.818244 -142.199106)
			(xy 453.795089 -142.218542) (xy 453.744969 -142.252348) (xy 453.691196 -142.279977) (xy 453.634529 -142.301042)
			(xy 453.575765 -142.315243) (xy 453.515732 -142.322383) (xy 453.485504 -142.322804) (xy 453.455274 -142.322414)
			(xy 453.395236 -142.315288) (xy 453.336467 -142.30109) (xy 453.279797 -142.280019) (xy 453.226028 -142.252374)
			(xy 453.175919 -142.218545) (xy 453.152764 -142.199106) (xy 453.1457 -142.193452) (xy 453.128782 -142.187071)
			(xy 453.119744 -142.18666) (xy 453.089264 -142.18666) (xy 453.080228 -142.187086) (xy 453.063311 -142.193459)
			(xy 453.056244 -142.199106) (xy 453.033089 -142.218542) (xy 452.982969 -142.252348) (xy 452.929196 -142.279977)
			(xy 452.872529 -142.301042) (xy 452.813765 -142.315243) (xy 452.753732 -142.322383) (xy 452.723504 -142.322804)
			(xy 452.693274 -142.322414) (xy 452.633236 -142.315288) (xy 452.574467 -142.30109) (xy 452.517797 -142.280019)
			(xy 452.464028 -142.252374) (xy 452.413919 -142.218545) (xy 452.390764 -142.199106) (xy 452.3837 -142.193452)
			(xy 452.366782 -142.187071) (xy 452.357744 -142.18666) (xy 452.327264 -142.18666) (xy 452.318228 -142.187086)
			(xy 452.301311 -142.193459) (xy 452.294244 -142.199106) (xy 452.271106 -142.218529) (xy 452.221023 -142.252315)
			(xy 452.167293 -142.279935) (xy 452.11067 -142.300998) (xy 452.051952 -142.31521) (xy 451.991965 -142.322369)
			(xy 451.961758 -142.322804) (xy 451.961504 -142.322804) (xy 451.929541 -142.322331) (xy 451.86612 -142.31432)
			(xy 451.804202 -142.298423) (xy 451.744766 -142.27489) (xy 451.688747 -142.244094) (xy 451.63703 -142.20652)
			(xy 451.59043 -142.16276) (xy 451.549683 -142.113505) (xy 451.515429 -142.059531) (xy 451.488211 -142.001689)
			(xy 451.468457 -141.940893) (xy 451.456478 -141.878099) (xy 451.452464 -141.8143) (xy 451.053972 -141.8143)
			(xy 451.032648 -141.859616) (xy 450.998397 -141.913587) (xy 450.957652 -141.96284) (xy 450.911055 -142.006597)
			(xy 450.859341 -142.044169) (xy 450.803327 -142.074964) (xy 450.743894 -142.098495) (xy 450.68198 -142.114392)
			(xy 450.618563 -142.122404) (xy 450.586602 -142.122906) (xy 450.555487 -142.122403) (xy 450.493721 -142.114816)
			(xy 450.433344 -142.099744) (xy 450.37526 -142.077411) (xy 450.320337 -142.048153) (xy 450.269398 -142.012407)
			(xy 450.223206 -141.970708) (xy 450.182451 -141.92368) (xy 450.164708 -141.898116) (xy 450.159079 -141.890632)
			(xy 450.143713 -141.879953) (xy 450.134736 -141.877288) (xy 450.104764 -141.869668) (xy 450.095715 -141.867729)
			(xy 450.077342 -141.869829) (xy 450.06895 -141.873732) (xy 450.041758 -141.887174) (xy 449.984156 -141.906173)
			(xy 449.924271 -141.915805) (xy 449.893944 -141.916404) (xy 449.867564 -141.915932) (xy 449.815308 -141.908668)
			(xy 449.764551 -141.894272) (xy 449.716262 -141.873018) (xy 449.671362 -141.845313) (xy 449.630709 -141.811685)
			(xy 449.595078 -141.772775) (xy 449.579746 -141.751304) (xy 449.573109 -141.742662) (xy 449.554431 -141.731476)
			(xy 449.543678 -141.729714) (xy 449.456048 -141.719808) (xy 449.435474 -141.726666) (xy 449.427092 -141.734286)
			(xy 449.403555 -141.755333) (xy 449.352185 -141.79205) (xy 449.296665 -141.822125) (xy 449.237849 -141.845096)
			(xy 449.176642 -141.86061) (xy 449.113985 -141.868428) (xy 449.082414 -141.868906) (xy 449.050451 -141.86843)
			(xy 448.987029 -141.860419) (xy 448.925111 -141.844523) (xy 448.865673 -141.820992) (xy 448.809654 -141.790196)
			(xy 448.757936 -141.752622) (xy 448.711335 -141.708862) (xy 448.670587 -141.659607) (xy 448.636333 -141.605633)
			(xy 448.609114 -141.547791) (xy 448.589359 -141.486994) (xy 448.577381 -141.4242) (xy 448.573366 -141.3604)
			(xy 416.49271 -141.3604) (xy 416.483619 -141.368278) (xy 416.437768 -141.397746) (xy 416.38819 -141.420389)
			(xy 416.335894 -141.435745) (xy 416.281944 -141.443501) (xy 416.254692 -141.443964) (xy 416.225777 -141.443393)
			(xy 416.168608 -141.434677) (xy 416.113409 -141.41743) (xy 416.061447 -141.392048) (xy 416.013912 -141.359113)
			(xy 415.971893 -141.31938) (xy 415.953702 -141.296898) (xy 415.946084 -141.288101) (xy 415.925192 -141.277912)
			(xy 415.91357 -141.27734) (xy 415.833814 -141.27734) (xy 415.822183 -141.277887) (xy 415.801272 -141.288069)
			(xy 415.793682 -141.296898) (xy 415.7789 -141.315294) (xy 415.745532 -141.348667) (xy 415.727134 -141.363446)
			(xy 415.718305 -141.371032) (xy 415.708136 -141.391949) (xy 415.707576 -141.403578) (xy 415.707576 -141.483334)
			(xy 415.708083 -141.494971) (xy 415.718292 -141.515881) (xy 415.727134 -141.523466) (xy 415.749608 -141.541668)
			(xy 415.789343 -141.583686) (xy 415.822282 -141.631219) (xy 415.847671 -141.683178) (xy 415.86493 -141.738373)
			(xy 415.873663 -141.795541) (xy 415.8742 -141.824456) (xy 415.873635 -141.854718) (xy 415.864083 -141.914484)
			(xy 415.845213 -141.971991) (xy 415.817497 -142.025796) (xy 415.800032 -142.050516) (xy 415.794744 -142.058306)
			(xy 415.789661 -142.076418) (xy 415.790126 -142.085822) (xy 415.79673 -142.152878) (xy 415.798021 -142.162085)
			(xy 415.806221 -142.178754) (xy 415.812732 -142.18539) (xy 415.83437 -142.206042) (xy 415.873166 -142.25157)
			(xy 415.906352 -142.301337) (xy 415.93347 -142.354653) (xy 415.954143 -142.410783) (xy 415.968088 -142.468951)
			(xy 415.975112 -142.528354) (xy 415.975546 -142.558262) (xy 415.975044 -142.590223) (xy 415.967033 -142.653641)
			(xy 415.951136 -142.715555) (xy 415.927604 -142.774988) (xy 415.89681 -142.831003) (xy 415.859237 -142.882718)
			(xy 415.81548 -142.929315) (xy 415.766227 -142.97006) (xy 415.712256 -143.004311) (xy 415.654417 -143.031528)
			(xy 415.593624 -143.051281) (xy 415.530834 -143.063259) (xy 415.467038 -143.067273) (xy 415.403242 -143.063259)
			(xy 415.340452 -143.051281) (xy 415.279659 -143.031528) (xy 415.22182 -143.004311) (xy 415.167849 -142.97006)
			(xy 415.118596 -142.929315) (xy 415.074839 -142.882718) (xy 415.037266 -142.831003) (xy 415.006472 -142.774988)
			(xy 414.98294 -142.715555) (xy 414.967043 -142.653641) (xy 414.959032 -142.590223) (xy 414.95853 -142.558262)
			(xy 414.959068 -142.525802) (xy 414.967313 -142.461409) (xy 414.983689 -142.398589) (xy 415.00793 -142.338365)
			(xy 415.039642 -142.281718) (xy 415.078307 -142.229569) (xy 415.123298 -142.182768) (xy 415.148268 -142.162022)
			(xy 415.155167 -142.155853) (xy 415.164414 -142.13984) (xy 415.166302 -142.13078) (xy 415.179256 -142.05458)
			(xy 415.175446 -142.036546) (xy 415.170366 -142.028672) (xy 415.156388 -142.00567) (xy 415.134282 -141.956595)
			(xy 415.119278 -141.904905) (xy 415.111672 -141.851621) (xy 415.111184 -141.82471) (xy 415.111184 -141.824456)
			(xy 415.111711 -141.795539) (xy 415.120434 -141.738367) (xy 415.137688 -141.683167) (xy 415.163078 -141.631204)
			(xy 415.196022 -141.583671) (xy 415.235764 -141.541655) (xy 415.25825 -141.523466) (xy 415.267071 -141.515873)
			(xy 415.277245 -141.494961) (xy 415.277808 -141.483334) (xy 415.277808 -141.403578) (xy 415.277264 -141.391947)
			(xy 415.267078 -141.371038) (xy 415.25825 -141.363446) (xy 415.235778 -141.345242) (xy 415.196044 -141.303223)
			(xy 415.163106 -141.255691) (xy 415.137716 -141.203732) (xy 415.120456 -141.148538) (xy 415.111722 -141.091371)
			(xy 415.111184 -141.062456) (xy 415.111651 -141.035212) (xy 415.119413 -140.981279) (xy 415.134774 -140.929)
			(xy 415.157419 -140.87944) (xy 415.186888 -140.833608) (xy 415.222581 -140.792437) (xy 415.26377 -140.756766)
			(xy 415.286444 -140.741654) (xy 415.29348 -140.73682) (xy 415.304025 -140.723406) (xy 415.309544 -140.707261)
			(xy 415.309812 -140.698728) (xy 415.309812 -140.613384) (xy 415.309483 -140.604865) (xy 415.303938 -140.588755)
			(xy 415.29343 -140.575344) (xy 415.286444 -140.570458) (xy 415.263755 -140.555379) (xy 415.22259 -140.519693)
			(xy 415.186922 -140.478513) (xy 415.157476 -140.432676) (xy 415.134852 -140.383117) (xy 415.119509 -140.330842)
			(xy 415.111761 -140.276916) (xy 415.111764 -140.222436) (xy 415.119519 -140.168512) (xy 415.134868 -140.116239)
			(xy 415.157499 -140.066682) (xy 415.18695 -140.020849) (xy 415.222624 -139.979674) (xy 415.263793 -139.943993)
			(xy 415.286444 -139.928854) (xy 415.29348 -139.92402) (xy 415.304025 -139.910606) (xy 415.309544 -139.894461)
			(xy 415.309812 -139.885928) (xy 415.309812 -139.800584) (xy 415.309483 -139.792065) (xy 415.303938 -139.775955)
			(xy 415.29343 -139.762544) (xy 415.286444 -139.757658) (xy 415.263752 -139.742571) (xy 415.222558 -139.7069)
			(xy 415.186862 -139.665726) (xy 415.157393 -139.61989) (xy 415.134751 -139.570325) (xy 415.119397 -139.51804)
			(xy 415.111644 -139.464102) (xy 415.111184 -139.436856) (xy 415.111628 -139.410477) (xy 415.118886 -139.358219)
			(xy 415.133272 -139.30746) (xy 415.154511 -139.259165) (xy 415.182199 -139.214256) (xy 415.215808 -139.173587)
			(xy 415.254697 -139.137934) (xy 415.298126 -139.107977) (xy 415.321496 -139.095734) (xy 415.33445 -139.089384)
			(xy 415.34969 -139.064746) (xy 415.34969 -138.945366) (xy 415.33445 -138.920728) (xy 415.321496 -138.914378)
			(xy 415.297876 -138.901988) (xy 415.254014 -138.871641) (xy 415.214801 -138.835486) (xy 415.181 -138.794227)
			(xy 415.153269 -138.748666) (xy 415.132146 -138.69969) (xy 415.124646 -138.674094) (xy 415.121344 -138.661648)
			(xy 415.104072 -138.64336) (xy 414.999678 -138.608562) (xy 414.974532 -138.61288) (xy 414.964626 -138.620754)
			(xy 414.944484 -138.635843) (xy 414.901013 -138.6612) (xy 414.854582 -138.680613) (xy 414.805998 -138.693744)
			(xy 414.756109 -138.700363) (xy 414.730946 -138.700764) (xy 414.730692 -138.700764) (xy 414.703438 -138.700366)
			(xy 414.649485 -138.692607) (xy 414.597185 -138.67725) (xy 414.547603 -138.654605) (xy 414.501748 -138.625136)
			(xy 414.460554 -138.58944) (xy 414.42486 -138.548245) (xy 414.395391 -138.50239) (xy 414.372748 -138.452807)
			(xy 414.357391 -138.400507) (xy 414.349634 -138.346554) (xy 411.383923 -138.346554) (xy 411.377565 -138.349546)
			(xy 411.316772 -138.369299) (xy 411.253982 -138.381277) (xy 411.190186 -138.385291) (xy 411.12639 -138.381277)
			(xy 411.0636 -138.369299) (xy 411.002807 -138.349546) (xy 410.944968 -138.322329) (xy 410.890997 -138.288078)
			(xy 410.841744 -138.247333) (xy 410.797987 -138.200736) (xy 410.760414 -138.149021) (xy 410.72962 -138.093006)
			(xy 410.706088 -138.033573) (xy 410.690191 -137.971659) (xy 410.68218 -137.908241) (xy 408.419765 -137.908241)
			(xy 409.650438 -139.138914) (xy 409.659345 -139.14685) (xy 409.681992 -139.154249) (xy 409.693872 -139.153138)
			(xy 409.774644 -139.1412) (xy 409.780574 -139.140157) (xy 409.791739 -139.13566) (xy 409.796742 -139.13231)
			(xy 409.801314 -139.129008) (xy 409.809188 -139.120118) (xy 409.811982 -139.114784) (xy 409.829987 -139.081864)
			(xy 409.871545 -139.019382) (xy 409.91904 -138.961286) (xy 409.972014 -138.908137) (xy 410.029952 -138.86045)
			(xy 410.092295 -138.818685) (xy 410.15844 -138.783248) (xy 410.227747 -138.75448) (xy 410.299544 -138.732661)
			(xy 410.373138 -138.718) (xy 410.447816 -138.710641) (xy 410.485336 -138.710162) (xy 410.525269 -138.710687)
			(xy 410.604698 -138.719038) (xy 410.682819 -138.735646) (xy 410.758776 -138.760329) (xy 410.831737 -138.792815)
			(xy 410.900903 -138.83275) (xy 410.965516 -138.879695) (xy 411.024868 -138.933137) (xy 411.078309 -138.992489)
			(xy 411.125254 -139.057102) (xy 411.165188 -139.126268) (xy 411.197674 -139.19923) (xy 411.222355 -139.275187)
			(xy 411.238963 -139.353308) (xy 411.247314 -139.432737) (xy 411.247844 -139.47267) (xy 411.247392 -139.510189)
			(xy 411.240016 -139.584862) (xy 411.225341 -139.658451) (xy 411.203511 -139.730242) (xy 411.174735 -139.799542)
			(xy 411.139292 -139.865682) (xy 411.097525 -139.92802) (xy 411.049838 -139.985956) (xy 410.996691 -140.038927)
			(xy 410.938599 -140.086424) (xy 410.876123 -140.127985) (xy 410.843222 -140.146024) (xy 410.837888 -140.148818)
			(xy 410.828998 -140.156692) (xy 410.825696 -140.161264) (xy 410.822349 -140.166267) (xy 410.817865 -140.177436)
			(xy 410.816806 -140.183362) (xy 410.804868 -140.264134) (xy 410.803699 -140.276019) (xy 410.811108 -140.298689)
			(xy 410.819092 -140.307568) (xy 422.927572 -152.416048) (xy 423.422102 -152.416048) (xy 423.422102 -152.361552)
			(xy 423.429857 -152.307611) (xy 423.44521 -152.255322) (xy 423.467847 -152.205751) (xy 423.497308 -152.159905)
			(xy 423.532993 -152.118718) (xy 423.574176 -152.083029) (xy 423.620019 -152.053564) (xy 423.669589 -152.030922)
			(xy 423.721876 -152.015565) (xy 423.775816 -152.007805) (xy 423.803064 -152.007316) (xy 423.83198 -152.007854)
			(xy 423.889151 -152.016578) (xy 423.944349 -152.033832) (xy 423.996311 -152.05922) (xy 424.043846 -152.09216)
			(xy 424.085863 -152.131898) (xy 424.104054 -152.154382) (xy 424.111677 -152.163172) (xy 424.132566 -152.173362)
			(xy 424.144186 -152.17394) (xy 424.223942 -152.17394) (xy 424.235578 -152.173432) (xy 424.256489 -152.163223)
			(xy 424.264074 -152.154382) (xy 424.280827 -152.133599) (xy 424.319181 -152.096469) (xy 424.362335 -152.065047)
			(xy 424.409449 -152.039948) (xy 424.459601 -152.021662) (xy 424.511812 -152.010545) (xy 424.565064 -152.006815)
			(xy 424.618316 -152.010545) (xy 424.670527 -152.021662) (xy 424.720679 -152.039948) (xy 424.767793 -152.065047)
			(xy 424.810947 -152.096469) (xy 424.849301 -152.133599) (xy 424.866054 -152.154382) (xy 424.873677 -152.163172)
			(xy 424.894566 -152.173362) (xy 424.906186 -152.17394) (xy 424.985942 -152.17394) (xy 424.997578 -152.173432)
			(xy 425.018489 -152.163223) (xy 425.026074 -152.154382) (xy 425.042827 -152.133599) (xy 425.081181 -152.096469)
			(xy 425.124335 -152.065047) (xy 425.171449 -152.039948) (xy 425.221601 -152.021662) (xy 425.273812 -152.010545)
			(xy 425.327064 -152.006815) (xy 425.380316 -152.010545) (xy 425.432527 -152.021662) (xy 425.482679 -152.039948)
			(xy 425.529793 -152.065047) (xy 425.572947 -152.096469) (xy 425.611301 -152.133599) (xy 425.628054 -152.154382)
			(xy 425.635677 -152.163172) (xy 425.656566 -152.173362) (xy 425.668186 -152.17394) (xy 425.747942 -152.17394)
			(xy 425.759578 -152.173432) (xy 425.780489 -152.163223) (xy 425.788074 -152.154382) (xy 425.806275 -152.131907)
			(xy 425.848293 -152.092172) (xy 425.895826 -152.059233) (xy 425.947785 -152.033843) (xy 426.002981 -152.016585)
			(xy 426.060149 -152.007853) (xy 426.089064 -152.007316) (xy 426.11632 -152.007728) (xy 426.170279 -152.015482)
			(xy 426.222584 -152.030836) (xy 426.272172 -152.053478) (xy 426.318032 -152.082946) (xy 426.359232 -152.118642)
			(xy 426.394932 -152.159839) (xy 426.424405 -152.205696) (xy 426.447052 -152.255282) (xy 426.462411 -152.307586)
			(xy 426.470169 -152.361544) (xy 426.470169 -152.416056) (xy 426.462411 -152.470014) (xy 426.447052 -152.522318)
			(xy 426.424405 -152.571904) (xy 426.394932 -152.617761) (xy 426.359232 -152.658958) (xy 426.318032 -152.694654)
			(xy 426.272172 -152.724122) (xy 426.222584 -152.746764) (xy 426.170279 -152.762118) (xy 426.11632 -152.769872)
			(xy 426.089064 -152.770332) (xy 426.060148 -152.769793) (xy 426.002976 -152.761072) (xy 425.947777 -152.74382)
			(xy 425.895814 -152.718432) (xy 425.84828 -152.685491) (xy 425.806264 -152.645751) (xy 425.788074 -152.623266)
			(xy 425.780474 -152.614451) (xy 425.759568 -152.604273) (xy 425.747942 -152.603708) (xy 425.668186 -152.603708)
			(xy 425.656554 -152.604251) (xy 425.635645 -152.614437) (xy 425.628054 -152.623266) (xy 425.611301 -152.644049)
			(xy 425.572947 -152.681179) (xy 425.529793 -152.712601) (xy 425.482679 -152.7377) (xy 425.432527 -152.755986)
			(xy 425.380316 -152.767103) (xy 425.327064 -152.770833) (xy 425.273812 -152.767103) (xy 425.221601 -152.755986)
			(xy 425.171449 -152.7377) (xy 425.124335 -152.712601) (xy 425.081181 -152.681179) (xy 425.042827 -152.644049)
			(xy 425.026074 -152.623266) (xy 425.018474 -152.614451) (xy 424.997568 -152.604273) (xy 424.985942 -152.603708)
			(xy 424.906186 -152.603708) (xy 424.894554 -152.604251) (xy 424.873645 -152.614437) (xy 424.866054 -152.623266)
			(xy 424.849301 -152.644049) (xy 424.810947 -152.681179) (xy 424.767793 -152.712601) (xy 424.720679 -152.7377)
			(xy 424.670527 -152.755986) (xy 424.618316 -152.767103) (xy 424.565064 -152.770833) (xy 424.511812 -152.767103)
			(xy 424.459601 -152.755986) (xy 424.409449 -152.7377) (xy 424.362335 -152.712601) (xy 424.319181 -152.681179)
			(xy 424.280827 -152.644049) (xy 424.264074 -152.623266) (xy 424.256474 -152.614451) (xy 424.235568 -152.604273)
			(xy 424.223942 -152.603708) (xy 424.144186 -152.603708) (xy 424.132554 -152.604251) (xy 424.111645 -152.614437)
			(xy 424.104054 -152.623266) (xy 424.085824 -152.645717) (xy 424.043813 -152.685455) (xy 423.996287 -152.718399)
			(xy 423.944333 -152.743794) (xy 423.889142 -152.761057) (xy 423.831978 -152.769793) (xy 423.803064 -152.770332)
			(xy 423.775816 -152.769795) (xy 423.721876 -152.762035) (xy 423.669589 -152.746678) (xy 423.620019 -152.724036)
			(xy 423.574176 -152.694571) (xy 423.532993 -152.658882) (xy 423.497308 -152.617695) (xy 423.467847 -152.571849)
			(xy 423.44521 -152.522278) (xy 423.429857 -152.469989) (xy 423.422102 -152.416048) (xy 422.927572 -152.416048)
			(xy 424.285918 -153.774394) (xy 436.382169 -153.774394) (xy 436.386165 -153.564508) (xy 436.39815 -153.354926)
			(xy 436.418104 -153.145952) (xy 436.446 -152.93789) (xy 436.481797 -152.73104) (xy 436.525442 -152.525703)
			(xy 436.576874 -152.322177) (xy 436.636016 -152.120756) (xy 436.702784 -151.921733) (xy 436.77708 -151.725396)
			(xy 436.858798 -151.53203) (xy 436.947817 -151.341915) (xy 437.04401 -151.155327) (xy 437.147237 -150.972536)
			(xy 437.257348 -150.793808) (xy 437.374183 -150.619401) (xy 437.497573 -150.449569) (xy 437.62734 -150.284557)
			(xy 437.763294 -150.124606) (xy 437.90524 -149.969946) (xy 438.05297 -149.820802) (xy 438.206272 -149.677391)
			(xy 438.364922 -149.53992) (xy 438.528691 -149.408588) (xy 438.697341 -149.283587) (xy 438.870627 -149.165096)
			(xy 439.048299 -149.053289) (xy 439.230099 -148.948327) (xy 439.415763 -148.850362) (xy 439.605021 -148.759537)
			(xy 439.797601 -148.675983) (xy 439.993222 -148.59982) (xy 440.1916 -148.531161) (xy 440.392449 -148.470104)
			(xy 440.595476 -148.416737) (xy 440.800389 -148.371139) (xy 441.006888 -148.333374) (xy 441.214675 -148.303499)
			(xy 441.42345 -148.281556) (xy 441.632908 -148.267577) (xy 441.842747 -148.261582) (xy 442.052661 -148.263581)
			(xy 442.262348 -148.273569) (xy 442.471502 -148.291534) (xy 442.67982 -148.317448) (xy 442.887001 -148.351273)
			(xy 443.092745 -148.392962) (xy 443.296751 -148.442454) (xy 443.498726 -148.499676) (xy 443.698376 -148.564546)
			(xy 443.895411 -148.63697) (xy 444.089547 -148.716843) (xy 444.2805 -148.804049) (xy 444.467996 -148.898461)
			(xy 444.651761 -148.999943) (xy 444.831529 -149.108347) (xy 445.00704 -149.223517) (xy 445.178039 -149.345285)
			(xy 445.344279 -149.473474) (xy 445.505518 -149.6079) (xy 445.661522 -149.748367) (xy 445.812065 -149.894671)
			(xy 445.956929 -150.0466) (xy 446.095904 -150.203934) (xy 446.228789 -150.366445) (xy 446.35539 -150.533898)
			(xy 446.475525 -150.706048) (xy 446.589019 -150.882648) (xy 446.695707 -151.06344) (xy 446.795434 -151.248163)
			(xy 446.888057 -151.436549) (xy 446.973441 -151.628324) (xy 447.051462 -151.823211) (xy 447.122007 -152.020927)
			(xy 447.184974 -152.221185) (xy 447.240271 -152.423695) (xy 447.287818 -152.628164) (xy 447.327546 -152.834295)
			(xy 447.359398 -153.041788) (xy 447.383328 -153.250344) (xy 447.3993 -153.45966) (xy 447.407292 -153.669432)
			(xy 447.407792 -153.774394) (xy 447.407292 -153.879356) (xy 447.3993 -154.089128) (xy 447.383328 -154.298444)
			(xy 447.359398 -154.507) (xy 447.327546 -154.714493) (xy 447.287818 -154.920624) (xy 447.240271 -155.125093)
			(xy 447.184974 -155.327603) (xy 447.122007 -155.527861) (xy 447.051462 -155.725577) (xy 446.973441 -155.920464)
			(xy 446.888057 -156.112239) (xy 446.795434 -156.300625) (xy 446.695707 -156.485348) (xy 446.589019 -156.66614)
			(xy 446.475525 -156.84274) (xy 446.35539 -157.01489) (xy 446.228789 -157.182343) (xy 446.095904 -157.344854)
			(xy 445.956929 -157.502188) (xy 445.812065 -157.654117) (xy 445.661522 -157.800421) (xy 445.505518 -157.940888)
			(xy 445.344279 -158.075314) (xy 445.178039 -158.203503) (xy 445.00704 -158.325271) (xy 444.831529 -158.440441)
			(xy 444.651761 -158.548845) (xy 444.467996 -158.650327) (xy 444.2805 -158.744739) (xy 444.089547 -158.831945)
			(xy 443.895411 -158.911818) (xy 443.698376 -158.984242) (xy 443.498726 -159.049112) (xy 443.296751 -159.106334)
			(xy 443.092745 -159.155826) (xy 442.887001 -159.197515) (xy 442.67982 -159.23134) (xy 442.471502 -159.257254)
			(xy 442.262348 -159.275219) (xy 442.052661 -159.285207) (xy 441.842747 -159.287206) (xy 441.632908 -159.281211)
			(xy 441.42345 -159.267232) (xy 441.214675 -159.245289) (xy 441.006888 -159.215414) (xy 440.800389 -159.177649)
			(xy 440.595476 -159.132051) (xy 440.392449 -159.078684) (xy 440.1916 -159.017627) (xy 439.993222 -158.948968)
			(xy 439.797601 -158.872805) (xy 439.605021 -158.789251) (xy 439.415763 -158.698426) (xy 439.230099 -158.600461)
			(xy 439.048299 -158.495499) (xy 438.870627 -158.383692) (xy 438.697341 -158.265201) (xy 438.528691 -158.1402)
			(xy 438.364922 -158.008868) (xy 438.206272 -157.871397) (xy 438.05297 -157.727986) (xy 437.90524 -157.578842)
			(xy 437.763294 -157.424182) (xy 437.62734 -157.264231) (xy 437.497573 -157.099219) (xy 437.374183 -156.929387)
			(xy 437.257348 -156.75498) (xy 437.147237 -156.576252) (xy 437.04401 -156.393461) (xy 436.947817 -156.206873)
			(xy 436.858798 -156.016758) (xy 436.77708 -155.823392) (xy 436.702784 -155.627055) (xy 436.636016 -155.428032)
			(xy 436.576874 -155.226611) (xy 436.525442 -155.023085) (xy 436.481797 -154.817748) (xy 436.446 -154.610898)
			(xy 436.418104 -154.402836) (xy 436.39815 -154.193862) (xy 436.386165 -153.98428) (xy 436.382169 -153.774394)
			(xy 424.285918 -153.774394) (xy 425.015406 -154.503882) (xy 425.019216 -154.507438) (xy 425.025734 -154.512233)
			(xy 425.040872 -154.517923) (xy 425.048934 -154.518614) (xy 425.058332 -154.518868) (xy 425.076366 -154.512772)
			(xy 425.083478 -154.506676) (xy 425.104107 -154.490144) (xy 425.149062 -154.462328) (xy 425.197426 -154.440985)
			(xy 425.248274 -154.426523) (xy 425.300632 -154.41922) (xy 425.327064 -154.418792) (xy 425.354698 -154.419286)
			(xy 425.409388 -154.427266) (xy 425.462354 -154.44305) (xy 425.512491 -154.466308) (xy 425.558749 -154.496554)
			(xy 425.600162 -154.533154) (xy 425.618402 -154.55392) (xy 425.62526 -154.560524) (xy 425.633896 -154.567382)
			(xy 425.643294 -154.573478) (xy 425.65701 -154.580082) (xy 425.668948 -154.5844) (xy 425.679616 -154.585416)
			(xy 425.736512 -154.585416) (xy 425.74718 -154.5844) (xy 425.759118 -154.580082) (xy 425.772834 -154.573478)
			(xy 425.782232 -154.567382) (xy 425.790868 -154.560524) (xy 425.797726 -154.55392) (xy 425.815945 -154.533133)
			(xy 425.857352 -154.496519) (xy 425.903611 -154.466267) (xy 425.953754 -154.443012) (xy 426.00673 -154.427241)
			(xy 426.061427 -154.419283) (xy 426.089064 -154.418792) (xy 426.116319 -154.419253) (xy 426.170273 -154.427006)
			(xy 426.222576 -154.442359) (xy 426.27216 -154.464999) (xy 426.318018 -154.494466) (xy 426.359215 -154.53016)
			(xy 426.394912 -154.571353) (xy 426.424384 -154.617208) (xy 426.447029 -154.666791) (xy 426.462387 -154.719091)
			(xy 426.470145 -154.773046) (xy 426.470145 -154.827554) (xy 426.462387 -154.881509) (xy 426.447029 -154.933809)
			(xy 426.424384 -154.983392) (xy 426.394912 -155.029247) (xy 426.359215 -155.07044) (xy 426.318018 -155.106134)
			(xy 426.27216 -155.135601) (xy 426.222576 -155.158241) (xy 426.170273 -155.173594) (xy 426.116319 -155.181347)
			(xy 426.089064 -155.181808) (xy 426.061429 -155.181316) (xy 426.006737 -155.173339) (xy 425.953768 -155.157558)
			(xy 425.903628 -155.134302) (xy 425.857367 -155.104059) (xy 425.815951 -155.067459) (xy 425.797726 -155.04668)
			(xy 425.790868 -155.040076) (xy 425.782232 -155.033218) (xy 425.772834 -155.027122) (xy 425.759118 -155.020518)
			(xy 425.74718 -155.0162) (xy 425.736512 -155.015184) (xy 425.679616 -155.015184) (xy 425.668948 -155.0162)
			(xy 425.65701 -155.020518) (xy 425.643294 -155.027122) (xy 425.633896 -155.033218) (xy 425.62145 -155.043124)
			(xy 425.620688 -155.043886) (xy 425.614592 -155.050998) (xy 425.608496 -155.069032) (xy 425.60875 -155.07843)
			(xy 425.609367 -155.086508) (xy 425.615074 -155.101659) (xy 425.619926 -155.108148) (xy 425.623482 -155.111958)
			(xy 427.162722 -156.651198) (xy 427.169541 -156.658539) (xy 427.177286 -156.677003) (xy 427.177708 -156.687012)
			(xy 427.177708 -156.957776) (xy 427.178196 -156.967737) (xy 427.185787 -156.986158) (xy 427.19244 -156.99359)
			(xy 427.881499 -157.682649) (xy 429.638454 -157.682649) (xy 429.638454 -157.618727) (xy 429.646465 -157.555309)
			(xy 429.662362 -157.493395) (xy 429.685894 -157.433962) (xy 429.716688 -157.377947) (xy 429.754261 -157.326232)
			(xy 429.798018 -157.279635) (xy 429.847271 -157.23889) (xy 429.901242 -157.204639) (xy 429.959081 -157.177422)
			(xy 430.019874 -157.157669) (xy 430.082664 -157.145691) (xy 430.14646 -157.141678) (xy 430.210256 -157.145691)
			(xy 430.273046 -157.157669) (xy 430.333839 -157.177422) (xy 430.391678 -157.204639) (xy 430.445649 -157.23889)
			(xy 430.494902 -157.279635) (xy 430.538659 -157.326232) (xy 430.576232 -157.377947) (xy 430.607026 -157.433962)
			(xy 430.630558 -157.493395) (xy 430.646455 -157.555309) (xy 430.654466 -157.618727) (xy 430.654968 -157.650688)
			(xy 430.654466 -157.682649) (xy 430.646455 -157.746067) (xy 430.630558 -157.807981) (xy 430.607026 -157.867414)
			(xy 430.576232 -157.923429) (xy 430.538659 -157.975144) (xy 430.494902 -158.021741) (xy 430.445649 -158.062486)
			(xy 430.391678 -158.096737) (xy 430.333839 -158.123954) (xy 430.273046 -158.143707) (xy 430.210256 -158.155685)
			(xy 430.14646 -158.159699) (xy 430.082664 -158.155685) (xy 430.019874 -158.143707) (xy 429.959081 -158.123954)
			(xy 429.901242 -158.096737) (xy 429.847271 -158.062486) (xy 429.798018 -158.021741) (xy 429.754261 -157.975144)
			(xy 429.716688 -157.923429) (xy 429.685894 -157.867414) (xy 429.662362 -157.807981) (xy 429.646465 -157.746067)
			(xy 429.638454 -157.682649) (xy 427.881499 -157.682649) (xy 428.928022 -158.729172) (xy 428.934865 -158.736571)
			(xy 428.942586 -158.75517) (xy 428.943008 -158.76524) (xy 428.943008 -161.669687) (xy 430.664614 -161.669687)
			(xy 430.664614 -161.605765) (xy 430.672625 -161.542347) (xy 430.688522 -161.480433) (xy 430.712054 -161.421)
			(xy 430.742848 -161.364985) (xy 430.780421 -161.31327) (xy 430.824178 -161.266673) (xy 430.873431 -161.225928)
			(xy 430.927402 -161.191677) (xy 430.985241 -161.16446) (xy 431.046034 -161.144707) (xy 431.108824 -161.132729)
			(xy 431.17262 -161.128716) (xy 431.236416 -161.132729) (xy 431.299206 -161.144707) (xy 431.359999 -161.16446)
			(xy 431.417838 -161.191677) (xy 431.471809 -161.225928) (xy 431.521062 -161.266673) (xy 431.564819 -161.31327)
			(xy 431.602392 -161.364985) (xy 431.633186 -161.421) (xy 431.656718 -161.480433) (xy 431.672615 -161.542347)
			(xy 431.680626 -161.605765) (xy 431.681128 -161.637726) (xy 431.680626 -161.669687) (xy 431.672615 -161.733105)
			(xy 431.656718 -161.795019) (xy 431.633186 -161.854452) (xy 431.611601 -161.893715) (xy 433.6641 -161.893715)
			(xy 433.6641 -161.829793) (xy 433.672111 -161.766375) (xy 433.688008 -161.704461) (xy 433.71154 -161.645028)
			(xy 433.742334 -161.589013) (xy 433.779907 -161.537298) (xy 433.823664 -161.490701) (xy 433.872917 -161.449956)
			(xy 433.926888 -161.415705) (xy 433.984727 -161.388488) (xy 434.04552 -161.368735) (xy 434.10831 -161.356757)
			(xy 434.172106 -161.352744) (xy 434.235902 -161.356757) (xy 434.298692 -161.368735) (xy 434.359485 -161.388488)
			(xy 434.417324 -161.415705) (xy 434.471295 -161.449956) (xy 434.520548 -161.490701) (xy 434.564305 -161.537298)
			(xy 434.601878 -161.589013) (xy 434.632672 -161.645028) (xy 434.656204 -161.704461) (xy 434.672101 -161.766375)
			(xy 434.680112 -161.829793) (xy 434.680614 -161.861754) (xy 434.680112 -161.893715) (xy 434.672101 -161.957133)
			(xy 434.656204 -162.019047) (xy 434.632672 -162.07848) (xy 434.601878 -162.134495) (xy 434.564305 -162.18621)
			(xy 434.520548 -162.232807) (xy 434.471295 -162.273552) (xy 434.417324 -162.307803) (xy 434.359485 -162.33502)
			(xy 434.298692 -162.354773) (xy 434.235902 -162.366751) (xy 434.172106 -162.370765) (xy 434.10831 -162.366751)
			(xy 434.04552 -162.354773) (xy 433.984727 -162.33502) (xy 433.926888 -162.307803) (xy 433.872917 -162.273552)
			(xy 433.823664 -162.232807) (xy 433.779907 -162.18621) (xy 433.742334 -162.134495) (xy 433.71154 -162.07848)
			(xy 433.688008 -162.019047) (xy 433.672111 -161.957133) (xy 433.6641 -161.893715) (xy 431.611601 -161.893715)
			(xy 431.602392 -161.910467) (xy 431.564819 -161.962182) (xy 431.521062 -162.008779) (xy 431.471809 -162.049524)
			(xy 431.417838 -162.083775) (xy 431.359999 -162.110992) (xy 431.299206 -162.130745) (xy 431.236416 -162.142723)
			(xy 431.17262 -162.146737) (xy 431.108824 -162.142723) (xy 431.046034 -162.130745) (xy 430.985241 -162.110992)
			(xy 430.927402 -162.083775) (xy 430.873431 -162.049524) (xy 430.824178 -162.008779) (xy 430.780421 -161.962182)
			(xy 430.742848 -161.910467) (xy 430.712054 -161.854452) (xy 430.688522 -161.795019) (xy 430.672625 -161.733105)
			(xy 430.664614 -161.669687) (xy 428.943008 -161.669687) (xy 428.943008 -162.981132) (xy 431.703226 -162.981132)
			(xy 431.703712 -162.953881) (xy 431.711468 -162.899933) (xy 431.726823 -162.847638) (xy 431.749465 -162.798061)
			(xy 431.778931 -162.752211) (xy 431.814622 -162.71102) (xy 431.855813 -162.675329) (xy 431.901663 -162.645863)
			(xy 431.95124 -162.623221) (xy 432.003535 -162.607866) (xy 432.057483 -162.60011) (xy 432.111985 -162.60011)
			(xy 432.165933 -162.607866) (xy 432.218228 -162.623221) (xy 432.267805 -162.645863) (xy 432.313655 -162.675329)
			(xy 432.354846 -162.71102) (xy 432.390537 -162.752211) (xy 432.420003 -162.798061) (xy 432.442645 -162.847638)
			(xy 432.458 -162.899933) (xy 432.465756 -162.953881) (xy 432.466242 -162.981132) (xy 432.466242 -162.981386)
			(xy 432.465737 -163.009154) (xy 432.457659 -163.064101) (xy 432.441715 -163.1173) (xy 432.430428 -163.142676)
			(xy 432.426364 -163.151312) (xy 432.425094 -163.170616) (xy 432.44897 -163.245546) (xy 432.452196 -163.254454)
			(xy 432.464066 -163.269202) (xy 432.472084 -163.274248) (xy 432.472338 -163.274248) (xy 432.49128 -163.285255)
			(xy 432.527398 -163.310054) (xy 432.544474 -163.323778) (xy 432.551474 -163.329046) (xy 432.567976 -163.334892)
			(xy 432.576732 -163.335208) (xy 432.857656 -163.335208) (xy 432.866405 -163.334868) (xy 432.882896 -163.329015)
			(xy 432.889914 -163.323778) (xy 432.906982 -163.310044) (xy 432.943103 -163.285246) (xy 432.96205 -163.274248)
			(xy 432.962304 -163.274248) (xy 432.970271 -163.269143) (xy 432.982126 -163.254417) (xy 432.985418 -163.245546)
			(xy 433.009294 -163.170616) (xy 433.008024 -163.151312) (xy 433.00396 -163.142676) (xy 432.992652 -163.117308)
			(xy 432.976697 -163.064109) (xy 432.968642 -163.009156) (xy 432.968146 -162.981386) (xy 432.968146 -162.981132)
			(xy 432.968632 -162.953881) (xy 432.976388 -162.899933) (xy 432.991743 -162.847638) (xy 433.014385 -162.798061)
			(xy 433.043851 -162.752211) (xy 433.079542 -162.71102) (xy 433.120733 -162.675329) (xy 433.166583 -162.645863)
			(xy 433.21616 -162.623221) (xy 433.268455 -162.607866) (xy 433.322403 -162.60011) (xy 433.376905 -162.60011)
			(xy 433.430853 -162.607866) (xy 433.483148 -162.623221) (xy 433.532725 -162.645863) (xy 433.578575 -162.675329)
			(xy 433.619766 -162.71102) (xy 433.655457 -162.752211) (xy 433.684923 -162.798061) (xy 433.707565 -162.847638)
			(xy 433.72292 -162.899933) (xy 433.730676 -162.953881) (xy 433.731162 -162.981132) (xy 433.73078 -163.006773)
			(xy 433.7239 -163.05759) (xy 433.710281 -163.10703) (xy 433.690169 -163.154203) (xy 433.663925 -163.198261)
			(xy 433.632021 -163.23841) (xy 433.613814 -163.256468) (xy 433.606956 -163.263072) (xy 433.598828 -163.280598)
			(xy 433.593494 -163.368736) (xy 433.59959 -163.38677) (xy 433.605686 -163.394136) (xy 433.627414 -163.421524)
			(xy 433.663909 -163.481153) (xy 433.691899 -163.545216) (xy 433.710857 -163.612507) (xy 433.720424 -163.681761)
			(xy 433.721002 -163.716716) (xy 433.720559 -163.747448) (xy 433.713149 -163.808462) (xy 433.698438 -163.868139)
			(xy 433.676641 -163.925608) (xy 433.648076 -163.98003) (xy 433.61316 -164.030612) (xy 433.572401 -164.076617)
			(xy 433.526395 -164.117374) (xy 433.475811 -164.152288) (xy 433.421387 -164.18085) (xy 433.363918 -164.202644)
			(xy 433.304241 -164.217353) (xy 433.243226 -164.22476) (xy 433.212494 -164.225224) (xy 433.177528 -164.224646)
			(xy 433.108259 -164.215044) (xy 433.04096 -164.196035) (xy 432.976903 -164.167978) (xy 432.917298 -164.131405)
			(xy 432.889914 -164.109654) (xy 432.882915 -164.104384) (xy 432.866412 -164.098538) (xy 432.857656 -164.098224)
			(xy 432.576732 -164.098224) (xy 432.567982 -164.098552) (xy 432.55149 -164.104413) (xy 432.544474 -164.109654)
			(xy 432.517086 -164.131396) (xy 432.457473 -164.167951) (xy 432.393416 -164.195997) (xy 432.326122 -164.215008)
			(xy 432.256858 -164.224624) (xy 432.221894 -164.225224) (xy 432.191163 -164.22475) (xy 432.130151 -164.217341)
			(xy 432.070476 -164.202632) (xy 432.013009 -164.180837) (xy 431.958588 -164.152275) (xy 431.908006 -164.117362)
			(xy 431.862001 -164.076606) (xy 431.821245 -164.030602) (xy 431.78633 -163.980021) (xy 431.757767 -163.9256)
			(xy 431.735971 -163.868134) (xy 431.721261 -163.808459) (xy 431.713851 -163.747446) (xy 431.713386 -163.716716)
			(xy 431.71398 -163.681761) (xy 431.723539 -163.612509) (xy 431.742493 -163.545218) (xy 431.770486 -163.481157)
			(xy 431.806988 -163.421535) (xy 431.828702 -163.394136) (xy 431.834798 -163.38677) (xy 431.840894 -163.368736)
			(xy 431.83556 -163.280598) (xy 431.827432 -163.263072) (xy 431.820574 -163.256468) (xy 431.802354 -163.238422)
			(xy 431.770447 -163.198275) (xy 431.744205 -163.154216) (xy 431.724101 -163.107039) (xy 431.710496 -163.057594)
			(xy 431.703637 -163.006773) (xy 431.703226 -162.981132) (xy 428.943008 -162.981132) (xy 428.943008 -165.63467)
			(xy 436.051706 -165.63467) (xy 436.052124 -165.608038) (xy 436.059536 -165.555293) (xy 436.074213 -165.504091)
			(xy 436.095869 -165.455429) (xy 436.124084 -165.410252) (xy 436.158307 -165.369438) (xy 436.197875 -165.333781)
			(xy 436.242018 -165.303974) (xy 436.289877 -165.280597) (xy 436.340523 -165.264104) (xy 436.366666 -165.259004)
			(xy 436.379936 -165.256189) (xy 436.404446 -165.244591) (xy 436.42504 -165.226952) (xy 436.440266 -165.204515)
			(xy 436.44905 -165.178861) (xy 436.450772 -165.1518) (xy 436.445313 -165.12524) (xy 436.439564 -165.112954)
			(xy 436.426391 -165.086074) (xy 436.405689 -165.029905) (xy 436.39171 -164.971697) (xy 436.384647 -164.912253)
			(xy 436.384192 -164.882322) (xy 436.384192 -164.882068) (xy 436.384694 -164.850107) (xy 436.392705 -164.786689)
			(xy 436.408602 -164.724775) (xy 436.432134 -164.665342) (xy 436.462928 -164.609327) (xy 436.500501 -164.557612)
			(xy 436.544258 -164.511015) (xy 436.593511 -164.47027) (xy 436.647482 -164.436019) (xy 436.705321 -164.408802)
			(xy 436.766114 -164.389049) (xy 436.828904 -164.377071) (xy 436.8927 -164.373058) (xy 436.956496 -164.377071)
			(xy 437.019286 -164.389049) (xy 437.080079 -164.408802) (xy 437.137918 -164.436019) (xy 437.191889 -164.47027)
			(xy 437.241142 -164.511015) (xy 437.284899 -164.557612) (xy 437.322472 -164.609327) (xy 437.353266 -164.665342)
			(xy 437.376798 -164.724775) (xy 437.392695 -164.786689) (xy 437.400706 -164.850107) (xy 437.401208 -164.882068)
			(xy 437.400642 -164.915287) (xy 437.391993 -164.98116) (xy 437.374838 -165.045345) (xy 437.34947 -165.10675)
			(xy 437.31632 -165.164327) (xy 437.275954 -165.217096) (xy 437.229059 -165.264159) (xy 437.176433 -165.304713)
			(xy 437.118974 -165.338067) (xy 437.057661 -165.363654) (xy 436.999734 -165.379357) (xy 440.651386 -165.379357)
			(xy 440.651386 -165.315435) (xy 440.659397 -165.252017) (xy 440.675294 -165.190103) (xy 440.698826 -165.13067)
			(xy 440.72962 -165.074655) (xy 440.767193 -165.02294) (xy 440.81095 -164.976343) (xy 440.860203 -164.935598)
			(xy 440.914174 -164.901347) (xy 440.972013 -164.87413) (xy 441.032806 -164.854377) (xy 441.095596 -164.842399)
			(xy 441.159392 -164.838386) (xy 441.223188 -164.842399) (xy 441.285978 -164.854377) (xy 441.346771 -164.87413)
			(xy 441.40461 -164.901347) (xy 441.458581 -164.935598) (xy 441.507834 -164.976343) (xy 441.551591 -165.02294)
			(xy 441.589164 -165.074655) (xy 441.619958 -165.13067) (xy 441.64349 -165.190103) (xy 441.659387 -165.252017)
			(xy 441.667398 -165.315435) (xy 441.6679 -165.347396) (xy 441.667398 -165.379357) (xy 441.659387 -165.442775)
			(xy 441.64349 -165.504689) (xy 441.619958 -165.564122) (xy 441.589164 -165.620137) (xy 441.551591 -165.671852)
			(xy 441.507834 -165.718449) (xy 441.458581 -165.759194) (xy 441.40461 -165.793445) (xy 441.346771 -165.820662)
			(xy 441.285978 -165.840415) (xy 441.223188 -165.852393) (xy 441.159392 -165.856407) (xy 441.095596 -165.852393)
			(xy 441.032806 -165.840415) (xy 440.972013 -165.820662) (xy 440.914174 -165.793445) (xy 440.860203 -165.759194)
			(xy 440.81095 -165.718449) (xy 440.767193 -165.671852) (xy 440.72962 -165.620137) (xy 440.698826 -165.564122)
			(xy 440.675294 -165.504689) (xy 440.659397 -165.442775) (xy 440.651386 -165.379357) (xy 436.999734 -165.379357)
			(xy 436.993537 -165.381037) (xy 436.927695 -165.38992) (xy 436.894478 -165.390576) (xy 436.880907 -165.391063)
			(xy 436.854745 -165.398299) (xy 436.831415 -165.412175) (xy 436.812566 -165.431708) (xy 436.799531 -165.455518)
			(xy 436.793232 -165.481922) (xy 436.794113 -165.509052) (xy 436.797704 -165.522148) (xy 436.805629 -165.549602)
			(xy 436.814169 -165.6061) (xy 436.814722 -165.63467) (xy 436.814236 -165.661921) (xy 436.80648 -165.715869)
			(xy 436.791125 -165.768164) (xy 436.768483 -165.817741) (xy 436.739017 -165.863591) (xy 436.703326 -165.904782)
			(xy 436.662135 -165.940473) (xy 436.616285 -165.969939) (xy 436.566708 -165.992581) (xy 436.514413 -166.007936)
			(xy 436.460465 -166.015692) (xy 436.405963 -166.015692) (xy 436.352015 -166.007936) (xy 436.29972 -165.992581)
			(xy 436.250143 -165.969939) (xy 436.204293 -165.940473) (xy 436.163102 -165.904782) (xy 436.127411 -165.863591)
			(xy 436.097945 -165.817741) (xy 436.075303 -165.768164) (xy 436.059948 -165.715869) (xy 436.052192 -165.661921)
			(xy 436.051706 -165.63467) (xy 428.943008 -165.63467) (xy 428.943008 -166.335413) (xy 431.164994 -166.335413)
			(xy 431.164994 -166.271491) (xy 431.173005 -166.208073) (xy 431.188902 -166.146159) (xy 431.212434 -166.086726)
			(xy 431.243228 -166.030711) (xy 431.280801 -165.978996) (xy 431.324558 -165.932399) (xy 431.373811 -165.891654)
			(xy 431.427782 -165.857403) (xy 431.485621 -165.830186) (xy 431.546414 -165.810433) (xy 431.609204 -165.798455)
			(xy 431.673 -165.794442) (xy 431.736796 -165.798455) (xy 431.799586 -165.810433) (xy 431.860379 -165.830186)
			(xy 431.918218 -165.857403) (xy 431.972189 -165.891654) (xy 432.021442 -165.932399) (xy 432.065199 -165.978996)
			(xy 432.098488 -166.024814) (xy 437.325768 -166.024814) (xy 437.329839 -165.969192) (xy 437.341965 -165.914755)
			(xy 437.361888 -165.862664) (xy 437.389184 -165.814029) (xy 437.42327 -165.769886) (xy 437.463419 -165.731177)
			(xy 437.508777 -165.698726) (xy 437.558377 -165.673225) (xy 437.611161 -165.655218) (xy 437.666004 -165.645088)
			(xy 437.721738 -165.643051) (xy 437.777175 -165.649151) (xy 437.831132 -165.663257) (xy 437.882461 -165.685069)
			(xy 437.930067 -165.714123) (xy 437.972935 -165.749798) (xy 438.010152 -165.791335) (xy 438.040925 -165.837848)
			(xy 438.064597 -165.888345) (xy 438.080665 -165.941752) (xy 438.088785 -165.996928) (xy 438.089294 -166.024814)
			(xy 438.088785 -166.0527) (xy 438.080665 -166.107876) (xy 438.064597 -166.161283) (xy 438.040925 -166.21178)
			(xy 438.010152 -166.258293) (xy 437.972935 -166.29983) (xy 437.930067 -166.335505) (xy 437.882461 -166.364559)
			(xy 437.831132 -166.386371) (xy 437.777175 -166.400477) (xy 437.721738 -166.406577) (xy 437.666004 -166.40454)
			(xy 437.611161 -166.39441) (xy 437.558377 -166.376403) (xy 437.508777 -166.350902) (xy 437.463419 -166.318451)
			(xy 437.42327 -166.279742) (xy 437.389184 -166.235599) (xy 437.361888 -166.186964) (xy 437.341965 -166.134873)
			(xy 437.329839 -166.080436) (xy 437.325768 -166.024814) (xy 432.098488 -166.024814) (xy 432.102772 -166.030711)
			(xy 432.133566 -166.086726) (xy 432.157098 -166.146159) (xy 432.172995 -166.208073) (xy 432.181006 -166.271491)
			(xy 432.181508 -166.303452) (xy 432.181006 -166.335413) (xy 432.172995 -166.398831) (xy 432.157098 -166.460745)
			(xy 432.133566 -166.520178) (xy 432.102772 -166.576193) (xy 432.065199 -166.627908) (xy 432.021442 -166.674505)
			(xy 431.972189 -166.71525) (xy 431.918218 -166.749501) (xy 431.860379 -166.776718) (xy 431.799586 -166.796471)
			(xy 431.736796 -166.808449) (xy 431.673 -166.812463) (xy 431.609204 -166.808449) (xy 431.546414 -166.796471)
			(xy 431.485621 -166.776718) (xy 431.427782 -166.749501) (xy 431.373811 -166.71525) (xy 431.324558 -166.674505)
			(xy 431.280801 -166.627908) (xy 431.243228 -166.576193) (xy 431.212434 -166.520178) (xy 431.188902 -166.460745)
			(xy 431.173005 -166.398831) (xy 431.164994 -166.335413) (xy 428.943008 -166.335413) (xy 428.943008 -167.159389)
			(xy 435.982104 -167.159389) (xy 435.982104 -167.095467) (xy 435.990115 -167.032049) (xy 436.006012 -166.970135)
			(xy 436.029544 -166.910702) (xy 436.060338 -166.854687) (xy 436.097911 -166.802972) (xy 436.141668 -166.756375)
			(xy 436.190921 -166.71563) (xy 436.244892 -166.681379) (xy 436.302731 -166.654162) (xy 436.363524 -166.634409)
			(xy 436.426314 -166.622431) (xy 436.49011 -166.618418) (xy 436.553906 -166.622431) (xy 436.616696 -166.634409)
			(xy 436.677489 -166.654162) (xy 436.735328 -166.681379) (xy 436.789299 -166.71563) (xy 436.838552 -166.756375)
			(xy 436.882309 -166.802972) (xy 436.919882 -166.854687) (xy 436.945405 -166.901114) (xy 439.684414 -166.901114)
			(xy 439.684922 -166.867954) (xy 439.693538 -166.802196) (xy 439.710627 -166.738116) (xy 439.735899 -166.676799)
			(xy 439.768924 -166.619287) (xy 439.809143 -166.566554) (xy 439.855874 -166.519495) (xy 439.881772 -166.498778)
			(xy 439.889646 -166.492682) (xy 439.899806 -166.475156) (xy 439.91149 -166.384224) (xy 439.90641 -166.364666)
			(xy 439.900314 -166.356792) (xy 439.88545 -166.336729) (xy 439.860505 -166.293476) (xy 439.841412 -166.247339)
			(xy 439.828498 -166.199106) (xy 439.821983 -166.149602) (xy 439.821574 -166.124636) (xy 439.82206 -166.097385)
			(xy 439.829816 -166.043437) (xy 439.845171 -165.991142) (xy 439.867813 -165.941565) (xy 439.897279 -165.895715)
			(xy 439.93297 -165.854524) (xy 439.974161 -165.818833) (xy 440.020011 -165.789367) (xy 440.069588 -165.766725)
			(xy 440.121883 -165.75137) (xy 440.175831 -165.743614) (xy 440.230333 -165.743614) (xy 440.284281 -165.75137)
			(xy 440.336576 -165.766725) (xy 440.386153 -165.789367) (xy 440.432003 -165.818833) (xy 440.473194 -165.854524)
			(xy 440.508885 -165.895715) (xy 440.538351 -165.941565) (xy 440.560993 -165.991142) (xy 440.576348 -166.043437)
			(xy 440.584104 -166.097385) (xy 440.58459 -166.124636) (xy 440.58459 -166.12489) (xy 440.584122 -166.150829)
			(xy 440.577073 -166.202226) (xy 440.563131 -166.252195) (xy 440.542552 -166.299817) (xy 440.515716 -166.344215)
			(xy 440.499754 -166.364666) (xy 440.493404 -166.37254) (xy 440.487562 -166.391844) (xy 440.497214 -166.48303)
			(xy 440.506612 -166.50081) (xy 440.514486 -166.50716) (xy 440.539136 -166.527886) (xy 440.58348 -166.574594)
			(xy 440.621573 -166.626526) (xy 440.652805 -166.682851) (xy 440.676677 -166.742669) (xy 440.692806 -166.805022)
			(xy 440.700935 -166.868912) (xy 440.70143 -166.901114) (xy 440.700928 -166.933075) (xy 440.692917 -166.996493)
			(xy 440.67702 -167.058407) (xy 440.653488 -167.11784) (xy 440.622694 -167.173855) (xy 440.585121 -167.22557)
			(xy 440.541364 -167.272167) (xy 440.492111 -167.312912) (xy 440.43814 -167.347163) (xy 440.380301 -167.37438)
			(xy 440.319508 -167.394133) (xy 440.256718 -167.406111) (xy 440.192922 -167.410125) (xy 440.129126 -167.406111)
			(xy 440.066336 -167.394133) (xy 440.005543 -167.37438) (xy 439.947704 -167.347163) (xy 439.893733 -167.312912)
			(xy 439.84448 -167.272167) (xy 439.800723 -167.22557) (xy 439.76315 -167.173855) (xy 439.732356 -167.11784)
			(xy 439.708824 -167.058407) (xy 439.692927 -166.996493) (xy 439.684916 -166.933075) (xy 439.684414 -166.901114)
			(xy 436.945405 -166.901114) (xy 436.950676 -166.910702) (xy 436.974208 -166.970135) (xy 436.990105 -167.032049)
			(xy 436.998116 -167.095467) (xy 436.998618 -167.127428) (xy 436.998116 -167.159389) (xy 436.990105 -167.222807)
			(xy 436.974208 -167.284721) (xy 436.950676 -167.344154) (xy 436.919882 -167.400169) (xy 436.882309 -167.451884)
			(xy 436.838552 -167.498481) (xy 436.789299 -167.539226) (xy 436.735328 -167.573477) (xy 436.677489 -167.600694)
			(xy 436.616696 -167.620447) (xy 436.553906 -167.632425) (xy 436.49011 -167.636439) (xy 436.426314 -167.632425)
			(xy 436.363524 -167.620447) (xy 436.302731 -167.600694) (xy 436.244892 -167.573477) (xy 436.190921 -167.539226)
			(xy 436.141668 -167.498481) (xy 436.097911 -167.451884) (xy 436.060338 -167.400169) (xy 436.029544 -167.344154)
			(xy 436.006012 -167.284721) (xy 435.990115 -167.222807) (xy 435.982104 -167.159389) (xy 428.943008 -167.159389)
			(xy 428.943008 -167.9021) (xy 442.036696 -167.9021) (xy 442.04071 -167.838303) (xy 442.052689 -167.775512)
			(xy 442.072443 -167.714718) (xy 442.099661 -167.656879) (xy 442.133913 -167.602907) (xy 442.17466 -167.553655)
			(xy 442.221259 -167.509897) (xy 442.272975 -167.472326) (xy 442.328993 -167.441532) (xy 442.388428 -167.418003)
			(xy 442.450343 -167.402108) (xy 442.513762 -167.394099) (xy 442.545724 -167.39362) (xy 442.58075 -167.394179)
			(xy 442.650137 -167.403798) (xy 442.717548 -167.42285) (xy 442.781705 -167.450975) (xy 442.841394 -167.48764)
			(xy 442.868812 -167.509444) (xy 442.877854 -167.516115) (xy 442.899595 -167.521664) (xy 442.910722 -167.520112)
			(xy 442.99886 -167.50284) (xy 443.017148 -167.489632) (xy 443.022482 -167.479726) (xy 443.036978 -167.45435)
			(xy 443.072462 -167.407918) (xy 443.114608 -167.367436) (xy 443.162432 -167.333851) (xy 443.214816 -167.307946)
			(xy 443.270535 -167.290328) (xy 443.328289 -167.281408) (xy 443.357508 -167.280844) (xy 443.384755 -167.281427)
			(xy 443.438695 -167.289183) (xy 443.490983 -167.304537) (xy 443.540553 -167.327176) (xy 443.586396 -167.356639)
			(xy 443.62758 -167.392326) (xy 443.663266 -167.43351) (xy 443.692728 -167.479355) (xy 443.715366 -167.528925)
			(xy 443.730719 -167.581212) (xy 443.738474 -167.635153) (xy 443.738474 -167.689647) (xy 443.730719 -167.743588)
			(xy 443.715366 -167.795875) (xy 443.692728 -167.845445) (xy 443.663266 -167.89129) (xy 443.62758 -167.932474)
			(xy 443.586396 -167.968161) (xy 443.540553 -167.997624) (xy 443.490983 -168.020263) (xy 443.438695 -168.035617)
			(xy 443.384755 -168.043373) (xy 443.357508 -168.04386) (xy 443.325888 -168.043231) (xy 443.263515 -168.032786)
			(xy 443.203725 -168.012182) (xy 443.175644 -167.997632) (xy 443.165494 -167.992823) (xy 443.143102 -167.991495)
			(xy 443.132464 -167.995092) (xy 443.048898 -168.028874) (xy 443.033658 -168.045384) (xy 443.030356 -168.056306)
			(xy 443.020152 -168.086766) (xy 442.993111 -168.145036) (xy 442.958948 -168.199438) (xy 442.918206 -168.249106)
			(xy 442.871535 -168.293248) (xy 442.819678 -168.331162) (xy 442.763458 -168.362244) (xy 442.703773 -168.386)
			(xy 442.641571 -168.402052) (xy 442.577844 -168.410144) (xy 442.545724 -168.410636) (xy 442.513762 -168.410101)
			(xy 442.450343 -168.402092) (xy 442.388428 -168.386197) (xy 442.328992 -168.362668) (xy 442.272975 -168.331874)
			(xy 442.221259 -168.294303) (xy 442.17466 -168.250545) (xy 442.133913 -168.201293) (xy 442.099661 -168.147321)
			(xy 442.072443 -168.089482) (xy 442.052689 -168.028688) (xy 442.04071 -167.965897) (xy 442.036696 -167.9021)
			(xy 428.943008 -167.9021) (xy 428.943008 -170.268095) (xy 433.77078 -170.268095) (xy 433.77078 -170.204173)
			(xy 433.778791 -170.140755) (xy 433.794688 -170.078841) (xy 433.81822 -170.019408) (xy 433.849014 -169.963393)
			(xy 433.886587 -169.911678) (xy 433.930344 -169.865081) (xy 433.979597 -169.824336) (xy 434.033568 -169.790085)
			(xy 434.091407 -169.762868) (xy 434.1522 -169.743115) (xy 434.21499 -169.731137) (xy 434.278786 -169.727124)
			(xy 434.342582 -169.731137) (xy 434.405372 -169.743115) (xy 434.427143 -169.750189) (xy 435.363614 -169.750189)
			(xy 435.363614 -169.686267) (xy 435.371625 -169.622849) (xy 435.387522 -169.560935) (xy 435.411054 -169.501502)
			(xy 435.441848 -169.445487) (xy 435.479421 -169.393772) (xy 435.523178 -169.347175) (xy 435.572431 -169.30643)
			(xy 435.626402 -169.272179) (xy 435.684241 -169.244962) (xy 435.745034 -169.225209) (xy 435.807824 -169.213231)
			(xy 435.87162 -169.209218) (xy 435.935416 -169.213231) (xy 435.998206 -169.225209) (xy 436.058999 -169.244962)
			(xy 436.116838 -169.272179) (xy 436.170809 -169.30643) (xy 436.220062 -169.347175) (xy 436.263819 -169.393772)
			(xy 436.301392 -169.445487) (xy 436.332186 -169.501502) (xy 436.355718 -169.560935) (xy 436.371615 -169.622849)
			(xy 436.379626 -169.686267) (xy 436.380128 -169.718228) (xy 436.379626 -169.750189) (xy 436.378535 -169.758825)
			(xy 442.84493 -169.758825) (xy 442.84493 -169.694903) (xy 442.852941 -169.631485) (xy 442.868838 -169.569571)
			(xy 442.89237 -169.510138) (xy 442.923164 -169.454123) (xy 442.960737 -169.402408) (xy 443.004494 -169.355811)
			(xy 443.053747 -169.315066) (xy 443.107718 -169.280815) (xy 443.165557 -169.253598) (xy 443.22635 -169.233845)
			(xy 443.28914 -169.221867) (xy 443.352936 -169.217854) (xy 443.416732 -169.221867) (xy 443.479522 -169.233845)
			(xy 443.540315 -169.253598) (xy 443.598154 -169.280815) (xy 443.652125 -169.315066) (xy 443.701378 -169.355811)
			(xy 443.745135 -169.402408) (xy 443.782708 -169.454123) (xy 443.813502 -169.510138) (xy 443.837034 -169.569571)
			(xy 443.852931 -169.631485) (xy 443.860942 -169.694903) (xy 443.861444 -169.726864) (xy 443.860942 -169.758825)
			(xy 443.852931 -169.822243) (xy 443.837034 -169.884157) (xy 443.813502 -169.94359) (xy 443.782708 -169.999605)
			(xy 443.745135 -170.05132) (xy 443.701378 -170.097917) (xy 443.652125 -170.138662) (xy 443.598154 -170.172913)
			(xy 443.540315 -170.20013) (xy 443.479522 -170.219883) (xy 443.416732 -170.231861) (xy 443.352936 -170.235875)
			(xy 443.28914 -170.231861) (xy 443.22635 -170.219883) (xy 443.165557 -170.20013) (xy 443.107718 -170.172913)
			(xy 443.053747 -170.138662) (xy 443.004494 -170.097917) (xy 442.960737 -170.05132) (xy 442.923164 -169.999605)
			(xy 442.89237 -169.94359) (xy 442.868838 -169.884157) (xy 442.852941 -169.822243) (xy 442.84493 -169.758825)
			(xy 436.378535 -169.758825) (xy 436.371615 -169.813607) (xy 436.355718 -169.875521) (xy 436.332186 -169.934954)
			(xy 436.301392 -169.990969) (xy 436.263819 -170.042684) (xy 436.220062 -170.089281) (xy 436.170809 -170.130026)
			(xy 436.116838 -170.164277) (xy 436.058999 -170.191494) (xy 435.998206 -170.211247) (xy 435.935416 -170.223225)
			(xy 435.87162 -170.227239) (xy 435.807824 -170.223225) (xy 435.745034 -170.211247) (xy 435.684241 -170.191494)
			(xy 435.626402 -170.164277) (xy 435.572431 -170.130026) (xy 435.523178 -170.089281) (xy 435.479421 -170.042684)
			(xy 435.441848 -169.990969) (xy 435.411054 -169.934954) (xy 435.387522 -169.875521) (xy 435.371625 -169.813607)
			(xy 435.363614 -169.750189) (xy 434.427143 -169.750189) (xy 434.466165 -169.762868) (xy 434.524004 -169.790085)
			(xy 434.577975 -169.824336) (xy 434.627228 -169.865081) (xy 434.670985 -169.911678) (xy 434.708558 -169.963393)
			(xy 434.739352 -170.019408) (xy 434.762884 -170.078841) (xy 434.778781 -170.140755) (xy 434.786792 -170.204173)
			(xy 434.787294 -170.236134) (xy 434.786799 -170.26763) (xy 438.106818 -170.26763) (xy 438.110889 -170.212008)
			(xy 438.123015 -170.157571) (xy 438.142938 -170.10548) (xy 438.170234 -170.056845) (xy 438.20432 -170.012702)
			(xy 438.244469 -169.973993) (xy 438.289827 -169.941542) (xy 438.339427 -169.916041) (xy 438.392211 -169.898034)
			(xy 438.447054 -169.887904) (xy 438.502788 -169.885867) (xy 438.558225 -169.891967) (xy 438.612182 -169.906073)
			(xy 438.663511 -169.927885) (xy 438.711117 -169.956939) (xy 438.753985 -169.992614) (xy 438.791202 -170.034151)
			(xy 438.821975 -170.080664) (xy 438.845647 -170.131161) (xy 438.861715 -170.184568) (xy 438.869835 -170.239744)
			(xy 438.870344 -170.26763) (xy 438.869835 -170.295516) (xy 438.861715 -170.350692) (xy 438.845647 -170.404099)
			(xy 438.821975 -170.454596) (xy 438.791202 -170.501109) (xy 438.753985 -170.542646) (xy 438.711117 -170.578321)
			(xy 438.689626 -170.591437) (xy 440.690502 -170.591437) (xy 440.690502 -170.527515) (xy 440.698513 -170.464097)
			(xy 440.71441 -170.402183) (xy 440.737942 -170.34275) (xy 440.768736 -170.286735) (xy 440.806309 -170.23502)
			(xy 440.850066 -170.188423) (xy 440.899319 -170.147678) (xy 440.95329 -170.113427) (xy 441.011129 -170.08621)
			(xy 441.071922 -170.066457) (xy 441.134712 -170.054479) (xy 441.198508 -170.050466) (xy 441.262304 -170.054479)
			(xy 441.325094 -170.066457) (xy 441.385887 -170.08621) (xy 441.443726 -170.113427) (xy 441.497697 -170.147678)
			(xy 441.54695 -170.188423) (xy 441.590707 -170.23502) (xy 441.62828 -170.286735) (xy 441.659074 -170.34275)
			(xy 441.682606 -170.402183) (xy 441.698503 -170.464097) (xy 441.706514 -170.527515) (xy 441.707016 -170.559476)
			(xy 442.25159 -170.559476) (xy 442.255661 -170.503854) (xy 442.267787 -170.449417) (xy 442.28771 -170.397326)
			(xy 442.315006 -170.348691) (xy 442.349092 -170.304548) (xy 442.389241 -170.265839) (xy 442.434599 -170.233388)
			(xy 442.484199 -170.207887) (xy 442.536983 -170.18988) (xy 442.591826 -170.17975) (xy 442.64756 -170.177713)
			(xy 442.702997 -170.183813) (xy 442.756954 -170.197919) (xy 442.808283 -170.219731) (xy 442.855889 -170.248785)
			(xy 442.898757 -170.28446) (xy 442.935974 -170.325997) (xy 442.966747 -170.37251) (xy 442.990419 -170.423007)
			(xy 443.006487 -170.476414) (xy 443.014607 -170.53159) (xy 443.015116 -170.559476) (xy 443.014607 -170.587362)
			(xy 443.006487 -170.642538) (xy 442.990419 -170.695945) (xy 442.966747 -170.746442) (xy 442.935974 -170.792955)
			(xy 442.898757 -170.834492) (xy 442.855889 -170.870167) (xy 442.808283 -170.899221) (xy 442.756954 -170.921033)
			(xy 442.702997 -170.935139) (xy 442.64756 -170.941239) (xy 442.591826 -170.939202) (xy 442.536983 -170.929072)
			(xy 442.484199 -170.911065) (xy 442.434599 -170.885564) (xy 442.389241 -170.853113) (xy 442.349092 -170.814404)
			(xy 442.315006 -170.770261) (xy 442.28771 -170.721626) (xy 442.267787 -170.669535) (xy 442.255661 -170.615098)
			(xy 442.25159 -170.559476) (xy 441.707016 -170.559476) (xy 441.706514 -170.591437) (xy 441.698503 -170.654855)
			(xy 441.682606 -170.716769) (xy 441.659074 -170.776202) (xy 441.62828 -170.832217) (xy 441.590707 -170.883932)
			(xy 441.54695 -170.930529) (xy 441.497697 -170.971274) (xy 441.443726 -171.005525) (xy 441.385887 -171.032742)
			(xy 441.325094 -171.052495) (xy 441.262304 -171.064473) (xy 441.198508 -171.068487) (xy 441.134712 -171.064473)
			(xy 441.071922 -171.052495) (xy 441.011129 -171.032742) (xy 440.95329 -171.005525) (xy 440.899319 -170.971274)
			(xy 440.850066 -170.930529) (xy 440.806309 -170.883932) (xy 440.768736 -170.832217) (xy 440.737942 -170.776202)
			(xy 440.71441 -170.716769) (xy 440.698513 -170.654855) (xy 440.690502 -170.591437) (xy 438.689626 -170.591437)
			(xy 438.663511 -170.607375) (xy 438.612182 -170.629187) (xy 438.558225 -170.643293) (xy 438.502788 -170.649393)
			(xy 438.447054 -170.647356) (xy 438.392211 -170.637226) (xy 438.339427 -170.619219) (xy 438.289827 -170.593718)
			(xy 438.244469 -170.561267) (xy 438.20432 -170.522558) (xy 438.170234 -170.478415) (xy 438.142938 -170.42978)
			(xy 438.123015 -170.377689) (xy 438.110889 -170.323252) (xy 438.106818 -170.26763) (xy 434.786799 -170.26763)
			(xy 434.786792 -170.268095) (xy 434.778781 -170.331513) (xy 434.762884 -170.393427) (xy 434.739352 -170.45286)
			(xy 434.708558 -170.508875) (xy 434.670985 -170.56059) (xy 434.627228 -170.607187) (xy 434.577975 -170.647932)
			(xy 434.524004 -170.682183) (xy 434.466165 -170.7094) (xy 434.405372 -170.729153) (xy 434.342582 -170.741131)
			(xy 434.278786 -170.745145) (xy 434.21499 -170.741131) (xy 434.1522 -170.729153) (xy 434.091407 -170.7094)
			(xy 434.033568 -170.682183) (xy 433.979597 -170.647932) (xy 433.930344 -170.607187) (xy 433.886587 -170.56059)
			(xy 433.849014 -170.508875) (xy 433.81822 -170.45286) (xy 433.794688 -170.393427) (xy 433.778791 -170.331513)
			(xy 433.77078 -170.268095) (xy 428.943008 -170.268095) (xy 428.943008 -171.161413) (xy 431.164994 -171.161413)
			(xy 431.164994 -171.097491) (xy 431.173005 -171.034073) (xy 431.188902 -170.972159) (xy 431.212434 -170.912726)
			(xy 431.243228 -170.856711) (xy 431.280801 -170.804996) (xy 431.324558 -170.758399) (xy 431.373811 -170.717654)
			(xy 431.427782 -170.683403) (xy 431.485621 -170.656186) (xy 431.546414 -170.636433) (xy 431.609204 -170.624455)
			(xy 431.673 -170.620442) (xy 431.736796 -170.624455) (xy 431.799586 -170.636433) (xy 431.860379 -170.656186)
			(xy 431.918218 -170.683403) (xy 431.972189 -170.717654) (xy 432.021442 -170.758399) (xy 432.065199 -170.804996)
			(xy 432.102772 -170.856711) (xy 432.133566 -170.912726) (xy 432.157098 -170.972159) (xy 432.172995 -171.034073)
			(xy 432.181006 -171.097491) (xy 432.181508 -171.129452) (xy 432.181006 -171.161413) (xy 432.172995 -171.224831)
			(xy 432.157098 -171.286745) (xy 432.133566 -171.346178) (xy 432.102772 -171.402193) (xy 432.065199 -171.453908)
			(xy 432.021442 -171.500505) (xy 431.972189 -171.54125) (xy 431.918218 -171.575501) (xy 431.860379 -171.602718)
			(xy 431.799586 -171.622471) (xy 431.736796 -171.634449) (xy 431.673 -171.638463) (xy 431.609204 -171.634449)
			(xy 431.546414 -171.622471) (xy 431.485621 -171.602718) (xy 431.427782 -171.575501) (xy 431.373811 -171.54125)
			(xy 431.324558 -171.500505) (xy 431.280801 -171.453908) (xy 431.243228 -171.402193) (xy 431.212434 -171.346178)
			(xy 431.188902 -171.286745) (xy 431.173005 -171.224831) (xy 431.164994 -171.161413) (xy 428.943008 -171.161413)
			(xy 428.943008 -171.775077) (xy 436.038238 -171.775077) (xy 436.038238 -171.711155) (xy 436.046249 -171.647737)
			(xy 436.062146 -171.585823) (xy 436.085678 -171.52639) (xy 436.116472 -171.470375) (xy 436.154045 -171.41866)
			(xy 436.197802 -171.372063) (xy 436.247055 -171.331318) (xy 436.301026 -171.297067) (xy 436.358865 -171.26985)
			(xy 436.419658 -171.250097) (xy 436.482448 -171.238119) (xy 436.546244 -171.234106) (xy 436.61004 -171.238119)
			(xy 436.67283 -171.250097) (xy 436.733623 -171.26985) (xy 436.791462 -171.297067) (xy 436.845433 -171.331318)
			(xy 436.894686 -171.372063) (xy 436.938443 -171.41866) (xy 436.976016 -171.470375) (xy 437.00681 -171.52639)
			(xy 437.030342 -171.585823) (xy 437.046239 -171.647737) (xy 437.05425 -171.711155) (xy 437.054752 -171.743116)
			(xy 437.05425 -171.775077) (xy 437.046239 -171.838495) (xy 437.030342 -171.900409) (xy 437.00681 -171.959842)
			(xy 436.976016 -172.015857) (xy 436.938443 -172.067572) (xy 436.894686 -172.114169) (xy 436.845433 -172.154914)
			(xy 436.791462 -172.189165) (xy 436.733623 -172.216382) (xy 436.67283 -172.236135) (xy 436.61004 -172.248113)
			(xy 436.546244 -172.252127) (xy 436.482448 -172.248113) (xy 436.419658 -172.236135) (xy 436.358865 -172.216382)
			(xy 436.301026 -172.189165) (xy 436.247055 -172.154914) (xy 436.197802 -172.114169) (xy 436.154045 -172.067572)
			(xy 436.116472 -172.015857) (xy 436.085678 -171.959842) (xy 436.062146 -171.900409) (xy 436.046249 -171.838495)
			(xy 436.038238 -171.775077) (xy 428.943008 -171.775077) (xy 428.943008 -172.64888) (xy 433.527452 -172.64888)
			(xy 433.531523 -172.593258) (xy 433.543649 -172.538821) (xy 433.563572 -172.48673) (xy 433.590868 -172.438095)
			(xy 433.624954 -172.393952) (xy 433.665103 -172.355243) (xy 433.710461 -172.322792) (xy 433.760061 -172.297291)
			(xy 433.812845 -172.279284) (xy 433.867688 -172.269154) (xy 433.923422 -172.267117) (xy 433.978859 -172.273217)
			(xy 434.032816 -172.287323) (xy 434.084145 -172.309135) (xy 434.131751 -172.338189) (xy 434.174619 -172.373864)
			(xy 434.211836 -172.415401) (xy 434.242609 -172.461914) (xy 434.266281 -172.512411) (xy 434.282349 -172.565818)
			(xy 434.290469 -172.620994) (xy 434.290978 -172.64888) (xy 434.290469 -172.676766) (xy 434.282349 -172.731942)
			(xy 434.266281 -172.785349) (xy 434.242609 -172.835846) (xy 434.211836 -172.882359) (xy 434.174619 -172.923896)
			(xy 434.131751 -172.959571) (xy 434.084145 -172.988625) (xy 434.032816 -173.010437) (xy 433.978859 -173.024543)
			(xy 433.923422 -173.030643) (xy 433.867688 -173.028606) (xy 433.812845 -173.018476) (xy 433.760061 -173.000469)
			(xy 433.710461 -172.974968) (xy 433.665103 -172.942517) (xy 433.624954 -172.903808) (xy 433.590868 -172.859665)
			(xy 433.563572 -172.81103) (xy 433.543649 -172.758939) (xy 433.531523 -172.704502) (xy 433.527452 -172.64888)
			(xy 428.943008 -172.64888) (xy 428.943008 -174.760636) (xy 428.942579 -174.770704) (xy 428.934856 -174.789299)
			(xy 428.928022 -174.796704) (xy 425.613576 -178.11115) (xy 425.610866 -178.113998) (xy 425.606264 -178.120372)
			(xy 425.604432 -178.12385) (xy 425.601848 -178.129277) (xy 425.599024 -178.140956) (xy 425.598844 -178.146964)
			(xy 425.598844 -180.018901) (xy 427.708054 -180.018901) (xy 427.708054 -179.954979) (xy 427.716065 -179.891561)
			(xy 427.731962 -179.829647) (xy 427.755494 -179.770214) (xy 427.786288 -179.714199) (xy 427.823861 -179.662484)
			(xy 427.867618 -179.615887) (xy 427.916871 -179.575142) (xy 427.970842 -179.540891) (xy 428.028681 -179.513674)
			(xy 428.089474 -179.493921) (xy 428.152264 -179.481943) (xy 428.21606 -179.47793) (xy 428.279856 -179.481943)
			(xy 428.342646 -179.493921) (xy 428.403439 -179.513674) (xy 428.461278 -179.540891) (xy 428.515249 -179.575142)
			(xy 428.564502 -179.615887) (xy 428.608259 -179.662484) (xy 428.645832 -179.714199) (xy 428.676626 -179.770214)
			(xy 428.700158 -179.829647) (xy 428.716055 -179.891561) (xy 428.724066 -179.954979) (xy 428.724568 -179.98694)
			(xy 428.724066 -180.018901) (xy 428.716055 -180.082319) (xy 428.700158 -180.144233) (xy 428.676626 -180.203666)
			(xy 428.645832 -180.259681) (xy 428.608259 -180.311396) (xy 428.564502 -180.357993) (xy 428.515249 -180.398738)
			(xy 428.461278 -180.432989) (xy 428.403439 -180.460206) (xy 428.342646 -180.479959) (xy 428.279856 -180.491937)
			(xy 428.21606 -180.495951) (xy 428.152264 -180.491937) (xy 428.089474 -180.479959) (xy 428.028681 -180.460206)
			(xy 427.970842 -180.432989) (xy 427.916871 -180.398738) (xy 427.867618 -180.357993) (xy 427.823861 -180.311396)
			(xy 427.786288 -180.259681) (xy 427.755494 -180.203666) (xy 427.731962 -180.144233) (xy 427.716065 -180.082319)
			(xy 427.708054 -180.018901) (xy 425.598844 -180.018901) (xy 425.598844 -181.32806) (xy 442.083952 -181.32806)
			(xy 442.084389 -181.289772) (xy 442.09101 -181.213482) (xy 442.104157 -181.138042) (xy 442.123733 -181.06401)
			(xy 442.136276 -181.027832) (xy 442.138946 -181.0194) (xy 442.138933 -181.001725) (xy 442.136276 -180.993288)
			(xy 442.123707 -180.957118) (xy 442.104114 -180.883087) (xy 442.090966 -180.807644) (xy 442.084361 -180.73135)
			(xy 442.083952 -180.69306) (xy 442.084389 -180.654772) (xy 442.09101 -180.578482) (xy 442.104157 -180.503042)
			(xy 442.123733 -180.42901) (xy 442.136276 -180.392832) (xy 442.138946 -180.3844) (xy 442.138933 -180.366725)
			(xy 442.136276 -180.358288) (xy 442.123707 -180.322118) (xy 442.104114 -180.248087) (xy 442.090966 -180.172644)
			(xy 442.084361 -180.09635) (xy 442.083952 -180.05806) (xy 442.084389 -180.019772) (xy 442.09101 -179.943482)
			(xy 442.104157 -179.868042) (xy 442.123733 -179.79401) (xy 442.136276 -179.757832) (xy 442.138946 -179.7494)
			(xy 442.138933 -179.731725) (xy 442.136276 -179.723288) (xy 442.123707 -179.687118) (xy 442.104114 -179.613087)
			(xy 442.090966 -179.537644) (xy 442.084361 -179.46135) (xy 442.083952 -179.42306) (xy 442.084428 -179.381958)
			(xy 442.092016 -179.300105) (xy 442.107124 -179.219301) (xy 442.129623 -179.140236) (xy 442.15932 -179.063584)
			(xy 442.195963 -178.989998) (xy 442.239239 -178.920108) (xy 442.288778 -178.854508) (xy 442.344159 -178.793759)
			(xy 442.404908 -178.738378) (xy 442.470508 -178.688839) (xy 442.540398 -178.645563) (xy 442.613984 -178.60892)
			(xy 442.690636 -178.579223) (xy 442.769701 -178.556724) (xy 442.850505 -178.541616) (xy 442.932358 -178.534028)
			(xy 442.97346 -178.533552) (xy 443.011748 -178.533983) (xy 443.088038 -178.540606) (xy 443.163478 -178.553754)
			(xy 443.23751 -178.573332) (xy 443.273688 -178.585876) (xy 443.282125 -178.588527) (xy 443.299795 -178.588527)
			(xy 443.308232 -178.585876) (xy 443.3444 -178.573301) (xy 443.418432 -178.55371) (xy 443.493875 -178.540564)
			(xy 443.57017 -178.53396) (xy 443.60846 -178.533552) (xy 443.646748 -178.533983) (xy 443.723038 -178.540606)
			(xy 443.798478 -178.553754) (xy 443.87251 -178.573332) (xy 443.908688 -178.585876) (xy 443.917125 -178.588527)
			(xy 443.934795 -178.588527) (xy 443.943232 -178.585876) (xy 443.9794 -178.573301) (xy 444.053432 -178.55371)
			(xy 444.128875 -178.540564) (xy 444.20517 -178.53396) (xy 444.24346 -178.533552) (xy 444.281748 -178.533983)
			(xy 444.358038 -178.540606) (xy 444.433478 -178.553754) (xy 444.50751 -178.573332) (xy 444.543688 -178.585876)
			(xy 444.552125 -178.588527) (xy 444.569795 -178.588527) (xy 444.578232 -178.585876) (xy 444.6144 -178.573301)
			(xy 444.688432 -178.55371) (xy 444.763875 -178.540564) (xy 444.84017 -178.53396) (xy 444.87846 -178.533552)
			(xy 444.916748 -178.533983) (xy 444.993038 -178.540606) (xy 445.068478 -178.553754) (xy 445.14251 -178.573332)
			(xy 445.178688 -178.585876) (xy 445.187125 -178.588527) (xy 445.204795 -178.588527) (xy 445.213232 -178.585876)
			(xy 445.2494 -178.573301) (xy 445.323432 -178.55371) (xy 445.398875 -178.540564) (xy 445.47517 -178.53396)
			(xy 445.51346 -178.533552) (xy 445.554561 -178.534105) (xy 445.636412 -178.541686) (xy 445.717214 -178.556786)
			(xy 445.796278 -178.579278) (xy 445.87293 -178.608969) (xy 445.946515 -178.645606) (xy 446.016406 -178.688877)
			(xy 446.082006 -178.738411) (xy 446.142756 -178.793787) (xy 446.198138 -178.854532) (xy 446.247678 -178.920128)
			(xy 446.290955 -178.990015) (xy 446.327598 -179.063597) (xy 446.357296 -179.140246) (xy 446.379795 -179.219308)
			(xy 446.394903 -179.300109) (xy 446.402492 -179.381959) (xy 446.402968 -179.42306) (xy 446.402542 -179.461348)
			(xy 446.395918 -179.537639) (xy 446.382768 -179.613079) (xy 446.363189 -179.687111) (xy 446.350644 -179.723288)
			(xy 446.348013 -179.73173) (xy 446.348 -179.749396) (xy 446.350644 -179.757832) (xy 446.36322 -179.794)
			(xy 446.382811 -179.868032) (xy 446.395956 -179.943475) (xy 446.40256 -180.01977) (xy 446.402968 -180.05806)
			(xy 446.402542 -180.096348) (xy 446.395918 -180.172639) (xy 446.382768 -180.248079) (xy 446.363189 -180.322111)
			(xy 446.350644 -180.358288) (xy 446.348013 -180.36673) (xy 446.348 -180.384396) (xy 446.350644 -180.392832)
			(xy 446.36322 -180.429) (xy 446.382811 -180.503032) (xy 446.395956 -180.578475) (xy 446.40256 -180.65477)
			(xy 446.402968 -180.69306) (xy 446.402542 -180.731348) (xy 446.395918 -180.807639) (xy 446.382768 -180.883079)
			(xy 446.363189 -180.957111) (xy 446.350644 -180.993288) (xy 446.348013 -181.00173) (xy 446.348 -181.019396)
			(xy 446.350644 -181.027832) (xy 446.36322 -181.064) (xy 446.382811 -181.138032) (xy 446.395956 -181.213475)
			(xy 446.40256 -181.28977) (xy 446.402968 -181.32806) (xy 446.40251 -181.369164) (xy 446.394928 -181.451021)
			(xy 446.379825 -181.531829) (xy 446.35733 -181.610899) (xy 446.327635 -181.687555) (xy 446.290994 -181.761145)
			(xy 446.247718 -181.83104) (xy 446.198178 -181.896643) (xy 446.142795 -181.957395) (xy 446.082043 -182.012778)
			(xy 446.01644 -182.062318) (xy 445.946545 -182.105594) (xy 445.872955 -182.142235) (xy 445.796299 -182.17193)
			(xy 445.717229 -182.194425) (xy 445.636421 -182.209528) (xy 445.554564 -182.21711) (xy 445.51346 -182.217568)
			(xy 445.475172 -182.217136) (xy 445.398882 -182.210514) (xy 445.323442 -182.197366) (xy 445.24941 -182.177789)
			(xy 445.213232 -182.165244) (xy 445.204795 -182.162593) (xy 445.187125 -182.162593) (xy 445.178688 -182.165244)
			(xy 445.142518 -182.177814) (xy 445.068487 -182.197406) (xy 444.993044 -182.210554) (xy 444.91675 -182.217159)
			(xy 444.87846 -182.217568) (xy 444.840172 -182.217136) (xy 444.763882 -182.210514) (xy 444.688442 -182.197366)
			(xy 444.61441 -182.177789) (xy 444.578232 -182.165244) (xy 444.569795 -182.162593) (xy 444.552125 -182.162593)
			(xy 444.543688 -182.165244) (xy 444.507518 -182.177814) (xy 444.433487 -182.197406) (xy 444.358044 -182.210554)
			(xy 444.28175 -182.217159) (xy 444.24346 -182.217568) (xy 444.205172 -182.217136) (xy 444.128882 -182.210514)
			(xy 444.053442 -182.197366) (xy 443.97941 -182.177789) (xy 443.943232 -182.165244) (xy 443.934795 -182.162593)
			(xy 443.917125 -182.162593) (xy 443.908688 -182.165244) (xy 443.872518 -182.177814) (xy 443.798487 -182.197406)
			(xy 443.723044 -182.210554) (xy 443.64675 -182.217159) (xy 443.60846 -182.217568) (xy 443.570172 -182.217136)
			(xy 443.493882 -182.210514) (xy 443.418442 -182.197366) (xy 443.34441 -182.177789) (xy 443.308232 -182.165244)
			(xy 443.299795 -182.162593) (xy 443.282125 -182.162593) (xy 443.273688 -182.165244) (xy 443.237518 -182.177814)
			(xy 443.163487 -182.197406) (xy 443.088044 -182.210554) (xy 443.01175 -182.217159) (xy 442.97346 -182.217568)
			(xy 442.932356 -182.217171) (xy 442.850498 -182.209583) (xy 442.76969 -182.194473) (xy 442.69062 -182.171972)
			(xy 442.613964 -182.142271) (xy 442.540376 -182.105625) (xy 442.470483 -182.062344) (xy 442.404881 -182.012799)
			(xy 442.34413 -181.957413) (xy 442.28875 -181.896658) (xy 442.239211 -181.831051) (xy 442.195937 -181.761154)
			(xy 442.159296 -181.687562) (xy 442.129602 -181.610904) (xy 442.107109 -181.531832) (xy 442.092006 -181.451023)
			(xy 442.084425 -181.369164) (xy 442.083952 -181.32806) (xy 425.598844 -181.32806) (xy 425.598844 -186.5851)
			(xy 427.63843 -186.5851) (xy 427.642421 -186.496233) (xy 427.654362 -186.408081) (xy 427.674157 -186.321355)
			(xy 427.701647 -186.236752) (xy 427.73661 -186.154954) (xy 427.778764 -186.076619) (xy 427.827771 -186.002379)
			(xy 427.883235 -185.93283) (xy 427.944711 -185.868534) (xy 428.011703 -185.810006) (xy 428.083671 -185.75772)
			(xy 428.160037 -185.712096) (xy 428.240185 -185.6735) (xy 428.32347 -185.642245) (xy 428.409221 -185.618581)
			(xy 428.496749 -185.602699) (xy 428.585348 -185.594727) (xy 428.629826 -185.594244) (xy 430.382426 -185.594244)
			(xy 430.426902 -185.594748) (xy 430.515496 -185.602724) (xy 430.603018 -185.618609) (xy 430.688764 -185.642275)
			(xy 430.772044 -185.673532) (xy 430.852186 -185.712129) (xy 430.928546 -185.757754) (xy 431.000509 -185.810039)
			(xy 431.067496 -185.868565) (xy 431.128966 -185.93286) (xy 431.184426 -186.002407) (xy 431.233429 -186.076644)
			(xy 431.27558 -186.154975) (xy 431.31054 -186.23677) (xy 431.338027 -186.321368) (xy 431.357821 -186.40809)
			(xy 431.369761 -186.496237) (xy 431.373752 -186.5851) (xy 435.182544 -186.5851) (xy 435.186535 -186.496237)
			(xy 435.198476 -186.408089) (xy 435.218269 -186.321366) (xy 435.245757 -186.236767) (xy 435.280717 -186.154972)
			(xy 435.322869 -186.07664) (xy 435.371872 -186.002402) (xy 435.427332 -185.932856) (xy 435.488804 -185.86856)
			(xy 435.555791 -185.810034) (xy 435.627755 -185.757748) (xy 435.704116 -185.712123) (xy 435.784259 -185.673527)
			(xy 435.867539 -185.64227) (xy 435.953286 -185.618604) (xy 436.040809 -185.602719) (xy 436.129404 -185.594744)
			(xy 436.17388 -185.594244) (xy 437.92648 -185.594244) (xy 437.970958 -185.594731) (xy 438.059556 -185.602704)
			(xy 438.147083 -185.618586) (xy 438.232834 -185.64225) (xy 438.316118 -185.673506) (xy 438.396265 -185.712101)
			(xy 438.47263 -185.757726) (xy 438.544598 -185.810012) (xy 438.611589 -185.868539) (xy 438.673063 -185.932835)
			(xy 438.728527 -186.002383) (xy 438.777533 -186.076623) (xy 438.819687 -186.154957) (xy 438.85465 -186.236755)
			(xy 438.882139 -186.321357) (xy 438.901934 -186.408083) (xy 438.913875 -186.496233) (xy 438.917866 -186.5851)
			(xy 442.72653 -186.5851) (xy 442.730521 -186.496232) (xy 442.742462 -186.40808) (xy 442.762258 -186.321353)
			(xy 442.789748 -186.23675) (xy 442.824711 -186.154952) (xy 442.866866 -186.076617) (xy 442.915873 -186.002376)
			(xy 442.971338 -185.932828) (xy 443.032814 -185.868531) (xy 443.099806 -185.810004) (xy 443.171775 -185.757717)
			(xy 443.248141 -185.712093) (xy 443.32829 -185.673498) (xy 443.411576 -185.642243) (xy 443.497328 -185.618579)
			(xy 443.584856 -185.602698) (xy 443.673455 -185.594727) (xy 443.717934 -185.594244) (xy 445.470534 -185.594244)
			(xy 445.51501 -185.594748) (xy 445.603603 -185.602725) (xy 445.691125 -185.61861) (xy 445.77687 -185.642277)
			(xy 445.860149 -185.673535) (xy 445.940291 -185.712131) (xy 446.01665 -185.757756) (xy 446.088613 -185.810042)
			(xy 446.155599 -185.868568) (xy 446.217069 -185.932863) (xy 446.272528 -186.002409) (xy 446.32153 -186.076647)
			(xy 446.363681 -186.154977) (xy 446.398641 -186.236771) (xy 446.426128 -186.32137) (xy 446.445921 -186.408091)
			(xy 446.457861 -186.496238) (xy 446.461852 -186.5851) (xy 450.27033 -186.5851) (xy 450.274321 -186.496232)
			(xy 450.286262 -186.40808) (xy 450.306058 -186.321353) (xy 450.333548 -186.23675) (xy 450.368511 -186.154952)
			(xy 450.410666 -186.076617) (xy 450.459673 -186.002376) (xy 450.515138 -185.932828) (xy 450.576614 -185.868531)
			(xy 450.643606 -185.810004) (xy 450.715575 -185.757717) (xy 450.791941 -185.712093) (xy 450.87209 -185.673498)
			(xy 450.955376 -185.642243) (xy 451.041128 -185.618579) (xy 451.128656 -185.602698) (xy 451.217255 -185.594727)
			(xy 451.261734 -185.594244) (xy 453.014334 -185.594244) (xy 453.05881 -185.594748) (xy 453.147403 -185.602725)
			(xy 453.234925 -185.61861) (xy 453.32067 -185.642277) (xy 453.403949 -185.673535) (xy 453.484091 -185.712131)
			(xy 453.56045 -185.757756) (xy 453.632413 -185.810042) (xy 453.699399 -185.868568) (xy 453.760869 -185.932863)
			(xy 453.816328 -186.002409) (xy 453.86533 -186.076647) (xy 453.907481 -186.154977) (xy 453.942441 -186.236771)
			(xy 453.969928 -186.32137) (xy 453.989721 -186.408091) (xy 454.001661 -186.496238) (xy 454.005652 -186.5851)
			(xy 454.001661 -186.673962) (xy 453.989721 -186.762109) (xy 453.969928 -186.84883) (xy 453.942441 -186.933429)
			(xy 453.907481 -187.015223) (xy 453.86533 -187.093553) (xy 453.816328 -187.167791) (xy 453.760869 -187.237337)
			(xy 453.699399 -187.301632) (xy 453.632413 -187.360158) (xy 453.56045 -187.412444) (xy 453.484091 -187.458069)
			(xy 453.403949 -187.496665) (xy 453.32067 -187.527923) (xy 453.234925 -187.55159) (xy 453.147403 -187.567475)
			(xy 453.05881 -187.575452) (xy 453.014334 -187.575952) (xy 451.261734 -187.575952) (xy 451.217255 -187.575473)
			(xy 451.128656 -187.567502) (xy 451.041128 -187.551621) (xy 450.955376 -187.527957) (xy 450.87209 -187.496702)
			(xy 450.791941 -187.458107) (xy 450.715575 -187.412483) (xy 450.643606 -187.360196) (xy 450.576614 -187.301669)
			(xy 450.515138 -187.237372) (xy 450.459673 -187.167824) (xy 450.410666 -187.093583) (xy 450.368511 -187.015248)
			(xy 450.333548 -186.93345) (xy 450.306058 -186.848847) (xy 450.286262 -186.76212) (xy 450.274321 -186.673968)
			(xy 450.27033 -186.5851) (xy 446.461852 -186.5851) (xy 446.457861 -186.673962) (xy 446.445921 -186.762109)
			(xy 446.426128 -186.84883) (xy 446.398641 -186.933429) (xy 446.363681 -187.015223) (xy 446.32153 -187.093553)
			(xy 446.272528 -187.167791) (xy 446.217069 -187.237337) (xy 446.155599 -187.301632) (xy 446.088613 -187.360158)
			(xy 446.01665 -187.412444) (xy 445.940291 -187.458069) (xy 445.860149 -187.496665) (xy 445.77687 -187.527923)
			(xy 445.691125 -187.55159) (xy 445.603603 -187.567475) (xy 445.51501 -187.575452) (xy 445.470534 -187.575952)
			(xy 443.717934 -187.575952) (xy 443.673455 -187.575473) (xy 443.584856 -187.567502) (xy 443.497328 -187.551621)
			(xy 443.411576 -187.527957) (xy 443.32829 -187.496702) (xy 443.248141 -187.458107) (xy 443.171775 -187.412483)
			(xy 443.099806 -187.360196) (xy 443.032814 -187.301669) (xy 442.971338 -187.237372) (xy 442.915873 -187.167824)
			(xy 442.866866 -187.093583) (xy 442.824711 -187.015248) (xy 442.789748 -186.93345) (xy 442.762258 -186.848847)
			(xy 442.742462 -186.76212) (xy 442.730521 -186.673968) (xy 442.72653 -186.5851) (xy 438.917866 -186.5851)
			(xy 438.913875 -186.673967) (xy 438.901934 -186.762117) (xy 438.882139 -186.848843) (xy 438.85465 -186.933445)
			(xy 438.819687 -187.015243) (xy 438.777533 -187.093577) (xy 438.728527 -187.167817) (xy 438.673063 -187.237365)
			(xy 438.611589 -187.301661) (xy 438.544598 -187.360188) (xy 438.47263 -187.412474) (xy 438.396265 -187.458099)
			(xy 438.316118 -187.496694) (xy 438.232834 -187.52795) (xy 438.147083 -187.551614) (xy 438.059556 -187.567496)
			(xy 437.970958 -187.575469) (xy 437.92648 -187.575952) (xy 436.17388 -187.575952) (xy 436.129404 -187.575456)
			(xy 436.040809 -187.567481) (xy 435.953286 -187.551596) (xy 435.867539 -187.52793) (xy 435.784259 -187.496673)
			(xy 435.704116 -187.458077) (xy 435.627755 -187.412452) (xy 435.555791 -187.360166) (xy 435.488804 -187.30164)
			(xy 435.427332 -187.237344) (xy 435.371872 -187.167798) (xy 435.322869 -187.09356) (xy 435.280717 -187.015228)
			(xy 435.245757 -186.933433) (xy 435.218269 -186.848834) (xy 435.198476 -186.762111) (xy 435.186535 -186.673963)
			(xy 435.182544 -186.5851) (xy 431.373752 -186.5851) (xy 431.369761 -186.673963) (xy 431.357821 -186.76211)
			(xy 431.338027 -186.848832) (xy 431.31054 -186.93343) (xy 431.27558 -187.015225) (xy 431.233429 -187.093556)
			(xy 431.184426 -187.167793) (xy 431.128966 -187.23734) (xy 431.067496 -187.301635) (xy 431.000509 -187.360161)
			(xy 430.928546 -187.412446) (xy 430.852186 -187.458071) (xy 430.772044 -187.496668) (xy 430.688764 -187.527925)
			(xy 430.603018 -187.551591) (xy 430.515496 -187.567476) (xy 430.426902 -187.575452) (xy 430.382426 -187.575952)
			(xy 428.629826 -187.575952) (xy 428.585348 -187.575473) (xy 428.496749 -187.567501) (xy 428.409221 -187.551619)
			(xy 428.32347 -187.527955) (xy 428.240185 -187.4967) (xy 428.160037 -187.458104) (xy 428.083671 -187.41248)
			(xy 428.011703 -187.360194) (xy 427.944711 -187.301666) (xy 427.883235 -187.23737) (xy 427.827771 -187.167821)
			(xy 427.778764 -187.093581) (xy 427.73661 -187.015246) (xy 427.701647 -186.933448) (xy 427.674157 -186.848845)
			(xy 427.654362 -186.762119) (xy 427.642421 -186.673967) (xy 427.63843 -186.5851) (xy 425.598844 -186.5851)
			(xy 425.598844 -190.240412) (xy 425.598417 -190.25048) (xy 425.590693 -190.269076) (xy 425.583858 -190.27648)
			(xy 425.576536 -190.283803) (xy 450.846438 -190.283803) (xy 450.846438 -190.219881) (xy 450.854449 -190.156463)
			(xy 450.870346 -190.094549) (xy 450.893878 -190.035116) (xy 450.924672 -189.979101) (xy 450.962245 -189.927386)
			(xy 451.006002 -189.880789) (xy 451.055255 -189.840044) (xy 451.109226 -189.805793) (xy 451.167065 -189.778576)
			(xy 451.227858 -189.758823) (xy 451.290648 -189.746845) (xy 451.354444 -189.742832) (xy 451.41824 -189.746845)
			(xy 451.48103 -189.758823) (xy 451.541823 -189.778576) (xy 451.599662 -189.805793) (xy 451.653633 -189.840044)
			(xy 451.702886 -189.880789) (xy 451.746643 -189.927386) (xy 451.784216 -189.979101) (xy 451.81501 -190.035116)
			(xy 451.838542 -190.094549) (xy 451.854439 -190.156463) (xy 451.86245 -190.219881) (xy 451.862952 -190.251842)
			(xy 451.86245 -190.283803) (xy 451.854439 -190.347221) (xy 451.838542 -190.409135) (xy 451.81501 -190.468568)
			(xy 451.784216 -190.524583) (xy 451.746643 -190.576298) (xy 451.702886 -190.622895) (xy 451.653633 -190.66364)
			(xy 451.599662 -190.697891) (xy 451.541823 -190.725108) (xy 451.48103 -190.744861) (xy 451.41824 -190.756839)
			(xy 451.354444 -190.760853) (xy 451.290648 -190.756839) (xy 451.227858 -190.744861) (xy 451.167065 -190.725108)
			(xy 451.109226 -190.697891) (xy 451.055255 -190.66364) (xy 451.006002 -190.622895) (xy 450.962245 -190.576298)
			(xy 450.924672 -190.524583) (xy 450.893878 -190.468568) (xy 450.870346 -190.409135) (xy 450.854449 -190.347221)
			(xy 450.846438 -190.283803) (xy 425.576536 -190.283803) (xy 424.300396 -191.560196) (xy 424.292998 -191.567042)
			(xy 424.2744 -191.574776) (xy 424.264328 -191.575182) (xy 419.57244 -191.575182) (xy 419.563535 -191.575611)
			(xy 419.546822 -191.581776) (xy 419.533215 -191.593274) (xy 419.528498 -191.600836) (xy 419.500558 -191.653668)
			(xy 419.500558 -191.654176) (xy 419.488366 -191.677544) (xy 419.485318 -191.683386) (xy 419.482566 -191.689417)
			(xy 419.479988 -191.702416) (xy 419.480238 -191.70904) (xy 419.481 -191.72301) (xy 419.489128 -191.734694)
			(xy 419.513453 -191.770628) (xy 419.555687 -191.846438) (xy 419.590228 -191.926048) (xy 419.616736 -192.00868)
			(xy 419.634954 -192.093527) (xy 419.644702 -192.179757) (xy 419.645719 -192.21831) (xy 420.698437 -192.21831)
			(xy 420.702372 -192.164539) (xy 420.714095 -192.111915) (xy 420.733355 -192.061558) (xy 420.759741 -192.014541)
			(xy 420.792693 -191.971868) (xy 420.831506 -191.934447) (xy 420.875354 -191.903077) (xy 420.923302 -191.878425)
			(xy 420.974329 -191.861017) (xy 421.027347 -191.851224) (xy 421.081226 -191.849255) (xy 421.134817 -191.855152)
			(xy 421.186978 -191.868788) (xy 421.236598 -191.889875) (xy 421.282619 -191.917961) (xy 421.324061 -191.952449)
			(xy 421.360039 -191.992603) (xy 421.389787 -192.037567) (xy 421.412672 -192.086384) (xy 421.428204 -192.138013)
			(xy 421.436054 -192.191353) (xy 421.436546 -192.21831) (xy 422.487105 -192.21831) (xy 422.49104 -192.164539)
			(xy 422.502763 -192.111915) (xy 422.522023 -192.061558) (xy 422.548409 -192.014541) (xy 422.581361 -191.971868)
			(xy 422.620174 -191.934447) (xy 422.664022 -191.903077) (xy 422.71197 -191.878425) (xy 422.762997 -191.861017)
			(xy 422.816015 -191.851224) (xy 422.869894 -191.849255) (xy 422.923485 -191.855152) (xy 422.975646 -191.868788)
			(xy 423.025266 -191.889875) (xy 423.071287 -191.917961) (xy 423.112729 -191.952449) (xy 423.148707 -191.992603)
			(xy 423.178455 -192.037567) (xy 423.20134 -192.086384) (xy 423.216872 -192.138013) (xy 423.224722 -192.191353)
			(xy 423.225214 -192.21831) (xy 423.224908 -192.2351) (xy 424.277753 -192.2351) (xy 424.281726 -192.151703)
			(xy 424.293608 -192.06906) (xy 424.313293 -191.987922) (xy 424.3406 -191.909022) (xy 424.375284 -191.833075)
			(xy 424.41703 -191.760769) (xy 424.465461 -191.692758) (xy 424.520136 -191.629659) (xy 424.580563 -191.572044)
			(xy 424.646192 -191.520433) (xy 424.71643 -191.475294) (xy 424.790641 -191.437036) (xy 424.868153 -191.406005)
			(xy 424.948263 -191.382483) (xy 425.030246 -191.366683) (xy 425.11336 -191.358747) (xy 425.155106 -191.358266)
			(xy 425.19732 -191.358765) (xy 425.281357 -191.366886) (xy 425.364224 -191.383051) (xy 425.445152 -191.407111)
			(xy 425.52339 -191.438842) (xy 425.598215 -191.477951) (xy 425.668931 -191.524074) (xy 425.702222 -191.550036)
			(xy 425.71154 -191.556809) (xy 425.733972 -191.561947) (xy 425.756404 -191.556809) (xy 425.765722 -191.550036)
			(xy 425.79904 -191.524082) (xy 425.869795 -191.477957) (xy 425.944655 -191.438848) (xy 426.022929 -191.407116)
			(xy 426.103891 -191.383056) (xy 426.186791 -191.366891) (xy 426.270861 -191.358771) (xy 426.313092 -191.358266)
			(xy 426.35614 -191.358828) (xy 426.441821 -191.367266) (xy 426.526263 -191.384061) (xy 426.608652 -191.409053)
			(xy 426.688194 -191.441999) (xy 426.764125 -191.482583) (xy 426.835712 -191.530414) (xy 426.902266 -191.585031)
			(xy 426.963146 -191.645909) (xy 427.017766 -191.712461) (xy 427.0656 -191.784046) (xy 427.106187 -191.859975)
			(xy 427.139136 -191.939516) (xy 427.16413 -192.021904) (xy 427.180929 -192.106345) (xy 427.18937 -192.192026)
			(xy 427.189694 -192.21831) (xy 428.242491 -192.21831) (xy 428.246426 -192.164539) (xy 428.258149 -192.111915)
			(xy 428.277409 -192.061558) (xy 428.303795 -192.014541) (xy 428.336747 -191.971868) (xy 428.37556 -191.934447)
			(xy 428.419408 -191.903077) (xy 428.467356 -191.878425) (xy 428.518383 -191.861017) (xy 428.571401 -191.851224)
			(xy 428.62528 -191.849255) (xy 428.678871 -191.855152) (xy 428.731032 -191.868788) (xy 428.780652 -191.889875)
			(xy 428.826673 -191.917961) (xy 428.868115 -191.952449) (xy 428.904093 -191.992603) (xy 428.933841 -192.037567)
			(xy 428.956726 -192.086384) (xy 428.972258 -192.138013) (xy 428.980108 -192.191353) (xy 428.9806 -192.21831)
			(xy 430.031159 -192.21831) (xy 430.035094 -192.164539) (xy 430.046817 -192.111915) (xy 430.066077 -192.061558)
			(xy 430.092463 -192.014541) (xy 430.125415 -191.971868) (xy 430.164228 -191.934447) (xy 430.208076 -191.903077)
			(xy 430.256024 -191.878425) (xy 430.307051 -191.861017) (xy 430.360069 -191.851224) (xy 430.413948 -191.849255)
			(xy 430.467539 -191.855152) (xy 430.5197 -191.868788) (xy 430.56932 -191.889875) (xy 430.615341 -191.917961)
			(xy 430.656783 -191.952449) (xy 430.692761 -191.992603) (xy 430.722509 -192.037567) (xy 430.745394 -192.086384)
			(xy 430.760926 -192.138013) (xy 430.768776 -192.191353) (xy 430.769268 -192.21831) (xy 430.768962 -192.2351)
			(xy 431.821869 -192.2351) (xy 431.825841 -192.151707) (xy 431.837723 -192.069069) (xy 431.857405 -191.987934)
			(xy 431.88471 -191.909038) (xy 431.919392 -191.833094) (xy 431.961134 -191.760791) (xy 432.009561 -191.692783)
			(xy 432.064232 -191.629686) (xy 432.124654 -191.572072) (xy 432.190278 -191.520461) (xy 432.260511 -191.475322)
			(xy 432.334717 -191.437064) (xy 432.412223 -191.406032) (xy 432.492328 -191.382508) (xy 432.574307 -191.366704)
			(xy 432.657416 -191.358765) (xy 432.69916 -191.358266) (xy 432.741391 -191.358786) (xy 432.825461 -191.366902)
			(xy 432.908361 -191.383063) (xy 432.989324 -191.407119) (xy 433.067599 -191.438847) (xy 433.142462 -191.477953)
			(xy 433.213218 -191.524075) (xy 433.24653 -191.550036) (xy 433.255848 -191.556809) (xy 433.27828 -191.561947)
			(xy 433.300712 -191.556809) (xy 433.31003 -191.550036) (xy 433.343331 -191.524091) (xy 433.414057 -191.477989)
			(xy 433.488884 -191.438896) (xy 433.567121 -191.40717) (xy 433.648044 -191.383107) (xy 433.730903 -191.366929)
			(xy 433.814934 -191.358786) (xy 433.857146 -191.358266) (xy 433.900195 -191.358776) (xy 433.985878 -191.36722)
			(xy 434.07032 -191.38402) (xy 434.15271 -191.409016) (xy 434.232253 -191.441967) (xy 434.308183 -191.482555)
			(xy 434.37977 -191.53039) (xy 434.446323 -191.585011) (xy 434.507203 -191.645892) (xy 434.561822 -191.712446)
			(xy 434.609655 -191.784034) (xy 434.650242 -191.859965) (xy 434.683191 -191.939509) (xy 434.708185 -192.021899)
			(xy 434.724983 -192.106342) (xy 434.733424 -192.192025) (xy 434.733748 -192.21831) (xy 435.786545 -192.21831)
			(xy 435.79048 -192.164539) (xy 435.802203 -192.111915) (xy 435.821463 -192.061558) (xy 435.847849 -192.014541)
			(xy 435.880801 -191.971868) (xy 435.919614 -191.934447) (xy 435.963462 -191.903077) (xy 436.01141 -191.878425)
			(xy 436.062437 -191.861017) (xy 436.115455 -191.851224) (xy 436.169334 -191.849255) (xy 436.222925 -191.855152)
			(xy 436.275086 -191.868788) (xy 436.324706 -191.889875) (xy 436.370727 -191.917961) (xy 436.412169 -191.952449)
			(xy 436.448147 -191.992603) (xy 436.477895 -192.037567) (xy 436.50078 -192.086384) (xy 436.516312 -192.138013)
			(xy 436.524162 -192.191353) (xy 436.524654 -192.21831) (xy 437.575213 -192.21831) (xy 437.579148 -192.164539)
			(xy 437.590871 -192.111915) (xy 437.610131 -192.061558) (xy 437.636517 -192.014541) (xy 437.669469 -191.971868)
			(xy 437.708282 -191.934447) (xy 437.75213 -191.903077) (xy 437.800078 -191.878425) (xy 437.851105 -191.861017)
			(xy 437.904123 -191.851224) (xy 437.958002 -191.849255) (xy 438.011593 -191.855152) (xy 438.063754 -191.868788)
			(xy 438.113374 -191.889875) (xy 438.159395 -191.917961) (xy 438.200837 -191.952449) (xy 438.236815 -191.992603)
			(xy 438.266563 -192.037567) (xy 438.289448 -192.086384) (xy 438.30498 -192.138013) (xy 438.31283 -192.191353)
			(xy 438.313322 -192.21831) (xy 438.313016 -192.2351) (xy 439.365853 -192.2351) (xy 439.369826 -192.151702)
			(xy 439.381709 -192.069059) (xy 439.401393 -191.98792) (xy 439.428701 -191.90902) (xy 439.463385 -191.833073)
			(xy 439.505132 -191.760766) (xy 439.553563 -191.692756) (xy 439.608239 -191.629657) (xy 439.668666 -191.572041)
			(xy 439.734296 -191.52043) (xy 439.804535 -191.475291) (xy 439.878746 -191.437033) (xy 439.956258 -191.406003)
			(xy 440.036369 -191.382482) (xy 440.118353 -191.366682) (xy 440.201468 -191.358747) (xy 440.243214 -191.358266)
			(xy 440.285428 -191.358761) (xy 440.369466 -191.366882) (xy 440.452332 -191.383048) (xy 440.53326 -191.407108)
			(xy 440.611499 -191.43884) (xy 440.686323 -191.47795) (xy 440.757039 -191.524074) (xy 440.79033 -191.550036)
			(xy 440.799648 -191.556809) (xy 440.82208 -191.561947) (xy 440.844512 -191.556809) (xy 440.85383 -191.550036)
			(xy 440.887145 -191.524079) (xy 440.9579 -191.477954) (xy 441.032762 -191.438845) (xy 441.111036 -191.407114)
			(xy 441.191999 -191.383054) (xy 441.274899 -191.36689) (xy 441.358969 -191.35877) (xy 441.4012 -191.358266)
			(xy 441.444248 -191.35882) (xy 441.52993 -191.367259) (xy 441.614371 -191.384055) (xy 441.69676 -191.409047)
			(xy 441.776303 -191.441994) (xy 441.852233 -191.482579) (xy 441.92382 -191.53041) (xy 441.990374 -191.585028)
			(xy 442.051254 -191.645907) (xy 442.105874 -191.712459) (xy 442.153708 -191.784044) (xy 442.194295 -191.859973)
			(xy 442.227244 -191.939515) (xy 442.252238 -192.021903) (xy 442.269037 -192.106345) (xy 442.277478 -192.192026)
			(xy 442.277802 -192.21831) (xy 443.330599 -192.21831) (xy 443.334534 -192.164539) (xy 443.346257 -192.111915)
			(xy 443.365517 -192.061558) (xy 443.391903 -192.014541) (xy 443.424855 -191.971868) (xy 443.463668 -191.934447)
			(xy 443.507516 -191.903077) (xy 443.555464 -191.878425) (xy 443.606491 -191.861017) (xy 443.659509 -191.851224)
			(xy 443.713388 -191.849255) (xy 443.766979 -191.855152) (xy 443.81914 -191.868788) (xy 443.86876 -191.889875)
			(xy 443.914781 -191.917961) (xy 443.956223 -191.952449) (xy 443.992201 -191.992603) (xy 444.021949 -192.037567)
			(xy 444.044834 -192.086384) (xy 444.060366 -192.138013) (xy 444.068216 -192.191353) (xy 444.068708 -192.21831)
			(xy 445.119267 -192.21831) (xy 445.123202 -192.164539) (xy 445.134925 -192.111915) (xy 445.154185 -192.061558)
			(xy 445.180571 -192.014541) (xy 445.213523 -191.971868) (xy 445.252336 -191.934447) (xy 445.296184 -191.903077)
			(xy 445.344132 -191.878425) (xy 445.395159 -191.861017) (xy 445.448177 -191.851224) (xy 445.502056 -191.849255)
			(xy 445.555647 -191.855152) (xy 445.607808 -191.868788) (xy 445.657428 -191.889875) (xy 445.703449 -191.917961)
			(xy 445.744891 -191.952449) (xy 445.780869 -191.992603) (xy 445.810617 -192.037567) (xy 445.833502 -192.086384)
			(xy 445.849034 -192.138013) (xy 445.856884 -192.191353) (xy 445.857376 -192.21831) (xy 445.85707 -192.2351)
			(xy 446.909969 -192.2351) (xy 446.913941 -192.151706) (xy 446.925823 -192.069068) (xy 446.945505 -191.987933)
			(xy 446.972811 -191.909036) (xy 447.007493 -191.833092) (xy 447.049236 -191.760789) (xy 447.097663 -191.692781)
			(xy 447.152335 -191.629684) (xy 447.212757 -191.572069) (xy 447.278382 -191.520459) (xy 447.348616 -191.47532)
			(xy 447.422822 -191.437061) (xy 447.500329 -191.40603) (xy 447.580435 -191.382506) (xy 447.662414 -191.366703)
			(xy 447.745524 -191.358764) (xy 447.787268 -191.358266) (xy 447.829474 -191.358769) (xy 447.913495 -191.366882)
			(xy 447.996348 -191.383027) (xy 448.077268 -191.407053) (xy 448.155506 -191.43874) (xy 448.23034 -191.477794)
			(xy 448.301077 -191.523854) (xy 448.334384 -191.549782) (xy 448.343702 -191.556555) (xy 448.366134 -191.561693)
			(xy 448.388566 -191.556555) (xy 448.397884 -191.549782) (xy 448.431191 -191.523854) (xy 448.501926 -191.47779)
			(xy 448.576759 -191.438733) (xy 448.654997 -191.407045) (xy 448.735918 -191.383019) (xy 448.818772 -191.366877)
			(xy 448.902794 -191.358768) (xy 448.945 -191.358266) (xy 448.988048 -191.35882) (xy 449.07373 -191.367259)
			(xy 449.158171 -191.384055) (xy 449.24056 -191.409047) (xy 449.320103 -191.441994) (xy 449.396033 -191.482579)
			(xy 449.46762 -191.53041) (xy 449.534174 -191.585028) (xy 449.595054 -191.645907) (xy 449.649674 -191.712459)
			(xy 449.697508 -191.784044) (xy 449.738095 -191.859973) (xy 449.771044 -191.939515) (xy 449.796038 -192.021903)
			(xy 449.812837 -192.106345) (xy 449.821278 -192.192026) (xy 449.821602 -192.21831) (xy 450.874399 -192.21831)
			(xy 450.878334 -192.164539) (xy 450.890057 -192.111915) (xy 450.909317 -192.061558) (xy 450.935703 -192.014541)
			(xy 450.968655 -191.971868) (xy 451.007468 -191.934447) (xy 451.051316 -191.903077) (xy 451.099264 -191.878425)
			(xy 451.150291 -191.861017) (xy 451.203309 -191.851224) (xy 451.257188 -191.849255) (xy 451.310779 -191.855152)
			(xy 451.36294 -191.868788) (xy 451.41256 -191.889875) (xy 451.458581 -191.917961) (xy 451.500023 -191.952449)
			(xy 451.536001 -191.992603) (xy 451.565749 -192.037567) (xy 451.588634 -192.086384) (xy 451.604166 -192.138013)
			(xy 451.612016 -192.191353) (xy 451.612508 -192.21831) (xy 452.663067 -192.21831) (xy 452.667002 -192.164539)
			(xy 452.678725 -192.111915) (xy 452.697985 -192.061558) (xy 452.724371 -192.014541) (xy 452.757323 -191.971868)
			(xy 452.796136 -191.934447) (xy 452.839984 -191.903077) (xy 452.887932 -191.878425) (xy 452.938959 -191.861017)
			(xy 452.991977 -191.851224) (xy 453.045856 -191.849255) (xy 453.099447 -191.855152) (xy 453.151608 -191.868788)
			(xy 453.201228 -191.889875) (xy 453.247249 -191.917961) (xy 453.288691 -191.952449) (xy 453.324669 -191.992603)
			(xy 453.354417 -192.037567) (xy 453.377302 -192.086384) (xy 453.392834 -192.138013) (xy 453.400684 -192.191353)
			(xy 453.401176 -192.21831) (xy 453.400684 -192.245267) (xy 453.396041 -192.276818) (xy 454.454757 -192.276818)
			(xy 454.454757 -192.19333) (xy 454.462693 -192.11022) (xy 454.478493 -192.028242) (xy 454.502014 -191.948136)
			(xy 454.533043 -191.870628) (xy 454.5713 -191.796422) (xy 454.616436 -191.726187) (xy 454.668045 -191.660561)
			(xy 454.725658 -191.600139) (xy 454.788754 -191.545466) (xy 454.856761 -191.497038) (xy 454.929064 -191.455294)
			(xy 455.005007 -191.420612) (xy 455.083903 -191.393306) (xy 455.165037 -191.373623) (xy 455.247675 -191.361742)
			(xy 455.331068 -191.357769) (xy 455.414461 -191.361742) (xy 455.497099 -191.373623) (xy 455.578233 -191.393306)
			(xy 455.657129 -191.420612) (xy 455.733072 -191.455294) (xy 455.805375 -191.497038) (xy 455.873382 -191.545466)
			(xy 455.936478 -191.600139) (xy 455.994091 -191.660561) (xy 456.0457 -191.726187) (xy 456.090836 -191.796422)
			(xy 456.129093 -191.870628) (xy 456.160122 -191.948136) (xy 456.183643 -192.028242) (xy 456.199443 -192.11022)
			(xy 456.207379 -192.19333) (xy 456.207876 -192.235074) (xy 456.207379 -192.276818) (xy 456.199443 -192.359928)
			(xy 456.183643 -192.441906) (xy 456.160122 -192.522012) (xy 456.129093 -192.59952) (xy 456.090836 -192.673727)
			(xy 456.0457 -192.743961) (xy 455.994091 -192.809587) (xy 455.936478 -192.870009) (xy 455.873382 -192.924682)
			(xy 455.805375 -192.97311) (xy 455.733072 -193.014854) (xy 455.657129 -193.049536) (xy 455.578233 -193.076842)
			(xy 455.497099 -193.096525) (xy 455.414461 -193.108406) (xy 455.331068 -193.112379) (xy 455.247675 -193.108406)
			(xy 455.165037 -193.096525) (xy 455.083903 -193.076842) (xy 455.005007 -193.049536) (xy 454.929064 -193.014854)
			(xy 454.856761 -192.97311) (xy 454.788754 -192.924682) (xy 454.725658 -192.870009) (xy 454.668045 -192.809587)
			(xy 454.616436 -192.743961) (xy 454.5713 -192.673727) (xy 454.533043 -192.59952) (xy 454.502014 -192.522012)
			(xy 454.478493 -192.441906) (xy 454.462693 -192.359928) (xy 454.454757 -192.276818) (xy 453.396041 -192.276818)
			(xy 453.392834 -192.298607) (xy 453.377302 -192.350236) (xy 453.354417 -192.399053) (xy 453.324669 -192.444017)
			(xy 453.288691 -192.484171) (xy 453.247249 -192.518659) (xy 453.201228 -192.546745) (xy 453.151608 -192.567832)
			(xy 453.099447 -192.581468) (xy 453.045856 -192.587365) (xy 452.991977 -192.585396) (xy 452.938959 -192.575603)
			(xy 452.887932 -192.558195) (xy 452.839984 -192.533543) (xy 452.796136 -192.502173) (xy 452.757323 -192.464752)
			(xy 452.724371 -192.422079) (xy 452.697985 -192.375062) (xy 452.678725 -192.324705) (xy 452.667002 -192.272081)
			(xy 452.663067 -192.21831) (xy 451.612508 -192.21831) (xy 451.612016 -192.245267) (xy 451.604166 -192.298607)
			(xy 451.588634 -192.350236) (xy 451.565749 -192.399053) (xy 451.536001 -192.444017) (xy 451.500023 -192.484171)
			(xy 451.458581 -192.518659) (xy 451.41256 -192.546745) (xy 451.36294 -192.567832) (xy 451.310779 -192.581468)
			(xy 451.257188 -192.587365) (xy 451.203309 -192.585396) (xy 451.150291 -192.575603) (xy 451.099264 -192.558195)
			(xy 451.051316 -192.533543) (xy 451.007468 -192.502173) (xy 450.968655 -192.464752) (xy 450.935703 -192.422079)
			(xy 450.909317 -192.375062) (xy 450.890057 -192.324705) (xy 450.878334 -192.272081) (xy 450.874399 -192.21831)
			(xy 449.821602 -192.21831) (xy 449.821808 -192.235074) (xy 449.82129 -192.276798) (xy 449.813321 -192.359866)
			(xy 449.797502 -192.441803) (xy 449.773975 -192.521867) (xy 449.742952 -192.599335) (xy 449.724272 -192.636648)
			(xy 449.719281 -192.647808) (xy 449.719288 -192.67222) (xy 449.724272 -192.683384) (xy 449.742993 -192.720679)
			(xy 449.77403 -192.798146) (xy 449.79756 -192.878214) (xy 449.813371 -192.960157) (xy 449.82132 -193.043231)
			(xy 449.821808 -193.084958) (xy 449.821348 -193.127336) (xy 449.813168 -193.211697) (xy 449.796881 -193.294873)
			(xy 449.772639 -193.376089) (xy 449.740669 -193.454584) (xy 449.701268 -193.529626) (xy 449.654806 -193.600512)
			(xy 449.601717 -193.666581) (xy 449.542496 -193.727216) (xy 449.477698 -193.781849) (xy 449.443094 -193.806318)
			(xy 449.435415 -193.812098) (xy 449.424717 -193.828048) (xy 449.420621 -193.846812) (xy 449.421758 -193.856356)
			(xy 449.424724 -193.875842) (xy 449.4279 -193.915133) (xy 449.428108 -193.934842) (xy 449.428108 -193.935096)
			(xy 449.427623 -193.96693) (xy 449.423835 -193.996305) (xy 450.73475 -193.996305) (xy 450.738632 -193.933559)
			(xy 450.75022 -193.87177) (xy 450.769337 -193.811881) (xy 450.795692 -193.754806) (xy 450.828882 -193.701416)
			(xy 450.868402 -193.652524) (xy 450.913647 -193.608878) (xy 450.963928 -193.571143) (xy 450.99097 -193.555112)
			(xy 451.001184 -193.5484) (xy 451.014318 -193.527832) (xy 451.016116 -193.515742) (xy 451.025006 -193.420238)
			(xy 451.015608 -193.397378) (xy 451.005956 -193.38925) (xy 450.985806 -193.371638) (xy 450.950309 -193.331589)
			(xy 450.920973 -193.28683) (xy 450.898414 -193.238301) (xy 450.883106 -193.187022) (xy 450.87537 -193.134068)
			(xy 450.874892 -193.10731) (xy 450.875408 -193.07971) (xy 450.883635 -193.025127) (xy 450.899905 -192.97238)
			(xy 450.923855 -192.922648) (xy 450.95495 -192.87704) (xy 450.992495 -192.836576) (xy 451.035652 -192.802159)
			(xy 451.083456 -192.77456) (xy 451.13484 -192.754393) (xy 451.188655 -192.74211) (xy 451.2437 -192.737985)
			(xy 451.298745 -192.74211) (xy 451.35256 -192.754393) (xy 451.403944 -192.77456) (xy 451.451748 -192.802159)
			(xy 451.494905 -192.836576) (xy 451.53245 -192.87704) (xy 451.563545 -192.922648) (xy 451.587495 -192.97238)
			(xy 451.603765 -193.025127) (xy 451.611992 -193.07971) (xy 451.612508 -193.10731) (xy 451.612028 -193.134068)
			(xy 451.604292 -193.187021) (xy 451.588984 -193.238301) (xy 451.566425 -193.286829) (xy 451.537089 -193.331588)
			(xy 451.501593 -193.371636) (xy 451.481444 -193.38925) (xy 451.471792 -193.397378) (xy 451.462394 -193.420238)
			(xy 451.471284 -193.515742) (xy 451.473087 -193.52783) (xy 451.48622 -193.548396) (xy 451.49643 -193.555112)
			(xy 451.523481 -193.571129) (xy 451.573764 -193.608865) (xy 451.619011 -193.652513) (xy 451.658532 -193.701406)
			(xy 451.691723 -193.754798) (xy 451.718079 -193.811875) (xy 451.737197 -193.871766) (xy 451.748786 -193.933557)
			(xy 451.752668 -193.996305) (xy 451.748784 -194.059053) (xy 451.737195 -194.120844) (xy 451.718076 -194.180734)
			(xy 451.691719 -194.237811) (xy 451.658526 -194.291202) (xy 451.619005 -194.340095) (xy 451.573757 -194.383741)
			(xy 451.523473 -194.421477) (xy 451.49643 -194.437508) (xy 451.486247 -194.44426) (xy 451.473098 -194.464799)
			(xy 451.471284 -194.476878) (xy 451.462394 -194.572382) (xy 451.471792 -194.595242) (xy 451.481444 -194.60337)
			(xy 451.501603 -194.620972) (xy 451.5371 -194.661023) (xy 451.566434 -194.705784) (xy 451.588992 -194.754315)
			(xy 451.604298 -194.805596) (xy 451.612032 -194.858551) (xy 451.612508 -194.88531) (xy 451.611992 -194.91291)
			(xy 451.603765 -194.967493) (xy 451.587495 -195.02024) (xy 451.563545 -195.069973) (xy 451.53245 -195.11558)
			(xy 451.494905 -195.156044) (xy 451.451748 -195.190461) (xy 451.403944 -195.21806) (xy 451.35256 -195.238227)
			(xy 451.298745 -195.25051) (xy 451.2437 -195.254635) (xy 451.188655 -195.25051) (xy 451.13484 -195.238227)
			(xy 451.083456 -195.21806) (xy 451.035652 -195.190461) (xy 450.992495 -195.156044) (xy 450.95495 -195.11558)
			(xy 450.923855 -195.069973) (xy 450.899905 -195.02024) (xy 450.883635 -194.967493) (xy 450.875408 -194.91291)
			(xy 450.874892 -194.88531) (xy 450.875386 -194.858553) (xy 450.883119 -194.8056) (xy 450.898425 -194.754321)
			(xy 450.920981 -194.705792) (xy 450.950314 -194.661034) (xy 450.985809 -194.620984) (xy 451.005956 -194.60337)
			(xy 451.015608 -194.595242) (xy 451.025006 -194.572382) (xy 451.016116 -194.476878) (xy 451.014301 -194.464793)
			(xy 451.001177 -194.444226) (xy 450.99097 -194.437508) (xy 450.963937 -194.421462) (xy 450.913655 -194.383728)
			(xy 450.868408 -194.340083) (xy 450.828888 -194.291192) (xy 450.795697 -194.237803) (xy 450.769341 -194.180728)
			(xy 450.750222 -194.12084) (xy 450.738633 -194.059051) (xy 450.73475 -193.996305) (xy 449.423835 -193.996305)
			(xy 449.41948 -194.030075) (xy 449.403314 -194.091657) (xy 449.379391 -194.15066) (xy 449.348107 -194.206112)
			(xy 449.309976 -194.257099) (xy 449.288154 -194.280282) (xy 449.281042 -194.287648) (xy 449.273676 -194.305936)
			(xy 449.274946 -194.397884) (xy 449.282566 -194.416172) (xy 449.289678 -194.423284) (xy 449.313193 -194.447219)
			(xy 449.354313 -194.500243) (xy 449.388099 -194.558217) (xy 449.413964 -194.620132) (xy 449.431457 -194.684912)
			(xy 449.440275 -194.75143) (xy 449.440808 -194.78498) (xy 449.440306 -194.816941) (xy 449.432295 -194.880359)
			(xy 449.416398 -194.942273) (xy 449.392866 -195.001706) (xy 449.362072 -195.057721) (xy 449.324499 -195.109436)
			(xy 449.280742 -195.156033) (xy 449.231489 -195.196778) (xy 449.177518 -195.231029) (xy 449.119679 -195.258246)
			(xy 449.058886 -195.277999) (xy 448.996096 -195.289977) (xy 448.9323 -195.293991) (xy 448.868504 -195.289977)
			(xy 448.805714 -195.277999) (xy 448.744921 -195.258246) (xy 448.687082 -195.231029) (xy 448.633111 -195.196778)
			(xy 448.583858 -195.156033) (xy 448.540101 -195.109436) (xy 448.502528 -195.057721) (xy 448.471734 -195.001706)
			(xy 448.448202 -194.942273) (xy 448.432305 -194.880359) (xy 448.424294 -194.816941) (xy 448.423792 -194.78498)
			(xy 448.424347 -194.751433) (xy 448.433183 -194.684923) (xy 448.450686 -194.620152) (xy 448.476552 -194.558244)
			(xy 448.510331 -194.500274) (xy 448.551438 -194.447247) (xy 448.574922 -194.423284) (xy 448.581637 -194.415955)
			(xy 448.589339 -194.397649) (xy 448.589908 -194.387724) (xy 448.590924 -194.305936) (xy 448.583558 -194.287648)
			(xy 448.576446 -194.280282) (xy 448.554602 -194.257121) (xy 448.516487 -194.206122) (xy 448.485214 -194.150663)
			(xy 448.461298 -194.091657) (xy 448.445131 -194.030075) (xy 448.436982 -193.96693) (xy 448.436492 -193.935096)
			(xy 448.436782 -193.911647) (xy 448.441231 -193.864959) (xy 448.445382 -193.841878) (xy 448.446775 -193.832388)
			(xy 448.443257 -193.81355) (xy 448.433055 -193.797328) (xy 448.42557 -193.791332) (xy 448.393513 -193.767219)
			(xy 448.333484 -193.714004) (xy 448.278568 -193.655525) (xy 448.229227 -193.592273) (xy 448.185872 -193.524776)
			(xy 448.148867 -193.4536) (xy 448.118521 -193.37934) (xy 448.095089 -193.302617) (xy 448.078766 -193.224074)
			(xy 448.07378 -193.184272) (xy 448.072114 -193.173871) (xy 448.061612 -193.155637) (xy 448.05346 -193.148966)
			(xy 447.993262 -193.10477) (xy 447.984553 -193.099028) (xy 447.964224 -193.094443) (xy 447.953892 -193.09588)
			(xy 447.953384 -193.09588) (xy 447.912263 -193.103363) (xy 447.829061 -193.111376) (xy 447.787268 -193.111882)
			(xy 447.745524 -193.111436) (xy 447.662414 -193.103497) (xy 447.580435 -193.087694) (xy 447.500329 -193.06417)
			(xy 447.422822 -193.033139) (xy 447.348616 -192.99488) (xy 447.278382 -192.949741) (xy 447.212757 -192.898131)
			(xy 447.152335 -192.840516) (xy 447.097663 -192.777419) (xy 447.049236 -192.709411) (xy 447.007493 -192.637108)
			(xy 446.972811 -192.561164) (xy 446.945505 -192.482267) (xy 446.925823 -192.401132) (xy 446.913941 -192.318494)
			(xy 446.909969 -192.2351) (xy 445.85707 -192.2351) (xy 445.856884 -192.245267) (xy 445.849034 -192.298607)
			(xy 445.833502 -192.350236) (xy 445.810617 -192.399053) (xy 445.780869 -192.444017) (xy 445.744891 -192.484171)
			(xy 445.703449 -192.518659) (xy 445.657428 -192.546745) (xy 445.607808 -192.567832) (xy 445.555647 -192.581468)
			(xy 445.502056 -192.587365) (xy 445.448177 -192.585396) (xy 445.395159 -192.575603) (xy 445.344132 -192.558195)
			(xy 445.296184 -192.533543) (xy 445.252336 -192.502173) (xy 445.213523 -192.464752) (xy 445.180571 -192.422079)
			(xy 445.154185 -192.375062) (xy 445.134925 -192.324705) (xy 445.123202 -192.272081) (xy 445.119267 -192.21831)
			(xy 444.068708 -192.21831) (xy 444.068216 -192.245267) (xy 444.060366 -192.298607) (xy 444.044834 -192.350236)
			(xy 444.021949 -192.399053) (xy 443.992201 -192.444017) (xy 443.956223 -192.484171) (xy 443.914781 -192.518659)
			(xy 443.86876 -192.546745) (xy 443.81914 -192.567832) (xy 443.766979 -192.581468) (xy 443.713388 -192.587365)
			(xy 443.659509 -192.585396) (xy 443.606491 -192.575603) (xy 443.555464 -192.558195) (xy 443.507516 -192.533543)
			(xy 443.463668 -192.502173) (xy 443.424855 -192.464752) (xy 443.391903 -192.422079) (xy 443.365517 -192.375062)
			(xy 443.346257 -192.324705) (xy 443.334534 -192.272081) (xy 443.330599 -192.21831) (xy 442.277802 -192.21831)
			(xy 442.278008 -192.235074) (xy 442.27749 -192.276798) (xy 442.269521 -192.359866) (xy 442.253702 -192.441803)
			(xy 442.230175 -192.521867) (xy 442.199152 -192.599335) (xy 442.180472 -192.636648) (xy 442.175481 -192.647808)
			(xy 442.175488 -192.67222) (xy 442.180472 -192.683384) (xy 442.199193 -192.720679) (xy 442.23023 -192.798146)
			(xy 442.25376 -192.878214) (xy 442.269571 -192.960157) (xy 442.27752 -193.043231) (xy 442.278008 -193.084958)
			(xy 442.277548 -193.127336) (xy 442.269368 -193.211697) (xy 442.253081 -193.294873) (xy 442.228839 -193.376089)
			(xy 442.196869 -193.454584) (xy 442.157468 -193.529626) (xy 442.111006 -193.600512) (xy 442.057917 -193.666581)
			(xy 441.998696 -193.727216) (xy 441.933898 -193.781849) (xy 441.899294 -193.806318) (xy 441.891615 -193.812098)
			(xy 441.880917 -193.828048) (xy 441.876821 -193.846812) (xy 441.877958 -193.856356) (xy 441.880924 -193.875842)
			(xy 441.8841 -193.915133) (xy 441.884308 -193.934842) (xy 441.884308 -193.935096) (xy 441.88386 -193.964738)
			(xy 441.880064 -193.996305) (xy 443.203582 -193.996305) (xy 443.207429 -193.934628) (xy 443.21891 -193.873908)
			(xy 443.237848 -193.815084) (xy 443.263949 -193.75907) (xy 443.296808 -193.706734) (xy 443.335917 -193.658887)
			(xy 443.380668 -193.616271) (xy 443.430368 -193.579546) (xy 443.457076 -193.564002) (xy 443.467998 -193.557906)
			(xy 443.481714 -193.53657) (xy 443.49035 -193.42735) (xy 443.48019 -193.403982) (xy 443.470284 -193.396108)
			(xy 443.448981 -193.378502) (xy 443.411338 -193.338041) (xy 443.38016 -193.292413) (xy 443.356144 -193.242641)
			(xy 443.33983 -193.18984) (xy 443.331583 -193.135196) (xy 443.331092 -193.107564) (xy 443.331092 -193.10731)
			(xy 443.331608 -193.07971) (xy 443.339835 -193.025127) (xy 443.356105 -192.97238) (xy 443.380055 -192.922648)
			(xy 443.41115 -192.87704) (xy 443.448695 -192.836576) (xy 443.491852 -192.802159) (xy 443.539656 -192.77456)
			(xy 443.59104 -192.754393) (xy 443.644855 -192.74211) (xy 443.6999 -192.737985) (xy 443.754945 -192.74211)
			(xy 443.80876 -192.754393) (xy 443.860144 -192.77456) (xy 443.907948 -192.802159) (xy 443.951105 -192.836576)
			(xy 443.98865 -192.87704) (xy 444.019745 -192.922648) (xy 444.043695 -192.97238) (xy 444.059965 -193.025127)
			(xy 444.068192 -193.07971) (xy 444.068708 -193.10731) (xy 444.068708 -193.107564) (xy 444.068205 -193.135194)
			(xy 444.059941 -193.189833) (xy 444.043621 -193.24263) (xy 444.019611 -193.292402) (xy 443.988448 -193.338037)
			(xy 443.950828 -193.378516) (xy 443.929516 -193.396108) (xy 443.91961 -193.403982) (xy 443.90945 -193.42735)
			(xy 443.918086 -193.53657) (xy 443.931802 -193.557906) (xy 443.942724 -193.564002) (xy 443.969441 -193.579531)
			(xy 444.019143 -193.616258) (xy 444.063896 -193.658875) (xy 444.103006 -193.706724) (xy 444.135866 -193.759062)
			(xy 444.161968 -193.815078) (xy 444.180907 -193.873903) (xy 444.192388 -193.934626) (xy 444.196235 -193.996305)
			(xy 444.192387 -194.057984) (xy 444.180904 -194.118706) (xy 444.161965 -194.177531) (xy 444.135862 -194.233547)
			(xy 444.103 -194.285884) (xy 444.063889 -194.333732) (xy 444.019136 -194.376349) (xy 443.969433 -194.413074)
			(xy 443.942724 -194.428618) (xy 443.931802 -194.434714) (xy 443.918086 -194.45605) (xy 443.90945 -194.56527)
			(xy 443.91961 -194.588638) (xy 443.929516 -194.596512) (xy 443.950829 -194.614107) (xy 443.988471 -194.65457)
			(xy 444.019648 -194.7002) (xy 444.043662 -194.749975) (xy 444.059974 -194.802777) (xy 444.068218 -194.857424)
			(xy 444.068708 -194.885056) (xy 444.068708 -194.88531) (xy 444.068192 -194.91291) (xy 444.059965 -194.967493)
			(xy 444.043695 -195.02024) (xy 444.019745 -195.069973) (xy 443.98865 -195.11558) (xy 443.951105 -195.156044)
			(xy 443.907948 -195.190461) (xy 443.860144 -195.21806) (xy 443.80876 -195.238227) (xy 443.754945 -195.25051)
			(xy 443.6999 -195.254635) (xy 443.644855 -195.25051) (xy 443.59104 -195.238227) (xy 443.539656 -195.21806)
			(xy 443.491852 -195.190461) (xy 443.448695 -195.156044) (xy 443.41115 -195.11558) (xy 443.380055 -195.069973)
			(xy 443.356105 -195.02024) (xy 443.339835 -194.967493) (xy 443.331608 -194.91291) (xy 443.331092 -194.88531)
			(xy 443.331092 -194.885056) (xy 443.331609 -194.857426) (xy 443.33987 -194.802788) (xy 443.356187 -194.749992)
			(xy 443.380195 -194.70022) (xy 443.411356 -194.654584) (xy 443.448973 -194.614105) (xy 443.470284 -194.596512)
			(xy 443.48019 -194.588638) (xy 443.49035 -194.56527) (xy 443.481714 -194.45605) (xy 443.467998 -194.434714)
			(xy 443.457076 -194.428618) (xy 443.430376 -194.413059) (xy 443.380676 -194.376335) (xy 443.335923 -194.33372)
			(xy 443.296814 -194.285874) (xy 443.263954 -194.233538) (xy 443.237852 -194.177525) (xy 443.218913 -194.118702)
			(xy 443.20743 -194.057982) (xy 443.203582 -193.996305) (xy 441.880064 -193.996305) (xy 441.876781 -194.023599)
			(xy 441.862737 -194.081196) (xy 441.841927 -194.136708) (xy 441.814648 -194.189344) (xy 441.78129 -194.238353)
			(xy 441.762134 -194.260978) (xy 441.756122 -194.268504) (xy 441.749715 -194.286652) (xy 441.749688 -194.296284)
			(xy 441.75299 -194.376294) (xy 441.761118 -194.39382) (xy 441.767976 -194.400678) (xy 441.791941 -194.424715)
			(xy 441.833935 -194.478042) (xy 441.868464 -194.53648) (xy 441.894913 -194.598991) (xy 441.912812 -194.664465)
			(xy 441.921843 -194.731738) (xy 441.922408 -194.765676) (xy 441.92194 -194.796408) (xy 441.914534 -194.857423)
			(xy 441.899827 -194.917101) (xy 441.878034 -194.974571) (xy 441.849473 -195.028994) (xy 441.814559 -195.079579)
			(xy 441.773803 -195.125586) (xy 441.727798 -195.166344) (xy 441.677215 -195.20126) (xy 441.622792 -195.229824)
			(xy 441.565324 -195.25162) (xy 441.505647 -195.26633) (xy 441.444632 -195.273738) (xy 441.4139 -195.274184)
			(xy 441.380915 -195.273672) (xy 441.315498 -195.265152) (xy 441.251733 -195.248242) (xy 441.19069 -195.223225)
			(xy 441.133397 -195.190523) (xy 441.080815 -195.150685) (xy 441.033827 -195.10438) (xy 440.993224 -195.052386)
			(xy 440.976004 -195.024248) (xy 440.971141 -195.01674) (xy 440.957345 -195.005375) (xy 440.940494 -194.999411)
			(xy 440.931554 -194.999102) (xy 440.8297 -195.000372) (xy 440.806332 -195.014342) (xy 440.799728 -195.02628)
			(xy 440.782239 -195.056445) (xy 440.740124 -195.112015) (xy 440.690652 -195.161151) (xy 440.663076 -195.18249)
			(xy 440.654694 -195.188586) (xy 440.64428 -195.206366) (xy 440.633866 -195.28917) (xy 440.632989 -195.299178)
			(xy 440.638229 -195.318557) (xy 440.644026 -195.326762) (xy 440.644534 -195.32727) (xy 440.664737 -195.353657)
			(xy 440.698681 -195.410791) (xy 440.724689 -195.471947) (xy 440.742295 -195.53603) (xy 440.751183 -195.60189)
			(xy 440.751722 -195.635118) (xy 440.751233 -195.666281) (xy 440.743421 -195.728115) (xy 440.727921 -195.788483)
			(xy 440.704978 -195.846431) (xy 440.69715 -195.86067) (xy 444.979806 -195.86067) (xy 444.980358 -195.827511)
			(xy 444.988967 -195.761756) (xy 445.006049 -195.697676) (xy 445.031313 -195.63636) (xy 445.064332 -195.578847)
			(xy 445.104544 -195.526113) (xy 445.151269 -195.479052) (xy 445.177164 -195.458334) (xy 445.18608 -195.45079)
			(xy 445.196404 -195.429868) (xy 445.196976 -195.418202) (xy 445.196976 -195.337938) (xy 445.196322 -195.326292)
			(xy 445.186023 -195.305392) (xy 445.177164 -195.297806) (xy 445.151253 -195.277107) (xy 445.10453 -195.230041)
			(xy 445.064319 -195.177303) (xy 445.031301 -195.119787) (xy 445.006036 -195.058469) (xy 444.988952 -194.994387)
			(xy 444.980339 -194.92863) (xy 444.979806 -194.89547) (xy 444.980389 -194.861624) (xy 444.98935 -194.794529)
			(xy 445.007136 -194.729217) (xy 445.033433 -194.666843) (xy 445.067774 -194.60851) (xy 445.109554 -194.555251)
			(xy 445.158032 -194.508008) (xy 445.212351 -194.467617) (xy 445.24168 -194.450716) (xy 445.241934 -194.450716)
			(xy 445.252442 -194.444053) (xy 445.265901 -194.423164) (xy 445.267588 -194.410838) (xy 445.276224 -194.314064)
			(xy 445.266318 -194.29095) (xy 445.256412 -194.282822) (xy 445.23545 -194.26523) (xy 445.198479 -194.224887)
			(xy 445.167879 -194.17952) (xy 445.144323 -194.130127) (xy 445.128331 -194.077794) (xy 445.120252 -194.023671)
			(xy 445.11976 -193.99631) (xy 445.120276 -193.96871) (xy 445.128503 -193.914127) (xy 445.144773 -193.86138)
			(xy 445.168723 -193.811648) (xy 445.199818 -193.76604) (xy 445.237363 -193.725576) (xy 445.28052 -193.691159)
			(xy 445.328324 -193.66356) (xy 445.379708 -193.643393) (xy 445.433523 -193.63111) (xy 445.488568 -193.626985)
			(xy 445.543613 -193.63111) (xy 445.597428 -193.643393) (xy 445.648812 -193.66356) (xy 445.696616 -193.691159)
			(xy 445.739773 -193.725576) (xy 445.777318 -193.76604) (xy 445.808413 -193.811648) (xy 445.832363 -193.86138)
			(xy 445.848633 -193.914127) (xy 445.85686 -193.96871) (xy 445.857376 -193.99631) (xy 445.85685 -194.023699)
			(xy 445.848747 -194.077874) (xy 445.832721 -194.130256) (xy 445.809124 -194.179691) (xy 445.778476 -194.225093)
			(xy 445.74145 -194.265462) (xy 445.72047 -194.283076) (xy 445.711189 -194.291389) (xy 445.701482 -194.31431)
			(xy 445.701928 -194.326764) (xy 445.709294 -194.410838) (xy 445.710915 -194.42324) (xy 445.724376 -194.444286)
			(xy 445.734948 -194.45097) (xy 445.735202 -194.45097) (xy 445.764509 -194.467862) (xy 445.818776 -194.508246)
			(xy 445.867207 -194.555471) (xy 445.908946 -194.608703) (xy 445.943257 -194.667) (xy 445.969532 -194.729333)
			(xy 445.987308 -194.7946) (xy 445.99627 -194.861648) (xy 445.996822 -194.89547) (xy 445.996289 -194.928629)
			(xy 445.987675 -194.994385) (xy 445.970589 -195.058465) (xy 445.945322 -195.119781) (xy 445.912301 -195.177293)
			(xy 445.872086 -195.230027) (xy 445.82536 -195.277088) (xy 445.799464 -195.297806) (xy 445.790534 -195.305337)
			(xy 445.780216 -195.326268) (xy 445.779652 -195.337938) (xy 445.779652 -195.418202) (xy 445.780274 -195.429853)
			(xy 445.790595 -195.450753) (xy 445.799464 -195.458334) (xy 445.825352 -195.47906) (xy 445.872075 -195.526122)
			(xy 445.912287 -195.578856) (xy 445.944591 -195.635118) (xy 447.30416 -195.635118) (xy 447.304644 -195.602396)
			(xy 447.313248 -195.537521) (xy 447.33031 -195.474341) (xy 447.355533 -195.413953) (xy 447.388478 -195.357407)
			(xy 447.428574 -195.305685) (xy 447.45148 -195.282312) (xy 447.458394 -195.274862) (xy 447.466263 -195.256142)
			(xy 447.46672 -195.24599) (xy 447.46672 -195.174108) (xy 447.466297 -195.163947) (xy 447.458431 -195.14521)
			(xy 447.45148 -195.137786) (xy 447.428566 -195.114423) (xy 447.388484 -195.062693) (xy 447.355551 -195.006143)
			(xy 447.330338 -194.945754) (xy 447.313283 -194.882574) (xy 447.304683 -194.817701) (xy 447.30416 -194.78498)
			(xy 447.304649 -194.753817) (xy 447.312461 -194.691983) (xy 447.327961 -194.631615) (xy 447.350904 -194.573667)
			(xy 447.38093 -194.51905) (xy 447.417564 -194.468628) (xy 447.460229 -194.423194) (xy 447.508251 -194.383466)
			(xy 447.560875 -194.350071) (xy 447.617269 -194.323534) (xy 447.676544 -194.304274) (xy 447.737765 -194.292595)
			(xy 447.799968 -194.288682) (xy 447.862171 -194.292595) (xy 447.923392 -194.304274) (xy 447.982667 -194.323534)
			(xy 448.039061 -194.350071) (xy 448.091685 -194.383466) (xy 448.139707 -194.423194) (xy 448.182372 -194.468628)
			(xy 448.219006 -194.51905) (xy 448.249032 -194.573667) (xy 448.271975 -194.631615) (xy 448.287475 -194.691983)
			(xy 448.295287 -194.753817) (xy 448.295776 -194.78498) (xy 448.29528 -194.817701) (xy 448.286677 -194.882576)
			(xy 448.269617 -194.945755) (xy 448.244396 -195.006143) (xy 448.211453 -195.062689) (xy 448.171361 -195.114412)
			(xy 448.148456 -195.137786) (xy 448.141504 -195.145206) (xy 448.133656 -195.163948) (xy 448.133216 -195.174108)
			(xy 448.133216 -195.24599) (xy 448.133631 -195.256152) (xy 448.141501 -195.274889) (xy 448.148456 -195.282312)
			(xy 448.171376 -195.305669) (xy 448.211456 -195.357401) (xy 448.244388 -195.413953) (xy 448.269599 -195.474343)
			(xy 448.286653 -195.537523) (xy 448.295254 -195.602397) (xy 448.295776 -195.635118) (xy 448.295287 -195.666281)
			(xy 448.287475 -195.728115) (xy 448.271975 -195.788483) (xy 448.249032 -195.846431) (xy 448.219006 -195.901048)
			(xy 448.200361 -195.92671) (xy 452.52386 -195.92671) (xy 452.524386 -195.893551) (xy 452.533002 -195.827794)
			(xy 452.550089 -195.763715) (xy 452.575358 -195.702399) (xy 452.60838 -195.644887) (xy 452.648596 -195.592153)
			(xy 452.695322 -195.545092) (xy 452.721218 -195.524374) (xy 452.730108 -195.516803) (xy 452.740448 -195.495902)
			(xy 452.74103 -195.484242) (xy 452.74103 -195.403978) (xy 452.740426 -195.392324) (xy 452.730093 -195.371425)
			(xy 452.721218 -195.363846) (xy 452.695316 -195.343136) (xy 452.648595 -195.296071) (xy 452.608384 -195.243334)
			(xy 452.575366 -195.18582) (xy 452.550099 -195.124504) (xy 452.533012 -195.060425) (xy 452.524395 -194.994669)
			(xy 452.52386 -194.96151) (xy 452.524347 -194.928552) (xy 452.532856 -194.863189) (xy 452.549744 -194.799474)
			(xy 452.57473 -194.738478) (xy 452.607392 -194.681224) (xy 452.647183 -194.628675) (xy 452.693435 -194.581711)
			(xy 452.74537 -194.541122) (xy 452.802118 -194.507589) (xy 452.832216 -194.49415) (xy 452.83247 -194.49415)
			(xy 452.840801 -194.490066) (xy 452.854011 -194.477061) (xy 452.861705 -194.460195) (xy 452.862696 -194.45097)
			(xy 452.868792 -194.360546) (xy 452.868984 -194.351147) (xy 452.863392 -194.333214) (xy 452.851756 -194.318466)
			(xy 452.8439 -194.313302) (xy 452.820726 -194.298934) (xy 452.778469 -194.26448) (xy 452.741745 -194.224179)
			(xy 452.711357 -194.178909) (xy 452.687966 -194.129659) (xy 452.672082 -194.0775) (xy 452.664051 -194.023572)
			(xy 452.66356 -193.99631) (xy 452.664076 -193.96871) (xy 452.672303 -193.914127) (xy 452.688573 -193.86138)
			(xy 452.712523 -193.811648) (xy 452.743618 -193.76604) (xy 452.781163 -193.725576) (xy 452.82432 -193.691159)
			(xy 452.872124 -193.66356) (xy 452.923508 -193.643393) (xy 452.977323 -193.63111) (xy 453.032368 -193.626985)
			(xy 453.087413 -193.63111) (xy 453.141228 -193.643393) (xy 453.192612 -193.66356) (xy 453.240416 -193.691159)
			(xy 453.283573 -193.725576) (xy 453.321118 -193.76604) (xy 453.352213 -193.811648) (xy 453.376163 -193.86138)
			(xy 453.392433 -193.914127) (xy 453.40066 -193.96871) (xy 453.401176 -193.99631) (xy 453.40064 -194.02357)
			(xy 453.392612 -194.077496) (xy 453.376734 -194.129652) (xy 453.353351 -194.178903) (xy 453.322972 -194.224176)
			(xy 453.28626 -194.264483) (xy 453.244015 -194.298946) (xy 453.220836 -194.313302) (xy 453.2129 -194.318382)
			(xy 453.201196 -194.333134) (xy 453.195646 -194.351128) (xy 453.195944 -194.360546) (xy 453.203056 -194.465194)
			(xy 453.219312 -194.488308) (xy 453.232266 -194.49415) (xy 453.232774 -194.49415) (xy 453.262863 -194.507578)
			(xy 453.319555 -194.541156) (xy 453.371437 -194.581775) (xy 453.417638 -194.628754) (xy 453.457384 -194.681307)
			(xy 453.490011 -194.738553) (xy 453.509014 -194.78498) (xy 454.83526 -194.78498) (xy 454.835762 -194.753019)
			(xy 454.843773 -194.689601) (xy 454.85967 -194.627687) (xy 454.883202 -194.568254) (xy 454.913996 -194.512239)
			(xy 454.951569 -194.460524) (xy 454.995326 -194.413927) (xy 455.044579 -194.373182) (xy 455.09855 -194.338931)
			(xy 455.156389 -194.311714) (xy 455.217182 -194.291961) (xy 455.279972 -194.279983) (xy 455.343768 -194.27597)
			(xy 455.407564 -194.279983) (xy 455.470354 -194.291961) (xy 455.531147 -194.311714) (xy 455.588986 -194.338931)
			(xy 455.642957 -194.373182) (xy 455.69221 -194.413927) (xy 455.735967 -194.460524) (xy 455.77354 -194.512239)
			(xy 455.804334 -194.568254) (xy 455.827866 -194.627687) (xy 455.843763 -194.689601) (xy 455.851774 -194.753019)
			(xy 455.852276 -194.78498) (xy 455.851769 -194.818529) (xy 455.842924 -194.885041) (xy 455.825413 -194.949813)
			(xy 455.799538 -195.011721) (xy 455.76575 -195.069691) (xy 455.724634 -195.122715) (xy 455.701146 -195.146676)
			(xy 455.694325 -195.15403) (xy 455.686491 -195.172475) (xy 455.685906 -195.18249) (xy 455.685144 -195.253864)
			(xy 455.68551 -195.263784) (xy 455.692822 -195.282216) (xy 455.699368 -195.289678) (xy 455.699622 -195.289932)
			(xy 455.721419 -195.313136) (xy 455.75954 -195.364125) (xy 455.790821 -195.419575) (xy 455.814745 -195.478572)
			(xy 455.830921 -195.540147) (xy 455.839081 -195.603286) (xy 455.839576 -195.635118) (xy 455.839087 -195.666281)
			(xy 455.831275 -195.728115) (xy 455.815775 -195.788483) (xy 455.792832 -195.846431) (xy 455.762806 -195.901048)
			(xy 455.726172 -195.95147) (xy 455.683507 -195.996904) (xy 455.635485 -196.036632) (xy 455.582861 -196.070027)
			(xy 455.526467 -196.096564) (xy 455.467192 -196.115824) (xy 455.405971 -196.127503) (xy 455.343768 -196.131416)
			(xy 455.281565 -196.127503) (xy 455.220344 -196.115824) (xy 455.161069 -196.096564) (xy 455.104675 -196.070027)
			(xy 455.052051 -196.036632) (xy 455.004029 -195.996904) (xy 454.961364 -195.95147) (xy 454.92473 -195.901048)
			(xy 454.894704 -195.846431) (xy 454.871761 -195.788483) (xy 454.856261 -195.728115) (xy 454.848449 -195.666281)
			(xy 454.84796 -195.635118) (xy 454.848434 -195.603283) (xy 454.856577 -195.540137) (xy 454.872744 -195.478554)
			(xy 454.896668 -195.419551) (xy 454.927956 -195.3641) (xy 454.96609 -195.313114) (xy 454.987914 -195.289932)
			(xy 454.988168 -195.289678) (xy 454.994684 -195.282194) (xy 455.002014 -195.263778) (xy 455.002392 -195.253864)
			(xy 455.00163 -195.18249) (xy 455.001132 -195.172459) (xy 454.993269 -195.153994) (xy 454.98639 -195.146676)
			(xy 454.962916 -195.122702) (xy 454.92179 -195.069687) (xy 454.887996 -195.011722) (xy 454.862124 -194.949815)
			(xy 454.844623 -194.885041) (xy 454.835797 -194.818528) (xy 454.83526 -194.78498) (xy 453.509014 -194.78498)
			(xy 453.514971 -194.799533) (xy 453.531847 -194.863226) (xy 453.540355 -194.928565) (xy 453.540876 -194.96151)
			(xy 453.540351 -194.994669) (xy 453.531733 -195.060425) (xy 453.514644 -195.124504) (xy 453.489375 -195.185819)
			(xy 453.456353 -195.243331) (xy 453.416138 -195.296065) (xy 453.369413 -195.343127) (xy 453.343518 -195.363846)
			(xy 453.334625 -195.371414) (xy 453.324285 -195.392317) (xy 453.323706 -195.403978) (xy 453.323706 -195.484242)
			(xy 453.324321 -195.495894) (xy 453.334648 -195.516792) (xy 453.343518 -195.524374) (xy 453.369416 -195.545089)
			(xy 453.41614 -195.592152) (xy 453.456353 -195.644887) (xy 453.489373 -195.7024) (xy 453.51464 -195.763716)
			(xy 453.531727 -195.827795) (xy 453.540342 -195.893551) (xy 453.540876 -195.92671) (xy 453.540374 -195.958671)
			(xy 453.532363 -196.022089) (xy 453.516466 -196.084003) (xy 453.492934 -196.143436) (xy 453.46214 -196.199451)
			(xy 453.424567 -196.251166) (xy 453.38081 -196.297763) (xy 453.331557 -196.338508) (xy 453.277586 -196.372759)
			(xy 453.219747 -196.399976) (xy 453.158954 -196.419729) (xy 453.096164 -196.431707) (xy 453.032368 -196.435721)
			(xy 452.968572 -196.431707) (xy 452.905782 -196.419729) (xy 452.844989 -196.399976) (xy 452.78715 -196.372759)
			(xy 452.733179 -196.338508) (xy 452.683926 -196.297763) (xy 452.640169 -196.251166) (xy 452.602596 -196.199451)
			(xy 452.571802 -196.143436) (xy 452.54827 -196.084003) (xy 452.532373 -196.022089) (xy 452.524362 -195.958671)
			(xy 452.52386 -195.92671) (xy 448.200361 -195.92671) (xy 448.182372 -195.95147) (xy 448.139707 -195.996904)
			(xy 448.091685 -196.036632) (xy 448.039061 -196.070027) (xy 447.982667 -196.096564) (xy 447.923392 -196.115824)
			(xy 447.862171 -196.127503) (xy 447.799968 -196.131416) (xy 447.737765 -196.127503) (xy 447.676544 -196.115824)
			(xy 447.617269 -196.096564) (xy 447.560875 -196.070027) (xy 447.508251 -196.036632) (xy 447.460229 -195.996904)
			(xy 447.417564 -195.95147) (xy 447.38093 -195.901048) (xy 447.350904 -195.846431) (xy 447.327961 -195.788483)
			(xy 447.312461 -195.728115) (xy 447.304649 -195.666281) (xy 447.30416 -195.635118) (xy 445.944591 -195.635118)
			(xy 445.945308 -195.636367) (xy 445.970577 -195.697681) (xy 445.987666 -195.761758) (xy 445.996286 -195.827512)
			(xy 445.996822 -195.86067) (xy 445.99632 -195.892631) (xy 445.988309 -195.956049) (xy 445.972412 -196.017963)
			(xy 445.94888 -196.077396) (xy 445.918086 -196.133411) (xy 445.880513 -196.185126) (xy 445.836756 -196.231723)
			(xy 445.787503 -196.272468) (xy 445.733532 -196.306719) (xy 445.675693 -196.333936) (xy 445.6149 -196.353689)
			(xy 445.55211 -196.365667) (xy 445.488314 -196.369681) (xy 445.424518 -196.365667) (xy 445.361728 -196.353689)
			(xy 445.300935 -196.333936) (xy 445.243096 -196.306719) (xy 445.189125 -196.272468) (xy 445.139872 -196.231723)
			(xy 445.096115 -196.185126) (xy 445.058542 -196.133411) (xy 445.027748 -196.077396) (xy 445.004216 -196.017963)
			(xy 444.988319 -195.956049) (xy 444.980308 -195.892631) (xy 444.979806 -195.86067) (xy 440.69715 -195.86067)
			(xy 440.674952 -195.901048) (xy 440.638318 -195.95147) (xy 440.595653 -195.996904) (xy 440.547631 -196.036632)
			(xy 440.495007 -196.070027) (xy 440.438613 -196.096564) (xy 440.379338 -196.115824) (xy 440.318117 -196.127503)
			(xy 440.255914 -196.131416) (xy 440.193711 -196.127503) (xy 440.13249 -196.115824) (xy 440.073215 -196.096564)
			(xy 440.016821 -196.070027) (xy 439.964197 -196.036632) (xy 439.916175 -195.996904) (xy 439.87351 -195.95147)
			(xy 439.836876 -195.901048) (xy 439.80685 -195.846431) (xy 439.783907 -195.788483) (xy 439.768407 -195.728115)
			(xy 439.760595 -195.666281) (xy 439.760106 -195.635118) (xy 439.760613 -195.602166) (xy 439.769361 -195.536846)
			(xy 439.786677 -195.473258) (xy 439.812258 -195.412521) (xy 439.845654 -195.355706) (xy 439.886276 -195.30381)
			(xy 439.93341 -195.257748) (xy 439.959496 -195.237608) (xy 439.967878 -195.231512) (xy 439.978292 -195.213732)
			(xy 439.988706 -195.130928) (xy 439.98959 -195.12092) (xy 439.984346 -195.10154) (xy 439.978546 -195.093336)
			(xy 439.978038 -195.092828) (xy 439.957844 -195.066434) (xy 439.923897 -195.009303) (xy 439.897886 -194.948148)
			(xy 439.880279 -194.884067) (xy 439.87139 -194.818208) (xy 439.87085 -194.78498) (xy 439.871404 -194.752519)
			(xy 439.87988 -194.688153) (xy 439.896684 -194.625444) (xy 439.921529 -194.565464) (xy 439.95399 -194.50924)
			(xy 439.993511 -194.457733) (xy 440.039417 -194.411826) (xy 440.090922 -194.372302) (xy 440.147144 -194.339839)
			(xy 440.207123 -194.314991) (xy 440.269831 -194.298184) (xy 440.334197 -194.289705) (xy 440.366658 -194.289172)
			(xy 440.39845 -194.289732) (xy 440.461513 -194.297867) (xy 440.523018 -194.313997) (xy 440.581956 -194.337857)
			(xy 440.637361 -194.369056) (xy 440.688323 -194.407081) (xy 440.734006 -194.451308) (xy 440.773661 -194.501013)
			(xy 440.790584 -194.527932) (xy 440.797696 -194.539616) (xy 440.821572 -194.55257) (xy 440.92368 -194.55003)
			(xy 440.932447 -194.549354) (xy 440.9488 -194.542936) (xy 440.96202 -194.531368) (xy 440.966606 -194.523868)
			(xy 440.96686 -194.52336) (xy 440.981988 -194.496451) (xy 441.017771 -194.446144) (xy 441.038234 -194.42303)
			(xy 441.044838 -194.415664) (xy 441.051696 -194.39763) (xy 441.049918 -194.307968) (xy 441.042298 -194.290188)
			(xy 441.03544 -194.28333) (xy 441.013202 -194.260064) (xy 440.974339 -194.20876) (xy 440.942435 -194.152862)
			(xy 440.918027 -194.093308) (xy 440.901524 -194.031098) (xy 440.893203 -193.967277) (xy 440.892692 -193.935096)
			(xy 440.892982 -193.911647) (xy 440.897431 -193.864959) (xy 440.901582 -193.841878) (xy 440.902975 -193.832388)
			(xy 440.899457 -193.81355) (xy 440.889255 -193.797328) (xy 440.88177 -193.791332) (xy 440.849713 -193.767219)
			(xy 440.789684 -193.714004) (xy 440.734768 -193.655525) (xy 440.685427 -193.592273) (xy 440.642072 -193.524776)
			(xy 440.605067 -193.4536) (xy 440.574721 -193.37934) (xy 440.551289 -193.302617) (xy 440.534966 -193.224074)
			(xy 440.52998 -193.184272) (xy 440.528314 -193.173871) (xy 440.517812 -193.155637) (xy 440.50966 -193.148966)
			(xy 440.449462 -193.10477) (xy 440.440753 -193.099028) (xy 440.420424 -193.094443) (xy 440.410092 -193.09588)
			(xy 440.409584 -193.09588) (xy 440.3684 -193.103372) (xy 440.285071 -193.111385) (xy 440.243214 -193.111882)
			(xy 440.201468 -193.111453) (xy 440.118353 -193.103518) (xy 440.036369 -193.087718) (xy 439.956258 -193.064197)
			(xy 439.878746 -193.033167) (xy 439.804535 -192.994909) (xy 439.734296 -192.94977) (xy 439.668666 -192.898159)
			(xy 439.608239 -192.840543) (xy 439.553563 -192.777444) (xy 439.505132 -192.709434) (xy 439.463385 -192.637127)
			(xy 439.428701 -192.56118) (xy 439.401393 -192.48228) (xy 439.381709 -192.401141) (xy 439.369826 -192.318498)
			(xy 439.365853 -192.2351) (xy 438.313016 -192.2351) (xy 438.31283 -192.245267) (xy 438.30498 -192.298607)
			(xy 438.289448 -192.350236) (xy 438.266563 -192.399053) (xy 438.236815 -192.444017) (xy 438.200837 -192.484171)
			(xy 438.159395 -192.518659) (xy 438.113374 -192.546745) (xy 438.063754 -192.567832) (xy 438.011593 -192.581468)
			(xy 437.958002 -192.587365) (xy 437.904123 -192.585396) (xy 437.851105 -192.575603) (xy 437.800078 -192.558195)
			(xy 437.75213 -192.533543) (xy 437.708282 -192.502173) (xy 437.669469 -192.464752) (xy 437.636517 -192.422079)
			(xy 437.610131 -192.375062) (xy 437.590871 -192.324705) (xy 437.579148 -192.272081) (xy 437.575213 -192.21831)
			(xy 436.524654 -192.21831) (xy 436.524162 -192.245267) (xy 436.516312 -192.298607) (xy 436.50078 -192.350236)
			(xy 436.477895 -192.399053) (xy 436.448147 -192.444017) (xy 436.412169 -192.484171) (xy 436.370727 -192.518659)
			(xy 436.324706 -192.546745) (xy 436.275086 -192.567832) (xy 436.222925 -192.581468) (xy 436.169334 -192.587365)
			(xy 436.115455 -192.585396) (xy 436.062437 -192.575603) (xy 436.01141 -192.558195) (xy 435.963462 -192.533543)
			(xy 435.919614 -192.502173) (xy 435.880801 -192.464752) (xy 435.847849 -192.422079) (xy 435.821463 -192.375062)
			(xy 435.802203 -192.324705) (xy 435.79048 -192.272081) (xy 435.786545 -192.21831) (xy 434.733748 -192.21831)
			(xy 434.733954 -192.235074) (xy 434.733442 -192.276799) (xy 434.725473 -192.359867) (xy 434.709653 -192.441803)
			(xy 434.686124 -192.521867) (xy 434.655099 -192.599335) (xy 434.636418 -192.636648) (xy 434.631424 -192.647807)
			(xy 434.631431 -192.672221) (xy 434.636418 -192.683384) (xy 434.655134 -192.720681) (xy 434.686173 -192.798148)
			(xy 434.709705 -192.878215) (xy 434.725517 -192.960157) (xy 434.733466 -193.043231) (xy 434.733954 -193.084958)
			(xy 434.733517 -193.127337) (xy 434.725337 -193.211699) (xy 434.709049 -193.294877) (xy 434.684805 -193.376093)
			(xy 434.652832 -193.454589) (xy 434.613429 -193.529631) (xy 434.566964 -193.600518) (xy 434.513872 -193.666586)
			(xy 434.454648 -193.727219) (xy 434.389846 -193.78185) (xy 434.35524 -193.806318) (xy 434.347552 -193.812086)
			(xy 434.33686 -193.828044) (xy 434.332767 -193.846811) (xy 434.333904 -193.856356) (xy 434.33687 -193.875842)
			(xy 434.340046 -193.915133) (xy 434.340254 -193.934842) (xy 434.340254 -193.935096) (xy 434.339785 -193.966931)
			(xy 434.335996 -193.996305) (xy 435.659505 -193.996305) (xy 435.663352 -193.934626) (xy 435.674834 -193.873904)
			(xy 435.693774 -193.815079) (xy 435.719878 -193.759065) (xy 435.75274 -193.706728) (xy 435.791853 -193.658882)
			(xy 435.836608 -193.616267) (xy 435.886312 -193.579545) (xy 435.913022 -193.564002) (xy 435.923944 -193.557906)
			(xy 435.93766 -193.53657) (xy 435.946296 -193.42735) (xy 435.936136 -193.403982) (xy 435.92623 -193.396108)
			(xy 435.904915 -193.378516) (xy 435.867276 -193.338051) (xy 435.8361 -193.292419) (xy 435.812087 -193.242644)
			(xy 435.795775 -193.189842) (xy 435.787529 -193.135196) (xy 435.787038 -193.107564) (xy 435.787038 -193.10731)
			(xy 435.787554 -193.07971) (xy 435.795781 -193.025127) (xy 435.812051 -192.97238) (xy 435.836001 -192.922648)
			(xy 435.867096 -192.87704) (xy 435.904641 -192.836576) (xy 435.947798 -192.802159) (xy 435.995602 -192.77456)
			(xy 436.046986 -192.754393) (xy 436.100801 -192.74211) (xy 436.155846 -192.737985) (xy 436.210891 -192.74211)
			(xy 436.264706 -192.754393) (xy 436.31609 -192.77456) (xy 436.363894 -192.802159) (xy 436.407051 -192.836576)
			(xy 436.444596 -192.87704) (xy 436.475691 -192.922648) (xy 436.499641 -192.97238) (xy 436.515911 -193.025127)
			(xy 436.524138 -193.07971) (xy 436.524654 -193.10731) (xy 436.524654 -193.107564) (xy 436.524134 -193.135193)
			(xy 436.515871 -193.189831) (xy 436.499553 -193.242626) (xy 436.475546 -193.292398) (xy 436.444387 -193.338034)
			(xy 436.406771 -193.378514) (xy 436.385462 -193.396108) (xy 436.375556 -193.403982) (xy 436.365396 -193.42735)
			(xy 436.374032 -193.53657) (xy 436.387748 -193.557906) (xy 436.39867 -193.564002) (xy 436.425385 -193.579533)
			(xy 436.475083 -193.616262) (xy 436.519832 -193.658881) (xy 436.558938 -193.70673) (xy 436.591795 -193.759068)
			(xy 436.617894 -193.815083) (xy 436.636831 -193.873907) (xy 436.648311 -193.934628) (xy 436.652158 -193.996305)
			(xy 436.64831 -194.057982) (xy 436.636829 -194.118703) (xy 436.617891 -194.177526) (xy 436.591791 -194.233541)
			(xy 436.558932 -194.285878) (xy 436.519825 -194.333726) (xy 436.475076 -194.376345) (xy 436.425377 -194.413072)
			(xy 436.39867 -194.428618) (xy 436.387748 -194.434714) (xy 436.374032 -194.45605) (xy 436.365396 -194.56527)
			(xy 436.375556 -194.588638) (xy 436.385462 -194.596512) (xy 436.406785 -194.614095) (xy 436.444424 -194.654562)
			(xy 436.475599 -194.700195) (xy 436.499611 -194.749972) (xy 436.515921 -194.802776) (xy 436.524165 -194.857423)
			(xy 436.524654 -194.885056) (xy 436.524654 -194.88531) (xy 436.524138 -194.91291) (xy 436.515911 -194.967493)
			(xy 436.499641 -195.02024) (xy 436.475691 -195.069973) (xy 436.444596 -195.11558) (xy 436.407051 -195.156044)
			(xy 436.363894 -195.190461) (xy 436.31609 -195.21806) (xy 436.264706 -195.238227) (xy 436.210891 -195.25051)
			(xy 436.155846 -195.254635) (xy 436.100801 -195.25051) (xy 436.046986 -195.238227) (xy 435.995602 -195.21806)
			(xy 435.947798 -195.190461) (xy 435.904641 -195.156044) (xy 435.867096 -195.11558) (xy 435.836001 -195.069973)
			(xy 435.812051 -195.02024) (xy 435.795781 -194.967493) (xy 435.787554 -194.91291) (xy 435.787038 -194.88531)
			(xy 435.787038 -194.885056) (xy 435.787575 -194.857427) (xy 435.795835 -194.802791) (xy 435.81215 -194.749996)
			(xy 435.836153 -194.700224) (xy 435.86731 -194.654588) (xy 435.904922 -194.614107) (xy 435.92623 -194.596512)
			(xy 435.936136 -194.588638) (xy 435.946296 -194.56527) (xy 435.93766 -194.45605) (xy 435.923944 -194.434714)
			(xy 435.913022 -194.428618) (xy 435.88632 -194.413061) (xy 435.836615 -194.376339) (xy 435.791859 -194.333726)
			(xy 435.752746 -194.28588) (xy 435.719882 -194.233544) (xy 435.693778 -194.17753) (xy 435.674837 -194.118706)
			(xy 435.663353 -194.057983) (xy 435.659505 -193.996305) (xy 434.335996 -193.996305) (xy 434.33164 -194.030077)
			(xy 434.315472 -194.09166) (xy 434.291547 -194.150663) (xy 434.260259 -194.206114) (xy 434.222124 -194.2571)
			(xy 434.2003 -194.280282) (xy 434.193188 -194.287648) (xy 434.185822 -194.305936) (xy 434.187092 -194.397884)
			(xy 434.194712 -194.416172) (xy 434.201824 -194.423284) (xy 434.22533 -194.447229) (xy 434.266452 -194.50025)
			(xy 434.300241 -194.558221) (xy 434.326107 -194.620134) (xy 434.343602 -194.684913) (xy 434.352421 -194.75143)
			(xy 434.352954 -194.78498) (xy 434.352452 -194.816941) (xy 434.344441 -194.880359) (xy 434.328544 -194.942273)
			(xy 434.305012 -195.001706) (xy 434.274218 -195.057721) (xy 434.236645 -195.109436) (xy 434.192888 -195.156033)
			(xy 434.143635 -195.196778) (xy 434.089664 -195.231029) (xy 434.031825 -195.258246) (xy 433.971032 -195.277999)
			(xy 433.908242 -195.289977) (xy 433.844446 -195.293991) (xy 433.78065 -195.289977) (xy 433.71786 -195.277999)
			(xy 433.657067 -195.258246) (xy 433.599228 -195.231029) (xy 433.545257 -195.196778) (xy 433.496004 -195.156033)
			(xy 433.452247 -195.109436) (xy 433.414674 -195.057721) (xy 433.38388 -195.001706) (xy 433.360348 -194.942273)
			(xy 433.344451 -194.880359) (xy 433.33644 -194.816941) (xy 433.335938 -194.78498) (xy 433.33648 -194.751432)
			(xy 433.345317 -194.684922) (xy 433.362821 -194.62015) (xy 433.38869 -194.558242) (xy 433.422472 -194.500272)
			(xy 433.463583 -194.447246) (xy 433.487068 -194.423284) (xy 433.493776 -194.415949) (xy 433.501484 -194.397648)
			(xy 433.502054 -194.387724) (xy 433.50307 -194.305936) (xy 433.495704 -194.287648) (xy 433.488592 -194.280282)
			(xy 433.466756 -194.257113) (xy 433.428638 -194.206117) (xy 433.397363 -194.15066) (xy 433.373445 -194.091655)
			(xy 433.357278 -194.030074) (xy 433.349128 -193.96693) (xy 433.348638 -193.935096) (xy 433.348929 -193.911647)
			(xy 433.353378 -193.864959) (xy 433.357528 -193.841878) (xy 433.358903 -193.832387) (xy 433.355387 -193.813554)
			(xy 433.345195 -193.797331) (xy 433.337716 -193.791332) (xy 433.305647 -193.767235) (xy 433.24562 -193.714016)
			(xy 433.190706 -193.655535) (xy 433.141366 -193.59228) (xy 433.098013 -193.524782) (xy 433.06101 -193.453604)
			(xy 433.030665 -193.379342) (xy 433.007234 -193.302618) (xy 432.990911 -193.224075) (xy 432.985926 -193.184272)
			(xy 432.984278 -193.173867) (xy 432.973765 -193.155633) (xy 432.965606 -193.148966) (xy 432.905408 -193.10477)
			(xy 432.896686 -193.099052) (xy 432.876368 -193.094452) (xy 432.866038 -193.09588) (xy 432.86553 -193.09588)
			(xy 432.824345 -193.103365) (xy 432.741017 -193.111383) (xy 432.69916 -193.111882) (xy 432.657416 -193.111435)
			(xy 432.574307 -193.103496) (xy 432.492328 -193.087692) (xy 432.412223 -193.064168) (xy 432.334717 -193.033136)
			(xy 432.260511 -192.994878) (xy 432.190278 -192.949739) (xy 432.124654 -192.898128) (xy 432.064232 -192.840514)
			(xy 432.009561 -192.777417) (xy 431.961134 -192.709409) (xy 431.919392 -192.637106) (xy 431.88471 -192.561162)
			(xy 431.857405 -192.482266) (xy 431.837723 -192.401131) (xy 431.825841 -192.318493) (xy 431.821869 -192.2351)
			(xy 430.768962 -192.2351) (xy 430.768776 -192.245267) (xy 430.760926 -192.298607) (xy 430.745394 -192.350236)
			(xy 430.722509 -192.399053) (xy 430.692761 -192.444017) (xy 430.656783 -192.484171) (xy 430.615341 -192.518659)
			(xy 430.56932 -192.546745) (xy 430.5197 -192.567832) (xy 430.467539 -192.581468) (xy 430.413948 -192.587365)
			(xy 430.360069 -192.585396) (xy 430.307051 -192.575603) (xy 430.256024 -192.558195) (xy 430.208076 -192.533543)
			(xy 430.164228 -192.502173) (xy 430.125415 -192.464752) (xy 430.092463 -192.422079) (xy 430.066077 -192.375062)
			(xy 430.046817 -192.324705) (xy 430.035094 -192.272081) (xy 430.031159 -192.21831) (xy 428.9806 -192.21831)
			(xy 428.980108 -192.245267) (xy 428.972258 -192.298607) (xy 428.956726 -192.350236) (xy 428.933841 -192.399053)
			(xy 428.904093 -192.444017) (xy 428.868115 -192.484171) (xy 428.826673 -192.518659) (xy 428.780652 -192.546745)
			(xy 428.731032 -192.567832) (xy 428.678871 -192.581468) (xy 428.62528 -192.587365) (xy 428.571401 -192.585396)
			(xy 428.518383 -192.575603) (xy 428.467356 -192.558195) (xy 428.419408 -192.533543) (xy 428.37556 -192.502173)
			(xy 428.336747 -192.464752) (xy 428.303795 -192.422079) (xy 428.277409 -192.375062) (xy 428.258149 -192.324705)
			(xy 428.246426 -192.272081) (xy 428.242491 -192.21831) (xy 427.189694 -192.21831) (xy 427.1899 -192.235074)
			(xy 427.189383 -192.276798) (xy 427.181414 -192.359866) (xy 427.165595 -192.441803) (xy 427.142067 -192.521867)
			(xy 427.111044 -192.599335) (xy 427.092364 -192.636648) (xy 427.087374 -192.647808) (xy 427.087381 -192.67222)
			(xy 427.092364 -192.683384) (xy 427.111084 -192.720679) (xy 427.142121 -192.798147) (xy 427.165652 -192.878214)
			(xy 427.181463 -192.960157) (xy 427.189412 -193.043231) (xy 427.1899 -193.084958) (xy 427.189443 -193.127336)
			(xy 427.181263 -193.211697) (xy 427.164976 -193.294874) (xy 427.140734 -193.37609) (xy 427.108763 -193.454585)
			(xy 427.069362 -193.529626) (xy 427.0229 -193.600513) (xy 426.96981 -193.666582) (xy 426.910589 -193.727216)
			(xy 426.84579 -193.781849) (xy 426.811186 -193.806318) (xy 426.803506 -193.812096) (xy 426.792809 -193.828048)
			(xy 426.788713 -193.846812) (xy 426.78985 -193.856356) (xy 426.792817 -193.875842) (xy 426.795992 -193.915133)
			(xy 426.7962 -193.934842) (xy 426.7962 -193.935096) (xy 426.79571 -193.967798) (xy 426.791922 -193.996305)
			(xy 428.115478 -193.996305) (xy 428.119325 -193.934628) (xy 428.130806 -193.873908) (xy 428.149743 -193.815085)
			(xy 428.175844 -193.759071) (xy 428.208703 -193.706735) (xy 428.247811 -193.658888) (xy 428.292561 -193.616272)
			(xy 428.342261 -193.579546) (xy 428.368968 -193.564002) (xy 428.37989 -193.557906) (xy 428.393606 -193.53657)
			(xy 428.402242 -193.42735) (xy 428.392082 -193.403982) (xy 428.382176 -193.396108) (xy 428.360871 -193.378504)
			(xy 428.323229 -193.338043) (xy 428.292051 -193.292414) (xy 428.268036 -193.242641) (xy 428.251722 -193.189841)
			(xy 428.243475 -193.135196) (xy 428.242984 -193.107564) (xy 428.242984 -193.10731) (xy 428.2435 -193.07971)
			(xy 428.251727 -193.025127) (xy 428.267997 -192.97238) (xy 428.291947 -192.922648) (xy 428.323042 -192.87704)
			(xy 428.360587 -192.836576) (xy 428.403744 -192.802159) (xy 428.451548 -192.77456) (xy 428.502932 -192.754393)
			(xy 428.556747 -192.74211) (xy 428.611792 -192.737985) (xy 428.666837 -192.74211) (xy 428.720652 -192.754393)
			(xy 428.772036 -192.77456) (xy 428.81984 -192.802159) (xy 428.862997 -192.836576) (xy 428.900542 -192.87704)
			(xy 428.931637 -192.922648) (xy 428.955587 -192.97238) (xy 428.971857 -193.025127) (xy 428.980084 -193.07971)
			(xy 428.9806 -193.10731) (xy 428.9806 -193.107564) (xy 428.9801 -193.135194) (xy 428.971836 -193.189834)
			(xy 428.955515 -193.24263) (xy 428.931505 -193.292402) (xy 428.900341 -193.338038) (xy 428.86272 -193.378516)
			(xy 428.841408 -193.396108) (xy 428.831502 -193.403982) (xy 428.821342 -193.42735) (xy 428.829978 -193.53657)
			(xy 428.843694 -193.557906) (xy 428.854616 -193.564002) (xy 428.881334 -193.579531) (xy 428.931036 -193.616257)
			(xy 428.97579 -193.658874) (xy 429.0149 -193.706723) (xy 429.047761 -193.759061) (xy 429.073864 -193.815077)
			(xy 429.092803 -193.873903) (xy 429.104284 -193.934626) (xy 429.108131 -193.996305) (xy 429.104283 -194.057984)
			(xy 429.0928 -194.118707) (xy 429.07386 -194.177532) (xy 429.047757 -194.233548) (xy 429.014895 -194.285885)
			(xy 428.975783 -194.333733) (xy 428.931029 -194.376349) (xy 428.881325 -194.413074) (xy 428.854616 -194.428618)
			(xy 428.843694 -194.434714) (xy 428.829978 -194.45605) (xy 428.821342 -194.56527) (xy 428.831502 -194.588638)
			(xy 428.841408 -194.596512) (xy 428.86274 -194.614084) (xy 428.900377 -194.654554) (xy 428.931549 -194.700191)
			(xy 428.955559 -194.749969) (xy 428.971868 -194.802774) (xy 428.980111 -194.857423) (xy 428.9806 -194.885056)
			(xy 428.9806 -194.88531) (xy 428.980084 -194.91291) (xy 428.971857 -194.967493) (xy 428.955587 -195.02024)
			(xy 428.931637 -195.069973) (xy 428.900542 -195.11558) (xy 428.862997 -195.156044) (xy 428.81984 -195.190461)
			(xy 428.772036 -195.21806) (xy 428.720652 -195.238227) (xy 428.666837 -195.25051) (xy 428.611792 -195.254635)
			(xy 428.556747 -195.25051) (xy 428.502932 -195.238227) (xy 428.451548 -195.21806) (xy 428.403744 -195.190461)
			(xy 428.360587 -195.156044) (xy 428.323042 -195.11558) (xy 428.291947 -195.069973) (xy 428.267997 -195.02024)
			(xy 428.251727 -194.967493) (xy 428.2435 -194.91291) (xy 428.242984 -194.88531) (xy 428.242984 -194.885056)
			(xy 428.243504 -194.857426) (xy 428.251765 -194.802788) (xy 428.268082 -194.749993) (xy 428.292089 -194.70022)
			(xy 428.323249 -194.654584) (xy 428.360866 -194.614105) (xy 428.382176 -194.596512) (xy 428.392082 -194.588638)
			(xy 428.402242 -194.56527) (xy 428.393606 -194.45605) (xy 428.37989 -194.434714) (xy 428.368968 -194.428618)
			(xy 428.342269 -194.413059) (xy 428.292569 -194.376335) (xy 428.247817 -194.333719) (xy 428.208708 -194.285873)
			(xy 428.175849 -194.233537) (xy 428.149747 -194.177524) (xy 428.130808 -194.118701) (xy 428.119326 -194.057981)
			(xy 428.115478 -193.996305) (xy 426.791922 -193.996305) (xy 426.787095 -194.032632) (xy 426.770028 -194.095769)
			(xy 426.744805 -194.156114) (xy 426.711865 -194.212616) (xy 426.671779 -194.264296) (xy 426.64888 -194.287648)
			(xy 426.642067 -194.295069) (xy 426.634332 -194.313652) (xy 426.633894 -194.323716) (xy 426.633894 -194.40652)
			(xy 426.641514 -194.425062) (xy 426.64888 -194.432428) (xy 426.671767 -194.45579) (xy 426.711851 -194.507467)
			(xy 426.744789 -194.563968) (xy 426.770007 -194.624311) (xy 426.787068 -194.687448) (xy 426.795674 -194.75228)
			(xy 426.7962 -194.78498) (xy 426.795711 -194.816143) (xy 426.787899 -194.877977) (xy 426.772399 -194.938345)
			(xy 426.749456 -194.996293) (xy 426.71943 -195.05091) (xy 426.682796 -195.101332) (xy 426.640131 -195.146766)
			(xy 426.592109 -195.186494) (xy 426.539485 -195.219889) (xy 426.483091 -195.246426) (xy 426.423816 -195.265686)
			(xy 426.362595 -195.277365) (xy 426.300392 -195.281278) (xy 426.238189 -195.277365) (xy 426.176968 -195.265686)
			(xy 426.117693 -195.246426) (xy 426.061299 -195.219889) (xy 426.008675 -195.186494) (xy 425.960653 -195.146766)
			(xy 425.917988 -195.101332) (xy 425.881354 -195.05091) (xy 425.851328 -194.996293) (xy 425.828385 -194.938345)
			(xy 425.812885 -194.877977) (xy 425.805073 -194.816143) (xy 425.804584 -194.78498) (xy 425.805128 -194.75228)
			(xy 425.813732 -194.687449) (xy 425.830789 -194.624312) (xy 425.856002 -194.563968) (xy 425.888933 -194.507464)
			(xy 425.929009 -194.455782) (xy 425.951904 -194.432428) (xy 425.958725 -194.425013) (xy 425.966456 -194.406425)
			(xy 425.96689 -194.39636) (xy 425.96689 -194.313556) (xy 425.95927 -194.295014) (xy 425.951904 -194.287648)
			(xy 425.92902 -194.264282) (xy 425.888933 -194.212608) (xy 425.855993 -194.156108) (xy 425.830774 -194.095765)
			(xy 425.813713 -194.032629) (xy 425.805108 -193.967796) (xy 425.804584 -193.935096) (xy 425.804875 -193.911647)
			(xy 425.809323 -193.864959) (xy 425.813474 -193.841878) (xy 425.814871 -193.832388) (xy 425.811351 -193.81355)
			(xy 425.801148 -193.797327) (xy 425.793662 -193.791332) (xy 425.761604 -193.767222) (xy 425.701574 -193.714006)
			(xy 425.646659 -193.655527) (xy 425.597318 -193.592274) (xy 425.553963 -193.524777) (xy 425.516958 -193.4536)
			(xy 425.486613 -193.37934) (xy 425.463181 -193.302617) (xy 425.446857 -193.224074) (xy 425.441872 -193.184272)
			(xy 425.440208 -193.173871) (xy 425.429705 -193.155636) (xy 425.421552 -193.148966) (xy 425.361354 -193.10477)
			(xy 425.352648 -193.099024) (xy 425.332317 -193.094441) (xy 425.321984 -193.09588) (xy 425.321476 -193.09588)
			(xy 425.280292 -193.103373) (xy 425.196963 -193.111386) (xy 425.155106 -193.111882) (xy 425.11336 -193.111453)
			(xy 425.030246 -193.103517) (xy 424.948263 -193.087717) (xy 424.868153 -193.064195) (xy 424.790641 -193.033164)
			(xy 424.71643 -192.994906) (xy 424.646192 -192.949767) (xy 424.580563 -192.898156) (xy 424.520136 -192.840541)
			(xy 424.465461 -192.777442) (xy 424.41703 -192.709431) (xy 424.375284 -192.637125) (xy 424.3406 -192.561178)
			(xy 424.313293 -192.482278) (xy 424.293608 -192.40114) (xy 424.281726 -192.318497) (xy 424.277753 -192.2351)
			(xy 423.224908 -192.2351) (xy 423.224722 -192.245267) (xy 423.216872 -192.298607) (xy 423.20134 -192.350236)
			(xy 423.178455 -192.399053) (xy 423.148707 -192.444017) (xy 423.112729 -192.484171) (xy 423.071287 -192.518659)
			(xy 423.025266 -192.546745) (xy 422.975646 -192.567832) (xy 422.923485 -192.581468) (xy 422.869894 -192.587365)
			(xy 422.816015 -192.585396) (xy 422.762997 -192.575603) (xy 422.71197 -192.558195) (xy 422.664022 -192.533543)
			(xy 422.620174 -192.502173) (xy 422.581361 -192.464752) (xy 422.548409 -192.422079) (xy 422.522023 -192.375062)
			(xy 422.502763 -192.324705) (xy 422.49104 -192.272081) (xy 422.487105 -192.21831) (xy 421.436546 -192.21831)
			(xy 421.436054 -192.245267) (xy 421.428204 -192.298607) (xy 421.412672 -192.350236) (xy 421.389787 -192.399053)
			(xy 421.360039 -192.444017) (xy 421.324061 -192.484171) (xy 421.282619 -192.518659) (xy 421.236598 -192.546745)
			(xy 421.186978 -192.567832) (xy 421.134817 -192.581468) (xy 421.081226 -192.587365) (xy 421.027347 -192.585396)
			(xy 420.974329 -192.575603) (xy 420.923302 -192.558195) (xy 420.875354 -192.533543) (xy 420.831506 -192.502173)
			(xy 420.792693 -192.464752) (xy 420.759741 -192.422079) (xy 420.733355 -192.375062) (xy 420.714095 -192.324705)
			(xy 420.702372 -192.272081) (xy 420.698437 -192.21831) (xy 419.645719 -192.21831) (xy 419.645846 -192.223136)
			(xy 419.645846 -192.240662) (xy 419.645142 -192.281218) (xy 419.637156 -192.361943) (xy 419.621749 -192.441586)
			(xy 419.599051 -192.519465) (xy 419.569257 -192.594915) (xy 419.551358 -192.631314) (xy 419.551104 -192.631822)
			(xy 419.546786 -192.642744) (xy 419.542722 -192.66027) (xy 419.543992 -192.671446) (xy 419.546786 -192.680336)
			(xy 419.547294 -192.681352) (xy 419.547548 -192.682114) (xy 419.566374 -192.719517) (xy 419.597628 -192.797207)
			(xy 419.621334 -192.877523) (xy 419.637276 -192.959733) (xy 419.64531 -193.043088) (xy 419.645846 -193.084958)
			(xy 419.64536 -193.126853) (xy 419.637372 -193.210262) (xy 419.621464 -193.292529) (xy 419.597782 -193.372903)
			(xy 419.566541 -193.450652) (xy 419.528027 -193.525067) (xy 419.482591 -193.595469) (xy 419.430647 -193.661216)
			(xy 419.372668 -193.721708) (xy 419.309184 -193.776395) (xy 419.27526 -193.800984) (xy 419.271509 -193.803742)
			(xy 419.264993 -193.81039) (xy 419.262306 -193.814192) (xy 419.259004 -193.820288) (xy 419.245288 -193.848228)
			(xy 419.245288 -193.851022) (xy 419.245542 -193.853816) (xy 419.245796 -193.856356) (xy 419.24875 -193.875907)
			(xy 419.251931 -193.915324) (xy 419.252146 -193.935096) (xy 419.251656 -193.96693) (xy 419.247865 -193.996305)
			(xy 420.571401 -193.996305) (xy 420.575248 -193.934627) (xy 420.58673 -193.873905) (xy 420.60567 -193.81508)
			(xy 420.631773 -193.759066) (xy 420.664635 -193.706729) (xy 420.703746 -193.658883) (xy 420.748501 -193.616268)
			(xy 420.798204 -193.579545) (xy 420.824914 -193.564002) (xy 420.835836 -193.557906) (xy 420.849552 -193.53657)
			(xy 420.858188 -193.42735) (xy 420.848028 -193.403982) (xy 420.838122 -193.396108) (xy 420.816806 -193.378518)
			(xy 420.779167 -193.338052) (xy 420.747992 -193.29242) (xy 420.723979 -193.242645) (xy 420.707666 -193.189842)
			(xy 420.699421 -193.135196) (xy 420.69893 -193.107564) (xy 420.69893 -193.10731) (xy 420.699446 -193.07971)
			(xy 420.707673 -193.025127) (xy 420.723943 -192.97238) (xy 420.747893 -192.922648) (xy 420.778988 -192.87704)
			(xy 420.816533 -192.836576) (xy 420.85969 -192.802159) (xy 420.907494 -192.77456) (xy 420.958878 -192.754393)
			(xy 421.012693 -192.74211) (xy 421.067738 -192.737985) (xy 421.122783 -192.74211) (xy 421.176598 -192.754393)
			(xy 421.227982 -192.77456) (xy 421.275786 -192.802159) (xy 421.318943 -192.836576) (xy 421.356488 -192.87704)
			(xy 421.387583 -192.922648) (xy 421.411533 -192.97238) (xy 421.427803 -193.025127) (xy 421.43603 -193.07971)
			(xy 421.436546 -193.10731) (xy 421.436546 -193.107564) (xy 421.436029 -193.135193) (xy 421.427766 -193.189831)
			(xy 421.411448 -193.242627) (xy 421.38744 -193.292399) (xy 421.35628 -193.338035) (xy 421.318664 -193.378514)
			(xy 421.297354 -193.396108) (xy 421.287448 -193.403982) (xy 421.277288 -193.42735) (xy 421.285924 -193.53657)
			(xy 421.29964 -193.557906) (xy 421.310562 -193.564002) (xy 421.337278 -193.579533) (xy 421.386976 -193.616261)
			(xy 421.431726 -193.65888) (xy 421.470832 -193.706729) (xy 421.50369 -193.759067) (xy 421.52979 -193.815082)
			(xy 421.548727 -193.873906) (xy 421.560207 -193.934628) (xy 421.564054 -193.996305) (xy 421.560206 -194.057982)
			(xy 421.548724 -194.118703) (xy 421.529786 -194.177527) (xy 421.503685 -194.233542) (xy 421.470827 -194.285879)
			(xy 421.431719 -194.333727) (xy 421.386969 -194.376345) (xy 421.337269 -194.413073) (xy 421.310562 -194.428618)
			(xy 421.29964 -194.434714) (xy 421.285924 -194.45605) (xy 421.277288 -194.56527) (xy 421.287448 -194.588638)
			(xy 421.297354 -194.596512) (xy 421.318675 -194.614097) (xy 421.356315 -194.654563) (xy 421.38749 -194.700196)
			(xy 421.411502 -194.749972) (xy 421.427813 -194.802776) (xy 421.436057 -194.857423) (xy 421.436546 -194.885056)
			(xy 421.436546 -194.88531) (xy 421.43603 -194.91291) (xy 421.427803 -194.967493) (xy 421.411533 -195.02024)
			(xy 421.387583 -195.069973) (xy 421.356488 -195.11558) (xy 421.318943 -195.156044) (xy 421.275786 -195.190461)
			(xy 421.227982 -195.21806) (xy 421.176598 -195.238227) (xy 421.122783 -195.25051) (xy 421.067738 -195.254635)
			(xy 421.012693 -195.25051) (xy 420.958878 -195.238227) (xy 420.907494 -195.21806) (xy 420.85969 -195.190461)
			(xy 420.816533 -195.156044) (xy 420.778988 -195.11558) (xy 420.747893 -195.069973) (xy 420.723943 -195.02024)
			(xy 420.707673 -194.967493) (xy 420.699446 -194.91291) (xy 420.69893 -194.88531) (xy 420.69893 -194.885056)
			(xy 420.699433 -194.857426) (xy 420.707695 -194.802786) (xy 420.724014 -194.749989) (xy 420.748024 -194.700216)
			(xy 420.779188 -194.654581) (xy 420.816809 -194.614104) (xy 420.838122 -194.596512) (xy 420.848028 -194.588638)
			(xy 420.858188 -194.56527) (xy 420.849552 -194.45605) (xy 420.835836 -194.434714) (xy 420.824914 -194.428618)
			(xy 420.798213 -194.413061) (xy 420.748508 -194.376339) (xy 420.703753 -194.333725) (xy 420.664641 -194.285879)
			(xy 420.631777 -194.233543) (xy 420.605673 -194.177529) (xy 420.586732 -194.118705) (xy 420.575249 -194.057983)
			(xy 420.571401 -193.996305) (xy 419.247865 -193.996305) (xy 419.243506 -194.030074) (xy 419.227338 -194.091654)
			(xy 419.203419 -194.150658) (xy 419.172144 -194.206115) (xy 419.134025 -194.257111) (xy 419.112192 -194.280282)
			(xy 419.10508 -194.287648) (xy 419.100508 -194.299078) (xy 419.097714 -194.311778) (xy 419.098222 -194.360038)
			(xy 419.098222 -194.360546) (xy 419.09873 -194.387724) (xy 419.098868 -194.392756) (xy 419.100913 -194.402612)
			(xy 419.102794 -194.407282) (xy 419.106604 -194.416172) (xy 419.113716 -194.423284) (xy 419.137198 -194.447248)
			(xy 419.178302 -194.500275) (xy 419.212079 -194.558246) (xy 419.237943 -194.620154) (xy 419.255444 -194.684925)
			(xy 419.264279 -194.751434) (xy 419.264846 -194.78498) (xy 419.264344 -194.816941) (xy 419.256333 -194.880359)
			(xy 419.240436 -194.942273) (xy 419.216904 -195.001706) (xy 419.18611 -195.057721) (xy 419.148537 -195.109436)
			(xy 419.10478 -195.156033) (xy 419.055527 -195.196778) (xy 419.001556 -195.231029) (xy 418.943717 -195.258246)
			(xy 418.882924 -195.277999) (xy 418.820134 -195.289977) (xy 418.756338 -195.293991) (xy 418.692542 -195.289977)
			(xy 418.629752 -195.277999) (xy 418.568959 -195.258246) (xy 418.51112 -195.231029) (xy 418.457149 -195.196778)
			(xy 418.407896 -195.156033) (xy 418.364139 -195.109436) (xy 418.326566 -195.057721) (xy 418.295772 -195.001706)
			(xy 418.27224 -194.942273) (xy 418.256343 -194.880359) (xy 418.248332 -194.816941) (xy 418.24783 -194.78498)
			(xy 418.248363 -194.75143) (xy 418.257182 -194.684912) (xy 418.274676 -194.620134) (xy 418.300542 -194.55822)
			(xy 418.33433 -194.500248) (xy 418.375452 -194.447226) (xy 418.39896 -194.423284) (xy 418.406072 -194.416172)
			(xy 418.409882 -194.407282) (xy 418.411724 -194.402601) (xy 418.413765 -194.392752) (xy 418.413946 -194.387724)
			(xy 418.414454 -194.360546) (xy 418.414454 -194.360038) (xy 418.414962 -194.311778) (xy 418.412168 -194.299078)
			(xy 418.407596 -194.287648) (xy 418.400484 -194.280282) (xy 418.378661 -194.2571) (xy 418.340527 -194.206114)
			(xy 418.30924 -194.150662) (xy 418.285316 -194.091659) (xy 418.269148 -194.030077) (xy 418.261004 -193.966931)
			(xy 418.26053 -193.935096) (xy 418.26053 -193.934588) (xy 418.260818 -193.911139) (xy 418.265275 -193.864452)
			(xy 418.26942 -193.84137) (xy 418.270182 -193.832226) (xy 418.258498 -193.808604) (xy 418.252148 -193.798698)
			(xy 418.244782 -193.789554) (xy 418.2364 -193.781426) (xy 418.201724 -193.754214) (xy 418.137436 -193.693901)
			(xy 418.079521 -193.627445) (xy 418.028562 -193.555517) (xy 417.985073 -193.478841) (xy 417.949492 -193.39819)
			(xy 417.922178 -193.314378) (xy 417.903407 -193.228249) (xy 417.897818 -193.184526) (xy 417.897818 -193.184272)
			(xy 417.896548 -193.17335) (xy 417.889944 -193.16192) (xy 417.887735 -193.158726) (xy 417.882508 -193.152983)
			(xy 417.87953 -193.15049) (xy 417.819586 -193.106294) (xy 417.8173 -193.10477) (xy 417.81297 -193.10176)
			(xy 417.803368 -193.097402) (xy 417.79825 -193.096134) (xy 417.78809 -193.093848) (xy 417.777676 -193.09588)
			(xy 417.736427 -193.103364) (xy 417.652971 -193.111378) (xy 417.611052 -193.111882) (xy 417.568092 -193.111356)
			(xy 417.482586 -193.102947) (xy 417.398311 -193.086214) (xy 417.316078 -193.061318) (xy 417.236674 -193.028497)
			(xy 417.160862 -192.988067) (xy 417.089368 -192.940415) (xy 417.022878 -192.885998) (xy 416.96203 -192.825338)
			(xy 416.907407 -192.759017) (xy 416.859533 -192.687671) (xy 416.818868 -192.611985) (xy 416.785801 -192.532683)
			(xy 416.76065 -192.450528) (xy 416.743656 -192.366306) (xy 416.734982 -192.280826) (xy 416.734244 -192.237868)
			(xy 416.734244 -192.234566) (xy 416.73483 -192.189145) (xy 416.744243 -192.098791) (xy 416.75304 -192.054226)
			(xy 416.75558 -192.042288) (xy 416.756596 -192.037716) (xy 416.749484 -192.022476) (xy 416.746259 -192.015951)
			(xy 416.736708 -192.004977) (xy 416.730688 -192.000886) (xy 416.730434 -192.000632) (xy 416.670236 -191.967866)
			(xy 416.669728 -191.967866) (xy 416.639502 -191.95161) (xy 416.629864 -191.947582) (xy 416.609008 -191.94686)
			(xy 416.589592 -191.954508) (xy 416.581844 -191.961516) (xy 416.574732 -191.968628) (xy 416.572028 -191.97148)
			(xy 416.567438 -191.97786) (xy 416.565588 -191.981328) (xy 416.563004 -191.986755) (xy 416.560177 -191.998434)
			(xy 416.56 -192.004442) (xy 416.56 -195.037964) (xy 416.561016 -195.047362) (xy 416.561016 -195.04787)
			(xy 416.562203 -195.053102) (xy 416.56642 -195.062965) (xy 416.569398 -195.067428) (xy 416.574732 -195.073778)
			(xy 416.994086 -195.493132) (xy 417.003594 -195.501606) (xy 417.027986 -195.508816) (xy 417.040568 -195.506848)
			(xy 417.128198 -195.488306) (xy 417.132273 -195.486986) (xy 417.13993 -195.483145) (xy 417.143438 -195.480686)
			(xy 417.147248 -195.477638) (xy 417.150042 -195.475098) (xy 417.151058 -195.474336) (xy 417.15817 -195.464684)
			(xy 417.16071 -195.457572) (xy 417.173198 -195.426585) (xy 417.205314 -195.368003) (xy 417.245008 -195.314266)
			(xy 417.267898 -195.289932) (xy 417.27501 -195.282312) (xy 417.277804 -195.275454) (xy 417.279328 -195.271644)
			(xy 417.282376 -195.258182) (xy 417.281868 -195.21805) (xy 417.28136 -195.181982) (xy 417.281266 -195.177836)
			(xy 417.279867 -195.169663) (xy 417.278566 -195.165726) (xy 417.27374 -195.154042) (xy 417.266374 -195.146676)
			(xy 417.24289 -195.122713) (xy 417.20178 -195.069687) (xy 417.167996 -195.011717) (xy 417.142126 -194.949809)
			(xy 417.124618 -194.885038) (xy 417.115775 -194.818528) (xy 417.115244 -194.78498) (xy 417.115746 -194.753019)
			(xy 417.123757 -194.689601) (xy 417.139654 -194.627687) (xy 417.163186 -194.568254) (xy 417.19398 -194.512239)
			(xy 417.231553 -194.460524) (xy 417.27531 -194.413927) (xy 417.324563 -194.373182) (xy 417.378534 -194.338931)
			(xy 417.436373 -194.311714) (xy 417.497166 -194.291961) (xy 417.559956 -194.279983) (xy 417.623752 -194.27597)
			(xy 417.687548 -194.279983) (xy 417.750338 -194.291961) (xy 417.811131 -194.311714) (xy 417.86897 -194.338931)
			(xy 417.922941 -194.373182) (xy 417.972194 -194.413927) (xy 418.015951 -194.460524) (xy 418.053524 -194.512239)
			(xy 418.084318 -194.568254) (xy 418.10785 -194.627687) (xy 418.123747 -194.689601) (xy 418.131758 -194.753019)
			(xy 418.13226 -194.78498) (xy 418.131723 -194.818528) (xy 418.122897 -194.885042) (xy 418.105397 -194.949816)
			(xy 418.079525 -195.011724) (xy 418.045733 -195.06969) (xy 418.004608 -195.122705) (xy 417.98113 -195.146676)
			(xy 417.973764 -195.154042) (xy 417.968938 -195.165726) (xy 417.967671 -195.169672) (xy 417.966261 -195.177839)
			(xy 417.966144 -195.181982) (xy 417.965636 -195.20916) (xy 417.965636 -195.209668) (xy 417.965128 -195.258182)
			(xy 417.968176 -195.271644) (xy 417.972494 -195.282566) (xy 417.979606 -195.289932) (xy 418.001429 -195.313114)
			(xy 418.039562 -195.3641) (xy 418.070848 -195.419552) (xy 418.094771 -195.478555) (xy 418.110937 -195.540138)
			(xy 418.11908 -195.603284) (xy 418.11956 -195.635118) (xy 418.119499 -195.64784) (xy 418.118226 -195.673253)
			(xy 418.11702 -195.685918) (xy 418.113465 -195.716108) (xy 418.099923 -195.775371) (xy 418.079238 -195.832533)
			(xy 418.070111 -195.85051) (xy 422.347898 -195.85051) (xy 422.348409 -195.81735) (xy 422.357026 -195.751593)
			(xy 422.374115 -195.687512) (xy 422.399386 -195.626196) (xy 422.43241 -195.568684) (xy 422.472629 -195.515951)
			(xy 422.519359 -195.468891) (xy 422.545256 -195.448174) (xy 422.554153 -195.44061) (xy 422.564487 -195.419703)
			(xy 422.565068 -195.408042) (xy 422.565068 -195.327778) (xy 422.564451 -195.316127) (xy 422.554126 -195.295227)
			(xy 422.545256 -195.287646) (xy 422.519362 -195.266926) (xy 422.472639 -195.219863) (xy 422.432427 -195.167129)
			(xy 422.399406 -195.109617) (xy 422.374138 -195.048302) (xy 422.357051 -194.984224) (xy 422.348433 -194.918469)
			(xy 422.347898 -194.88531) (xy 422.348452 -194.85191) (xy 422.357209 -194.785686) (xy 422.374561 -194.721179)
			(xy 422.400208 -194.659499) (xy 422.433709 -194.601707) (xy 422.474488 -194.548798) (xy 422.521842 -194.501683)
			(xy 422.574958 -194.461174) (xy 422.603676 -194.444112) (xy 422.613891 -194.437401) (xy 422.627024 -194.416832)
			(xy 422.628822 -194.404742) (xy 422.637712 -194.309238) (xy 422.628314 -194.286378) (xy 422.618662 -194.27825)
			(xy 422.598514 -194.260636) (xy 422.563016 -194.220588) (xy 422.53368 -194.175829) (xy 422.511121 -194.127301)
			(xy 422.495813 -194.076021) (xy 422.488076 -194.023068) (xy 422.487598 -193.99631) (xy 422.488114 -193.96871)
			(xy 422.496341 -193.914127) (xy 422.512611 -193.86138) (xy 422.536561 -193.811648) (xy 422.567656 -193.76604)
			(xy 422.605201 -193.725576) (xy 422.648358 -193.691159) (xy 422.696162 -193.66356) (xy 422.747546 -193.643393)
			(xy 422.801361 -193.63111) (xy 422.856406 -193.626985) (xy 422.911451 -193.63111) (xy 422.965266 -193.643393)
			(xy 423.01665 -193.66356) (xy 423.064454 -193.691159) (xy 423.107611 -193.725576) (xy 423.145156 -193.76604)
			(xy 423.176251 -193.811648) (xy 423.200201 -193.86138) (xy 423.216471 -193.914127) (xy 423.224698 -193.96871)
			(xy 423.225214 -193.99631) (xy 423.224732 -194.023068) (xy 423.216996 -194.076021) (xy 423.201688 -194.1273)
			(xy 423.17913 -194.175829) (xy 423.149795 -194.220587) (xy 423.114298 -194.260636) (xy 423.09415 -194.27825)
			(xy 423.084498 -194.286378) (xy 423.0751 -194.309238) (xy 423.08399 -194.404742) (xy 423.085791 -194.41683)
			(xy 423.098925 -194.437396) (xy 423.109136 -194.444112) (xy 423.137843 -194.461196) (xy 423.190973 -194.50169)
			(xy 423.238341 -194.548795) (xy 423.279131 -194.601698) (xy 423.312639 -194.659489) (xy 423.338288 -194.721171)
			(xy 423.355448 -194.78498) (xy 424.659298 -194.78498) (xy 424.6598 -194.753019) (xy 424.667811 -194.689601)
			(xy 424.683708 -194.627687) (xy 424.70724 -194.568254) (xy 424.738034 -194.512239) (xy 424.775607 -194.460524)
			(xy 424.819364 -194.413927) (xy 424.868617 -194.373182) (xy 424.922588 -194.338931) (xy 424.980427 -194.311714)
			(xy 425.04122 -194.291961) (xy 425.10401 -194.279983) (xy 425.167806 -194.27597) (xy 425.231602 -194.279983)
			(xy 425.294392 -194.291961) (xy 425.355185 -194.311714) (xy 425.413024 -194.338931) (xy 425.466995 -194.373182)
			(xy 425.516248 -194.413927) (xy 425.560005 -194.460524) (xy 425.597578 -194.512239) (xy 425.628372 -194.568254)
			(xy 425.651904 -194.627687) (xy 425.667801 -194.689601) (xy 425.675812 -194.753019) (xy 425.676314 -194.78498)
			(xy 425.675796 -194.818528) (xy 425.666952 -194.88504) (xy 425.649442 -194.949811) (xy 425.623569 -195.011719)
			(xy 425.589783 -195.069689) (xy 425.54867 -195.122714) (xy 425.525184 -195.146676) (xy 425.518369 -195.154035)
			(xy 425.51053 -195.172476) (xy 425.509944 -195.18249) (xy 425.509182 -195.253864) (xy 425.509538 -195.263785)
			(xy 425.516856 -195.282218) (xy 425.523406 -195.289678) (xy 425.52366 -195.289932) (xy 425.545446 -195.313146)
			(xy 425.583571 -195.364132) (xy 425.614854 -195.419579) (xy 425.638781 -195.478575) (xy 425.654958 -195.540148)
			(xy 425.663119 -195.603286) (xy 425.663614 -195.635118) (xy 425.663125 -195.666281) (xy 425.655313 -195.728115)
			(xy 425.639813 -195.788483) (xy 425.61687 -195.846431) (xy 425.614628 -195.85051) (xy 429.891952 -195.85051)
			(xy 429.892481 -195.817351) (xy 429.901097 -195.751595) (xy 429.918184 -195.687516) (xy 429.943452 -195.6262)
			(xy 429.976474 -195.568688) (xy 430.016689 -195.515954) (xy 430.063415 -195.468892) (xy 430.08931 -195.448174)
			(xy 430.098199 -195.440602) (xy 430.10854 -195.419702) (xy 430.109122 -195.408042) (xy 430.109122 -195.327778)
			(xy 430.108486 -195.31613) (xy 430.098173 -195.295231) (xy 430.08931 -195.287646) (xy 430.063407 -195.266938)
			(xy 430.016686 -195.219872) (xy 429.976475 -195.167135) (xy 429.943457 -195.109621) (xy 429.918191 -195.048304)
			(xy 429.901104 -194.984225) (xy 429.892487 -194.918469) (xy 429.891952 -194.88531) (xy 429.892529 -194.851911)
			(xy 429.901285 -194.785689) (xy 429.918635 -194.721184) (xy 429.944279 -194.659504) (xy 429.977777 -194.601713)
			(xy 430.018553 -194.548803) (xy 430.065903 -194.501687) (xy 430.119014 -194.461175) (xy 430.14773 -194.444112)
			(xy 430.157956 -194.437415) (xy 430.171081 -194.416835) (xy 430.172876 -194.404742) (xy 430.181766 -194.309238)
			(xy 430.172368 -194.286378) (xy 430.162716 -194.27825) (xy 430.142579 -194.260624) (xy 430.107078 -194.220579)
			(xy 430.077739 -194.175824) (xy 430.055178 -194.127298) (xy 430.039868 -194.07602) (xy 430.03213 -194.023067)
			(xy 430.031652 -193.99631) (xy 430.032168 -193.96871) (xy 430.040395 -193.914127) (xy 430.056665 -193.86138)
			(xy 430.080615 -193.811648) (xy 430.11171 -193.76604) (xy 430.149255 -193.725576) (xy 430.192412 -193.691159)
			(xy 430.240216 -193.66356) (xy 430.2916 -193.643393) (xy 430.345415 -193.63111) (xy 430.40046 -193.626985)
			(xy 430.455505 -193.63111) (xy 430.50932 -193.643393) (xy 430.560704 -193.66356) (xy 430.608508 -193.691159)
			(xy 430.651665 -193.725576) (xy 430.68921 -193.76604) (xy 430.720305 -193.811648) (xy 430.744255 -193.86138)
			(xy 430.760525 -193.914127) (xy 430.768752 -193.96871) (xy 430.769268 -193.99631) (xy 430.768767 -194.023067)
			(xy 430.761033 -194.076018) (xy 430.745727 -194.127296) (xy 430.723172 -194.175825) (xy 430.693841 -194.220584)
			(xy 430.65835 -194.260635) (xy 430.638204 -194.27825) (xy 430.628552 -194.286378) (xy 430.619154 -194.309238)
			(xy 430.628044 -194.404742) (xy 430.629865 -194.416825) (xy 430.642986 -194.437391) (xy 430.65319 -194.444112)
			(xy 430.68191 -194.461175) (xy 430.735037 -194.501675) (xy 430.782403 -194.548783) (xy 430.82319 -194.60169)
			(xy 430.856696 -194.659484) (xy 430.882344 -194.721168) (xy 430.899692 -194.78568) (xy 430.90844 -194.851908)
			(xy 430.908968 -194.88531) (xy 430.908446 -194.918469) (xy 430.899828 -194.984225) (xy 430.882739 -195.048304)
			(xy 430.857469 -195.10962) (xy 430.824447 -195.167132) (xy 430.784231 -195.219866) (xy 430.737505 -195.266927)
			(xy 430.71161 -195.287646) (xy 430.702715 -195.295213) (xy 430.692377 -195.316117) (xy 430.691798 -195.327778)
			(xy 430.691798 -195.408042) (xy 430.692416 -195.419693) (xy 430.702741 -195.440591) (xy 430.71161 -195.448174)
			(xy 430.737506 -195.468891) (xy 430.78423 -195.515954) (xy 430.824444 -195.568688) (xy 430.857464 -195.626201)
			(xy 430.861139 -195.635118) (xy 432.216052 -195.635118) (xy 432.216538 -195.602396) (xy 432.225143 -195.537521)
			(xy 432.242204 -195.474341) (xy 432.267426 -195.413953) (xy 432.300371 -195.357407) (xy 432.340466 -195.305685)
			(xy 432.363372 -195.282312) (xy 432.370285 -195.274861) (xy 432.378155 -195.256142) (xy 432.378612 -195.24599)
			(xy 432.378612 -195.174108) (xy 432.378191 -195.163946) (xy 432.370324 -195.14521) (xy 432.363372 -195.137786)
			(xy 432.340456 -195.114425) (xy 432.300375 -195.062694) (xy 432.267442 -195.006143) (xy 432.24223 -194.945754)
			(xy 432.225175 -194.882574) (xy 432.216575 -194.817701) (xy 432.216052 -194.78498) (xy 432.216541 -194.753817)
			(xy 432.224353 -194.691983) (xy 432.239853 -194.631615) (xy 432.262796 -194.573667) (xy 432.292822 -194.51905)
			(xy 432.329456 -194.468628) (xy 432.372121 -194.423194) (xy 432.420143 -194.383466) (xy 432.472767 -194.350071)
			(xy 432.529161 -194.323534) (xy 432.588436 -194.304274) (xy 432.649657 -194.292595) (xy 432.71186 -194.288682)
			(xy 432.774063 -194.292595) (xy 432.835284 -194.304274) (xy 432.894559 -194.323534) (xy 432.950953 -194.350071)
			(xy 433.003577 -194.383466) (xy 433.051599 -194.423194) (xy 433.094264 -194.468628) (xy 433.130898 -194.51905)
			(xy 433.160924 -194.573667) (xy 433.183867 -194.631615) (xy 433.199367 -194.691983) (xy 433.207179 -194.753817)
			(xy 433.207668 -194.78498) (xy 433.207174 -194.817701) (xy 433.198571 -194.882576) (xy 433.18151 -194.945756)
			(xy 433.15629 -195.006143) (xy 433.123346 -195.06269) (xy 433.083253 -195.114413) (xy 433.060348 -195.137786)
			(xy 433.053395 -195.145205) (xy 433.045548 -195.163948) (xy 433.045108 -195.174108) (xy 433.045108 -195.24599)
			(xy 433.045524 -195.256152) (xy 433.053394 -195.274889) (xy 433.060348 -195.282312) (xy 433.083266 -195.305671)
			(xy 433.123347 -195.357402) (xy 433.156279 -195.413954) (xy 433.181491 -195.474343) (xy 433.198545 -195.537524)
			(xy 433.207145 -195.602397) (xy 433.207668 -195.635118) (xy 433.207179 -195.666281) (xy 433.199367 -195.728115)
			(xy 433.183867 -195.788483) (xy 433.160924 -195.846431) (xy 433.153934 -195.859146) (xy 437.436006 -195.859146)
			(xy 437.43654 -195.825987) (xy 437.445153 -195.76023) (xy 437.462237 -195.69615) (xy 437.487505 -195.634834)
			(xy 437.520526 -195.577322) (xy 437.560741 -195.524588) (xy 437.607468 -195.477528) (xy 437.633364 -195.45681)
			(xy 437.642291 -195.449277) (xy 437.652609 -195.428347) (xy 437.653176 -195.416678) (xy 437.653176 -195.336414)
			(xy 437.652535 -195.324766) (xy 437.642227 -195.303867) (xy 437.633364 -195.296282) (xy 437.607489 -195.27554)
			(xy 437.560765 -195.228481) (xy 437.52055 -195.17575) (xy 437.487528 -195.118242) (xy 437.462257 -195.056931)
			(xy 437.445165 -194.992856) (xy 437.436543 -194.927104) (xy 437.436006 -194.893946) (xy 437.436558 -194.860171)
			(xy 437.445503 -194.793217) (xy 437.46323 -194.728034) (xy 437.489425 -194.665771) (xy 437.523629 -194.607521)
			(xy 437.565241 -194.55431) (xy 437.613527 -194.507073) (xy 437.667639 -194.46664) (xy 437.696864 -194.4497)
			(xy 437.70804 -194.443604) (xy 437.721756 -194.422522) (xy 437.730138 -194.326002) (xy 437.730593 -194.313552)
			(xy 437.720859 -194.290647) (xy 437.711596 -194.282314) (xy 437.690742 -194.26471) (xy 437.653979 -194.224379)
			(xy 437.623556 -194.179072) (xy 437.600139 -194.129779) (xy 437.584237 -194.077574) (xy 437.576198 -194.023596)
			(xy 437.575706 -193.99631) (xy 437.576222 -193.96871) (xy 437.584449 -193.914127) (xy 437.600719 -193.86138)
			(xy 437.624669 -193.811648) (xy 437.655764 -193.76604) (xy 437.693309 -193.725576) (xy 437.736466 -193.691159)
			(xy 437.78427 -193.66356) (xy 437.835654 -193.643393) (xy 437.889469 -193.63111) (xy 437.944514 -193.626985)
			(xy 437.999559 -193.63111) (xy 438.053374 -193.643393) (xy 438.104758 -193.66356) (xy 438.152562 -193.691159)
			(xy 438.195719 -193.725576) (xy 438.233264 -193.76604) (xy 438.264359 -193.811648) (xy 438.288309 -193.86138)
			(xy 438.304579 -193.914127) (xy 438.312806 -193.96871) (xy 438.313322 -193.99631) (xy 438.312875 -194.023599)
			(xy 438.304841 -194.077582) (xy 438.288937 -194.129791) (xy 438.265509 -194.179085) (xy 438.23507 -194.224386)
			(xy 438.198285 -194.264704) (xy 438.177432 -194.282314) (xy 438.168177 -194.29065) (xy 438.158457 -194.313554)
			(xy 438.15889 -194.326002) (xy 438.167272 -194.422522) (xy 438.180988 -194.443604) (xy 438.192164 -194.4497)
			(xy 438.22139 -194.466639) (xy 438.27551 -194.507065) (xy 438.323803 -194.554299) (xy 438.365418 -194.607509)
			(xy 438.399623 -194.66576) (xy 438.425816 -194.728027) (xy 438.443537 -194.793212) (xy 438.452473 -194.86017)
			(xy 438.453022 -194.893946) (xy 438.452471 -194.927105) (xy 438.443861 -194.99286) (xy 438.426778 -195.056939)
			(xy 438.401513 -195.118255) (xy 438.368495 -195.175768) (xy 438.328282 -195.228502) (xy 438.281558 -195.275564)
			(xy 438.255664 -195.296282) (xy 438.246745 -195.303824) (xy 438.236421 -195.324747) (xy 438.235852 -195.336414)
			(xy 438.235852 -195.416678) (xy 438.236488 -195.428327) (xy 438.246799 -195.449227) (xy 438.255664 -195.45681)
			(xy 438.281541 -195.47755) (xy 438.328264 -195.52461) (xy 438.368477 -195.577341) (xy 438.401499 -195.63485)
			(xy 438.42677 -195.696161) (xy 438.443862 -195.760236) (xy 438.452484 -195.825988) (xy 438.453022 -195.859146)
			(xy 438.45252 -195.891107) (xy 438.444509 -195.954525) (xy 438.428612 -196.016439) (xy 438.40508 -196.075872)
			(xy 438.374286 -196.131887) (xy 438.336713 -196.183602) (xy 438.292956 -196.230199) (xy 438.243703 -196.270944)
			(xy 438.189732 -196.305195) (xy 438.131893 -196.332412) (xy 438.0711 -196.352165) (xy 438.00831 -196.364143)
			(xy 437.944514 -196.368157) (xy 437.880718 -196.364143) (xy 437.817928 -196.352165) (xy 437.757135 -196.332412)
			(xy 437.699296 -196.305195) (xy 437.645325 -196.270944) (xy 437.596072 -196.230199) (xy 437.552315 -196.183602)
			(xy 437.514742 -196.131887) (xy 437.483948 -196.075872) (xy 437.460416 -196.016439) (xy 437.444519 -195.954525)
			(xy 437.436508 -195.891107) (xy 437.436006 -195.859146) (xy 433.153934 -195.859146) (xy 433.130898 -195.901048)
			(xy 433.094264 -195.95147) (xy 433.051599 -195.996904) (xy 433.003577 -196.036632) (xy 432.950953 -196.070027)
			(xy 432.894559 -196.096564) (xy 432.835284 -196.115824) (xy 432.774063 -196.127503) (xy 432.71186 -196.131416)
			(xy 432.649657 -196.127503) (xy 432.588436 -196.115824) (xy 432.529161 -196.096564) (xy 432.472767 -196.070027)
			(xy 432.420143 -196.036632) (xy 432.372121 -195.996904) (xy 432.329456 -195.95147) (xy 432.292822 -195.901048)
			(xy 432.262796 -195.846431) (xy 432.239853 -195.788483) (xy 432.224353 -195.728115) (xy 432.216541 -195.666281)
			(xy 432.216052 -195.635118) (xy 430.861139 -195.635118) (xy 430.882732 -195.687516) (xy 430.899818 -195.751595)
			(xy 430.908434 -195.817351) (xy 430.908968 -195.85051) (xy 430.908466 -195.882471) (xy 430.900455 -195.945889)
			(xy 430.884558 -196.007803) (xy 430.861026 -196.067236) (xy 430.830232 -196.123251) (xy 430.792659 -196.174966)
			(xy 430.748902 -196.221563) (xy 430.699649 -196.262308) (xy 430.645678 -196.296559) (xy 430.587839 -196.323776)
			(xy 430.527046 -196.343529) (xy 430.464256 -196.355507) (xy 430.40046 -196.359521) (xy 430.336664 -196.355507)
			(xy 430.273874 -196.343529) (xy 430.213081 -196.323776) (xy 430.155242 -196.296559) (xy 430.101271 -196.262308)
			(xy 430.052018 -196.221563) (xy 430.008261 -196.174966) (xy 429.970688 -196.123251) (xy 429.939894 -196.067236)
			(xy 429.916362 -196.007803) (xy 429.900465 -195.945889) (xy 429.892454 -195.882471) (xy 429.891952 -195.85051)
			(xy 425.614628 -195.85051) (xy 425.586844 -195.901048) (xy 425.55021 -195.95147) (xy 425.507545 -195.996904)
			(xy 425.459523 -196.036632) (xy 425.406899 -196.070027) (xy 425.350505 -196.096564) (xy 425.29123 -196.115824)
			(xy 425.230009 -196.127503) (xy 425.167806 -196.131416) (xy 425.105603 -196.127503) (xy 425.044382 -196.115824)
			(xy 424.985107 -196.096564) (xy 424.928713 -196.070027) (xy 424.876089 -196.036632) (xy 424.828067 -195.996904)
			(xy 424.785402 -195.95147) (xy 424.748768 -195.901048) (xy 424.718742 -195.846431) (xy 424.695799 -195.788483)
			(xy 424.680299 -195.728115) (xy 424.672487 -195.666281) (xy 424.671998 -195.635118) (xy 424.67249 -195.603284)
			(xy 424.680632 -195.540139) (xy 424.696796 -195.478558) (xy 424.720717 -195.419554) (xy 424.752001 -195.364102)
			(xy 424.790131 -195.313115) (xy 424.811952 -195.289932) (xy 424.812206 -195.289678) (xy 424.818727 -195.282198)
			(xy 424.826053 -195.263779) (xy 424.82643 -195.253864) (xy 424.825668 -195.18249) (xy 424.82516 -195.17246)
			(xy 424.817303 -195.153996) (xy 424.810428 -195.146676) (xy 424.786943 -195.122713) (xy 424.74582 -195.069695)
			(xy 424.712029 -195.011727) (xy 424.68616 -194.949818) (xy 424.66866 -194.885043) (xy 424.659835 -194.818529)
			(xy 424.659298 -194.78498) (xy 423.355448 -194.78498) (xy 423.355637 -194.785682) (xy 423.364386 -194.851909)
			(xy 423.364914 -194.88531) (xy 423.364413 -194.91847) (xy 423.355794 -194.984228) (xy 423.338703 -195.048308)
			(xy 423.31343 -195.109624) (xy 423.280404 -195.167136) (xy 423.240184 -195.219869) (xy 423.193454 -195.266929)
			(xy 423.167556 -195.287646) (xy 423.158652 -195.295203) (xy 423.148321 -195.316115) (xy 423.147744 -195.327778)
			(xy 423.147744 -195.408042) (xy 423.148346 -195.419696) (xy 423.158681 -195.440595) (xy 423.167556 -195.448174)
			(xy 423.193462 -195.468879) (xy 423.240184 -195.515945) (xy 423.280395 -195.568682) (xy 423.313414 -195.626197)
			(xy 423.33868 -195.687514) (xy 423.355765 -195.751594) (xy 423.36438 -195.817351) (xy 423.364914 -195.85051)
			(xy 423.364412 -195.882471) (xy 423.356401 -195.945889) (xy 423.340504 -196.007803) (xy 423.316972 -196.067236)
			(xy 423.286178 -196.123251) (xy 423.248605 -196.174966) (xy 423.204848 -196.221563) (xy 423.155595 -196.262308)
			(xy 423.101624 -196.296559) (xy 423.043785 -196.323776) (xy 422.982992 -196.343529) (xy 422.920202 -196.355507)
			(xy 422.856406 -196.359521) (xy 422.79261 -196.355507) (xy 422.72982 -196.343529) (xy 422.669027 -196.323776)
			(xy 422.611188 -196.296559) (xy 422.557217 -196.262308) (xy 422.507964 -196.221563) (xy 422.464207 -196.174966)
			(xy 422.426634 -196.123251) (xy 422.39584 -196.067236) (xy 422.372308 -196.007803) (xy 422.356411 -195.945889)
			(xy 422.3484 -195.882471) (xy 422.347898 -195.85051) (xy 418.070111 -195.85051) (xy 418.051719 -195.886737)
			(xy 418.017779 -195.937171) (xy 417.977928 -195.983076) (xy 417.932763 -196.023765) (xy 417.882962 -196.058626)
			(xy 417.829273 -196.087137) (xy 417.801044 -196.098414) (xy 417.800536 -196.098668) (xy 417.794734 -196.101064)
			(xy 417.78445 -196.108258) (xy 417.780216 -196.112892) (xy 417.776914 -196.116702) (xy 417.77412 -196.122544)
			(xy 417.770056 -196.134228) (xy 417.753038 -196.213476) (xy 417.752022 -196.218302) (xy 417.750542 -196.226628)
			(xy 417.752568 -196.243406) (xy 417.759974 -196.258597) (xy 417.765738 -196.264784) (xy 417.843462 -196.342508)
			(xy 417.85032 -196.348096) (xy 417.85794 -196.352668) (xy 417.864036 -196.354446) (xy 417.877571 -196.358699)
			(xy 417.904253 -196.368357) (xy 417.917376 -196.37375) (xy 419.607746 -197.073774) (xy 419.614608 -197.076372)
			(xy 419.629193 -197.07792) (xy 419.636448 -197.076822) (xy 419.643306 -197.075552) (xy 419.656006 -197.069202)
			(xy 419.661848 -197.064122) (xy 419.682412 -197.045847) (xy 419.72794 -197.014964) (xy 419.777545 -196.991177)
			(xy 419.83013 -196.975012) (xy 419.884531 -196.966827) (xy 419.912038 -196.966332) (xy 419.939645 -196.96685)
			(xy 419.994241 -196.975081) (xy 420.047001 -196.991353) (xy 420.096749 -197.015304) (xy 420.142374 -197.046399)
			(xy 420.182857 -197.083944) (xy 420.217295 -197.127101) (xy 420.23157 -197.150736) (xy 420.233348 -197.15353)
			(xy 420.265098 -197.172072) (xy 420.271005 -197.17534) (xy 420.284006 -197.178958) (xy 420.290752 -197.179184)
			(xy 420.576502 -197.179184) (xy 420.581392 -197.179042) (xy 420.59098 -197.177115) (xy 420.595552 -197.175374)
			(xy 420.666418 -197.14591) (xy 421.50538 -196.798438) (xy 421.540749 -196.784465) (xy 421.614208 -196.764789)
			(xy 421.689606 -196.754869) (xy 421.72763 -196.754242) (xy 422.71188 -196.754496) (xy 423.572686 -196.754496)
			(xy 423.573702 -196.754496) (xy 423.585516 -196.753662) (xy 423.606469 -196.742686) (xy 423.613834 -196.733414)
			(xy 423.614596 -196.732398) (xy 423.66311 -196.661532) (xy 423.66565 -196.657294) (xy 423.669224 -196.648084)
			(xy 423.670222 -196.643244) (xy 423.670476 -196.640958) (xy 423.671 -196.63483) (xy 423.669462 -196.622632)
			(xy 423.667428 -196.616828) (xy 423.667428 -196.616574) (xy 423.656195 -196.585044) (xy 423.64406 -196.519227)
			(xy 423.643298 -196.485764) (xy 423.643298 -196.485002) (xy 423.643814 -196.457402) (xy 423.652041 -196.402819)
			(xy 423.668311 -196.350072) (xy 423.692261 -196.30034) (xy 423.723356 -196.254732) (xy 423.760901 -196.214268)
			(xy 423.804058 -196.179851) (xy 423.851862 -196.152252) (xy 423.903246 -196.132085) (xy 423.957061 -196.119802)
			(xy 424.012106 -196.115677) (xy 424.067151 -196.119802) (xy 424.120966 -196.132085) (xy 424.17235 -196.152252)
			(xy 424.220154 -196.179851) (xy 424.263311 -196.214268) (xy 424.300856 -196.254732) (xy 424.331951 -196.30034)
			(xy 424.355901 -196.350072) (xy 424.372171 -196.402819) (xy 424.380398 -196.457402) (xy 424.380914 -196.485002)
			(xy 424.380335 -196.514515) (xy 424.370941 -196.572788) (xy 424.352393 -196.628824) (xy 424.325164 -196.681193)
			(xy 424.308016 -196.70522) (xy 424.307508 -196.705728) (xy 424.304738 -196.709617) (xy 424.300518 -196.718179)
			(xy 424.299126 -196.722746) (xy 424.296586 -196.734176) (xy 424.301666 -196.763132) (xy 424.307 -196.794374)
			(xy 424.310302 -196.81317) (xy 424.311318 -196.819012) (xy 424.312216 -196.823075) (xy 424.315161 -196.830856)
			(xy 424.31716 -196.834506) (xy 424.324018 -196.845174) (xy 424.332908 -196.851016) (xy 424.360651 -196.869969)
			(xy 424.412012 -196.913292) (xy 424.458032 -196.962251) (xy 424.498095 -197.016193) (xy 424.531667 -197.074397)
			(xy 424.5583 -197.136086) (xy 424.577637 -197.200435) (xy 424.589421 -197.266586) (xy 424.591988 -197.300088)
			(xy 424.591988 -197.300596) (xy 424.593505 -197.33429) (xy 424.589686 -197.401631) (xy 424.578095 -197.468076)
			(xy 424.558885 -197.532732) (xy 424.532317 -197.594728) (xy 424.498747 -197.65323) (xy 424.458628 -197.70745)
			(xy 424.4125 -197.756659) (xy 424.360983 -197.800195) (xy 424.333162 -197.819264) (xy 424.324272 -197.82536)
			(xy 424.318938 -197.833234) (xy 424.316167 -197.837672) (xy 424.312324 -197.847403) (xy 424.311318 -197.852538)
			(xy 424.303698 -197.895464) (xy 424.298364 -197.92569) (xy 424.29811 -197.927468) (xy 424.297662 -197.931593)
			(xy 424.297923 -197.939887) (xy 424.298618 -197.943978) (xy 424.301412 -197.955916) (xy 424.307762 -197.964552)
			(xy 424.323083 -197.985873) (xy 424.348185 -198.031985) (xy 424.366496 -198.08119) (xy 424.377646 -198.132494)
			(xy 424.381411 -198.184861) (xy 424.377714 -198.237232) (xy 424.36663 -198.288551) (xy 424.348383 -198.33778)
			(xy 424.323341 -198.383925) (xy 424.308016 -198.405242) (xy 424.307508 -198.40575) (xy 424.30474 -198.409639)
			(xy 424.300523 -198.418203) (xy 424.299126 -198.422768) (xy 424.296586 -198.434198) (xy 424.301666 -198.463154)
			(xy 424.307 -198.494396) (xy 424.310302 -198.513192) (xy 424.311318 -198.519034) (xy 424.312211 -198.523099)
			(xy 424.315145 -198.530887) (xy 424.31716 -198.534528) (xy 424.324018 -198.545196) (xy 424.332908 -198.551038)
			(xy 424.362458 -198.57124) (xy 424.416831 -198.617799) (xy 424.46507 -198.670688) (xy 424.506441 -198.729106)
			(xy 424.540318 -198.792165) (xy 424.566188 -198.858911) (xy 424.583656 -198.92833) (xy 424.59246 -198.99937)
			(xy 424.593004 -199.035162) (xy 424.592852 -199.053245) (xy 424.590567 -199.08934) (xy 424.588432 -199.107298)
			(xy 424.582844 -199.142858) (xy 424.580262 -199.156059) (xy 424.574038 -199.182232) (xy 424.570398 -199.195182)
			(xy 424.568366 -199.202802) (xy 424.57116 -199.217534) (xy 424.572559 -199.222464) (xy 424.577032 -199.231681)
			(xy 424.58005 -199.235822) (xy 424.628818 -199.300084) (xy 424.629834 -199.3011) (xy 424.630342 -199.302116)
			(xy 424.639232 -199.310498) (xy 424.644995 -199.314344) (xy 424.658003 -199.319097) (xy 424.664886 -199.319896)
			(xy 424.66895 -199.32015) (xy 427.023022 -199.32015) (xy 427.035358 -199.319271) (xy 427.057105 -199.307579)
			(xy 427.064678 -199.297798) (xy 427.100238 -199.244712) (xy 427.100238 -199.244204) (xy 427.111922 -199.226678)
			(xy 427.115255 -199.221425) (xy 427.119497 -199.209733) (xy 427.120304 -199.203564) (xy 427.121574 -199.190864)
			(xy 427.116494 -199.178926) (xy 427.107274 -199.156091) (xy 427.094277 -199.10859) (xy 427.087703 -199.059785)
			(xy 427.087284 -199.035162) (xy 427.087707 -199.009815) (xy 427.094653 -198.9596) (xy 427.108409 -198.910808)
			(xy 427.128717 -198.86436) (xy 427.155193 -198.821129) (xy 427.187338 -198.781931) (xy 427.205648 -198.764398)
			(xy 427.205902 -198.764144) (xy 427.209499 -198.760683) (xy 427.215381 -198.752621) (xy 427.217586 -198.748142)
			(xy 427.219872 -198.7423) (xy 427.221087 -198.738156) (xy 427.22224 -198.729599) (xy 427.222158 -198.725282)
			(xy 427.220888 -198.713598) (xy 427.218856 -198.692262) (xy 427.218856 -198.691754) (xy 427.214284 -198.64197)
			(xy 427.213709 -198.637003) (xy 427.210895 -198.62741) (xy 427.208696 -198.62292) (xy 427.20768 -198.621142)
			(xy 427.206918 -198.620126) (xy 427.20423 -198.616045) (xy 427.19758 -198.608886) (xy 427.19371 -198.605902)
			(xy 427.190916 -198.604124) (xy 427.164802 -198.587027) (xy 427.116678 -198.547278) (xy 427.073921 -198.501806)
			(xy 427.037207 -198.451328) (xy 427.007116 -198.396642) (xy 426.984124 -198.338613) (xy 426.968595 -198.278158)
			(xy 426.960773 -198.216233) (xy 426.960284 -198.185024) (xy 426.96076 -198.15383) (xy 426.968598 -198.091936)
			(xy 426.98414 -198.031514) (xy 427.007141 -197.97352) (xy 427.037237 -197.918871) (xy 427.073952 -197.86843)
			(xy 427.116707 -197.822994) (xy 427.164824 -197.783282) (xy 427.190916 -197.766178) (xy 427.19117 -197.765924)
			(xy 427.191678 -197.76567) (xy 427.196222 -197.762514) (xy 427.203917 -197.754569) (xy 427.206918 -197.749922)
			(xy 427.209966 -197.745096) (xy 427.213776 -197.73392) (xy 427.216316 -197.705218) (xy 427.216316 -197.70471)
			(xy 427.21911 -197.67423) (xy 427.221904 -197.643496) (xy 427.221874 -197.639763) (xy 427.220852 -197.632367)
			(xy 427.219872 -197.628764) (xy 427.21784 -197.623176) (xy 427.2161 -197.619239) (xy 427.211499 -197.611965)
			(xy 427.208696 -197.608698) (xy 427.205648 -197.605904) (xy 427.205394 -197.60565) (xy 427.187112 -197.588132)
			(xy 427.155038 -197.548955) (xy 427.128626 -197.505757) (xy 427.108371 -197.459353) (xy 427.094656 -197.410614)
			(xy 427.087737 -197.360456) (xy 427.087284 -197.33514) (xy 427.0878 -197.30754) (xy 427.096027 -197.252957)
			(xy 427.112297 -197.20021) (xy 427.136247 -197.150478) (xy 427.167342 -197.10487) (xy 427.204887 -197.064406)
			(xy 427.248044 -197.029989) (xy 427.295848 -197.00239) (xy 427.347232 -196.982223) (xy 427.401047 -196.96994)
			(xy 427.456092 -196.965815) (xy 427.511137 -196.96994) (xy 427.564952 -196.982223) (xy 427.616336 -197.00239)
			(xy 427.66414 -197.029989) (xy 427.707297 -197.064406) (xy 427.744842 -197.10487) (xy 427.775937 -197.150478)
			(xy 427.799887 -197.20021) (xy 427.816157 -197.252957) (xy 427.824384 -197.30754) (xy 427.8249 -197.33514)
			(xy 427.824479 -197.360457) (xy 427.817549 -197.410614) (xy 427.803824 -197.459352) (xy 427.783562 -197.505754)
			(xy 427.757144 -197.54895) (xy 427.725067 -197.588127) (xy 427.70679 -197.60565) (xy 427.706282 -197.606158)
			(xy 427.702292 -197.61014) (xy 427.696012 -197.619499) (xy 427.693836 -197.6247) (xy 427.692058 -197.629526)
			(xy 427.689518 -197.635622) (xy 427.6979 -197.728078) (xy 427.698479 -197.733043) (xy 427.7013 -197.742632)
			(xy 427.703488 -197.747128) (xy 427.70679 -197.752462) (xy 427.709719 -197.756314) (xy 427.716751 -197.762961)
			(xy 427.72076 -197.76567) (xy 427.721268 -197.766178) (xy 427.747976 -197.783657) (xy 427.797096 -197.824421)
			(xy 427.840576 -197.871153) (xy 427.877698 -197.923079) (xy 427.907847 -197.979342) (xy 427.919642 -198.009002)
			(xy 427.931034 -198.040504) (xy 427.946194 -198.105753) (xy 427.949868 -198.13905) (xy 427.951392 -198.156068)
			(xy 427.952154 -198.185024) (xy 427.951681 -198.216256) (xy 427.943839 -198.278225) (xy 427.928283 -198.33872)
			(xy 427.905258 -198.396785) (xy 427.875129 -198.451501) (xy 427.838371 -198.502004) (xy 427.795566 -198.547494)
			(xy 427.747391 -198.587254) (xy 427.721268 -198.604378) (xy 427.720506 -198.604886) (xy 427.716492 -198.607513)
			(xy 427.709464 -198.61404) (xy 427.706536 -198.61784) (xy 427.705012 -198.62038) (xy 427.702199 -198.62538)
			(xy 427.698617 -198.636277) (xy 427.6979 -198.64197) (xy 427.696884 -198.651114) (xy 427.693328 -198.691754)
			(xy 427.693328 -198.692262) (xy 427.692312 -198.701406) (xy 427.690026 -198.726552) (xy 427.690122 -198.73143)
			(xy 427.69191 -198.741019) (xy 427.693582 -198.745602) (xy 427.697646 -198.75627) (xy 427.706536 -198.764398)
			(xy 427.72486 -198.781918) (xy 427.757015 -198.821113) (xy 427.783496 -198.864345) (xy 427.803804 -198.910797)
			(xy 427.817556 -198.959593) (xy 427.824494 -199.009813) (xy 427.8249 -199.035162) (xy 427.824509 -199.059787)
			(xy 427.817945 -199.108598) (xy 427.80493 -199.156097) (xy 427.79569 -199.178926) (xy 427.79315 -199.185022)
			(xy 427.791372 -199.197468) (xy 427.79188 -199.203564) (xy 427.792726 -199.209723) (xy 427.796964 -199.221408)
			(xy 427.800262 -199.226678) (xy 427.811946 -199.244204) (xy 427.811946 -199.244712) (xy 427.847506 -199.297798)
			(xy 427.854942 -199.307726) (xy 427.876778 -199.319436) (xy 427.889162 -199.32015) (xy 430.987708 -199.32015)
			(xy 430.999686 -199.319502) (xy 431.021029 -199.308626) (xy 431.028602 -199.299322) (xy 431.040032 -199.283574)
			(xy 431.077116 -199.232266) (xy 431.080144 -199.227808) (xy 431.084486 -199.217947) (xy 431.085752 -199.212708)
			(xy 431.086006 -199.211438) (xy 431.086851 -199.205441) (xy 431.085952 -199.193368) (xy 431.084228 -199.187562)
			(xy 431.084228 -199.187308) (xy 431.074643 -199.155839) (xy 431.062917 -199.091108) (xy 431.06086 -199.058276)
			(xy 431.060352 -199.04964) (xy 431.060098 -199.035162) (xy 431.060566 -199.003928) (xy 431.068399 -198.941954)
			(xy 431.083948 -198.881453) (xy 431.106968 -198.823382) (xy 431.137094 -198.76866) (xy 431.173851 -198.718151)
			(xy 431.216656 -198.672656) (xy 431.264833 -198.632892) (xy 431.290984 -198.615808) (xy 431.291746 -198.6153)
			(xy 431.295762 -198.612676) (xy 431.302794 -198.606151) (xy 431.305716 -198.602346) (xy 431.30724 -198.599806)
			(xy 431.310059 -198.594807) (xy 431.313655 -198.583912) (xy 431.314352 -198.578216) (xy 431.315368 -198.569072)
			(xy 431.318924 -198.528432) (xy 431.318924 -198.527924) (xy 431.31994 -198.51878) (xy 431.322226 -198.493634)
			(xy 431.322128 -198.488757) (xy 431.320337 -198.479169) (xy 431.31867 -198.474584) (xy 431.314606 -198.463916)
			(xy 431.305716 -198.455788) (xy 431.28739 -198.438269) (xy 431.255233 -198.399075) (xy 431.22875 -198.355844)
			(xy 431.20844 -198.309391) (xy 431.194688 -198.260594) (xy 431.187751 -198.210373) (xy 431.187352 -198.185024)
			(xy 431.187769 -198.159706) (xy 431.194692 -198.109545) (xy 431.208412 -198.060803) (xy 431.22867 -198.014396)
			(xy 431.255086 -197.971196) (xy 431.287164 -197.932016) (xy 431.305462 -197.914514) (xy 431.30597 -197.914006)
			(xy 431.30996 -197.910024) (xy 431.31624 -197.900665) (xy 431.318416 -197.895464) (xy 431.320194 -197.890638)
			(xy 431.322734 -197.884542) (xy 431.314352 -197.792086) (xy 431.31378 -197.787118) (xy 431.310971 -197.777523)
			(xy 431.308764 -197.773036) (xy 431.305462 -197.767702) (xy 431.302534 -197.763849) (xy 431.295504 -197.757201)
			(xy 431.291492 -197.754494) (xy 431.290984 -197.753986) (xy 431.264279 -197.736504) (xy 431.215166 -197.695737)
			(xy 431.171692 -197.649002) (xy 431.134577 -197.597073) (xy 431.104436 -197.540809) (xy 431.09261 -197.511162)
			(xy 431.081213 -197.479661) (xy 431.066043 -197.414413) (xy 431.062384 -197.381114) (xy 431.06086 -197.364096)
			(xy 431.060098 -197.33514) (xy 431.060567 -197.303907) (xy 431.068402 -197.241934) (xy 431.083954 -197.181435)
			(xy 431.106975 -197.123366) (xy 431.137103 -197.068646) (xy 431.17386 -197.01814) (xy 431.216666 -196.972646)
			(xy 431.264843 -196.932885) (xy 431.290984 -196.915786) (xy 431.291746 -196.915278) (xy 431.295761 -196.912652)
			(xy 431.302791 -196.906126) (xy 431.305716 -196.902324) (xy 431.30724 -196.899784) (xy 431.310057 -196.894785)
			(xy 431.313649 -196.883889) (xy 431.314352 -196.878194) (xy 431.315368 -196.86905) (xy 431.318924 -196.82841)
			(xy 431.318924 -196.827902) (xy 431.31994 -196.818758) (xy 431.322226 -196.793612) (xy 431.322126 -196.788735)
			(xy 431.320331 -196.779149) (xy 431.31867 -196.774562) (xy 431.314606 -196.763894) (xy 431.305716 -196.755766)
			(xy 431.287391 -196.738247) (xy 431.255236 -196.699052) (xy 431.228756 -196.65582) (xy 431.208449 -196.609368)
			(xy 431.194699 -196.560571) (xy 431.187766 -196.510351) (xy 431.187352 -196.485002) (xy 431.187868 -196.457402)
			(xy 431.196095 -196.402819) (xy 431.212365 -196.350072) (xy 431.236315 -196.30034) (xy 431.26741 -196.254732)
			(xy 431.304955 -196.214268) (xy 431.348112 -196.179851) (xy 431.395916 -196.152252) (xy 431.4473 -196.132085)
			(xy 431.501115 -196.119802) (xy 431.55616 -196.115677) (xy 431.611205 -196.119802) (xy 431.66502 -196.132085)
			(xy 431.716404 -196.152252) (xy 431.764208 -196.179851) (xy 431.807365 -196.214268) (xy 431.84491 -196.254732)
			(xy 431.876005 -196.30034) (xy 431.899955 -196.350072) (xy 431.916225 -196.402819) (xy 431.924452 -196.457402)
			(xy 431.924968 -196.485002) (xy 431.924548 -196.51035) (xy 431.917607 -196.560569) (xy 431.903855 -196.609365)
			(xy 431.883553 -196.655818) (xy 431.857082 -196.699055) (xy 431.824941 -196.73826) (xy 431.806604 -196.755766)
			(xy 431.80635 -196.75602) (xy 431.802748 -196.759477) (xy 431.796855 -196.767535) (xy 431.794666 -196.772022)
			(xy 431.79238 -196.777864) (xy 431.791172 -196.782008) (xy 431.790031 -196.790565) (xy 431.790094 -196.794882)
			(xy 431.791364 -196.806566) (xy 431.793396 -196.827902) (xy 431.793396 -196.82841) (xy 431.797968 -196.878194)
			(xy 431.798539 -196.883162) (xy 431.801345 -196.892759) (xy 431.803556 -196.897244) (xy 431.804572 -196.899022)
			(xy 431.805334 -196.900038) (xy 431.808022 -196.904119) (xy 431.814673 -196.911277) (xy 431.818542 -196.914262)
			(xy 431.821336 -196.91604) (xy 431.847453 -196.933134) (xy 431.895585 -196.97288) (xy 431.93835 -197.018351)
			(xy 431.975071 -197.068828) (xy 432.005169 -197.123514) (xy 432.028167 -197.181544) (xy 432.043702 -197.242001)
			(xy 432.05153 -197.303929) (xy 432.051968 -197.33514) (xy 432.051495 -197.366336) (xy 432.043661 -197.428234)
			(xy 432.028123 -197.48866) (xy 432.005127 -197.546659) (xy 431.975035 -197.601314) (xy 431.938323 -197.651761)
			(xy 431.895571 -197.697204) (xy 431.847456 -197.736924) (xy 431.821336 -197.753986) (xy 431.821082 -197.75424)
			(xy 431.820574 -197.754494) (xy 431.816036 -197.757655) (xy 431.808356 -197.76561) (xy 431.805334 -197.770242)
			(xy 431.802286 -197.775068) (xy 431.798476 -197.786244) (xy 431.795936 -197.814946) (xy 431.795936 -197.815454)
			(xy 431.793142 -197.845934) (xy 431.790348 -197.876668) (xy 431.790375 -197.880402) (xy 431.791392 -197.887799)
			(xy 431.79238 -197.8914) (xy 431.794412 -197.896988) (xy 431.796148 -197.900928) (xy 431.800742 -197.908208)
			(xy 431.803556 -197.911466) (xy 431.806604 -197.91426) (xy 431.806858 -197.914514) (xy 431.825144 -197.93203)
			(xy 431.857225 -197.971205) (xy 431.883646 -198.014401) (xy 431.903907 -198.060806) (xy 431.91763 -198.109547)
			(xy 431.924554 -198.159706) (xy 431.924968 -198.185024) (xy 431.924546 -198.210372) (xy 431.917602 -198.260589)
			(xy 431.903849 -198.309383) (xy 431.883545 -198.355834) (xy 431.857072 -198.399069) (xy 431.82493 -198.438272)
			(xy 431.806604 -198.455788) (xy 431.80635 -198.456042) (xy 431.802749 -198.4595) (xy 431.796859 -198.467559)
			(xy 431.794666 -198.472044) (xy 431.79238 -198.477886) (xy 431.791165 -198.48203) (xy 431.79001 -198.490587)
			(xy 431.790094 -198.494904) (xy 431.791364 -198.506588) (xy 431.793396 -198.527924) (xy 431.793396 -198.528432)
			(xy 431.797968 -198.577962) (xy 431.798513 -198.582851) (xy 431.801199 -198.592311) (xy 431.803302 -198.596758)
			(xy 431.806096 -198.601584) (xy 431.810414 -198.608696) (xy 431.810922 -198.609204) (xy 431.821336 -198.615808)
			(xy 431.84747 -198.632913) (xy 431.895635 -198.672682) (xy 431.938429 -198.71818) (xy 431.975177 -198.768687)
			(xy 432.005299 -198.823405) (xy 432.028319 -198.88147) (xy 432.043871 -198.941964) (xy 432.051712 -199.003931)
			(xy 432.052222 -199.035162) (xy 432.052222 -199.040496) (xy 432.051714 -199.052434) (xy 432.049934 -199.086749)
			(xy 432.038081 -199.154431) (xy 432.028092 -199.187308) (xy 432.028092 -199.187562) (xy 432.02642 -199.193312)
			(xy 432.025518 -199.205249) (xy 432.026314 -199.211184) (xy 432.028092 -199.222614) (xy 432.065684 -199.27443)
			(xy 432.065684 -199.274938) (xy 432.083718 -199.299322) (xy 432.091322 -199.308583) (xy 432.11265 -199.31944)
			(xy 432.124612 -199.32015) (xy 434.567076 -199.32015) (xy 434.579418 -199.319281) (xy 434.601182 -199.307599)
			(xy 434.608732 -199.297798) (xy 434.644292 -199.244712) (xy 434.644292 -199.244204) (xy 434.655976 -199.226678)
			(xy 434.659312 -199.221426) (xy 434.663557 -199.209734) (xy 434.664358 -199.203564) (xy 434.665628 -199.190864)
			(xy 434.660548 -199.178926) (xy 434.651329 -199.15609) (xy 434.638334 -199.10859) (xy 434.631761 -199.059785)
			(xy 434.631338 -199.035162) (xy 434.631761 -199.009815) (xy 434.638706 -198.959599) (xy 434.652461 -198.910806)
			(xy 434.672767 -198.864356) (xy 434.699241 -198.821123) (xy 434.731384 -198.781922) (xy 434.749702 -198.764398)
			(xy 434.749956 -198.764144) (xy 434.753555 -198.760685) (xy 434.759443 -198.752625) (xy 434.76164 -198.748142)
			(xy 434.763926 -198.7423) (xy 434.76514 -198.738156) (xy 434.766292 -198.729599) (xy 434.766212 -198.725282)
			(xy 434.764942 -198.713598) (xy 434.76291 -198.692262) (xy 434.76291 -198.691754) (xy 434.758338 -198.64197)
			(xy 434.757764 -198.637003) (xy 434.754952 -198.627409) (xy 434.75275 -198.62292) (xy 434.751734 -198.621142)
			(xy 434.750972 -198.620126) (xy 434.748283 -198.616046) (xy 434.741629 -198.608893) (xy 434.737764 -198.605902)
			(xy 434.73497 -198.604124) (xy 434.708854 -198.587029) (xy 434.660725 -198.547283) (xy 434.617963 -198.501811)
			(xy 434.581245 -198.451334) (xy 434.55115 -198.396648) (xy 434.528156 -198.338618) (xy 434.512625 -198.278161)
			(xy 434.504802 -198.216234) (xy 434.504338 -198.185024) (xy 434.504814 -198.153829) (xy 434.512651 -198.091934)
			(xy 434.528192 -198.031511) (xy 434.551192 -197.973516) (xy 434.581286 -197.918864) (xy 434.618 -197.868421)
			(xy 434.660752 -197.822982) (xy 434.708868 -197.783266) (xy 434.73497 -197.766178) (xy 434.735224 -197.765924)
			(xy 434.735732 -197.76567) (xy 434.740273 -197.762511) (xy 434.74796 -197.754562) (xy 434.750972 -197.749922)
			(xy 434.75402 -197.745096) (xy 434.75783 -197.73392) (xy 434.76037 -197.705218) (xy 434.76037 -197.70471)
			(xy 434.763164 -197.67423) (xy 434.765958 -197.643496) (xy 434.765928 -197.639763) (xy 434.764905 -197.632367)
			(xy 434.763926 -197.628764) (xy 434.761894 -197.623176) (xy 434.760156 -197.619238) (xy 434.755559 -197.61196)
			(xy 434.75275 -197.608698) (xy 434.749702 -197.605904) (xy 434.749448 -197.60565) (xy 434.731164 -197.588133)
			(xy 434.699086 -197.548957) (xy 434.67267 -197.505761) (xy 434.652412 -197.459356) (xy 434.638694 -197.410616)
			(xy 434.631774 -197.360457) (xy 434.631338 -197.33514) (xy 434.631854 -197.30754) (xy 434.640081 -197.252957)
			(xy 434.656351 -197.20021) (xy 434.680301 -197.150478) (xy 434.711396 -197.10487) (xy 434.748941 -197.064406)
			(xy 434.792098 -197.029989) (xy 434.839902 -197.00239) (xy 434.891286 -196.982223) (xy 434.945101 -196.96994)
			(xy 435.000146 -196.965815) (xy 435.055191 -196.96994) (xy 435.109006 -196.982223) (xy 435.16039 -197.00239)
			(xy 435.208194 -197.029989) (xy 435.251351 -197.064406) (xy 435.288896 -197.10487) (xy 435.319991 -197.150478)
			(xy 435.343941 -197.20021) (xy 435.360211 -197.252957) (xy 435.368438 -197.30754) (xy 435.368954 -197.33514)
			(xy 435.368533 -197.360456) (xy 435.361602 -197.410613) (xy 435.347876 -197.459349) (xy 435.327612 -197.505751)
			(xy 435.301192 -197.548944) (xy 435.269113 -197.588118) (xy 435.250844 -197.60565) (xy 435.250336 -197.606158)
			(xy 435.246342 -197.610138) (xy 435.240056 -197.619495) (xy 435.23789 -197.6247) (xy 435.236112 -197.629526)
			(xy 435.233572 -197.635622) (xy 435.241954 -197.728078) (xy 435.242532 -197.733044) (xy 435.245352 -197.742634)
			(xy 435.247542 -197.747128) (xy 435.250844 -197.752462) (xy 435.253775 -197.756312) (xy 435.260811 -197.762952)
			(xy 435.264814 -197.76567) (xy 435.265322 -197.766178) (xy 435.292028 -197.783659) (xy 435.341143 -197.824426)
			(xy 435.384619 -197.871159) (xy 435.421737 -197.923087) (xy 435.451883 -197.97935) (xy 435.463696 -198.009002)
			(xy 435.475089 -198.040504) (xy 435.49025 -198.105753) (xy 435.493922 -198.13905) (xy 435.495446 -198.156068)
			(xy 435.496208 -198.185024) (xy 435.495735 -198.216255) (xy 435.487893 -198.278223) (xy 435.472335 -198.338717)
			(xy 435.449309 -198.39678) (xy 435.419178 -198.451495) (xy 435.382419 -198.501995) (xy 435.339612 -198.547482)
			(xy 435.291435 -198.587238) (xy 435.265322 -198.604378) (xy 435.26456 -198.604886) (xy 435.260543 -198.607509)
			(xy 435.253509 -198.614032) (xy 435.25059 -198.61784) (xy 435.249066 -198.62038) (xy 435.246255 -198.625381)
			(xy 435.242676 -198.636278) (xy 435.241954 -198.64197) (xy 435.240938 -198.651114) (xy 435.237382 -198.691754)
			(xy 435.237382 -198.692262) (xy 435.236366 -198.701406) (xy 435.23408 -198.726552) (xy 435.234176 -198.73143)
			(xy 435.235966 -198.741018) (xy 435.237636 -198.745602) (xy 435.2417 -198.75627) (xy 435.25059 -198.764398)
			(xy 435.268917 -198.781917) (xy 435.301075 -198.821111) (xy 435.327559 -198.864342) (xy 435.34787 -198.910794)
			(xy 435.361624 -198.959591) (xy 435.368562 -199.009813) (xy 435.368954 -199.035162) (xy 435.368563 -199.059787)
			(xy 435.361998 -199.108597) (xy 435.348981 -199.156096) (xy 435.339744 -199.178926) (xy 435.337204 -199.185022)
			(xy 435.335426 -199.197468) (xy 435.335934 -199.203564) (xy 435.336779 -199.209724) (xy 435.341014 -199.22141)
			(xy 435.344316 -199.226678) (xy 435.356 -199.244204) (xy 435.356 -199.244712) (xy 435.39156 -199.297798)
			(xy 435.399 -199.307717) (xy 435.420836 -199.319405) (xy 435.433216 -199.32015) (xy 438.531762 -199.32015)
			(xy 438.543746 -199.319512) (xy 438.565104 -199.308647) (xy 438.572656 -199.299322) (xy 438.584086 -199.283574)
			(xy 438.62117 -199.232266) (xy 438.624201 -199.227809) (xy 438.628546 -199.217949) (xy 438.629806 -199.212708)
			(xy 438.63006 -199.211438) (xy 438.630905 -199.205441) (xy 438.630005 -199.193368) (xy 438.628282 -199.187562)
			(xy 438.628282 -199.187308) (xy 438.618698 -199.155839) (xy 438.606973 -199.091108) (xy 438.604914 -199.058276)
			(xy 438.604406 -199.04964) (xy 438.604152 -199.035162) (xy 438.60462 -199.003928) (xy 438.612452 -198.941953)
			(xy 438.628 -198.881451) (xy 438.651019 -198.823378) (xy 438.681144 -198.768654) (xy 438.717898 -198.718143)
			(xy 438.760702 -198.672644) (xy 438.808877 -198.632877) (xy 438.835038 -198.615808) (xy 438.8358 -198.6153)
			(xy 438.839818 -198.612678) (xy 438.846856 -198.606157) (xy 438.84977 -198.602346) (xy 438.851294 -198.599806)
			(xy 438.854115 -198.594808) (xy 438.857715 -198.583913) (xy 438.858406 -198.578216) (xy 438.859422 -198.569072)
			(xy 438.862978 -198.528432) (xy 438.862978 -198.527924) (xy 438.863994 -198.51878) (xy 438.86628 -198.493634)
			(xy 438.866183 -198.488757) (xy 438.864393 -198.479168) (xy 438.862724 -198.474584) (xy 438.85866 -198.463916)
			(xy 438.84977 -198.455788) (xy 438.831446 -198.438268) (xy 438.799293 -198.399072) (xy 438.772813 -198.355841)
			(xy 438.752506 -198.309389) (xy 438.738755 -198.260592) (xy 438.73182 -198.210372) (xy 438.731406 -198.185024)
			(xy 438.731823 -198.159706) (xy 438.738745 -198.109544) (xy 438.752464 -198.060801) (xy 438.77272 -198.014392)
			(xy 438.799134 -197.97119) (xy 438.831209 -197.932007) (xy 438.849516 -197.914514) (xy 438.850024 -197.914006)
			(xy 438.854011 -197.910022) (xy 438.860284 -197.90066) (xy 438.86247 -197.895464) (xy 438.864248 -197.890638)
			(xy 438.866788 -197.884542) (xy 438.858406 -197.792086) (xy 438.857833 -197.787119) (xy 438.855022 -197.777524)
			(xy 438.852818 -197.773036) (xy 438.849516 -197.767702) (xy 438.84659 -197.763846) (xy 438.839564 -197.757192)
			(xy 438.835546 -197.754494) (xy 438.835038 -197.753986) (xy 438.808331 -197.736506) (xy 438.759213 -197.695741)
			(xy 438.715735 -197.649008) (xy 438.678616 -197.597081) (xy 438.648471 -197.540817) (xy 438.636664 -197.511162)
			(xy 438.625268 -197.479661) (xy 438.610099 -197.414412) (xy 438.606438 -197.381114) (xy 438.604914 -197.364096)
			(xy 438.604152 -197.33514) (xy 438.604621 -197.303907) (xy 438.612456 -197.241933) (xy 438.628006 -197.181433)
			(xy 438.651026 -197.123362) (xy 438.681152 -197.06864) (xy 438.717908 -197.018131) (xy 438.760712 -196.972634)
			(xy 438.808887 -196.932869) (xy 438.835038 -196.915786) (xy 438.8358 -196.915278) (xy 438.839817 -196.912655)
			(xy 438.846852 -196.906133) (xy 438.84977 -196.902324) (xy 438.851294 -196.899784) (xy 438.854113 -196.894785)
			(xy 438.857708 -196.88389) (xy 438.858406 -196.878194) (xy 438.859422 -196.86905) (xy 438.862978 -196.82841)
			(xy 438.862978 -196.827902) (xy 438.863994 -196.818758) (xy 438.86628 -196.793612) (xy 438.866181 -196.788735)
			(xy 438.864387 -196.779148) (xy 438.862724 -196.774562) (xy 438.85866 -196.763894) (xy 438.84977 -196.755766)
			(xy 438.831447 -196.738246) (xy 438.799296 -196.699049) (xy 438.772819 -196.655817) (xy 438.752515 -196.609365)
			(xy 438.738767 -196.560569) (xy 438.731834 -196.51035) (xy 438.731406 -196.485002) (xy 438.731922 -196.457402)
			(xy 438.740149 -196.402819) (xy 438.756419 -196.350072) (xy 438.780369 -196.30034) (xy 438.811464 -196.254732)
			(xy 438.849009 -196.214268) (xy 438.892166 -196.179851) (xy 438.93997 -196.152252) (xy 438.991354 -196.132085)
			(xy 439.045169 -196.119802) (xy 439.100214 -196.115677) (xy 439.155259 -196.119802) (xy 439.209074 -196.132085)
			(xy 439.260458 -196.152252) (xy 439.308262 -196.179851) (xy 439.351419 -196.214268) (xy 439.388964 -196.254732)
			(xy 439.420059 -196.30034) (xy 439.444009 -196.350072) (xy 439.460279 -196.402819) (xy 439.468506 -196.457402)
			(xy 439.469022 -196.485002) (xy 439.468602 -196.51035) (xy 439.46166 -196.560568) (xy 439.447907 -196.609363)
			(xy 439.427603 -196.655815) (xy 439.40113 -196.699049) (xy 439.368986 -196.738251) (xy 439.350658 -196.755766)
			(xy 439.350404 -196.75602) (xy 439.346805 -196.759479) (xy 439.340916 -196.767539) (xy 439.33872 -196.772022)
			(xy 439.336434 -196.777864) (xy 439.335226 -196.782009) (xy 439.334086 -196.790565) (xy 439.334148 -196.794882)
			(xy 439.335418 -196.806566) (xy 439.33745 -196.827902) (xy 439.33745 -196.82841) (xy 439.342022 -196.878194)
			(xy 439.342594 -196.883162) (xy 439.345402 -196.892758) (xy 439.34761 -196.897244) (xy 439.348626 -196.899022)
			(xy 439.349388 -196.900038) (xy 439.352074 -196.904121) (xy 439.358722 -196.911283) (xy 439.362596 -196.914262)
			(xy 439.36539 -196.91604) (xy 439.391505 -196.933136) (xy 439.439632 -196.972884) (xy 439.482392 -197.018357)
			(xy 439.519109 -197.068834) (xy 439.549203 -197.12352) (xy 439.572199 -197.181548) (xy 439.587732 -197.242004)
			(xy 439.595559 -197.30393) (xy 439.596022 -197.33514) (xy 439.595548 -197.366335) (xy 439.587715 -197.428232)
			(xy 439.572176 -197.488657) (xy 439.549178 -197.546655) (xy 439.519084 -197.601308) (xy 439.48237 -197.651753)
			(xy 439.439617 -197.697192) (xy 439.3915 -197.736908) (xy 439.36539 -197.753986) (xy 439.365136 -197.75424)
			(xy 439.364628 -197.754494) (xy 439.360087 -197.757652) (xy 439.3524 -197.765602) (xy 439.349388 -197.770242)
			(xy 439.34634 -197.775068) (xy 439.34253 -197.786244) (xy 439.33999 -197.814946) (xy 439.33999 -197.815454)
			(xy 439.337196 -197.845934) (xy 439.334402 -197.876668) (xy 439.334429 -197.880402) (xy 439.335447 -197.887799)
			(xy 439.336434 -197.8914) (xy 439.338466 -197.896988) (xy 439.340204 -197.900927) (xy 439.344801 -197.908204)
			(xy 439.34761 -197.911466) (xy 439.350658 -197.91426) (xy 439.350912 -197.914514) (xy 439.369199 -197.932029)
			(xy 439.401285 -197.971203) (xy 439.427708 -198.014398) (xy 439.447973 -198.060803) (xy 439.461697 -198.109545)
			(xy 439.468622 -198.159706) (xy 439.469022 -198.185024) (xy 439.4686 -198.210371) (xy 439.461656 -198.260588)
			(xy 439.447901 -198.309381) (xy 439.427595 -198.355831) (xy 439.40112 -198.399063) (xy 439.368975 -198.438263)
			(xy 439.350658 -198.455788) (xy 439.350404 -198.456042) (xy 439.346806 -198.459502) (xy 439.340921 -198.467563)
			(xy 439.33872 -198.472044) (xy 439.336434 -198.477886) (xy 439.33522 -198.48203) (xy 439.334066 -198.490587)
			(xy 439.334148 -198.494904) (xy 439.335418 -198.506588) (xy 439.33745 -198.527924) (xy 439.33745 -198.528432)
			(xy 439.342022 -198.577962) (xy 439.342568 -198.58285) (xy 439.345256 -198.59231) (xy 439.347356 -198.596758)
			(xy 439.35015 -198.601584) (xy 439.354468 -198.608696) (xy 439.354976 -198.609204) (xy 439.36539 -198.615808)
			(xy 439.391526 -198.632911) (xy 439.439695 -198.672679) (xy 439.482493 -198.718175) (xy 439.519245 -198.768682)
			(xy 439.54937 -198.8234) (xy 439.572391 -198.881466) (xy 439.587946 -198.941962) (xy 439.595787 -199.003931)
			(xy 439.596276 -199.035162) (xy 439.596276 -199.040496) (xy 439.595768 -199.052434) (xy 439.593988 -199.086749)
			(xy 439.582137 -199.154432) (xy 439.572146 -199.187308) (xy 439.572146 -199.187562) (xy 439.570475 -199.193312)
			(xy 439.569574 -199.205249) (xy 439.570368 -199.211184) (xy 439.572146 -199.222614) (xy 439.609738 -199.27443)
			(xy 439.609738 -199.274938) (xy 439.627772 -199.299322) (xy 439.635373 -199.30859) (xy 439.6567 -199.319467)
			(xy 439.668666 -199.32015) (xy 442.11113 -199.32015) (xy 442.123477 -199.319291) (xy 442.145258 -199.30762)
			(xy 442.152786 -199.297798) (xy 442.188346 -199.244712) (xy 442.188346 -199.244204) (xy 442.20003 -199.226678)
			(xy 442.203363 -199.221425) (xy 442.207604 -199.209733) (xy 442.208412 -199.203564) (xy 442.209682 -199.190864)
			(xy 442.204602 -199.178926) (xy 442.195382 -199.156091) (xy 442.182385 -199.10859) (xy 442.175811 -199.059785)
			(xy 442.175392 -199.035162) (xy 442.175815 -199.009815) (xy 442.182761 -198.9596) (xy 442.196518 -198.910809)
			(xy 442.216825 -198.86436) (xy 442.243302 -198.82113) (xy 442.275448 -198.781933) (xy 442.293756 -198.764398)
			(xy 442.29401 -198.764144) (xy 442.297606 -198.760683) (xy 442.303488 -198.75262) (xy 442.305694 -198.748142)
			(xy 442.30798 -198.7423) (xy 442.309195 -198.738156) (xy 442.310347 -198.729599) (xy 442.310266 -198.725282)
			(xy 442.308996 -198.713598) (xy 442.306964 -198.692262) (xy 442.306964 -198.691754) (xy 442.302392 -198.64197)
			(xy 442.301817 -198.637003) (xy 442.299003 -198.62741) (xy 442.296804 -198.62292) (xy 442.295788 -198.621142)
			(xy 442.295026 -198.620126) (xy 442.292339 -198.616044) (xy 442.285689 -198.608885) (xy 442.281818 -198.605902)
			(xy 442.279024 -198.604124) (xy 442.25291 -198.587028) (xy 442.204785 -198.547279) (xy 442.162027 -198.501806)
			(xy 442.125312 -198.451329) (xy 442.095221 -198.396643) (xy 442.072229 -198.338614) (xy 442.056699 -198.278159)
			(xy 442.048877 -198.216233) (xy 442.048392 -198.185024) (xy 442.048868 -198.15383) (xy 442.056706 -198.091936)
			(xy 442.072248 -198.031514) (xy 442.095249 -197.973521) (xy 442.125346 -197.918872) (xy 442.162061 -197.868431)
			(xy 442.204816 -197.822996) (xy 442.252934 -197.783285) (xy 442.279024 -197.766178) (xy 442.279278 -197.765924)
			(xy 442.279786 -197.76567) (xy 442.28433 -197.762514) (xy 442.292023 -197.754568) (xy 442.295026 -197.749922)
			(xy 442.298074 -197.745096) (xy 442.301884 -197.73392) (xy 442.304424 -197.705218) (xy 442.304424 -197.70471)
			(xy 442.307218 -197.67423) (xy 442.310012 -197.643496) (xy 442.309982 -197.639763) (xy 442.30896 -197.632367)
			(xy 442.30798 -197.628764) (xy 442.305948 -197.623176) (xy 442.304209 -197.619239) (xy 442.299608 -197.611964)
			(xy 442.296804 -197.608698) (xy 442.293756 -197.605904) (xy 442.293502 -197.60565) (xy 442.27522 -197.588133)
			(xy 442.243145 -197.548955) (xy 442.216732 -197.505758) (xy 442.196477 -197.459353) (xy 442.182761 -197.410614)
			(xy 442.175842 -197.360456) (xy 442.175392 -197.33514) (xy 442.175908 -197.30754) (xy 442.184135 -197.252957)
			(xy 442.200405 -197.20021) (xy 442.224355 -197.150478) (xy 442.25545 -197.10487) (xy 442.292995 -197.064406)
			(xy 442.336152 -197.029989) (xy 442.383956 -197.00239) (xy 442.43534 -196.982223) (xy 442.489155 -196.96994)
			(xy 442.5442 -196.965815) (xy 442.599245 -196.96994) (xy 442.65306 -196.982223) (xy 442.704444 -197.00239)
			(xy 442.752248 -197.029989) (xy 442.795405 -197.064406) (xy 442.83295 -197.10487) (xy 442.864045 -197.150478)
			(xy 442.887995 -197.20021) (xy 442.904265 -197.252957) (xy 442.912492 -197.30754) (xy 442.913008 -197.33514)
			(xy 442.912587 -197.360456) (xy 442.905655 -197.410611) (xy 442.891928 -197.459347) (xy 442.871662 -197.505747)
			(xy 442.84524 -197.548938) (xy 442.813158 -197.588109) (xy 442.794898 -197.60565) (xy 442.79439 -197.606158)
			(xy 442.790399 -197.61014) (xy 442.784118 -197.619499) (xy 442.781944 -197.6247) (xy 442.780166 -197.629526)
			(xy 442.777626 -197.635622) (xy 442.786008 -197.728078) (xy 442.786587 -197.733043) (xy 442.789409 -197.742632)
			(xy 442.791596 -197.747128) (xy 442.794898 -197.752462) (xy 442.797827 -197.756314) (xy 442.804859 -197.762959)
			(xy 442.808868 -197.76567) (xy 442.809376 -197.766178) (xy 442.836084 -197.783657) (xy 442.885203 -197.824422)
			(xy 442.928683 -197.871154) (xy 442.965804 -197.923081) (xy 442.995953 -197.979343) (xy 443.00775 -198.009002)
			(xy 443.019144 -198.040503) (xy 443.034307 -198.105753) (xy 443.037976 -198.13905) (xy 443.0395 -198.156068)
			(xy 443.040262 -198.185024) (xy 443.039789 -198.216256) (xy 443.031947 -198.278225) (xy 443.016391 -198.33872)
			(xy 442.993367 -198.396785) (xy 442.963238 -198.451502) (xy 442.92648 -198.502005) (xy 442.883676 -198.547496)
			(xy 442.835501 -198.587257) (xy 442.809376 -198.604378) (xy 442.808614 -198.604886) (xy 442.8046 -198.607512)
			(xy 442.797571 -198.614039) (xy 442.794644 -198.61784) (xy 442.79312 -198.62038) (xy 442.790306 -198.62538)
			(xy 442.786724 -198.636277) (xy 442.786008 -198.64197) (xy 442.784992 -198.651114) (xy 442.781436 -198.691754)
			(xy 442.781436 -198.692262) (xy 442.78042 -198.701406) (xy 442.778134 -198.726552) (xy 442.77823 -198.73143)
			(xy 442.780018 -198.741019) (xy 442.78169 -198.745602) (xy 442.785754 -198.75627) (xy 442.794644 -198.764398)
			(xy 442.812968 -198.781918) (xy 442.845122 -198.821114) (xy 442.871602 -198.864346) (xy 442.89191 -198.910797)
			(xy 442.905662 -198.959593) (xy 442.912599 -199.009813) (xy 442.913008 -199.035162) (xy 442.912616 -199.059787)
			(xy 442.906051 -199.108597) (xy 442.893033 -199.156095) (xy 442.883798 -199.178926) (xy 442.881258 -199.185022)
			(xy 442.87948 -199.197468) (xy 442.879988 -199.203564) (xy 442.880834 -199.209723) (xy 442.885072 -199.221407)
			(xy 442.88837 -199.226678) (xy 442.900054 -199.244204) (xy 442.900054 -199.244712) (xy 442.935614 -199.297798)
			(xy 442.94305 -199.307725) (xy 442.964886 -199.319432) (xy 442.97727 -199.32015) (xy 446.075816 -199.32015)
			(xy 446.087793 -199.3195) (xy 446.109133 -199.308622) (xy 446.11671 -199.299322) (xy 446.12814 -199.283574)
			(xy 446.165224 -199.232266) (xy 446.168252 -199.227808) (xy 446.172593 -199.217947) (xy 446.17386 -199.212708)
			(xy 446.174114 -199.211438) (xy 446.174959 -199.205441) (xy 446.17406 -199.193368) (xy 446.172336 -199.187562)
			(xy 446.172336 -199.187308) (xy 446.162751 -199.155839) (xy 446.151025 -199.091108) (xy 446.148968 -199.058276)
			(xy 446.14846 -199.04964) (xy 446.148206 -199.035162) (xy 446.148674 -199.003928) (xy 446.156507 -198.941954)
			(xy 446.172056 -198.881454) (xy 446.195076 -198.823383) (xy 446.225203 -198.768661) (xy 446.26196 -198.718153)
			(xy 446.304766 -198.672658) (xy 446.352943 -198.632895) (xy 446.379092 -198.615808) (xy 446.379854 -198.6153)
			(xy 446.38387 -198.612675) (xy 446.390901 -198.60615) (xy 446.393824 -198.602346) (xy 446.395348 -198.599806)
			(xy 446.398167 -198.594807) (xy 446.401762 -198.583912) (xy 446.40246 -198.578216) (xy 446.403476 -198.569072)
			(xy 446.407032 -198.528432) (xy 446.407032 -198.527924) (xy 446.408048 -198.51878) (xy 446.410334 -198.493634)
			(xy 446.410237 -198.488757) (xy 446.408445 -198.479169) (xy 446.406778 -198.474584) (xy 446.402714 -198.463916)
			(xy 446.393824 -198.455788) (xy 446.375502 -198.438267) (xy 446.343353 -198.39907) (xy 446.316876 -198.355838)
			(xy 446.296572 -198.309386) (xy 446.282823 -198.260591) (xy 446.275888 -198.210372) (xy 446.27546 -198.185024)
			(xy 446.275877 -198.159706) (xy 446.2828 -198.109545) (xy 446.29652 -198.060804) (xy 446.316779 -198.014397)
			(xy 446.343195 -197.971197) (xy 446.375273 -197.932018) (xy 446.39357 -197.914514) (xy 446.394078 -197.914006)
			(xy 446.398068 -197.910024) (xy 446.404347 -197.900664) (xy 446.406524 -197.895464) (xy 446.408302 -197.890638)
			(xy 446.410842 -197.884542) (xy 446.40246 -197.792086) (xy 446.401886 -197.787119) (xy 446.399074 -197.777525)
			(xy 446.396872 -197.773036) (xy 446.39357 -197.767702) (xy 446.390643 -197.763848) (xy 446.383612 -197.757199)
			(xy 446.3796 -197.754494) (xy 446.379092 -197.753986) (xy 446.352387 -197.736505) (xy 446.303273 -197.695737)
			(xy 446.259799 -197.649003) (xy 446.222683 -197.597074) (xy 446.192541 -197.54081) (xy 446.180718 -197.511162)
			(xy 446.16932 -197.479661) (xy 446.154151 -197.414413) (xy 446.150492 -197.381114) (xy 446.148968 -197.364096)
			(xy 446.148206 -197.33514) (xy 446.148675 -197.303907) (xy 446.156511 -197.241935) (xy 446.172062 -197.181436)
			(xy 446.195084 -197.123367) (xy 446.225212 -197.068647) (xy 446.26197 -197.018141) (xy 446.304776 -196.972648)
			(xy 446.352953 -196.932888) (xy 446.379092 -196.915786) (xy 446.379854 -196.915278) (xy 446.383869 -196.912652)
			(xy 446.390897 -196.906125) (xy 446.393824 -196.902324) (xy 446.395348 -196.899784) (xy 446.398165 -196.894785)
			(xy 446.401756 -196.883889) (xy 446.40246 -196.878194) (xy 446.403476 -196.86905) (xy 446.407032 -196.82841)
			(xy 446.407032 -196.827902) (xy 446.408048 -196.818758) (xy 446.410334 -196.793612) (xy 446.410234 -196.788735)
			(xy 446.408439 -196.779149) (xy 446.406778 -196.774562) (xy 446.402714 -196.763894) (xy 446.393824 -196.755766)
			(xy 446.375503 -196.738245) (xy 446.343356 -196.699047) (xy 446.316882 -196.655814) (xy 446.296581 -196.609362)
			(xy 446.282835 -196.560567) (xy 446.275903 -196.510349) (xy 446.27546 -196.485002) (xy 446.275976 -196.457402)
			(xy 446.284203 -196.402819) (xy 446.300473 -196.350072) (xy 446.324423 -196.30034) (xy 446.355518 -196.254732)
			(xy 446.393063 -196.214268) (xy 446.43622 -196.179851) (xy 446.484024 -196.152252) (xy 446.535408 -196.132085)
			(xy 446.589223 -196.119802) (xy 446.644268 -196.115677) (xy 446.699313 -196.119802) (xy 446.753128 -196.132085)
			(xy 446.804512 -196.152252) (xy 446.852316 -196.179851) (xy 446.895473 -196.214268) (xy 446.933018 -196.254732)
			(xy 446.964113 -196.30034) (xy 446.988063 -196.350072) (xy 447.004333 -196.402819) (xy 447.01256 -196.457402)
			(xy 447.013076 -196.485002) (xy 447.012656 -196.51035) (xy 447.005715 -196.560569) (xy 446.991964 -196.609365)
			(xy 446.971662 -196.655819) (xy 446.945191 -196.699056) (xy 446.91305 -196.738262) (xy 446.894712 -196.755766)
			(xy 446.894458 -196.75602) (xy 446.890856 -196.759477) (xy 446.884961 -196.767534) (xy 446.882774 -196.772022)
			(xy 446.880488 -196.777864) (xy 446.879279 -196.782008) (xy 446.878138 -196.790565) (xy 446.878202 -196.794882)
			(xy 446.879472 -196.806566) (xy 446.881504 -196.827902) (xy 446.881504 -196.82841) (xy 446.886076 -196.878194)
			(xy 446.886647 -196.883162) (xy 446.889453 -196.892759) (xy 446.891664 -196.897244) (xy 446.89268 -196.899022)
			(xy 446.893442 -196.900038) (xy 446.896126 -196.904123) (xy 446.90277 -196.91129) (xy 446.90665 -196.914262)
			(xy 446.909444 -196.91604) (xy 446.935561 -196.933135) (xy 446.983692 -196.972881) (xy 447.026456 -197.018352)
			(xy 447.063177 -197.068829) (xy 447.093274 -197.123515) (xy 447.116272 -197.181545) (xy 447.131807 -197.242001)
			(xy 447.139634 -197.30393) (xy 447.140076 -197.33514) (xy 447.139602 -197.366335) (xy 447.131768 -197.428231)
			(xy 447.116228 -197.488654) (xy 447.093229 -197.54665) (xy 447.063134 -197.601301) (xy 447.026418 -197.651744)
			(xy 446.983662 -197.69718) (xy 446.935543 -197.736892) (xy 446.909444 -197.753986) (xy 446.90919 -197.75424)
			(xy 446.908682 -197.754494) (xy 446.904144 -197.757655) (xy 446.896463 -197.765609) (xy 446.893442 -197.770242)
			(xy 446.890394 -197.775068) (xy 446.886584 -197.786244) (xy 446.884044 -197.814946) (xy 446.884044 -197.815454)
			(xy 446.88125 -197.845934) (xy 446.878456 -197.876668) (xy 446.878483 -197.880402) (xy 446.8795 -197.887799)
			(xy 446.880488 -197.8914) (xy 446.88252 -197.896988) (xy 446.884256 -197.900928) (xy 446.888851 -197.908207)
			(xy 446.891664 -197.911466) (xy 446.894712 -197.91426) (xy 446.894966 -197.914514) (xy 446.913251 -197.93203)
			(xy 446.945332 -197.971205) (xy 446.971752 -198.014402) (xy 446.992013 -198.060806) (xy 447.005735 -198.109547)
			(xy 447.01266 -198.159706) (xy 447.013076 -198.185024) (xy 447.012654 -198.210372) (xy 447.005711 -198.260589)
			(xy 446.991957 -198.309383) (xy 446.971654 -198.355835) (xy 446.945181 -198.39907) (xy 446.91304 -198.438273)
			(xy 446.894712 -198.455788) (xy 446.894458 -198.456042) (xy 446.890857 -198.4595) (xy 446.884966 -198.467559)
			(xy 446.882774 -198.472044) (xy 446.880488 -198.477886) (xy 446.879272 -198.48203) (xy 446.878118 -198.490587)
			(xy 446.878202 -198.494904) (xy 446.879472 -198.506588) (xy 446.881504 -198.527924) (xy 446.881504 -198.528432)
			(xy 446.886076 -198.577962) (xy 446.886621 -198.58285) (xy 446.889307 -198.592311) (xy 446.89141 -198.596758)
			(xy 446.894204 -198.601584) (xy 446.898522 -198.608696) (xy 446.89903 -198.609204) (xy 446.909444 -198.615808)
			(xy 446.935582 -198.63291) (xy 446.983755 -198.672675) (xy 447.026557 -198.71817) (xy 447.063312 -198.768677)
			(xy 447.09344 -198.823396) (xy 447.116464 -198.881462) (xy 447.13202 -198.941959) (xy 447.139863 -199.00393)
			(xy 447.14033 -199.035162) (xy 447.14033 -199.040496) (xy 447.139822 -199.052434) (xy 447.138042 -199.086749)
			(xy 447.12619 -199.154431) (xy 447.1162 -199.187308) (xy 447.1162 -199.187562) (xy 447.114528 -199.193312)
			(xy 447.113626 -199.205249) (xy 447.114422 -199.211184) (xy 447.1162 -199.222614) (xy 447.153792 -199.27443)
			(xy 447.153792 -199.274938) (xy 447.171826 -199.299322) (xy 447.179431 -199.308581) (xy 447.200758 -199.319435)
			(xy 447.21272 -199.32015) (xy 449.65493 -199.32015) (xy 449.667277 -199.319291) (xy 449.689058 -199.30762)
			(xy 449.696586 -199.297798) (xy 449.732146 -199.244712) (xy 449.732146 -199.244204) (xy 449.74383 -199.226678)
			(xy 449.747163 -199.221425) (xy 449.751404 -199.209733) (xy 449.752212 -199.203564) (xy 449.753482 -199.190864)
			(xy 449.748402 -199.178926) (xy 449.739182 -199.156091) (xy 449.726185 -199.10859) (xy 449.719611 -199.059785)
			(xy 449.719192 -199.035162) (xy 449.719615 -199.009815) (xy 449.726561 -198.9596) (xy 449.740318 -198.910809)
			(xy 449.760625 -198.86436) (xy 449.787102 -198.82113) (xy 449.819248 -198.781933) (xy 449.837556 -198.764398)
			(xy 449.83781 -198.764144) (xy 449.841406 -198.760683) (xy 449.847288 -198.75262) (xy 449.849494 -198.748142)
			(xy 449.85178 -198.7423) (xy 449.852995 -198.738156) (xy 449.854147 -198.729599) (xy 449.854066 -198.725282)
			(xy 449.852796 -198.713598) (xy 449.850764 -198.692262) (xy 449.850764 -198.691754) (xy 449.846192 -198.64197)
			(xy 449.845617 -198.637003) (xy 449.842803 -198.62741) (xy 449.840604 -198.62292) (xy 449.839588 -198.621142)
			(xy 449.838826 -198.620126) (xy 449.836139 -198.616044) (xy 449.829489 -198.608885) (xy 449.825618 -198.605902)
			(xy 449.822824 -198.604124) (xy 449.79671 -198.587028) (xy 449.748585 -198.547279) (xy 449.705827 -198.501806)
			(xy 449.669112 -198.451329) (xy 449.639021 -198.396643) (xy 449.616029 -198.338614) (xy 449.600499 -198.278159)
			(xy 449.592677 -198.216233) (xy 449.592192 -198.185024) (xy 449.592668 -198.15383) (xy 449.600506 -198.091936)
			(xy 449.616048 -198.031514) (xy 449.639049 -197.973521) (xy 449.669146 -197.918872) (xy 449.705861 -197.868431)
			(xy 449.748616 -197.822996) (xy 449.796734 -197.783285) (xy 449.822824 -197.766178) (xy 449.823078 -197.765924)
			(xy 449.823586 -197.76567) (xy 449.82813 -197.762514) (xy 449.835823 -197.754568) (xy 449.838826 -197.749922)
			(xy 449.841874 -197.745096) (xy 449.845684 -197.73392) (xy 449.848224 -197.705218) (xy 449.848224 -197.70471)
			(xy 449.851018 -197.67423) (xy 449.853812 -197.643496) (xy 449.853782 -197.639763) (xy 449.85276 -197.632367)
			(xy 449.85178 -197.628764) (xy 449.849748 -197.623176) (xy 449.848009 -197.619239) (xy 449.843408 -197.611964)
			(xy 449.840604 -197.608698) (xy 449.837556 -197.605904) (xy 449.837302 -197.60565) (xy 449.81902 -197.588133)
			(xy 449.786945 -197.548955) (xy 449.760532 -197.505758) (xy 449.740277 -197.459353) (xy 449.726561 -197.410614)
			(xy 449.719642 -197.360456) (xy 449.719192 -197.33514) (xy 449.719708 -197.30754) (xy 449.727935 -197.252957)
			(xy 449.744205 -197.20021) (xy 449.768155 -197.150478) (xy 449.79925 -197.10487) (xy 449.836795 -197.064406)
			(xy 449.879952 -197.029989) (xy 449.927756 -197.00239) (xy 449.97914 -196.982223) (xy 450.032955 -196.96994)
			(xy 450.088 -196.965815) (xy 450.143045 -196.96994) (xy 450.19686 -196.982223) (xy 450.248244 -197.00239)
			(xy 450.296048 -197.029989) (xy 450.339205 -197.064406) (xy 450.37675 -197.10487) (xy 450.407845 -197.150478)
			(xy 450.431795 -197.20021) (xy 450.448065 -197.252957) (xy 450.456292 -197.30754) (xy 450.456808 -197.33514)
			(xy 450.456387 -197.360456) (xy 450.449455 -197.410611) (xy 450.435728 -197.459347) (xy 450.415462 -197.505747)
			(xy 450.38904 -197.548938) (xy 450.356958 -197.588109) (xy 450.338698 -197.60565) (xy 450.33819 -197.606158)
			(xy 450.334199 -197.61014) (xy 450.327918 -197.619499) (xy 450.325744 -197.6247) (xy 450.323966 -197.629526)
			(xy 450.321426 -197.635622) (xy 450.329808 -197.728078) (xy 450.330387 -197.733043) (xy 450.333209 -197.742632)
			(xy 450.335396 -197.747128) (xy 450.338698 -197.752462) (xy 450.341627 -197.756314) (xy 450.348659 -197.762959)
			(xy 450.352668 -197.76567) (xy 450.353176 -197.766178) (xy 450.379884 -197.783657) (xy 450.429003 -197.824422)
			(xy 450.472483 -197.871154) (xy 450.509604 -197.923081) (xy 450.539753 -197.979343) (xy 450.55155 -198.009002)
			(xy 450.562944 -198.040503) (xy 450.578107 -198.105753) (xy 450.581776 -198.13905) (xy 450.5833 -198.156068)
			(xy 450.584062 -198.185024) (xy 450.583589 -198.216256) (xy 450.575747 -198.278225) (xy 450.560191 -198.33872)
			(xy 450.537167 -198.396785) (xy 450.507038 -198.451502) (xy 450.47028 -198.502005) (xy 450.427476 -198.547496)
			(xy 450.379301 -198.587257) (xy 450.353176 -198.604378) (xy 450.352414 -198.604886) (xy 450.3484 -198.607512)
			(xy 450.341371 -198.614039) (xy 450.338444 -198.61784) (xy 450.33692 -198.62038) (xy 450.334106 -198.62538)
			(xy 450.330524 -198.636277) (xy 450.329808 -198.64197) (xy 450.328792 -198.651114) (xy 450.325236 -198.691754)
			(xy 450.325236 -198.692262) (xy 450.32422 -198.701406) (xy 450.321934 -198.726552) (xy 450.32203 -198.73143)
			(xy 450.323818 -198.741019) (xy 450.32549 -198.745602) (xy 450.329554 -198.75627) (xy 450.338444 -198.764398)
			(xy 450.356768 -198.781918) (xy 450.388922 -198.821114) (xy 450.415402 -198.864346) (xy 450.43571 -198.910797)
			(xy 450.449462 -198.959593) (xy 450.456399 -199.009813) (xy 450.456808 -199.035162) (xy 450.456416 -199.059787)
			(xy 450.449851 -199.108597) (xy 450.436833 -199.156095) (xy 450.427598 -199.178926) (xy 450.425058 -199.185022)
			(xy 450.42328 -199.197468) (xy 450.423788 -199.203564) (xy 450.424634 -199.209723) (xy 450.428872 -199.221407)
			(xy 450.43217 -199.226678) (xy 450.443854 -199.244204) (xy 450.443854 -199.244712) (xy 450.479414 -199.297798)
			(xy 450.48685 -199.307725) (xy 450.508686 -199.319432) (xy 450.52107 -199.32015) (xy 453.619616 -199.32015)
			(xy 453.631593 -199.3195) (xy 453.652933 -199.308622) (xy 453.66051 -199.299322) (xy 453.67194 -199.283574)
			(xy 453.709024 -199.232266) (xy 453.712052 -199.227808) (xy 453.716393 -199.217947) (xy 453.71766 -199.212708)
			(xy 453.717914 -199.211438) (xy 453.718759 -199.205441) (xy 453.71786 -199.193368) (xy 453.716136 -199.187562)
			(xy 453.716136 -199.187308) (xy 453.706551 -199.155839) (xy 453.694825 -199.091108) (xy 453.692768 -199.058276)
			(xy 453.69226 -199.04964) (xy 453.692006 -199.035162) (xy 453.692474 -199.003928) (xy 453.700307 -198.941954)
			(xy 453.715856 -198.881454) (xy 453.738876 -198.823383) (xy 453.769003 -198.768661) (xy 453.80576 -198.718153)
			(xy 453.848566 -198.672658) (xy 453.896743 -198.632895) (xy 453.922892 -198.615808) (xy 453.923654 -198.6153)
			(xy 453.92767 -198.612675) (xy 453.934701 -198.60615) (xy 453.937624 -198.602346) (xy 453.939148 -198.599806)
			(xy 453.941967 -198.594807) (xy 453.945562 -198.583912) (xy 453.94626 -198.578216) (xy 453.947276 -198.569072)
			(xy 453.950832 -198.528432) (xy 453.950832 -198.527924) (xy 453.951848 -198.51878) (xy 453.954134 -198.493634)
			(xy 453.954037 -198.488757) (xy 453.952245 -198.479169) (xy 453.950578 -198.474584) (xy 453.946514 -198.463916)
			(xy 453.937624 -198.455788) (xy 453.919302 -198.438267) (xy 453.887153 -198.39907) (xy 453.860676 -198.355838)
			(xy 453.840372 -198.309386) (xy 453.826623 -198.260591) (xy 453.819688 -198.210372) (xy 453.81926 -198.185024)
			(xy 453.819677 -198.159706) (xy 453.8266 -198.109545) (xy 453.84032 -198.060804) (xy 453.860579 -198.014397)
			(xy 453.886995 -197.971197) (xy 453.919073 -197.932018) (xy 453.93737 -197.914514) (xy 453.937878 -197.914006)
			(xy 453.941868 -197.910024) (xy 453.948147 -197.900664) (xy 453.950324 -197.895464) (xy 453.952102 -197.890638)
			(xy 453.954642 -197.884542) (xy 453.94626 -197.792086) (xy 453.945686 -197.787119) (xy 453.942874 -197.777525)
			(xy 453.940672 -197.773036) (xy 453.93737 -197.767702) (xy 453.934443 -197.763848) (xy 453.927412 -197.757199)
			(xy 453.9234 -197.754494) (xy 453.922892 -197.753986) (xy 453.896187 -197.736505) (xy 453.847073 -197.695737)
			(xy 453.803599 -197.649003) (xy 453.766483 -197.597074) (xy 453.736341 -197.54081) (xy 453.724518 -197.511162)
			(xy 453.71312 -197.479661) (xy 453.697951 -197.414413) (xy 453.694292 -197.381114) (xy 453.692768 -197.364096)
			(xy 453.692006 -197.33514) (xy 453.692475 -197.303907) (xy 453.700311 -197.241935) (xy 453.715862 -197.181436)
			(xy 453.738884 -197.123367) (xy 453.769012 -197.068647) (xy 453.80577 -197.018141) (xy 453.848576 -196.972648)
			(xy 453.896753 -196.932888) (xy 453.922892 -196.915786) (xy 453.923654 -196.915278) (xy 453.927669 -196.912652)
			(xy 453.934697 -196.906125) (xy 453.937624 -196.902324) (xy 453.939148 -196.899784) (xy 453.941965 -196.894785)
			(xy 453.945556 -196.883889) (xy 453.94626 -196.878194) (xy 453.947276 -196.86905) (xy 453.950832 -196.82841)
			(xy 453.950832 -196.827902) (xy 453.951848 -196.818758) (xy 453.954134 -196.793612) (xy 453.954034 -196.788735)
			(xy 453.952239 -196.779149) (xy 453.950578 -196.774562) (xy 453.946514 -196.763894) (xy 453.937624 -196.755766)
			(xy 453.919303 -196.738245) (xy 453.887156 -196.699047) (xy 453.860682 -196.655814) (xy 453.840381 -196.609362)
			(xy 453.826635 -196.560567) (xy 453.819703 -196.510349) (xy 453.81926 -196.485002) (xy 453.819776 -196.457402)
			(xy 453.828003 -196.402819) (xy 453.844273 -196.350072) (xy 453.868223 -196.30034) (xy 453.899318 -196.254732)
			(xy 453.936863 -196.214268) (xy 453.98002 -196.179851) (xy 454.027824 -196.152252) (xy 454.079208 -196.132085)
			(xy 454.133023 -196.119802) (xy 454.188068 -196.115677) (xy 454.243113 -196.119802) (xy 454.296928 -196.132085)
			(xy 454.348312 -196.152252) (xy 454.396116 -196.179851) (xy 454.439273 -196.214268) (xy 454.476818 -196.254732)
			(xy 454.507913 -196.30034) (xy 454.531863 -196.350072) (xy 454.548133 -196.402819) (xy 454.55636 -196.457402)
			(xy 454.556876 -196.485002) (xy 454.556456 -196.51035) (xy 454.549515 -196.560569) (xy 454.535764 -196.609365)
			(xy 454.515462 -196.655819) (xy 454.488991 -196.699056) (xy 454.45685 -196.738262) (xy 454.438512 -196.755766)
			(xy 454.438258 -196.75602) (xy 454.434656 -196.759477) (xy 454.428761 -196.767534) (xy 454.426574 -196.772022)
			(xy 454.424288 -196.777864) (xy 454.423079 -196.782008) (xy 454.421938 -196.790565) (xy 454.422002 -196.794882)
			(xy 454.423272 -196.806566) (xy 454.425304 -196.827902) (xy 454.425304 -196.82841) (xy 454.429876 -196.878194)
			(xy 454.430447 -196.883162) (xy 454.433253 -196.892759) (xy 454.435464 -196.897244) (xy 454.43648 -196.899022)
			(xy 454.437242 -196.900038) (xy 454.439926 -196.904123) (xy 454.44657 -196.91129) (xy 454.45045 -196.914262)
			(xy 454.453244 -196.91604) (xy 454.479361 -196.933135) (xy 454.527492 -196.972881) (xy 454.570256 -197.018352)
			(xy 454.606977 -197.068829) (xy 454.637074 -197.123515) (xy 454.660072 -197.181545) (xy 454.675607 -197.242001)
			(xy 454.683434 -197.30393) (xy 454.683876 -197.33514) (xy 454.683402 -197.366335) (xy 454.675568 -197.428231)
			(xy 454.660028 -197.488654) (xy 454.637029 -197.54665) (xy 454.606934 -197.601301) (xy 454.570218 -197.651744)
			(xy 454.527462 -197.69718) (xy 454.479343 -197.736892) (xy 454.453244 -197.753986) (xy 454.45299 -197.75424)
			(xy 454.452482 -197.754494) (xy 454.447944 -197.757655) (xy 454.440263 -197.765609) (xy 454.437242 -197.770242)
			(xy 454.434194 -197.775068) (xy 454.430384 -197.786244) (xy 454.427844 -197.814946) (xy 454.427844 -197.815454)
			(xy 454.42505 -197.845934) (xy 454.422256 -197.876668) (xy 454.422283 -197.880402) (xy 454.4233 -197.887799)
			(xy 454.424288 -197.8914) (xy 454.42632 -197.896988) (xy 454.428056 -197.900928) (xy 454.432651 -197.908207)
			(xy 454.435464 -197.911466) (xy 454.438512 -197.91426) (xy 454.438766 -197.914514) (xy 454.457051 -197.93203)
			(xy 454.489132 -197.971205) (xy 454.515552 -198.014402) (xy 454.535813 -198.060806) (xy 454.549535 -198.109547)
			(xy 454.55646 -198.159706) (xy 454.556876 -198.185024) (xy 454.556454 -198.210372) (xy 454.549511 -198.260589)
			(xy 454.535757 -198.309383) (xy 454.515454 -198.355835) (xy 454.488981 -198.39907) (xy 454.45684 -198.438273)
			(xy 454.438512 -198.455788) (xy 454.438258 -198.456042) (xy 454.434657 -198.4595) (xy 454.428766 -198.467559)
			(xy 454.426574 -198.472044) (xy 454.424288 -198.477886) (xy 454.423072 -198.48203) (xy 454.421918 -198.490587)
			(xy 454.422002 -198.494904) (xy 454.423272 -198.506588) (xy 454.425304 -198.527924) (xy 454.425304 -198.528432)
			(xy 454.429876 -198.578216) (xy 454.430449 -198.583183) (xy 454.433259 -198.592778) (xy 454.435464 -198.597266)
			(xy 454.43648 -198.599044) (xy 454.437242 -198.60006) (xy 454.439927 -198.604144) (xy 454.446573 -198.611308)
			(xy 454.45045 -198.614284) (xy 454.453244 -198.616062) (xy 454.47936 -198.633157) (xy 454.527489 -198.672904)
			(xy 454.570251 -198.718375) (xy 454.60697 -198.768853) (xy 454.637064 -198.823539) (xy 454.66006 -198.881568)
			(xy 454.675592 -198.942025) (xy 454.683417 -199.003952) (xy 454.683876 -199.035162) (xy 454.683421 -199.06513)
			(xy 454.676193 -199.124629) (xy 454.66185 -199.182824) (xy 454.640601 -199.238867) (xy 454.612756 -199.291943)
			(xy 454.57872 -199.341277) (xy 454.538988 -199.386152) (xy 454.49414 -199.425914) (xy 454.469754 -199.44334)
			(xy 454.464928 -199.446642) (xy 454.457562 -199.454516) (xy 454.455784 -199.45731) (xy 454.453752 -199.46112)
			(xy 454.45173 -199.46501) (xy 454.448914 -199.473311) (xy 454.448164 -199.47763) (xy 454.446386 -199.498204)
			(xy 454.446132 -199.500744) (xy 454.445116 -199.512174) (xy 454.445116 -199.512682) (xy 454.441052 -199.558148)
			(xy 454.440611 -199.569278) (xy 454.44811 -199.590228) (xy 454.45553 -199.598534) (xy 455.586592 -200.729596)
			(xy 455.59344 -200.736994) (xy 455.601177 -200.755592) (xy 455.601578 -200.765664) (xy 455.601578 -200.916032)
			(xy 455.60234 -200.923906) (xy 455.60234 -200.924414) (xy 455.603864 -200.931018) (xy 455.610468 -200.9521)
			(xy 455.612754 -200.955656) (xy 455.618239 -200.964047) (xy 455.628404 -200.981329) (xy 455.633074 -200.9902)
			(xy 455.64371 -201.011542) (xy 455.660016 -201.056352) (xy 455.670422 -201.102887) (xy 455.672952 -201.126598)
			(xy 455.674476 -201.153014) (xy 455.674476 -201.160126) (xy 455.673996 -201.187309) (xy 455.666021 -201.241088)
			(xy 455.650232 -201.293111) (xy 455.626972 -201.34225) (xy 455.612246 -201.365104) (xy 455.609198 -201.372216)
			(xy 455.604118 -201.388472) (xy 455.603864 -201.389234) (xy 455.602809 -201.392891) (xy 455.601657 -201.400415)
			(xy 455.601578 -201.40422) (xy 455.601578 -210.266026) (xy 455.60234 -210.2739) (xy 455.60234 -210.274408)
			(xy 455.603864 -210.281012) (xy 455.610468 -210.302094) (xy 455.612754 -210.30565) (xy 455.618239 -210.314041)
			(xy 455.628404 -210.331323) (xy 455.633074 -210.340194) (xy 455.64371 -210.361536) (xy 455.660017 -210.406346)
			(xy 455.670424 -210.452881) (xy 455.672952 -210.476592) (xy 455.674476 -210.503008) (xy 455.674476 -210.51012)
			(xy 455.673997 -210.537303) (xy 455.666022 -210.591082) (xy 455.650234 -210.643106) (xy 455.626975 -210.692246)
			(xy 455.612246 -210.715098) (xy 455.609198 -210.72221) (xy 455.604118 -210.738466) (xy 455.603864 -210.739228)
			(xy 455.602808 -210.742885) (xy 455.601656 -210.750409) (xy 455.601578 -210.754214) (xy 455.601578 -219.61602)
			(xy 455.60234 -219.623894) (xy 455.60234 -219.624402) (xy 455.603864 -219.631006) (xy 455.610468 -219.652088)
			(xy 455.612754 -219.655644) (xy 455.618239 -219.664035) (xy 455.628405 -219.681317) (xy 455.633074 -219.690188)
			(xy 455.643711 -219.71153) (xy 455.660018 -219.75634) (xy 455.670426 -219.802875) (xy 455.672952 -219.826586)
			(xy 455.674476 -219.853002) (xy 455.674476 -219.860114) (xy 455.67399 -219.887295) (xy 455.666002 -219.941068)
			(xy 455.650203 -219.993084) (xy 455.626935 -220.042216) (xy 455.612246 -220.065092) (xy 455.609198 -220.072204)
			(xy 455.604118 -220.08846) (xy 455.603864 -220.089222) (xy 455.602808 -220.092879) (xy 455.601655 -220.100403)
			(xy 455.601578 -220.104208) (xy 455.601578 -228.966014) (xy 455.60234 -228.973888) (xy 455.60234 -228.974396)
			(xy 455.603864 -228.981) (xy 455.610468 -229.002082) (xy 455.612754 -229.005638) (xy 455.618239 -229.014029)
			(xy 455.628405 -229.031311) (xy 455.633074 -229.040182) (xy 455.643705 -229.061525) (xy 455.660001 -229.106337)
			(xy 455.670398 -229.152873) (xy 455.672952 -229.17658) (xy 455.674476 -229.202996) (xy 455.674476 -229.210108)
			(xy 455.67399 -229.237289) (xy 455.666004 -229.291063) (xy 455.650205 -229.343079) (xy 455.626938 -229.392211)
			(xy 455.612246 -229.415086) (xy 455.609198 -229.422198) (xy 455.604118 -229.438454) (xy 455.603864 -229.439216)
			(xy 455.602807 -229.442873) (xy 455.601653 -229.450397) (xy 455.601578 -229.454202) (xy 455.601578 -238.316008)
			(xy 455.60234 -238.323882) (xy 455.60234 -238.32439) (xy 455.603864 -238.330994) (xy 455.610468 -238.352076)
			(xy 455.612754 -238.355632) (xy 455.618239 -238.364023) (xy 455.628405 -238.381304) (xy 455.633074 -238.390176)
			(xy 455.643706 -238.411519) (xy 455.660002 -238.456331) (xy 455.670399 -238.502866) (xy 455.672952 -238.526574)
			(xy 455.674476 -238.55299) (xy 455.674476 -238.560102) (xy 455.673991 -238.587284) (xy 455.666005 -238.641057)
			(xy 455.650207 -238.693074) (xy 455.62694 -238.742207) (xy 455.612246 -238.76508) (xy 455.609198 -238.772192)
			(xy 455.604118 -238.788448) (xy 455.603864 -238.78921) (xy 455.602814 -238.792868) (xy 455.601674 -238.800391)
			(xy 455.601578 -238.804196) (xy 455.601578 -275.715984) (xy 455.60234 -275.723858) (xy 455.60234 -275.724366)
			(xy 455.603864 -275.73097) (xy 455.610468 -275.752052) (xy 455.612754 -275.755608) (xy 455.61824 -275.763999)
			(xy 455.628407 -275.78128) (xy 455.633074 -275.790152) (xy 455.643707 -275.811495) (xy 455.660006 -275.856306)
			(xy 455.670407 -275.902841) (xy 455.672952 -275.92655) (xy 455.674476 -275.952966) (xy 455.674476 -275.960078)
			(xy 455.673992 -275.98726) (xy 455.66601 -276.041035) (xy 455.650215 -276.093054) (xy 455.62695 -276.142189)
			(xy 455.612246 -276.165056) (xy 455.609198 -276.172168) (xy 455.604118 -276.188424) (xy 455.603864 -276.189186)
			(xy 455.602812 -276.192844) (xy 455.601668 -276.200367) (xy 455.601578 -276.204172) (xy 455.601578 -285.065978)
			(xy 455.60234 -285.073852) (xy 455.60234 -285.07436) (xy 455.603864 -285.080964) (xy 455.610468 -285.102046)
			(xy 455.612754 -285.105602) (xy 455.618238 -285.113994) (xy 455.628401 -285.131277) (xy 455.633074 -285.140146)
			(xy 455.643707 -285.161489) (xy 455.660007 -285.2063) (xy 455.670409 -285.252835) (xy 455.672952 -285.276544)
			(xy 455.674476 -285.30296) (xy 455.674476 -285.310072) (xy 455.673993 -285.337254) (xy 455.666011 -285.39103)
			(xy 455.650217 -285.443049) (xy 455.626953 -285.492185) (xy 455.612246 -285.51505) (xy 455.609198 -285.522162)
			(xy 455.604118 -285.538418) (xy 455.603864 -285.53918) (xy 455.602812 -285.542837) (xy 455.601667 -285.550361)
			(xy 455.601578 -285.554166) (xy 455.601578 -294.415972) (xy 455.60234 -294.423846) (xy 455.60234 -294.424354)
			(xy 455.603864 -294.430958) (xy 455.610468 -294.45204) (xy 455.612754 -294.455596) (xy 455.618238 -294.463988)
			(xy 455.628402 -294.48127) (xy 455.633074 -294.49014) (xy 455.643708 -294.511482) (xy 455.660008 -294.556294)
			(xy 455.67041 -294.602829) (xy 455.672952 -294.626538) (xy 455.674476 -294.652954) (xy 455.674476 -294.660066)
			(xy 455.673993 -294.687248) (xy 455.666012 -294.741024) (xy 455.650219 -294.793044) (xy 455.626955 -294.84218)
			(xy 455.612246 -294.865044) (xy 455.609198 -294.872156) (xy 455.604118 -294.888412) (xy 455.603864 -294.889174)
			(xy 455.602812 -294.892831) (xy 455.601666 -294.900355) (xy 455.601578 -294.90416) (xy 455.601578 -303.765966)
			(xy 455.60234 -303.77384) (xy 455.60234 -303.774348) (xy 455.603864 -303.780952) (xy 455.610468 -303.802034)
			(xy 455.612754 -303.80559) (xy 455.618238 -303.813982) (xy 455.628402 -303.831264) (xy 455.633074 -303.840134)
			(xy 455.643708 -303.861476) (xy 455.66001 -303.906287) (xy 455.670412 -303.952823) (xy 455.672952 -303.976532)
			(xy 455.674476 -304.002948) (xy 455.674476 -304.01006) (xy 455.673994 -304.037243) (xy 455.666014 -304.091019)
			(xy 455.650221 -304.143039) (xy 455.626958 -304.192176) (xy 455.612246 -304.215038) (xy 455.609198 -304.22215)
			(xy 455.604118 -304.238406) (xy 455.603864 -304.239168) (xy 455.602811 -304.242825) (xy 455.601664 -304.250349)
			(xy 455.601578 -304.254154) (xy 455.601578 -313.11596) (xy 455.60234 -313.123834) (xy 455.60234 -313.124342)
			(xy 455.603864 -313.130946) (xy 455.610468 -313.152028) (xy 455.612754 -313.155584) (xy 455.618238 -313.163976)
			(xy 455.628402 -313.181258) (xy 455.633074 -313.190128) (xy 455.643708 -313.21147) (xy 455.660011 -313.256281)
			(xy 455.670414 -313.302816) (xy 455.672952 -313.326526) (xy 455.674476 -313.352942) (xy 455.674476 -313.360054)
			(xy 455.673994 -313.387237) (xy 455.666015 -313.441013) (xy 455.650223 -313.493034) (xy 455.62696 -313.542171)
			(xy 455.612246 -313.565032) (xy 455.609198 -313.572144) (xy 455.604118 -313.5884) (xy 455.603864 -313.589162)
			(xy 455.602811 -313.592819) (xy 455.601663 -313.600343) (xy 455.601578 -313.604148) (xy 455.601578 -320.383154)
			(xy 455.601144 -320.393219) (xy 455.593414 -320.411808) (xy 455.586592 -320.419222) (xy 453.84085 -322.164964)
			(xy 453.83345 -322.171806) (xy 453.814852 -322.179528) (xy 453.804782 -322.17995) (xy 445.156844 -322.17995)
			(xy 445.150834 -322.180117) (xy 445.139151 -322.18294) (xy 445.13373 -322.185538) (xy 445.130255 -322.187376)
			(xy 445.123874 -322.191968) (xy 445.12103 -322.194682) (xy 445.117982 -322.19773) (xy 445.09944 -322.20535)
			(xy 445.084962 -322.20535) (xy 443.832742 -323.45757) (xy 443.826276 -323.464623) (xy 443.818705 -323.482179)
			(xy 443.818145 -323.50129) (xy 443.821058 -323.510402) (xy 443.822074 -323.512942) (xy 443.825211 -323.519783)
			(xy 443.834763 -323.531404) (xy 443.84087 -323.535802) (xy 443.841886 -323.536564) (xy 443.844172 -323.538088)
			(xy 443.846966 -323.539866) (xy 443.854078 -323.541898) (xy 443.857674 -323.542931) (xy 443.865069 -323.544074)
			(xy 443.86881 -323.544184) (xy 445.470534 -323.544184) (xy 445.515008 -323.544684) (xy 445.603598 -323.55266)
			(xy 445.691117 -323.568545) (xy 445.776859 -323.592211) (xy 445.860135 -323.623468) (xy 445.940274 -323.662063)
			(xy 446.016631 -323.707686) (xy 446.08859 -323.75997) (xy 446.155574 -323.818494) (xy 446.217042 -323.882787)
			(xy 446.272499 -323.95233) (xy 446.3215 -324.026565) (xy 446.363649 -324.104893) (xy 446.398607 -324.186684)
			(xy 446.426093 -324.271279) (xy 446.445885 -324.357998) (xy 446.457825 -324.446141) (xy 446.461816 -324.535)
			(xy 446.457825 -324.623859) (xy 446.445885 -324.712002) (xy 446.426093 -324.798721) (xy 446.398607 -324.883316)
			(xy 446.363649 -324.965107) (xy 446.3215 -325.043435) (xy 446.272499 -325.11767) (xy 446.230131 -325.1708)
			(xy 448.982592 -325.1708) (xy 448.983145 -325.137599) (xy 448.991799 -325.071764) (xy 449.008948 -325.007616)
			(xy 449.034299 -324.946244) (xy 449.067421 -324.888694) (xy 449.107751 -324.835943) (xy 449.154603 -324.78889)
			(xy 449.20718 -324.748334) (xy 449.264588 -324.714965) (xy 449.295012 -324.701662) (xy 449.304423 -324.697122)
			(xy 449.318916 -324.682109) (xy 449.326261 -324.662577) (xy 449.326254 -324.652132) (xy 449.325492 -324.62724)
			(xy 449.325975 -324.596509) (xy 449.333379 -324.535494) (xy 449.348084 -324.475816) (xy 449.369876 -324.418347)
			(xy 449.398436 -324.363923) (xy 449.433348 -324.313338) (xy 449.474103 -324.267331) (xy 449.520107 -324.226573)
			(xy 449.570689 -324.191656) (xy 449.62511 -324.163092) (xy 449.682578 -324.141296) (xy 449.742254 -324.126586)
			(xy 449.803269 -324.119178) (xy 449.834 -324.118732) (xy 449.864244 -324.119176) (xy 449.924301 -324.126386)
			(xy 449.983079 -324.14067) (xy 450.039748 -324.161825) (xy 450.093507 -324.189552) (xy 450.143598 -324.223461)
			(xy 450.16674 -324.242938) (xy 450.176561 -324.250585) (xy 450.200789 -324.256176) (xy 450.212968 -324.253606)
			(xy 450.294248 -324.23227) (xy 450.305946 -324.228398) (xy 450.324123 -324.211816) (xy 450.329046 -324.20052)
			(xy 450.329046 -324.200266) (xy 450.344169 -324.159582) (xy 450.380532 -324.080765) (xy 450.42365 -324.005431)
			(xy 450.473193 -323.934156) (xy 450.52878 -323.867489) (xy 450.589985 -323.805939) (xy 450.656339 -323.749979)
			(xy 450.727334 -323.700037) (xy 450.802426 -323.656497) (xy 450.881038 -323.619691) (xy 450.962568 -323.589903)
			(xy 451.046391 -323.567361) (xy 451.131864 -323.552237) (xy 451.218333 -323.544647) (xy 451.261734 -323.544184)
			(xy 453.014334 -323.544184) (xy 453.058812 -323.544608) (xy 453.147409 -323.552585) (xy 453.234934 -323.568471)
			(xy 453.320683 -323.592139) (xy 453.403965 -323.623398) (xy 453.48411 -323.661996) (xy 453.560472 -323.707623)
			(xy 453.632438 -323.759911) (xy 453.699426 -323.818439) (xy 453.760899 -323.882737) (xy 453.816361 -323.952286)
			(xy 453.861483 -324.020645) (xy 455.259942 -324.020645) (xy 455.259942 -323.956723) (xy 455.267953 -323.893305)
			(xy 455.28385 -323.831391) (xy 455.307382 -323.771958) (xy 455.338176 -323.715943) (xy 455.375749 -323.664228)
			(xy 455.419506 -323.617631) (xy 455.468759 -323.576886) (xy 455.52273 -323.542635) (xy 455.580569 -323.515418)
			(xy 455.641362 -323.495665) (xy 455.704152 -323.483687) (xy 455.767948 -323.479674) (xy 455.831744 -323.483687)
			(xy 455.894534 -323.495665) (xy 455.955327 -323.515418) (xy 456.013166 -323.542635) (xy 456.067137 -323.576886)
			(xy 456.11639 -323.617631) (xy 456.160147 -323.664228) (xy 456.19772 -323.715943) (xy 456.228514 -323.771958)
			(xy 456.252046 -323.831391) (xy 456.267943 -323.893305) (xy 456.275954 -323.956723) (xy 456.276456 -323.988684)
			(xy 456.275954 -324.020645) (xy 456.267943 -324.084063) (xy 456.252046 -324.145977) (xy 456.228514 -324.20541)
			(xy 456.19772 -324.261425) (xy 456.160147 -324.31314) (xy 456.11639 -324.359737) (xy 456.067137 -324.400482)
			(xy 456.013166 -324.434733) (xy 455.955327 -324.46195) (xy 455.894534 -324.481703) (xy 455.831744 -324.493681)
			(xy 455.767948 -324.497695) (xy 455.704152 -324.493681) (xy 455.641362 -324.481703) (xy 455.580569 -324.46195)
			(xy 455.52273 -324.434733) (xy 455.468759 -324.400482) (xy 455.419506 -324.359737) (xy 455.375749 -324.31314)
			(xy 455.338176 -324.261425) (xy 455.307382 -324.20541) (xy 455.28385 -324.145977) (xy 455.267953 -324.084063)
			(xy 455.259942 -324.020645) (xy 453.861483 -324.020645) (xy 453.865365 -324.026526) (xy 453.907517 -324.10486)
			(xy 453.942478 -324.186657) (xy 453.969966 -324.271259) (xy 453.98976 -324.357984) (xy 454.001701 -324.446134)
			(xy 454.005692 -324.535) (xy 454.001701 -324.623866) (xy 453.98976 -324.712016) (xy 453.969966 -324.798741)
			(xy 453.942478 -324.883343) (xy 453.907517 -324.96514) (xy 453.865365 -325.043474) (xy 453.816361 -325.117714)
			(xy 453.760899 -325.187263) (xy 453.699426 -325.251561) (xy 453.632438 -325.310089) (xy 453.560472 -325.362377)
			(xy 453.48411 -325.408004) (xy 453.403965 -325.446602) (xy 453.320683 -325.477861) (xy 453.234934 -325.501529)
			(xy 453.147409 -325.517415) (xy 453.058812 -325.525392) (xy 453.014334 -325.525892) (xy 451.261734 -325.525892)
			(xy 451.21642 -325.525419) (xy 451.126171 -325.517154) (xy 451.037053 -325.500681) (xy 450.949813 -325.476138)
			(xy 450.865179 -325.443729) (xy 450.783858 -325.403726) (xy 450.706531 -325.356463) (xy 450.633843 -325.302335)
			(xy 450.566403 -325.241795) (xy 450.504774 -325.175348) (xy 450.449472 -325.103551) (xy 450.400958 -325.027002)
			(xy 450.379846 -324.986904) (xy 450.374004 -324.975728) (xy 450.35343 -324.96125) (xy 450.245226 -324.947534)
			(xy 450.221858 -324.95617) (xy 450.213476 -324.965568) (xy 450.194295 -324.986517) (xy 450.15201 -325.024443)
			(xy 450.105765 -325.057425) (xy 450.056136 -325.085052) (xy 450.030088 -325.096378) (xy 450.02066 -325.100888)
			(xy 450.006167 -325.115913) (xy 449.998832 -325.135458) (xy 449.998846 -325.145908) (xy 449.999608 -325.1708)
			(xy 449.999106 -325.202761) (xy 449.991095 -325.266179) (xy 449.975198 -325.328093) (xy 449.951666 -325.387526)
			(xy 449.920872 -325.443541) (xy 449.883299 -325.495256) (xy 449.839542 -325.541853) (xy 449.797787 -325.576395)
			(xy 459.619598 -325.576395) (xy 459.619598 -325.512473) (xy 459.627609 -325.449055) (xy 459.643506 -325.387141)
			(xy 459.667038 -325.327708) (xy 459.697832 -325.271693) (xy 459.735405 -325.219978) (xy 459.779162 -325.173381)
			(xy 459.828415 -325.132636) (xy 459.882386 -325.098385) (xy 459.940225 -325.071168) (xy 460.001018 -325.051415)
			(xy 460.063808 -325.039437) (xy 460.127604 -325.035424) (xy 460.1914 -325.039437) (xy 460.25419 -325.051415)
			(xy 460.314983 -325.071168) (xy 460.372822 -325.098385) (xy 460.426793 -325.132636) (xy 460.476046 -325.173381)
			(xy 460.519803 -325.219978) (xy 460.557376 -325.271693) (xy 460.58817 -325.327708) (xy 460.611702 -325.387141)
			(xy 460.627599 -325.449055) (xy 460.63561 -325.512473) (xy 460.636112 -325.544434) (xy 460.63561 -325.576395)
			(xy 460.627599 -325.639813) (xy 460.611702 -325.701727) (xy 460.58817 -325.76116) (xy 460.557376 -325.817175)
			(xy 460.519803 -325.86889) (xy 460.476046 -325.915487) (xy 460.426793 -325.956232) (xy 460.372822 -325.990483)
			(xy 460.314983 -326.0177) (xy 460.25419 -326.037453) (xy 460.1914 -326.049431) (xy 460.127604 -326.053445)
			(xy 460.063808 -326.049431) (xy 460.001018 -326.037453) (xy 459.940225 -326.0177) (xy 459.882386 -325.990483)
			(xy 459.828415 -325.956232) (xy 459.779162 -325.915487) (xy 459.735405 -325.86889) (xy 459.697832 -325.817175)
			(xy 459.667038 -325.76116) (xy 459.643506 -325.701727) (xy 459.627609 -325.639813) (xy 459.619598 -325.576395)
			(xy 449.797787 -325.576395) (xy 449.790289 -325.582598) (xy 449.736318 -325.616849) (xy 449.678479 -325.644066)
			(xy 449.617686 -325.663819) (xy 449.554896 -325.675797) (xy 449.4911 -325.679811) (xy 449.427304 -325.675797)
			(xy 449.364514 -325.663819) (xy 449.303721 -325.644066) (xy 449.245882 -325.616849) (xy 449.191911 -325.582598)
			(xy 449.142658 -325.541853) (xy 449.098901 -325.495256) (xy 449.061328 -325.443541) (xy 449.030534 -325.387526)
			(xy 449.007002 -325.328093) (xy 448.991105 -325.266179) (xy 448.983094 -325.202761) (xy 448.982592 -325.1708)
			(xy 446.230131 -325.1708) (xy 446.217042 -325.187213) (xy 446.155574 -325.251506) (xy 446.08859 -325.31003)
			(xy 446.016631 -325.362314) (xy 445.940274 -325.407937) (xy 445.860135 -325.446532) (xy 445.776859 -325.477789)
			(xy 445.691117 -325.501455) (xy 445.603598 -325.51734) (xy 445.515008 -325.525316) (xy 445.470534 -325.525892)
			(xy 443.700916 -325.525892) (xy 443.657097 -325.524653) (xy 443.569918 -325.515408) (xy 443.483895 -325.4985)
			(xy 443.399702 -325.474063) (xy 443.317996 -325.442286) (xy 443.239414 -325.403419) (xy 443.164572 -325.357764)
			(xy 443.094054 -325.305679) (xy 443.028411 -325.24757) (xy 442.968155 -325.183891) (xy 442.913758 -325.115141)
			(xy 442.865644 -325.041855) (xy 442.82419 -324.964607) (xy 442.789719 -324.884001) (xy 442.762501 -324.800665)
			(xy 442.752226 -324.75805) (xy 442.750702 -324.751192) (xy 442.744352 -324.739254) (xy 442.742828 -324.73773)
			(xy 442.739272 -324.73392) (xy 442.734574 -324.729395) (xy 442.723387 -324.722697) (xy 442.717174 -324.720712)
			(xy 442.62802 -324.695058) (xy 442.61755 -324.693279) (xy 442.59678 -324.697631) (xy 442.587888 -324.70344)
			(xy 442.581538 -324.708774) (xy 441.663836 -325.626476) (xy 441.661129 -325.629326) (xy 441.656533 -325.635703)
			(xy 441.654692 -325.639176) (xy 441.652113 -325.644604) (xy 441.649297 -325.656283) (xy 441.649104 -325.66229)
			(xy 441.649104 -329.552257) (xy 446.51904 -329.552257) (xy 446.51904 -329.488335) (xy 446.527051 -329.424917)
			(xy 446.542948 -329.363003) (xy 446.56648 -329.30357) (xy 446.597274 -329.247555) (xy 446.634847 -329.19584)
			(xy 446.678604 -329.149243) (xy 446.727857 -329.108498) (xy 446.781828 -329.074247) (xy 446.839667 -329.04703)
			(xy 446.90046 -329.027277) (xy 446.96325 -329.015299) (xy 447.027046 -329.011286) (xy 447.090842 -329.015299)
			(xy 447.153632 -329.027277) (xy 447.214425 -329.04703) (xy 447.272264 -329.074247) (xy 447.326235 -329.108498)
			(xy 447.375488 -329.149243) (xy 447.419245 -329.19584) (xy 447.456818 -329.247555) (xy 447.487612 -329.30357)
			(xy 447.511144 -329.363003) (xy 447.527041 -329.424917) (xy 447.535052 -329.488335) (xy 447.535554 -329.520296)
			(xy 447.535052 -329.552257) (xy 447.527041 -329.615675) (xy 447.511144 -329.677589) (xy 447.487612 -329.737022)
			(xy 447.456818 -329.793037) (xy 447.419245 -329.844752) (xy 447.375488 -329.891349) (xy 447.326235 -329.932094)
			(xy 447.272264 -329.966345) (xy 447.214425 -329.993562) (xy 447.153632 -330.013315) (xy 447.090842 -330.025293)
			(xy 447.027046 -330.029307) (xy 446.96325 -330.025293) (xy 446.90046 -330.013315) (xy 446.839667 -329.993562)
			(xy 446.781828 -329.966345) (xy 446.727857 -329.932094) (xy 446.678604 -329.891349) (xy 446.634847 -329.844752)
			(xy 446.597274 -329.793037) (xy 446.56648 -329.737022) (xy 446.542948 -329.677589) (xy 446.527051 -329.615675)
			(xy 446.51904 -329.552257) (xy 441.649104 -329.552257) (xy 441.649104 -345.822778) (xy 441.64962 -345.832678)
			(xy 441.657195 -345.850978) (xy 441.663836 -345.858338) (xy 445.190626 -349.385128) (xy 445.19469 -349.389446)
			(xy 445.265302 -349.460058) (xy 445.272103 -349.467406) (xy 445.279814 -349.485869) (xy 445.280288 -349.495872)
			(xy 445.280288 -350.010222) (xy 445.280766 -350.020188) (xy 445.288341 -350.038625) (xy 445.29502 -350.046036)
			(xy 445.304926 -350.055942) (xy 445.311774 -350.063339) (xy 445.319505 -350.081938) (xy 445.319912 -350.09201)
			(xy 445.319912 -365.06023) (xy 445.320928 -365.069628) (xy 445.320928 -365.070136) (xy 445.322121 -365.075365)
			(xy 445.32635 -365.085221) (xy 445.32931 -365.089694) (xy 445.334644 -365.096044) (xy 445.370204 -365.131604)
			(xy 445.37688 -365.139017) (xy 445.384466 -365.157448) (xy 445.384461 -365.177378) (xy 445.376866 -365.195804)
			(xy 445.370204 -365.203232) (xy 439.680909 -370.892281) (xy 447.615812 -370.892281) (xy 447.615812 -370.828359)
			(xy 447.623823 -370.764941) (xy 447.63972 -370.703027) (xy 447.663252 -370.643594) (xy 447.694046 -370.587579)
			(xy 447.731619 -370.535864) (xy 447.775376 -370.489267) (xy 447.824629 -370.448522) (xy 447.8786 -370.414271)
			(xy 447.936439 -370.387054) (xy 447.997232 -370.367301) (xy 448.060022 -370.355323) (xy 448.123818 -370.35131)
			(xy 448.187614 -370.355323) (xy 448.250404 -370.367301) (xy 448.311197 -370.387054) (xy 448.369036 -370.414271)
			(xy 448.423007 -370.448522) (xy 448.47226 -370.489267) (xy 448.516017 -370.535864) (xy 448.55359 -370.587579)
			(xy 448.584384 -370.643594) (xy 448.607916 -370.703027) (xy 448.623813 -370.764941) (xy 448.631824 -370.828359)
			(xy 448.632326 -370.86032) (xy 448.631824 -370.892281) (xy 448.623813 -370.955699) (xy 448.607916 -371.017613)
			(xy 448.584384 -371.077046) (xy 448.55359 -371.133061) (xy 448.516017 -371.184776) (xy 448.47226 -371.231373)
			(xy 448.423007 -371.272118) (xy 448.369036 -371.306369) (xy 448.311197 -371.333586) (xy 448.250404 -371.353339)
			(xy 448.187614 -371.365317) (xy 448.123818 -371.369331) (xy 448.060022 -371.365317) (xy 447.997232 -371.353339)
			(xy 447.936439 -371.333586) (xy 447.8786 -371.306369) (xy 447.824629 -371.272118) (xy 447.775376 -371.231373)
			(xy 447.731619 -371.184776) (xy 447.694046 -371.133061) (xy 447.663252 -371.077046) (xy 447.63972 -371.017613)
			(xy 447.623823 -370.955699) (xy 447.615812 -370.892281) (xy 439.680909 -370.892281) (xy 439.499502 -371.07368)
			(xy 439.492104 -371.080529) (xy 439.473506 -371.088267) (xy 439.463434 -371.088666) (xy 432.405028 -371.088666)
			(xy 432.396833 -371.08897) (xy 432.381279 -371.094143) (xy 432.374548 -371.098826) (xy 432.374294 -371.09908)
			(xy 432.360832 -371.118384) (xy 432.358675 -371.121574) (xy 432.35523 -371.12846) (xy 432.353974 -371.1321)
			(xy 432.343813 -371.162628) (xy 432.316849 -371.221045) (xy 432.282731 -371.275595) (xy 432.242004 -371.325405)
			(xy 432.195319 -371.36968) (xy 432.143422 -371.407711) (xy 432.087142 -371.438893) (xy 432.027378 -371.462725)
			(xy 431.965085 -371.478828) (xy 431.901258 -371.486945) (xy 431.836918 -371.486945) (xy 431.773091 -371.478828)
			(xy 431.710798 -371.462725) (xy 431.651034 -371.438893) (xy 431.594754 -371.407711) (xy 431.542857 -371.36968)
			(xy 431.496172 -371.325405) (xy 431.455445 -371.275595) (xy 431.421327 -371.221045) (xy 431.394363 -371.162628)
			(xy 431.384202 -371.1321) (xy 431.382963 -371.128453) (xy 431.379522 -371.121561) (xy 431.377344 -371.118384)
			(xy 431.363882 -371.09908) (xy 431.363628 -371.098826) (xy 431.356888 -371.094153) (xy 431.341343 -371.08896)
			(xy 431.333148 -371.088666) (xy 430.404524 -371.088666) (xy 430.398515 -371.088836) (xy 430.386835 -371.091663)
			(xy 430.38141 -371.094254) (xy 430.377936 -371.096094) (xy 430.371558 -371.100688) (xy 430.36871 -371.103398)
			(xy 430.130966 -371.341142) (xy 430.128261 -371.343993) (xy 430.12367 -371.350373) (xy 430.121822 -371.353842)
			(xy 430.119238 -371.359269) (xy 430.116413 -371.370948) (xy 430.116234 -371.376956) (xy 430.116234 -372.5139)
			(xy 430.894749 -372.5139) (xy 430.898763 -372.450102) (xy 430.910741 -372.38731) (xy 430.930493 -372.326515)
			(xy 430.957709 -372.268674) (xy 430.99196 -372.214701) (xy 431.032705 -372.165445) (xy 431.079302 -372.121684)
			(xy 431.131015 -372.084108) (xy 431.187031 -372.05331) (xy 431.246464 -372.029774) (xy 431.308379 -372.013873)
			(xy 431.371798 -372.005856) (xy 431.40376 -372.005352) (xy 431.438096 -372.00595) (xy 431.506143 -372.015187)
			(xy 431.572328 -372.033497) (xy 431.635447 -372.060548) (xy 431.694352 -372.095847) (xy 431.721514 -372.116858)
			(xy 431.728537 -372.122057) (xy 431.745038 -372.127769) (xy 431.753772 -372.128034) (xy 431.783744 -372.12778)
			(xy 431.792474 -372.127308) (xy 431.808841 -372.121201) (xy 431.815748 -372.115842) (xy 431.838681 -372.097168)
			(xy 431.888097 -372.064671) (xy 431.940951 -372.038131) (xy 431.996528 -372.017905) (xy 432.054077 -372.004266)
			(xy 432.11282 -371.9974) (xy 432.142392 -371.99697) (xy 432.17257 -371.997388) (xy 432.232502 -372.004528)
			(xy 432.291169 -372.01871) (xy 432.347745 -372.039733) (xy 432.401436 -372.067303) (xy 432.451488 -372.101032)
			(xy 432.474624 -372.120414) (xy 432.48453 -372.12905) (xy 432.510184 -372.134384) (xy 432.605688 -372.104158)
			(xy 432.613717 -372.101208) (xy 432.627381 -372.090937) (xy 432.636951 -372.076772) (xy 432.63947 -372.068598)
			(xy 432.63947 -372.06809) (xy 432.647425 -372.038538) (xy 432.669413 -371.981425) (xy 432.698098 -371.927364)
			(xy 432.733065 -371.877137) (xy 432.773808 -371.831471) (xy 432.819738 -371.791025) (xy 432.870191 -371.756385)
			(xy 432.924437 -371.728052) (xy 432.981691 -371.706435) (xy 433.041127 -371.691847) (xy 433.101884 -371.684499)
			(xy 433.132484 -371.684042) (xy 433.16445 -371.684422) (xy 433.227879 -371.692433) (xy 433.289803 -371.708331)
			(xy 433.349246 -371.731864) (xy 433.405271 -371.762663) (xy 433.456994 -371.80024) (xy 433.503599 -371.844004)
			(xy 433.544352 -371.893264) (xy 433.578609 -371.947244) (xy 433.605831 -372.005091) (xy 433.625587 -372.065894)
			(xy 433.637567 -372.128694) (xy 433.641582 -372.1925) (xy 433.637567 -372.256306) (xy 433.625587 -372.319106)
			(xy 433.605831 -372.379909) (xy 433.578609 -372.437756) (xy 433.544352 -372.491736) (xy 433.503599 -372.540996)
			(xy 433.456994 -372.58476) (xy 433.405271 -372.622337) (xy 433.349246 -372.653136) (xy 433.289803 -372.676669)
			(xy 433.227879 -372.692567) (xy 433.16445 -372.700578) (xy 433.132484 -372.701058) (xy 433.102307 -372.700612)
			(xy 433.042375 -372.69348) (xy 432.983708 -372.679305) (xy 432.927132 -372.658287) (xy 432.87344 -372.630721)
			(xy 432.823388 -372.596994) (xy 432.800252 -372.577614) (xy 432.790346 -372.568978) (xy 432.764692 -372.563644)
			(xy 432.669188 -372.59387) (xy 432.661147 -372.596792) (xy 432.647485 -372.607076) (xy 432.637921 -372.621252)
			(xy 432.635406 -372.62943) (xy 432.635406 -372.629938) (xy 432.627492 -372.659501) (xy 432.605499 -372.716616)
			(xy 432.57681 -372.770677) (xy 432.541838 -372.820904) (xy 432.501091 -372.86657) (xy 432.455157 -372.907014)
			(xy 432.415556 -372.9342) (xy 435.971019 -372.9342) (xy 435.975032 -372.870412) (xy 435.987008 -372.807629)
			(xy 436.006757 -372.746843) (xy 436.033969 -372.689011) (xy 436.068214 -372.635045) (xy 436.108953 -372.585796)
			(xy 436.155542 -372.542042) (xy 436.207248 -372.504471) (xy 436.263254 -372.473676) (xy 436.322678 -372.450143)
			(xy 436.384583 -372.434243) (xy 436.447993 -372.426227) (xy 436.47995 -372.425722) (xy 436.513587 -372.426307)
			(xy 436.580276 -372.435167) (xy 436.645214 -372.45274) (xy 436.70727 -372.478718) (xy 436.765361 -372.512649)
			(xy 436.818473 -372.553941) (xy 436.865678 -372.601873) (xy 436.88635 -372.628414) (xy 436.894232 -372.637666)
			(xy 436.916112 -372.648154) (xy 436.92826 -372.64848) (xy 437.023256 -372.646194) (xy 437.044592 -372.63451)
			(xy 437.051704 -372.62435) (xy 437.069447 -372.598882) (xy 437.11019 -372.552055) (xy 437.156335 -372.51054)
			(xy 437.207193 -372.474956) (xy 437.262007 -372.445831) (xy 437.319961 -372.423601) (xy 437.380191 -372.408595)
			(xy 437.4418 -372.401039) (xy 437.472836 -372.400576) (xy 437.503567 -372.401022) (xy 437.564581 -372.408434)
			(xy 437.624257 -372.423146) (xy 437.681724 -372.444944) (xy 437.736145 -372.473509) (xy 437.786726 -372.508425)
			(xy 437.822629 -372.540233) (xy 450.515222 -372.540233) (xy 450.515222 -372.476311) (xy 450.523233 -372.412893)
			(xy 450.53913 -372.350979) (xy 450.562662 -372.291546) (xy 450.593456 -372.235531) (xy 450.631029 -372.183816)
			(xy 450.674786 -372.137219) (xy 450.724039 -372.096474) (xy 450.77801 -372.062223) (xy 450.835849 -372.035006)
			(xy 450.896642 -372.015253) (xy 450.959432 -372.003275) (xy 451.023228 -371.999262) (xy 451.087024 -372.003275)
			(xy 451.149814 -372.015253) (xy 451.210607 -372.035006) (xy 451.268446 -372.062223) (xy 451.322417 -372.096474)
			(xy 451.37167 -372.137219) (xy 451.415427 -372.183816) (xy 451.453 -372.235531) (xy 451.483794 -372.291546)
			(xy 451.507326 -372.350979) (xy 451.523223 -372.412893) (xy 451.531234 -372.476311) (xy 451.531736 -372.508272)
			(xy 451.531234 -372.540233) (xy 451.523223 -372.603651) (xy 451.507326 -372.665565) (xy 451.483794 -372.724998)
			(xy 451.453 -372.781013) (xy 451.415427 -372.832728) (xy 451.37167 -372.879325) (xy 451.322417 -372.92007)
			(xy 451.268446 -372.954321) (xy 451.210607 -372.981538) (xy 451.149814 -373.001291) (xy 451.087024 -373.013269)
			(xy 451.023228 -373.017283) (xy 450.959432 -373.013269) (xy 450.896642 -373.001291) (xy 450.835849 -372.981538)
			(xy 450.77801 -372.954321) (xy 450.724039 -372.92007) (xy 450.674786 -372.879325) (xy 450.631029 -372.832728)
			(xy 450.593456 -372.781013) (xy 450.562662 -372.724998) (xy 450.53913 -372.665565) (xy 450.523233 -372.603651)
			(xy 450.515222 -372.540233) (xy 437.822629 -372.540233) (xy 437.832731 -372.549183) (xy 437.873487 -372.595189)
			(xy 437.908401 -372.645772) (xy 437.936964 -372.700194) (xy 437.95876 -372.757663) (xy 437.97347 -372.817339)
			(xy 437.980879 -372.878353) (xy 437.981344 -372.909084) (xy 437.980822 -372.940396) (xy 437.973124 -373.002546)
			(xy 437.957855 -373.063281) (xy 437.935246 -373.121683) (xy 437.905639 -373.176867) (xy 437.869481 -373.227999)
			(xy 437.848756 -373.251476) (xy 437.842764 -373.25876) (xy 437.83599 -373.276345) (xy 437.835548 -373.285766)
			(xy 437.835802 -373.316754) (xy 437.836218 -373.326216) (xy 437.84312 -373.343837) (xy 437.849264 -373.351044)
			(xy 437.870452 -373.374575) (xy 437.907372 -373.426022) (xy 437.937615 -373.481656) (xy 437.960715 -373.540616)
			(xy 437.976313 -373.601988) (xy 437.984168 -373.664822) (xy 437.984646 -373.696484) (xy 437.984144 -373.728445)
			(xy 437.976133 -373.791863) (xy 437.960236 -373.853777) (xy 437.936704 -373.91321) (xy 437.90591 -373.969225)
			(xy 437.868337 -374.02094) (xy 437.82458 -374.067537) (xy 437.775327 -374.108282) (xy 437.721356 -374.142533)
			(xy 437.663517 -374.16975) (xy 437.602724 -374.189503) (xy 437.539934 -374.201481) (xy 437.476138 -374.205495)
			(xy 437.412342 -374.201481) (xy 437.349552 -374.189503) (xy 437.288759 -374.16975) (xy 437.23092 -374.142533)
			(xy 437.176949 -374.108282) (xy 437.127696 -374.067537) (xy 437.083939 -374.02094) (xy 437.046366 -373.969225)
			(xy 437.015572 -373.91321) (xy 436.99204 -373.853777) (xy 436.976143 -373.791863) (xy 436.968132 -373.728445)
			(xy 436.96763 -373.696484) (xy 436.968113 -373.66517) (xy 436.975816 -373.603018) (xy 436.991091 -373.542282)
			(xy 437.013708 -373.48388) (xy 437.043323 -373.428697) (xy 437.079488 -373.377567) (xy 437.100218 -373.354092)
			(xy 437.10622 -373.346815) (xy 437.11299 -373.329225) (xy 437.113426 -373.319802) (xy 437.113172 -373.288814)
			(xy 437.112778 -373.279349) (xy 437.105861 -373.261728) (xy 437.09971 -373.254524) (xy 437.09095 -373.244997)
			(xy 437.074307 -373.225173) (xy 437.066436 -373.2149) (xy 437.058558 -373.205644) (xy 437.036675 -373.195157)
			(xy 437.024526 -373.194834) (xy 436.92953 -373.19712) (xy 436.908194 -373.208804) (xy 436.901082 -373.218964)
			(xy 436.883321 -373.244419) (xy 436.842582 -373.291249) (xy 436.796442 -373.332767) (xy 436.745587 -373.368355)
			(xy 436.690775 -373.397482) (xy 436.632823 -373.419714) (xy 436.572594 -373.43472) (xy 436.510985 -373.442276)
			(xy 436.47995 -373.442738) (xy 436.447993 -373.442173) (xy 436.384583 -373.434157) (xy 436.322678 -373.418257)
			(xy 436.263254 -373.394724) (xy 436.207248 -373.363929) (xy 436.155542 -373.326358) (xy 436.108953 -373.282604)
			(xy 436.068214 -373.233355) (xy 436.033969 -373.179389) (xy 436.006757 -373.121557) (xy 435.987008 -373.060771)
			(xy 435.975032 -372.997988) (xy 435.971019 -372.9342) (xy 432.415556 -372.9342) (xy 432.4047 -372.941653)
			(xy 432.35045 -372.969984) (xy 432.293192 -372.991599) (xy 432.233753 -373.006185) (xy 432.172993 -373.01353)
			(xy 432.142392 -373.013986) (xy 432.108055 -373.013428) (xy 432.040005 -373.004184) (xy 431.973819 -372.985865)
			(xy 431.910701 -372.958805) (xy 431.851798 -372.923496) (xy 431.824638 -372.90248) (xy 431.817606 -372.897296)
			(xy 431.801112 -372.891576) (xy 431.79238 -372.891304) (xy 431.762408 -372.891558) (xy 431.753678 -372.89202)
			(xy 431.737311 -372.898135) (xy 431.730404 -372.903496) (xy 431.707481 -372.922183) (xy 431.658064 -372.95468)
			(xy 431.605208 -372.98122) (xy 431.549629 -373.001444) (xy 431.492077 -373.015079) (xy 431.433332 -373.02194)
			(xy 431.40376 -373.022368) (xy 431.371798 -373.021944) (xy 431.308379 -373.013927) (xy 431.246464 -372.998026)
			(xy 431.187031 -372.97449) (xy 431.131015 -372.943692) (xy 431.079302 -372.906116) (xy 431.032705 -372.862355)
			(xy 430.99196 -372.813099) (xy 430.957709 -372.759126) (xy 430.930493 -372.701285) (xy 430.910741 -372.64049)
			(xy 430.898763 -372.577698) (xy 430.894749 -372.5139) (xy 430.116234 -372.5139) (xy 430.116234 -373.906796)
			(xy 430.116407 -373.912804) (xy 430.119242 -373.924481) (xy 430.121822 -373.92991) (xy 430.123662 -373.933384)
			(xy 430.128256 -373.939762) (xy 430.130966 -373.94261) (xy 430.502314 -374.313958) (xy 430.505165 -374.316664)
			(xy 430.511544 -374.321256) (xy 430.515014 -374.323102) (xy 430.52044 -374.325688) (xy 430.53212 -374.328518)
			(xy 430.538128 -374.32869) (xy 435.36997 -374.32869)
		)
		(stroke
			(width 0)
			(type solid)
		)
		(fill yes)
		(layer "In13.Cu")
		(net "P3V3_AUX")
	)
	(gr_line
		(start 47.79137 -385.31038)
		(end 48.144684 -385.405376)
		(stroke
			(width 0.07112)
			(type default)
		)
		(layer "In13.Cu")
	)
	(gr_line
		(start 48.144684 -385.405376)
		(end 48.145192 -385.404868)
		(stroke
			(width 0.07112)
			(type default)
		)
		(layer "In13.Cu")
	)
	(gr_line
		(start 48.19142 -386.003292)
		(end 48.286162 -385.649724)
		(stroke
			(width 0.07112)
			(type default)
		)
		(layer "In13.Cu")
	)
	(gr_line
		(start 48.25873 -382.58496)
		(end 48.25873 -382.553464)
		(stroke
			(width 0.07112)
			(type default)
		)
		(layer "In13.Cu")
	)
	(gr_line
		(start 48.25873 -382.553464)
		(end 48.252126 -382.524508)
		(stroke
			(width 0.07112)
			(type default)
		)
		(layer "In13.Cu")
	)
	(gr_line
		(start 48.407828 -385.579112)
		(end 48.46066 -385.548632)
		(stroke
			(width 0.07112)
			(type default)
		)
		(layer "In13.Cu")
	)
	(gr_line
		(start 48.46066 -385.548632)
		(end 48.548798 -385.460494)
		(stroke
			(width 0.07112)
			(type default)
		)
		(layer "In13.Cu")
	)
	(gr_arc
		(start 48.532796 -382.490726)
		(mid 48.530185 -382.476466)
		(end 48.527208 -382.462278)
		(stroke
			(width 0.07112)
			(type default)
		)
		(layer "In13.Cu")
	)
	(gr_arc
		(start 48.539654 -382.553464)
		(mid 48.5371 -382.521999)
		(end 48.532796 -382.490726)
		(stroke
			(width 0.07112)
			(type default)
		)
		(layer "In13.Cu")
	)
	(gr_arc
		(start 48.54067 -382.58496)
		(mid 48.54038 -382.569205)
		(end 48.539654 -382.553464)
		(stroke
			(width 0.07112)
			(type default)
		)
		(layer "In13.Cu")
	)
	(gr_line
		(start 48.548798 -385.460494)
		(end 48.548798 -385.334764)
		(stroke
			(width 0.07112)
			(type default)
		)
		(layer "In13.Cu")
	)
	(gr_line
		(start 48.991266 -385.31038)
		(end 49.34458 -385.405376)
		(stroke
			(width 0.07112)
			(type default)
		)
		(layer "In13.Cu")
	)
	(gr_line
		(start 49.34458 -385.405376)
		(end 49.345088 -385.404868)
		(stroke
			(width 0.07112)
			(type default)
		)
		(layer "In13.Cu")
	)
	(gr_line
		(start 49.391316 -386.003292)
		(end 49.486058 -385.649724)
		(stroke
			(width 0.07112)
			(type default)
		)
		(layer "In13.Cu")
	)
	(gr_line
		(start 49.607724 -385.579112)
		(end 49.660556 -385.548632)
		(stroke
			(width 0.07112)
			(type default)
		)
		(layer "In13.Cu")
	)
	(gr_line
		(start 49.660556 -385.548632)
		(end 49.748694 -385.460494)
		(stroke
			(width 0.07112)
			(type default)
		)
		(layer "In13.Cu")
	)
	(gr_arc
		(start 49.740566 -382.284986)
		(mid 49.740566 -382.284732)
		(end 49.740566 -382.284478)
		(stroke
			(width 0.07112)
			(type default)
		)
		(layer "In13.Cu")
	)
	(gr_line
		(start 49.748694 -385.460494)
		(end 49.748694 -385.334764)
		(stroke
			(width 0.07112)
			(type default)
		)
		(layer "In13.Cu")
	)
	(gr_line
		(start 50.191416 -385.31038)
		(end 50.544476 -385.405376)
		(stroke
			(width 0.07112)
			(type default)
		)
		(layer "In13.Cu")
	)
	(gr_line
		(start 50.415952 -411.225238)
		(end 50.415698 -411.225238)
		(stroke
			(width 0.07112)
			(type default)
		)
		(layer "In13.Cu")
	)
	(gr_line
		(start 50.544476 -385.405376)
		(end 50.544984 -385.404868)
		(stroke
			(width 0.07112)
			(type default)
		)
		(layer "In13.Cu")
	)
	(gr_line
		(start 50.591212 -386.003292)
		(end 50.685954 -385.649724)
		(stroke
			(width 0.07112)
			(type default)
		)
		(layer "In13.Cu")
	)
	(gr_line
		(start 50.658522 -382.474978)
		(end 50.658522 -382.47447)
		(stroke
			(width 0.07112)
			(type default)
		)
		(layer "In13.Cu")
	)
	(gr_arc
		(start 50.737262 -367.420398)
		(mid 50.736372 -367.421286)
		(end 50.735484 -367.422176)
		(stroke
			(width 0.07112)
			(type default)
		)
		(layer "In13.Cu")
	)
	(gr_line
		(start 50.80762 -385.579112)
		(end 50.860452 -385.548632)
		(stroke
			(width 0.07112)
			(type default)
		)
		(layer "In13.Cu")
	)
	(gr_line
		(start 50.860452 -385.548632)
		(end 50.94859 -385.460494)
		(stroke
			(width 0.07112)
			(type default)
		)
		(layer "In13.Cu")
	)
	(gr_line
		(start 50.94859 -385.460494)
		(end 50.94859 -385.334764)
		(stroke
			(width 0.07112)
			(type default)
		)
		(layer "In13.Cu")
	)
	(gr_line
		(start 50.985928 -414.833054)
		(end 50.79365 -414.833054)
		(stroke
			(width 0.07112)
			(type default)
		)
		(layer "In13.Cu")
	)
	(gr_line
		(start 51.059842 -415.499804)
		(end 50.592482 -415.032444)
		(stroke
			(width 0.07112)
			(type default)
		)
		(layer "In13.Cu")
	)
	(gr_line
		(start 51.148234 -409.208224)
		(end 51.148234 -408.507184)
		(stroke
			(width 0.07112)
			(type default)
		)
		(layer "In13.Cu")
	)
	(gr_line
		(start 51.148234 -408.080464)
		(end 51.148234 -407.379424)
		(stroke
			(width 0.07112)
			(type default)
		)
		(layer "In13.Cu")
	)
	(gr_line
		(start 51.259232 -415.298636)
		(end 51.259232 -415.106358)
		(stroke
			(width 0.07112)
			(type default)
		)
		(layer "In13.Cu")
	)
	(gr_line
		(start 51.259232 -415.106358)
		(end 50.985928 -414.833054)
		(stroke
			(width 0.07112)
			(type default)
		)
		(layer "In13.Cu")
	)
	(gr_line
		(start 51.391312 -385.31038)
		(end 51.744626 -385.405376)
		(stroke
			(width 0.07112)
			(type default)
		)
		(layer "In13.Cu")
	)
	(gr_line
		(start 51.431444 -409.206954)
		(end 51.567334 -409.071064)
		(stroke
			(width 0.07112)
			(type default)
		)
		(layer "In13.Cu")
	)
	(gr_line
		(start 51.431444 -408.079194)
		(end 51.567334 -407.943304)
		(stroke
			(width 0.07112)
			(type default)
		)
		(layer "In13.Cu")
	)
	(gr_line
		(start 51.567334 -409.071064)
		(end 51.567334 -408.644344)
		(stroke
			(width 0.07112)
			(type default)
		)
		(layer "In13.Cu")
	)
	(gr_line
		(start 51.567334 -408.644344)
		(end 51.431444 -408.508454)
		(stroke
			(width 0.07112)
			(type default)
		)
		(layer "In13.Cu")
	)
	(gr_line
		(start 51.567334 -407.943304)
		(end 51.567334 -407.516584)
		(stroke
			(width 0.07112)
			(type default)
		)
		(layer "In13.Cu")
	)
	(gr_line
		(start 51.567334 -407.516584)
		(end 51.431444 -407.380694)
		(stroke
			(width 0.07112)
			(type default)
		)
		(layer "In13.Cu")
	)
	(gr_line
		(start 51.726084 -415.57321)
		(end 51.533806 -415.57321)
		(stroke
			(width 0.07112)
			(type default)
		)
		(layer "In13.Cu")
	)
	(gr_line
		(start 51.744626 -385.405376)
		(end 51.745134 -385.404868)
		(stroke
			(width 0.07112)
			(type default)
		)
		(layer "In13.Cu")
	)
	(gr_line
		(start 51.791362 -386.003292)
		(end 51.886104 -385.649724)
		(stroke
			(width 0.07112)
			(type default)
		)
		(layer "In13.Cu")
	)
	(gr_line
		(start 51.8287 -416.268662)
		(end 51.332638 -415.7726)
		(stroke
			(width 0.07112)
			(type default)
		)
		(layer "In13.Cu")
	)
	(gr_line
		(start 52.00777 -385.579112)
		(end 52.060602 -385.548632)
		(stroke
			(width 0.07112)
			(type default)
		)
		(layer "In13.Cu")
	)
	(gr_line
		(start 52.02809 -416.067494)
		(end 52.02809 -415.875216)
		(stroke
			(width 0.07112)
			(type default)
		)
		(layer "In13.Cu")
	)
	(gr_line
		(start 52.02809 -415.875216)
		(end 51.726084 -415.57321)
		(stroke
			(width 0.07112)
			(type default)
		)
		(layer "In13.Cu")
	)
	(gr_line
		(start 52.060602 -385.548632)
		(end 52.14874 -385.460494)
		(stroke
			(width 0.07112)
			(type default)
		)
		(layer "In13.Cu")
	)
	(gr_arc
		(start 52.140612 -382.800352)
		(mid 52.140612 -382.800098)
		(end 52.140612 -382.799844)
		(stroke
			(width 0.07112)
			(type default)
		)
		(layer "In13.Cu")
	)
	(gr_line
		(start 52.14874 -385.460494)
		(end 52.14874 -385.334764)
		(stroke
			(width 0.07112)
			(type default)
		)
		(layer "In13.Cu")
	)
	(gr_line
		(start 52.52339 -416.37077)
		(end 52.331366 -416.37077)
		(stroke
			(width 0.07112)
			(type default)
		)
		(layer "In13.Cu")
	)
	(gr_line
		(start 52.591208 -385.31038)
		(end 52.944522 -385.405376)
		(stroke
			(width 0.07112)
			(type default)
		)
		(layer "In13.Cu")
	)
	(gr_line
		(start 52.626006 -417.065968)
		(end 52.130198 -416.57016)
		(stroke
			(width 0.07112)
			(type default)
		)
		(layer "In13.Cu")
	)
	(gr_line
		(start 52.825396 -416.8648)
		(end 52.825396 -416.672776)
		(stroke
			(width 0.07112)
			(type default)
		)
		(layer "In13.Cu")
	)
	(gr_line
		(start 52.825396 -416.672776)
		(end 52.52339 -416.37077)
		(stroke
			(width 0.07112)
			(type default)
		)
		(layer "In13.Cu")
	)
	(gr_line
		(start 52.944522 -385.405376)
		(end 52.94503 -385.404868)
		(stroke
			(width 0.07112)
			(type default)
		)
		(layer "In13.Cu")
	)
	(gr_line
		(start 52.991258 -386.003292)
		(end 53.086 -385.649724)
		(stroke
			(width 0.07112)
			(type default)
		)
		(layer "In13.Cu")
	)
	(gr_line
		(start 53.207666 -385.579112)
		(end 53.260498 -385.548632)
		(stroke
			(width 0.07112)
			(type default)
		)
		(layer "In13.Cu")
	)
	(gr_line
		(start 53.260498 -385.548632)
		(end 53.348636 -385.460494)
		(stroke
			(width 0.07112)
			(type default)
		)
		(layer "In13.Cu")
	)
	(gr_line
		(start 53.32095 -417.168076)
		(end 53.128672 -417.168076)
		(stroke
			(width 0.07112)
			(type default)
		)
		(layer "In13.Cu")
	)
	(gr_line
		(start 53.348636 -385.460494)
		(end 53.348636 -385.334764)
		(stroke
			(width 0.07112)
			(type default)
		)
		(layer "In13.Cu")
	)
	(gr_line
		(start 53.423566 -417.863528)
		(end 52.927504 -417.367466)
		(stroke
			(width 0.07112)
			(type default)
		)
		(layer "In13.Cu")
	)
	(gr_line
		(start 53.622956 -417.66236)
		(end 53.622956 -417.470082)
		(stroke
			(width 0.07112)
			(type default)
		)
		(layer "In13.Cu")
	)
	(gr_line
		(start 53.622956 -417.470082)
		(end 53.32095 -417.168076)
		(stroke
			(width 0.07112)
			(type default)
		)
		(layer "In13.Cu")
	)
	(gr_line
		(start 53.709316 -413.877252)
		(end 53.517038 -413.877252)
		(stroke
			(width 0.07112)
			(type default)
		)
		(layer "In13.Cu")
	)
	(gr_line
		(start 53.791358 -385.31038)
		(end 54.144672 -385.405376)
		(stroke
			(width 0.07112)
			(type default)
		)
		(layer "In13.Cu")
	)
	(gr_line
		(start 53.811932 -414.572704)
		(end 53.31587 -414.076642)
		(stroke
			(width 0.07112)
			(type default)
		)
		(layer "In13.Cu")
	)
	(gr_line
		(start 54.011322 -414.371536)
		(end 54.011322 -414.179258)
		(stroke
			(width 0.07112)
			(type default)
		)
		(layer "In13.Cu")
	)
	(gr_line
		(start 54.011322 -414.179258)
		(end 53.709316 -413.877252)
		(stroke
			(width 0.07112)
			(type default)
		)
		(layer "In13.Cu")
	)
	(gr_line
		(start 54.144672 -385.405376)
		(end 54.14518 -385.404868)
		(stroke
			(width 0.07112)
			(type default)
		)
		(layer "In13.Cu")
	)
	(gr_line
		(start 54.191408 -386.003292)
		(end 54.28615 -385.649724)
		(stroke
			(width 0.07112)
			(type default)
		)
		(layer "In13.Cu")
	)
	(gr_line
		(start 54.211474 -409.302458)
		(end 54.211474 -408.601418)
		(stroke
			(width 0.07112)
			(type default)
		)
		(layer "In13.Cu")
	)
	(gr_line
		(start 54.211474 -408.105102)
		(end 54.211474 -407.404062)
		(stroke
			(width 0.07112)
			(type default)
		)
		(layer "In13.Cu")
	)
	(gr_arc
		(start 54.282086 -382.482598)
		(mid 54.282213 -382.482217)
		(end 54.28234 -382.481836)
		(stroke
			(width 0.07112)
			(type default)
		)
		(layer "In13.Cu")
	)
	(gr_line
		(start 54.407816 -385.579112)
		(end 54.460648 -385.548632)
		(stroke
			(width 0.07112)
			(type default)
		)
		(layer "In13.Cu")
	)
	(gr_line
		(start 54.460648 -385.548632)
		(end 54.548786 -385.460494)
		(stroke
			(width 0.07112)
			(type default)
		)
		(layer "In13.Cu")
	)
	(gr_line
		(start 54.494684 -409.301188)
		(end 54.630574 -409.165298)
		(stroke
			(width 0.07112)
			(type default)
		)
		(layer "In13.Cu")
	)
	(gr_line
		(start 54.494684 -408.103832)
		(end 54.630574 -407.967942)
		(stroke
			(width 0.07112)
			(type default)
		)
		(layer "In13.Cu")
	)
	(gr_line
		(start 54.506876 -414.674812)
		(end 54.314598 -414.674812)
		(stroke
			(width 0.07112)
			(type default)
		)
		(layer "In13.Cu")
	)
	(gr_arc
		(start 54.540658 -382.620266)
		(mid 54.540658 -382.619885)
		(end 54.540658 -382.619504)
		(stroke
			(width 0.07112)
			(type default)
		)
		(layer "In13.Cu")
	)
	(gr_line
		(start 54.548786 -385.460494)
		(end 54.548786 -385.334764)
		(stroke
			(width 0.07112)
			(type default)
		)
		(layer "In13.Cu")
	)
	(gr_line
		(start 54.609492 -415.370264)
		(end 54.11343 -414.874202)
		(stroke
			(width 0.07112)
			(type default)
		)
		(layer "In13.Cu")
	)
	(gr_line
		(start 54.613556 -418.460682)
		(end 54.421278 -418.460682)
		(stroke
			(width 0.07112)
			(type default)
		)
		(layer "In13.Cu")
	)
	(gr_line
		(start 54.630574 -409.165298)
		(end 54.630574 -408.738578)
		(stroke
			(width 0.07112)
			(type default)
		)
		(layer "In13.Cu")
	)
	(gr_line
		(start 54.630574 -408.738578)
		(end 54.494684 -408.602688)
		(stroke
			(width 0.07112)
			(type default)
		)
		(layer "In13.Cu")
	)
	(gr_line
		(start 54.630574 -407.967942)
		(end 54.630574 -407.541222)
		(stroke
			(width 0.07112)
			(type default)
		)
		(layer "In13.Cu")
	)
	(gr_line
		(start 54.630574 -407.541222)
		(end 54.494684 -407.405332)
		(stroke
			(width 0.07112)
			(type default)
		)
		(layer "In13.Cu")
	)
	(gr_line
		(start 54.716172 -419.156134)
		(end 54.22011 -418.660072)
		(stroke
			(width 0.07112)
			(type default)
		)
		(layer "In13.Cu")
	)
	(gr_line
		(start 54.808882 -415.169096)
		(end 54.808882 -414.976818)
		(stroke
			(width 0.07112)
			(type default)
		)
		(layer "In13.Cu")
	)
	(gr_line
		(start 54.808882 -414.976818)
		(end 54.506876 -414.674812)
		(stroke
			(width 0.07112)
			(type default)
		)
		(layer "In13.Cu")
	)
	(gr_line
		(start 54.915562 -418.954966)
		(end 54.915562 -418.762688)
		(stroke
			(width 0.07112)
			(type default)
		)
		(layer "In13.Cu")
	)
	(gr_line
		(start 54.915562 -418.762688)
		(end 54.613556 -418.460682)
		(stroke
			(width 0.07112)
			(type default)
		)
		(layer "In13.Cu")
	)
	(gr_line
		(start 54.991254 -385.31038)
		(end 55.344568 -385.405376)
		(stroke
			(width 0.07112)
			(type default)
		)
		(layer "In13.Cu")
	)
	(gr_arc
		(start 55.117238 -366.910112)
		(mid 55.116602 -366.911127)
		(end 55.115968 -366.912144)
		(stroke
			(width 0.07112)
			(type default)
		)
		(layer "In13.Cu")
	)
	(gr_line
		(start 55.304436 -415.472372)
		(end 55.112158 -415.472372)
		(stroke
			(width 0.07112)
			(type default)
		)
		(layer "In13.Cu")
	)
	(gr_line
		(start 55.344568 -385.405376)
		(end 55.345076 -385.404868)
		(stroke
			(width 0.07112)
			(type default)
		)
		(layer "In13.Cu")
	)
	(gr_line
		(start 55.374794 -367.036604)
		(end 55.374794 -367.03635)
		(stroke
			(width 0.07112)
			(type default)
		)
		(layer "In13.Cu")
	)
	(gr_line
		(start 55.391304 -386.003292)
		(end 55.486046 -385.649724)
		(stroke
			(width 0.07112)
			(type default)
		)
		(layer "In13.Cu")
	)
	(gr_line
		(start 55.407052 -416.167824)
		(end 54.91099 -415.671762)
		(stroke
			(width 0.07112)
			(type default)
		)
		(layer "In13.Cu")
	)
	(gr_line
		(start 55.411116 -419.258242)
		(end 55.218838 -419.258242)
		(stroke
			(width 0.07112)
			(type default)
		)
		(layer "In13.Cu")
	)
	(gr_line
		(start 55.458614 -382.922272)
		(end 55.458614 -382.921764)
		(stroke
			(width 0.07112)
			(type default)
		)
		(layer "In13.Cu")
	)
	(gr_line
		(start 55.513732 -419.953694)
		(end 55.01767 -419.457632)
		(stroke
			(width 0.07112)
			(type default)
		)
		(layer "In13.Cu")
	)
	(gr_line
		(start 55.606442 -415.966656)
		(end 55.606442 -415.774378)
		(stroke
			(width 0.07112)
			(type default)
		)
		(layer "In13.Cu")
	)
	(gr_line
		(start 55.606442 -415.774378)
		(end 55.304436 -415.472372)
		(stroke
			(width 0.07112)
			(type default)
		)
		(layer "In13.Cu")
	)
	(gr_line
		(start 55.607712 -385.579112)
		(end 55.660544 -385.548632)
		(stroke
			(width 0.07112)
			(type default)
		)
		(layer "In13.Cu")
	)
	(gr_line
		(start 55.660544 -385.548632)
		(end 55.748682 -385.460494)
		(stroke
			(width 0.07112)
			(type default)
		)
		(layer "In13.Cu")
	)
	(gr_line
		(start 55.713122 -419.752526)
		(end 55.713122 -419.560248)
		(stroke
			(width 0.07112)
			(type default)
		)
		(layer "In13.Cu")
	)
	(gr_line
		(start 55.713122 -419.560248)
		(end 55.411116 -419.258242)
		(stroke
			(width 0.07112)
			(type default)
		)
		(layer "In13.Cu")
	)
	(gr_line
		(start 55.748682 -385.460494)
		(end 55.748682 -385.334764)
		(stroke
			(width 0.07112)
			(type default)
		)
		(layer "In13.Cu")
	)
	(gr_arc
		(start 55.94858 -367.397538)
		(mid 55.947943 -367.398553)
		(end 55.94731 -367.39957)
		(stroke
			(width 0.07112)
			(type default)
		)
		(layer "In13.Cu")
	)
	(gr_line
		(start 56.191404 -385.31038)
		(end 56.544464 -385.405376)
		(stroke
			(width 0.07112)
			(type default)
		)
		(layer "In13.Cu")
	)
	(gr_line
		(start 56.206136 -367.52403)
		(end 56.206136 -367.523776)
		(stroke
			(width 0.07112)
			(type default)
		)
		(layer "In13.Cu")
	)
	(gr_line
		(start 56.208422 -420.055802)
		(end 56.016398 -420.055802)
		(stroke
			(width 0.07112)
			(type default)
		)
		(layer "In13.Cu")
	)
	(gr_line
		(start 56.311038 -420.751)
		(end 55.81523 -420.255192)
		(stroke
			(width 0.07112)
			(type default)
		)
		(layer "In13.Cu")
	)
	(gr_line
		(start 56.510428 -420.549832)
		(end 56.510428 -420.357808)
		(stroke
			(width 0.07112)
			(type default)
		)
		(layer "In13.Cu")
	)
	(gr_line
		(start 56.510428 -420.357808)
		(end 56.208422 -420.055802)
		(stroke
			(width 0.07112)
			(type default)
		)
		(layer "In13.Cu")
	)
	(gr_line
		(start 56.544464 -385.405376)
		(end 56.544972 -385.404868)
		(stroke
			(width 0.07112)
			(type default)
		)
		(layer "In13.Cu")
	)
	(gr_line
		(start 56.5912 -386.003292)
		(end 56.685942 -385.649724)
		(stroke
			(width 0.07112)
			(type default)
		)
		(layer "In13.Cu")
	)
	(gr_line
		(start 56.807608 -385.579112)
		(end 56.86044 -385.548632)
		(stroke
			(width 0.07112)
			(type default)
		)
		(layer "In13.Cu")
	)
	(gr_line
		(start 56.86044 -385.548632)
		(end 56.948578 -385.460494)
		(stroke
			(width 0.07112)
			(type default)
		)
		(layer "In13.Cu")
	)
	(gr_line
		(start 56.948578 -385.460494)
		(end 56.948578 -385.334764)
		(stroke
			(width 0.07112)
			(type default)
		)
		(layer "In13.Cu")
	)
	(gr_line
		(start 57.13984 -416.428174)
		(end 57.00395 -416.564064)
		(stroke
			(width 0.07112)
			(type default)
		)
		(layer "In13.Cu")
	)
	(gr_line
		(start 57.16651 -414.261046)
		(end 56.974232 -414.261046)
		(stroke
			(width 0.07112)
			(type default)
		)
		(layer "In13.Cu")
	)
	(gr_line
		(start 57.240424 -414.927796)
		(end 56.773064 -414.460436)
		(stroke
			(width 0.07112)
			(type default)
		)
		(layer "In13.Cu")
	)
	(gr_line
		(start 57.274714 -409.69438)
		(end 57.274714 -408.99334)
		(stroke
			(width 0.07112)
			(type default)
		)
		(layer "In13.Cu")
	)
	(gr_line
		(start 57.274714 -408.56662)
		(end 57.274714 -407.86558)
		(stroke
			(width 0.07112)
			(type default)
		)
		(layer "In13.Cu")
	)
	(gr_line
		(start 57.439814 -414.726628)
		(end 57.439814 -414.53435)
		(stroke
			(width 0.07112)
			(type default)
		)
		(layer "In13.Cu")
	)
	(gr_line
		(start 57.439814 -414.53435)
		(end 57.16651 -414.261046)
		(stroke
			(width 0.07112)
			(type default)
		)
		(layer "In13.Cu")
	)
	(gr_line
		(start 57.52592 -416.428174)
		(end 57.13984 -416.428174)
		(stroke
			(width 0.07112)
			(type default)
		)
		(layer "In13.Cu")
	)
	(gr_line
		(start 57.557924 -409.69311)
		(end 57.693814 -409.55722)
		(stroke
			(width 0.07112)
			(type default)
		)
		(layer "In13.Cu")
	)
	(gr_line
		(start 57.557924 -408.56535)
		(end 57.693814 -408.42946)
		(stroke
			(width 0.07112)
			(type default)
		)
		(layer "In13.Cu")
	)
	(gr_line
		(start 57.66181 -416.564064)
		(end 57.52592 -416.428174)
		(stroke
			(width 0.07112)
			(type default)
		)
		(layer "In13.Cu")
	)
	(gr_line
		(start 57.66308 -416.847274)
		(end 57.00268 -416.847274)
		(stroke
			(width 0.07112)
			(type default)
		)
		(layer "In13.Cu")
	)
	(gr_line
		(start 57.693814 -409.55722)
		(end 57.693814 -409.1305)
		(stroke
			(width 0.07112)
			(type default)
		)
		(layer "In13.Cu")
	)
	(gr_line
		(start 57.693814 -409.1305)
		(end 57.557924 -408.99461)
		(stroke
			(width 0.07112)
			(type default)
		)
		(layer "In13.Cu")
	)
	(gr_line
		(start 57.693814 -408.42946)
		(end 57.693814 -408.00274)
		(stroke
			(width 0.07112)
			(type default)
		)
		(layer "In13.Cu")
	)
	(gr_line
		(start 57.693814 -408.00274)
		(end 57.557924 -407.86685)
		(stroke
			(width 0.07112)
			(type default)
		)
		(layer "In13.Cu")
	)
	(gr_line
		(start 57.726072 -402.576284)
		(end 58.37428 -402.308314)
		(stroke
			(width 0.07112)
			(type default)
		)
		(layer "In13.Cu")
	)
	(gr_line
		(start 57.835292 -402.83765)
		(end 58.013092 -402.91131)
		(stroke
			(width 0.07112)
			(type default)
		)
		(layer "In13.Cu")
	)
	(gr_line
		(start 58.013092 -402.91131)
		(end 58.407554 -402.748242)
		(stroke
			(width 0.07112)
			(type default)
		)
		(layer "In13.Cu")
	)
	(gr_line
		(start 58.18632 -416.428174)
		(end 58.05043 -416.564064)
		(stroke
			(width 0.07112)
			(type default)
		)
		(layer "In13.Cu")
	)
	(gr_line
		(start 58.407554 -402.748242)
		(end 58.481214 -402.570442)
		(stroke
			(width 0.07112)
			(type default)
		)
		(layer "In13.Cu")
	)
	(gr_line
		(start 58.475372 -380.8476)
		(end 58.531252 -380.663196)
		(stroke
			(width 0.07112)
			(type default)
		)
		(layer "In13.Cu")
	)
	(gr_line
		(start 58.52287 -434.038756)
		(end 58.511694 -434.038756)
		(stroke
			(width 0.07112)
			(type default)
		)
		(layer "In13.Cu")
	)
	(gr_line
		(start 58.531252 -380.663196)
		(end 58.907934 -380.462282)
		(stroke
			(width 0.07112)
			(type default)
		)
		(layer "In13.Cu")
	)
	(gr_line
		(start 58.5724 -416.428174)
		(end 58.18632 -416.428174)
		(stroke
			(width 0.07112)
			(type default)
		)
		(layer "In13.Cu")
	)
	(gr_line
		(start 58.607706 -381.098044)
		(end 59.22645 -380.767844)
		(stroke
			(width 0.07112)
			(type default)
		)
		(layer "In13.Cu")
	)
	(gr_line
		(start 58.64987 -434.48986)
		(end 58.64987 -434.165756)
		(stroke
			(width 0.07112)
			(type default)
		)
		(layer "In13.Cu")
	)
	(gr_line
		(start 58.64987 -434.165756)
		(end 58.52287 -434.038756)
		(stroke
			(width 0.07112)
			(type default)
		)
		(layer "In13.Cu")
	)
	(gr_line
		(start 58.64987 -433.61864)
		(end 58.512964 -433.755546)
		(stroke
			(width 0.07112)
			(type default)
		)
		(layer "In13.Cu")
	)
	(gr_line
		(start 58.64987 -433.289964)
		(end 58.64987 -433.61864)
		(stroke
			(width 0.07112)
			(type default)
		)
		(layer "In13.Cu")
	)
	(gr_line
		(start 58.70829 -416.564064)
		(end 58.5724 -416.428174)
		(stroke
			(width 0.07112)
			(type default)
		)
		(layer "In13.Cu")
	)
	(gr_line
		(start 58.70956 -416.847274)
		(end 58.04916 -416.847274)
		(stroke
			(width 0.07112)
			(type default)
		)
		(layer "In13.Cu")
	)
	(gr_line
		(start 58.907934 -380.462282)
		(end 59.092338 -380.518416)
		(stroke
			(width 0.07112)
			(type default)
		)
		(layer "In13.Cu")
	)
	(gr_line
		(start 59.470544 -380.31674)
		(end 59.526424 -380.132336)
		(stroke
			(width 0.07112)
			(type default)
		)
		(layer "In13.Cu")
	)
	(gr_line
		(start 59.526424 -380.132336)
		(end 59.903106 -379.931422)
		(stroke
			(width 0.07112)
			(type default)
		)
		(layer "In13.Cu")
	)
	(gr_line
		(start 59.602624 -380.567184)
		(end 60.221622 -380.236984)
		(stroke
			(width 0.07112)
			(type default)
		)
		(layer "In13.Cu")
	)
	(gr_line
		(start 59.903106 -379.931422)
		(end 60.087256 -379.987556)
		(stroke
			(width 0.07112)
			(type default)
		)
		(layer "In13.Cu")
	)
	(gr_line
		(start 60.095384 -415.481262)
		(end 59.903106 -415.481262)
		(stroke
			(width 0.07112)
			(type default)
		)
		(layer "In13.Cu")
	)
	(gr_line
		(start 60.172854 -402.64588)
		(end 60.823348 -402.384006)
		(stroke
			(width 0.07112)
			(type default)
		)
		(layer "In13.Cu")
	)
	(gr_line
		(start 60.198 -416.176714)
		(end 59.701938 -415.680652)
		(stroke
			(width 0.07112)
			(type default)
		)
		(layer "In13.Cu")
	)
	(gr_line
		(start 60.279534 -402.908262)
		(end 60.456572 -402.9837)
		(stroke
			(width 0.07112)
			(type default)
		)
		(layer "In13.Cu")
	)
	(gr_line
		(start 60.337954 -409.579318)
		(end 60.337954 -408.878278)
		(stroke
			(width 0.07112)
			(type default)
		)
		(layer "In13.Cu")
	)
	(gr_line
		(start 60.337954 -408.451558)
		(end 60.337954 -407.750518)
		(stroke
			(width 0.07112)
			(type default)
		)
		(layer "In13.Cu")
	)
	(gr_line
		(start 60.39739 -415.975546)
		(end 60.39739 -415.783268)
		(stroke
			(width 0.07112)
			(type default)
		)
		(layer "In13.Cu")
	)
	(gr_line
		(start 60.39739 -415.783268)
		(end 60.095384 -415.481262)
		(stroke
			(width 0.07112)
			(type default)
		)
		(layer "In13.Cu")
	)
	(gr_line
		(start 60.456572 -402.9837)
		(end 60.852812 -402.824442)
		(stroke
			(width 0.07112)
			(type default)
		)
		(layer "In13.Cu")
	)
	(gr_line
		(start 60.465716 -379.78588)
		(end 60.521596 -379.601476)
		(stroke
			(width 0.07112)
			(type default)
		)
		(layer "In13.Cu")
	)
	(gr_line
		(start 60.521596 -379.601476)
		(end 60.898278 -379.400562)
		(stroke
			(width 0.07112)
			(type default)
		)
		(layer "In13.Cu")
	)
	(gr_line
		(start 60.522866 -435.038754)
		(end 60.51169 -435.038754)
		(stroke
			(width 0.07112)
			(type default)
		)
		(layer "In13.Cu")
	)
	(gr_line
		(start 60.597796 -380.036324)
		(end 61.216794 -379.706124)
		(stroke
			(width 0.07112)
			(type default)
		)
		(layer "In13.Cu")
	)
	(gr_line
		(start 60.621164 -409.578048)
		(end 60.757054 -409.442158)
		(stroke
			(width 0.07112)
			(type default)
		)
		(layer "In13.Cu")
	)
	(gr_line
		(start 60.621164 -408.450288)
		(end 60.757054 -408.314398)
		(stroke
			(width 0.07112)
			(type default)
		)
		(layer "In13.Cu")
	)
	(gr_line
		(start 60.649866 -435.489858)
		(end 60.649866 -435.165754)
		(stroke
			(width 0.07112)
			(type default)
		)
		(layer "In13.Cu")
	)
	(gr_line
		(start 60.649866 -435.165754)
		(end 60.522866 -435.038754)
		(stroke
			(width 0.07112)
			(type default)
		)
		(layer "In13.Cu")
	)
	(gr_line
		(start 60.649866 -434.618638)
		(end 60.51296 -434.755544)
		(stroke
			(width 0.07112)
			(type default)
		)
		(layer "In13.Cu")
	)
	(gr_line
		(start 60.649866 -434.289962)
		(end 60.649866 -434.618638)
		(stroke
			(width 0.07112)
			(type default)
		)
		(layer "In13.Cu")
	)
	(gr_line
		(start 60.757054 -409.442158)
		(end 60.757054 -409.015438)
		(stroke
			(width 0.07112)
			(type default)
		)
		(layer "In13.Cu")
	)
	(gr_line
		(start 60.757054 -409.015438)
		(end 60.621164 -408.879548)
		(stroke
			(width 0.07112)
			(type default)
		)
		(layer "In13.Cu")
	)
	(gr_line
		(start 60.757054 -408.314398)
		(end 60.757054 -407.887678)
		(stroke
			(width 0.07112)
			(type default)
		)
		(layer "In13.Cu")
	)
	(gr_line
		(start 60.757054 -407.887678)
		(end 60.621164 -407.751788)
		(stroke
			(width 0.07112)
			(type default)
		)
		(layer "In13.Cu")
	)
	(gr_line
		(start 60.852812 -402.824442)
		(end 60.927996 -402.647404)
		(stroke
			(width 0.07112)
			(type default)
		)
		(layer "In13.Cu")
	)
	(gr_line
		(start 60.85459 -414.37687)
		(end 60.662312 -414.37687)
		(stroke
			(width 0.07112)
			(type default)
		)
		(layer "In13.Cu")
	)
	(gr_line
		(start 60.892944 -416.278822)
		(end 60.700666 -416.278822)
		(stroke
			(width 0.07112)
			(type default)
		)
		(layer "In13.Cu")
	)
	(gr_line
		(start 60.898278 -379.400562)
		(end 61.082428 -379.456696)
		(stroke
			(width 0.07112)
			(type default)
		)
		(layer "In13.Cu")
	)
	(gr_line
		(start 60.928504 -415.04362)
		(end 60.461144 -414.57626)
		(stroke
			(width 0.07112)
			(type default)
		)
		(layer "In13.Cu")
	)
	(gr_line
		(start 60.99556 -416.974274)
		(end 60.499498 -416.478212)
		(stroke
			(width 0.07112)
			(type default)
		)
		(layer "In13.Cu")
	)
	(gr_line
		(start 61.127894 -414.842452)
		(end 61.127894 -414.650174)
		(stroke
			(width 0.07112)
			(type default)
		)
		(layer "In13.Cu")
	)
	(gr_line
		(start 61.127894 -414.650174)
		(end 60.85459 -414.37687)
		(stroke
			(width 0.07112)
			(type default)
		)
		(layer "In13.Cu")
	)
	(gr_line
		(start 61.19495 -416.773106)
		(end 61.19495 -416.580828)
		(stroke
			(width 0.07112)
			(type default)
		)
		(layer "In13.Cu")
	)
	(gr_line
		(start 61.19495 -416.580828)
		(end 60.892944 -416.278822)
		(stroke
			(width 0.07112)
			(type default)
		)
		(layer "In13.Cu")
	)
	(gr_line
		(start 61.594746 -415.117026)
		(end 61.402468 -415.117026)
		(stroke
			(width 0.07112)
			(type default)
		)
		(layer "In13.Cu")
	)
	(gr_line
		(start 61.697362 -415.812478)
		(end 61.2013 -415.316416)
		(stroke
			(width 0.07112)
			(type default)
		)
		(layer "In13.Cu")
	)
	(gr_line
		(start 61.896752 -415.61131)
		(end 61.896752 -415.419032)
		(stroke
			(width 0.07112)
			(type default)
		)
		(layer "In13.Cu")
	)
	(gr_line
		(start 61.896752 -415.419032)
		(end 61.594746 -415.117026)
		(stroke
			(width 0.07112)
			(type default)
		)
		(layer "In13.Cu")
	)
	(gr_line
		(start 62.392052 -415.914586)
		(end 62.200028 -415.914586)
		(stroke
			(width 0.07112)
			(type default)
		)
		(layer "In13.Cu")
	)
	(gr_line
		(start 62.494668 -416.609784)
		(end 61.99886 -416.113976)
		(stroke
			(width 0.07112)
			(type default)
		)
		(layer "In13.Cu")
	)
	(gr_line
		(start 62.522862 -434.038756)
		(end 62.511686 -434.038756)
		(stroke
			(width 0.07112)
			(type default)
		)
		(layer "In13.Cu")
	)
	(gr_line
		(start 62.649862 -434.48986)
		(end 62.649862 -434.165756)
		(stroke
			(width 0.07112)
			(type default)
		)
		(layer "In13.Cu")
	)
	(gr_line
		(start 62.649862 -434.165756)
		(end 62.522862 -434.038756)
		(stroke
			(width 0.07112)
			(type default)
		)
		(layer "In13.Cu")
	)
	(gr_line
		(start 62.649862 -433.61864)
		(end 62.512956 -433.755546)
		(stroke
			(width 0.07112)
			(type default)
		)
		(layer "In13.Cu")
	)
	(gr_line
		(start 62.649862 -433.289964)
		(end 62.649862 -433.61864)
		(stroke
			(width 0.07112)
			(type default)
		)
		(layer "In13.Cu")
	)
	(gr_line
		(start 62.694058 -416.408616)
		(end 62.694058 -416.216592)
		(stroke
			(width 0.07112)
			(type default)
		)
		(layer "In13.Cu")
	)
	(gr_line
		(start 62.694058 -416.216592)
		(end 62.392052 -415.914586)
		(stroke
			(width 0.07112)
			(type default)
		)
		(layer "In13.Cu")
	)
	(gr_line
		(start 62.84341 -413.884618)
		(end 62.651132 -413.884618)
		(stroke
			(width 0.07112)
			(type default)
		)
		(layer "In13.Cu")
	)
	(gr_line
		(start 62.917324 -414.551368)
		(end 62.449964 -414.084008)
		(stroke
			(width 0.07112)
			(type default)
		)
		(layer "In13.Cu")
	)
	(gr_line
		(start 63.116714 -414.3502)
		(end 63.116714 -414.157922)
		(stroke
			(width 0.07112)
			(type default)
		)
		(layer "In13.Cu")
	)
	(gr_line
		(start 63.116714 -414.157922)
		(end 62.84341 -413.884618)
		(stroke
			(width 0.07112)
			(type default)
		)
		(layer "In13.Cu")
	)
	(gr_line
		(start 63.205868 -416.728402)
		(end 63.013844 -416.728402)
		(stroke
			(width 0.07112)
			(type default)
		)
		(layer "In13.Cu")
	)
	(gr_line
		(start 63.279782 -417.394898)
		(end 62.812676 -416.927792)
		(stroke
			(width 0.07112)
			(type default)
		)
		(layer "In13.Cu")
	)
	(gr_line
		(start 63.401194 -409.497784)
		(end 63.401194 -408.796744)
		(stroke
			(width 0.07112)
			(type default)
		)
		(layer "In13.Cu")
	)
	(gr_line
		(start 63.401194 -408.32659)
		(end 63.401194 -407.62555)
		(stroke
			(width 0.07112)
			(type default)
		)
		(layer "In13.Cu")
	)
	(gr_line
		(start 63.479172 -417.19373)
		(end 63.479172 -417.001706)
		(stroke
			(width 0.07112)
			(type default)
		)
		(layer "In13.Cu")
	)
	(gr_line
		(start 63.479172 -417.001706)
		(end 63.205868 -416.728402)
		(stroke
			(width 0.07112)
			(type default)
		)
		(layer "In13.Cu")
	)
	(gr_line
		(start 63.583566 -414.624774)
		(end 63.391288 -414.624774)
		(stroke
			(width 0.07112)
			(type default)
		)
		(layer "In13.Cu")
	)
	(gr_line
		(start 63.65748 -415.291524)
		(end 63.19012 -414.824164)
		(stroke
			(width 0.07112)
			(type default)
		)
		(layer "In13.Cu")
	)
	(gr_line
		(start 63.684404 -409.496514)
		(end 63.820294 -409.360624)
		(stroke
			(width 0.07112)
			(type default)
		)
		(layer "In13.Cu")
	)
	(gr_line
		(start 63.684404 -408.32532)
		(end 63.820294 -408.18943)
		(stroke
			(width 0.07112)
			(type default)
		)
		(layer "In13.Cu")
	)
	(gr_line
		(start 63.820294 -409.360624)
		(end 63.820294 -408.933904)
		(stroke
			(width 0.07112)
			(type default)
		)
		(layer "In13.Cu")
	)
	(gr_line
		(start 63.820294 -408.933904)
		(end 63.684404 -408.798014)
		(stroke
			(width 0.07112)
			(type default)
		)
		(layer "In13.Cu")
	)
	(gr_line
		(start 63.820294 -408.18943)
		(end 63.820294 -407.76271)
		(stroke
			(width 0.07112)
			(type default)
		)
		(layer "In13.Cu")
	)
	(gr_line
		(start 63.820294 -407.76271)
		(end 63.684404 -407.62682)
		(stroke
			(width 0.07112)
			(type default)
		)
		(layer "In13.Cu")
	)
	(gr_line
		(start 63.85687 -415.090356)
		(end 63.85687 -414.898078)
		(stroke
			(width 0.07112)
			(type default)
		)
		(layer "In13.Cu")
	)
	(gr_line
		(start 63.85687 -414.898078)
		(end 63.583566 -414.624774)
		(stroke
			(width 0.07112)
			(type default)
		)
		(layer "In13.Cu")
	)
	(gr_line
		(start 63.85814 -402.236432)
		(end 64.512698 -401.983956)
		(stroke
			(width 0.07112)
			(type default)
		)
		(layer "In13.Cu")
	)
	(gr_line
		(start 63.941706 -363.82579)
		(end 63.942976 -363.82579)
		(stroke
			(width 0.07112)
			(type default)
		)
		(layer "In13.Cu")
	)
	(gr_line
		(start 63.96101 -402.500084)
		(end 64.137032 -402.578062)
		(stroke
			(width 0.07112)
			(type default)
		)
		(layer "In13.Cu")
	)
	(gr_line
		(start 64.137032 -402.578062)
		(end 64.535304 -402.424646)
		(stroke
			(width 0.07112)
			(type default)
		)
		(layer "In13.Cu")
	)
	(gr_line
		(start 64.323722 -415.36493)
		(end 64.131444 -415.36493)
		(stroke
			(width 0.07112)
			(type default)
		)
		(layer "In13.Cu")
	)
	(gr_line
		(start 64.426338 -416.060382)
		(end 63.930276 -415.56432)
		(stroke
			(width 0.07112)
			(type default)
		)
		(layer "In13.Cu")
	)
	(gr_line
		(start 64.522858 -435.038754)
		(end 64.511682 -435.038754)
		(stroke
			(width 0.07112)
			(type default)
		)
		(layer "In13.Cu")
	)
	(gr_line
		(start 64.535304 -402.424646)
		(end 64.613282 -402.248624)
		(stroke
			(width 0.07112)
			(type default)
		)
		(layer "In13.Cu")
	)
	(gr_line
		(start 64.625728 -415.859214)
		(end 64.625728 -415.666936)
		(stroke
			(width 0.07112)
			(type default)
		)
		(layer "In13.Cu")
	)
	(gr_line
		(start 64.625728 -415.666936)
		(end 64.323722 -415.36493)
		(stroke
			(width 0.07112)
			(type default)
		)
		(layer "In13.Cu")
	)
	(gr_line
		(start 64.649858 -435.489858)
		(end 64.649858 -435.165754)
		(stroke
			(width 0.07112)
			(type default)
		)
		(layer "In13.Cu")
	)
	(gr_line
		(start 64.649858 -435.165754)
		(end 64.522858 -435.038754)
		(stroke
			(width 0.07112)
			(type default)
		)
		(layer "In13.Cu")
	)
	(gr_line
		(start 64.649858 -434.618638)
		(end 64.512952 -434.755544)
		(stroke
			(width 0.07112)
			(type default)
		)
		(layer "In13.Cu")
	)
	(gr_line
		(start 64.649858 -434.289962)
		(end 64.649858 -434.618638)
		(stroke
			(width 0.07112)
			(type default)
		)
		(layer "In13.Cu")
	)
	(gr_line
		(start 65.121282 -416.16249)
		(end 64.929004 -416.16249)
		(stroke
			(width 0.07112)
			(type default)
		)
		(layer "In13.Cu")
	)
	(gr_line
		(start 65.13322 -401.744688)
		(end 65.787524 -401.492466)
		(stroke
			(width 0.07112)
			(type default)
		)
		(layer "In13.Cu")
	)
	(gr_line
		(start 65.223898 -416.857942)
		(end 64.727836 -416.36188)
		(stroke
			(width 0.07112)
			(type default)
		)
		(layer "In13.Cu")
	)
	(gr_line
		(start 65.235836 -402.008594)
		(end 65.411858 -402.086572)
		(stroke
			(width 0.07112)
			(type default)
		)
		(layer "In13.Cu")
	)
	(gr_line
		(start 65.411858 -402.086572)
		(end 65.810384 -401.933156)
		(stroke
			(width 0.07112)
			(type default)
		)
		(layer "In13.Cu")
	)
	(gr_line
		(start 65.423288 -416.656774)
		(end 65.423288 -416.464496)
		(stroke
			(width 0.07112)
			(type default)
		)
		(layer "In13.Cu")
	)
	(gr_line
		(start 65.423288 -416.464496)
		(end 65.121282 -416.16249)
		(stroke
			(width 0.07112)
			(type default)
		)
		(layer "In13.Cu")
	)
	(gr_line
		(start 65.787016 -414.39465)
		(end 65.594738 -414.39465)
		(stroke
			(width 0.07112)
			(type default)
		)
		(layer "In13.Cu")
	)
	(gr_line
		(start 65.810384 -401.933156)
		(end 65.888108 -401.757134)
		(stroke
			(width 0.07112)
			(type default)
		)
		(layer "In13.Cu")
	)
	(gr_line
		(start 65.86093 -415.0614)
		(end 65.39357 -414.59404)
		(stroke
			(width 0.07112)
			(type default)
		)
		(layer "In13.Cu")
	)
	(gr_line
		(start 66.06032 -414.860232)
		(end 66.06032 -414.667954)
		(stroke
			(width 0.07112)
			(type default)
		)
		(layer "In13.Cu")
	)
	(gr_line
		(start 66.06032 -414.667954)
		(end 65.787016 -414.39465)
		(stroke
			(width 0.07112)
			(type default)
		)
		(layer "In13.Cu")
	)
	(gr_line
		(start 66.399156 -401.256754)
		(end 67.053714 -401.004278)
		(stroke
			(width 0.07112)
			(type default)
		)
		(layer "In13.Cu")
	)
	(gr_line
		(start 66.464434 -409.316174)
		(end 66.464434 -408.615134)
		(stroke
			(width 0.07112)
			(type default)
		)
		(layer "In13.Cu")
	)
	(gr_line
		(start 66.464434 -408.188414)
		(end 66.464434 -407.487374)
		(stroke
			(width 0.07112)
			(type default)
		)
		(layer "In13.Cu")
	)
	(gr_line
		(start 66.502026 -401.52066)
		(end 66.677794 -401.598384)
		(stroke
			(width 0.07112)
			(type default)
		)
		(layer "In13.Cu")
	)
	(gr_line
		(start 66.522854 -434.038756)
		(end 66.511678 -434.038756)
		(stroke
			(width 0.07112)
			(type default)
		)
		(layer "In13.Cu")
	)
	(gr_line
		(start 66.527172 -415.134806)
		(end 66.334894 -415.134806)
		(stroke
			(width 0.07112)
			(type default)
		)
		(layer "In13.Cu")
	)
	(gr_line
		(start 66.601086 -415.801556)
		(end 66.133726 -415.334196)
		(stroke
			(width 0.07112)
			(type default)
		)
		(layer "In13.Cu")
	)
	(gr_line
		(start 66.649854 -434.48986)
		(end 66.649854 -434.165756)
		(stroke
			(width 0.07112)
			(type default)
		)
		(layer "In13.Cu")
	)
	(gr_line
		(start 66.649854 -434.165756)
		(end 66.522854 -434.038756)
		(stroke
			(width 0.07112)
			(type default)
		)
		(layer "In13.Cu")
	)
	(gr_line
		(start 66.649854 -433.61864)
		(end 66.512948 -433.755546)
		(stroke
			(width 0.07112)
			(type default)
		)
		(layer "In13.Cu")
	)
	(gr_line
		(start 66.649854 -433.289964)
		(end 66.649854 -433.61864)
		(stroke
			(width 0.07112)
			(type default)
		)
		(layer "In13.Cu")
	)
	(gr_line
		(start 66.677794 -401.598384)
		(end 67.07632 -401.444968)
		(stroke
			(width 0.07112)
			(type default)
		)
		(layer "In13.Cu")
	)
	(gr_line
		(start 66.747644 -409.314904)
		(end 66.883534 -409.179014)
		(stroke
			(width 0.07112)
			(type default)
		)
		(layer "In13.Cu")
	)
	(gr_line
		(start 66.747644 -408.187144)
		(end 66.883534 -408.051254)
		(stroke
			(width 0.07112)
			(type default)
		)
		(layer "In13.Cu")
	)
	(gr_line
		(start 66.800476 -415.600388)
		(end 66.800476 -415.40811)
		(stroke
			(width 0.07112)
			(type default)
		)
		(layer "In13.Cu")
	)
	(gr_line
		(start 66.800476 -415.40811)
		(end 66.527172 -415.134806)
		(stroke
			(width 0.07112)
			(type default)
		)
		(layer "In13.Cu")
	)
	(gr_line
		(start 66.876422 -402.363432)
		(end 67.521074 -402.087334)
		(stroke
			(width 0.07112)
			(type default)
		)
		(layer "In13.Cu")
	)
	(gr_line
		(start 66.883534 -409.179014)
		(end 66.883534 -408.752294)
		(stroke
			(width 0.07112)
			(type default)
		)
		(layer "In13.Cu")
	)
	(gr_line
		(start 66.883534 -408.752294)
		(end 66.747644 -408.616404)
		(stroke
			(width 0.07112)
			(type default)
		)
		(layer "In13.Cu")
	)
	(gr_line
		(start 66.883534 -408.051254)
		(end 66.883534 -407.624534)
		(stroke
			(width 0.07112)
			(type default)
		)
		(layer "In13.Cu")
	)
	(gr_line
		(start 66.883534 -407.624534)
		(end 66.747644 -407.488644)
		(stroke
			(width 0.07112)
			(type default)
		)
		(layer "In13.Cu")
	)
	(gr_line
		(start 66.98869 -402.623528)
		(end 67.167506 -402.694902)
		(stroke
			(width 0.07112)
			(type default)
		)
		(layer "In13.Cu")
	)
	(gr_line
		(start 67.07632 -401.444968)
		(end 67.154298 -401.268946)
		(stroke
			(width 0.07112)
			(type default)
		)
		(layer "In13.Cu")
	)
	(gr_line
		(start 67.167506 -402.694902)
		(end 67.559936 -402.527008)
		(stroke
			(width 0.07112)
			(type default)
		)
		(layer "In13.Cu")
	)
	(gr_line
		(start 67.267328 -415.874962)
		(end 67.07505 -415.874962)
		(stroke
			(width 0.07112)
			(type default)
		)
		(layer "In13.Cu")
	)
	(gr_line
		(start 67.341242 -416.541712)
		(end 66.873882 -416.074352)
		(stroke
			(width 0.07112)
			(type default)
		)
		(layer "In13.Cu")
	)
	(gr_line
		(start 67.40906 -398.571212)
		(end 68.057014 -398.302988)
		(stroke
			(width 0.07112)
			(type default)
		)
		(layer "In13.Cu")
	)
	(gr_line
		(start 67.518026 -398.832578)
		(end 67.69608 -398.906238)
		(stroke
			(width 0.07112)
			(type default)
		)
		(layer "In13.Cu")
	)
	(gr_line
		(start 67.540632 -416.340544)
		(end 67.540632 -416.148266)
		(stroke
			(width 0.07112)
			(type default)
		)
		(layer "In13.Cu")
	)
	(gr_line
		(start 67.540632 -416.148266)
		(end 67.267328 -415.874962)
		(stroke
			(width 0.07112)
			(type default)
		)
		(layer "In13.Cu")
	)
	(gr_line
		(start 67.559936 -402.527008)
		(end 67.631564 -402.347938)
		(stroke
			(width 0.07112)
			(type default)
		)
		(layer "In13.Cu")
	)
	(gr_line
		(start 67.69608 -398.906238)
		(end 68.090542 -398.74317)
		(stroke
			(width 0.07112)
			(type default)
		)
		(layer "In13.Cu")
	)
	(gr_line
		(start 67.91325 -401.919186)
		(end 68.557902 -401.643088)
		(stroke
			(width 0.07112)
			(type default)
		)
		(layer "In13.Cu")
	)
	(gr_line
		(start 68.025518 -402.179282)
		(end 68.204334 -402.250656)
		(stroke
			(width 0.07112)
			(type default)
		)
		(layer "In13.Cu")
	)
	(gr_line
		(start 68.090542 -398.74317)
		(end 68.164456 -398.565116)
		(stroke
			(width 0.07112)
			(type default)
		)
		(layer "In13.Cu")
	)
	(gr_line
		(start 68.115434 -400.595084)
		(end 68.769992 -400.342608)
		(stroke
			(width 0.07112)
			(type default)
		)
		(layer "In13.Cu")
	)
	(gr_line
		(start 68.204334 -402.250656)
		(end 68.596764 -402.082762)
		(stroke
			(width 0.07112)
			(type default)
		)
		(layer "In13.Cu")
	)
	(gr_line
		(start 68.218304 -400.85899)
		(end 68.394072 -400.936714)
		(stroke
			(width 0.07112)
			(type default)
		)
		(layer "In13.Cu")
	)
	(gr_line
		(start 68.394072 -400.936714)
		(end 68.792598 -400.783298)
		(stroke
			(width 0.07112)
			(type default)
		)
		(layer "In13.Cu")
	)
	(gr_line
		(start 68.426838 -399.322798)
		(end 69.077332 -399.060924)
		(stroke
			(width 0.07112)
			(type default)
		)
		(layer "In13.Cu")
	)
	(gr_line
		(start 68.451222 -398.13992)
		(end 69.09943 -397.87195)
		(stroke
			(width 0.07112)
			(type default)
		)
		(layer "In13.Cu")
	)
	(gr_line
		(start 68.52285 -435.038754)
		(end 68.511674 -435.038754)
		(stroke
			(width 0.07112)
			(type default)
		)
		(layer "In13.Cu")
	)
	(gr_line
		(start 68.533772 -399.58518)
		(end 68.710556 -399.660618)
		(stroke
			(width 0.07112)
			(type default)
		)
		(layer "In13.Cu")
	)
	(gr_line
		(start 68.560442 -398.401286)
		(end 68.738242 -398.4752)
		(stroke
			(width 0.07112)
			(type default)
		)
		(layer "In13.Cu")
	)
	(gr_line
		(start 68.596764 -402.082762)
		(end 68.668392 -401.903692)
		(stroke
			(width 0.07112)
			(type default)
		)
		(layer "In13.Cu")
	)
	(gr_line
		(start 68.64985 -435.489858)
		(end 68.64985 -435.165754)
		(stroke
			(width 0.07112)
			(type default)
		)
		(layer "In13.Cu")
	)
	(gr_line
		(start 68.64985 -435.165754)
		(end 68.52285 -435.038754)
		(stroke
			(width 0.07112)
			(type default)
		)
		(layer "In13.Cu")
	)
	(gr_line
		(start 68.64985 -434.618638)
		(end 68.512944 -434.755544)
		(stroke
			(width 0.07112)
			(type default)
		)
		(layer "In13.Cu")
	)
	(gr_line
		(start 68.64985 -434.289962)
		(end 68.64985 -434.618638)
		(stroke
			(width 0.07112)
			(type default)
		)
		(layer "In13.Cu")
	)
	(gr_line
		(start 68.710556 -399.660618)
		(end 69.106796 -399.501106)
		(stroke
			(width 0.07112)
			(type default)
		)
		(layer "In13.Cu")
	)
	(gr_line
		(start 68.738242 -398.4752)
		(end 69.132958 -398.311878)
		(stroke
			(width 0.07112)
			(type default)
		)
		(layer "In13.Cu")
	)
	(gr_line
		(start 68.792598 -400.783298)
		(end 68.870576 -400.607276)
		(stroke
			(width 0.07112)
			(type default)
		)
		(layer "In13.Cu")
	)
	(gr_line
		(start 68.950078 -401.47494)
		(end 69.594476 -401.198842)
		(stroke
			(width 0.07112)
			(type default)
		)
		(layer "In13.Cu")
	)
	(gr_line
		(start 69.062346 -401.735036)
		(end 69.241162 -401.80641)
		(stroke
			(width 0.07112)
			(type default)
		)
		(layer "In13.Cu")
	)
	(gr_line
		(start 69.106796 -399.501106)
		(end 69.18198 -399.324068)
		(stroke
			(width 0.07112)
			(type default)
		)
		(layer "In13.Cu")
	)
	(gr_line
		(start 69.132958 -398.311878)
		(end 69.206872 -398.134078)
		(stroke
			(width 0.07112)
			(type default)
		)
		(layer "In13.Cu")
	)
	(gr_line
		(start 69.19722 -414.036002)
		(end 69.004942 -414.036002)
		(stroke
			(width 0.07112)
			(type default)
		)
		(layer "In13.Cu")
	)
	(gr_line
		(start 69.241162 -401.80641)
		(end 69.633592 -401.638516)
		(stroke
			(width 0.07112)
			(type default)
		)
		(layer "In13.Cu")
	)
	(gr_line
		(start 69.299836 -414.731454)
		(end 68.803774 -414.235392)
		(stroke
			(width 0.07112)
			(type default)
		)
		(layer "In13.Cu")
	)
	(gr_line
		(start 69.499226 -414.530286)
		(end 69.499226 -414.338008)
		(stroke
			(width 0.07112)
			(type default)
		)
		(layer "In13.Cu")
	)
	(gr_line
		(start 69.499226 -414.338008)
		(end 69.19722 -414.036002)
		(stroke
			(width 0.07112)
			(type default)
		)
		(layer "In13.Cu")
	)
	(gr_line
		(start 69.525642 -397.69542)
		(end 70.17385 -397.42745)
		(stroke
			(width 0.07112)
			(type default)
		)
		(layer "In13.Cu")
	)
	(gr_line
		(start 69.527674 -409.444698)
		(end 69.527674 -408.743658)
		(stroke
			(width 0.07112)
			(type default)
		)
		(layer "In13.Cu")
	)
	(gr_line
		(start 69.527674 -408.316938)
		(end 69.527674 -407.615898)
		(stroke
			(width 0.07112)
			(type default)
		)
		(layer "In13.Cu")
	)
	(gr_line
		(start 69.633592 -401.638516)
		(end 69.70522 -401.459446)
		(stroke
			(width 0.07112)
			(type default)
		)
		(layer "In13.Cu")
	)
	(gr_line
		(start 69.634862 -397.956786)
		(end 69.812662 -398.030446)
		(stroke
			(width 0.07112)
			(type default)
		)
		(layer "In13.Cu")
	)
	(gr_line
		(start 69.689218 -416.683952)
		(end 69.689218 -415.982912)
		(stroke
			(width 0.07112)
			(type default)
		)
		(layer "In13.Cu")
	)
	(gr_line
		(start 69.810884 -409.443428)
		(end 69.946774 -409.307538)
		(stroke
			(width 0.07112)
			(type default)
		)
		(layer "In13.Cu")
	)
	(gr_line
		(start 69.810884 -408.315668)
		(end 69.946774 -408.179778)
		(stroke
			(width 0.07112)
			(type default)
		)
		(layer "In13.Cu")
	)
	(gr_line
		(start 69.812662 -398.030446)
		(end 70.207124 -397.867378)
		(stroke
			(width 0.07112)
			(type default)
		)
		(layer "In13.Cu")
	)
	(gr_line
		(start 69.946774 -409.307538)
		(end 69.946774 -408.880818)
		(stroke
			(width 0.07112)
			(type default)
		)
		(layer "In13.Cu")
	)
	(gr_line
		(start 69.946774 -408.880818)
		(end 69.810884 -408.744928)
		(stroke
			(width 0.07112)
			(type default)
		)
		(layer "In13.Cu")
	)
	(gr_line
		(start 69.946774 -408.179778)
		(end 69.946774 -407.753058)
		(stroke
			(width 0.07112)
			(type default)
		)
		(layer "In13.Cu")
	)
	(gr_line
		(start 69.946774 -407.753058)
		(end 69.810884 -407.617168)
		(stroke
			(width 0.07112)
			(type default)
		)
		(layer "In13.Cu")
	)
	(gr_line
		(start 69.972428 -416.682682)
		(end 70.108318 -416.546792)
		(stroke
			(width 0.07112)
			(type default)
		)
		(layer "In13.Cu")
	)
	(gr_line
		(start 69.9897 -398.69364)
		(end 70.640702 -398.431512)
		(stroke
			(width 0.07112)
			(type default)
		)
		(layer "In13.Cu")
	)
	(gr_line
		(start 70.096634 -398.955768)
		(end 70.273672 -399.031206)
		(stroke
			(width 0.07112)
			(type default)
		)
		(layer "In13.Cu")
	)
	(gr_line
		(start 70.108318 -416.546792)
		(end 70.108318 -416.120072)
		(stroke
			(width 0.07112)
			(type default)
		)
		(layer "In13.Cu")
	)
	(gr_line
		(start 70.108318 -416.120072)
		(end 69.972428 -415.984182)
		(stroke
			(width 0.07112)
			(type default)
		)
		(layer "In13.Cu")
	)
	(gr_line
		(start 70.207124 -397.867378)
		(end 70.280784 -397.689578)
		(stroke
			(width 0.07112)
			(type default)
		)
		(layer "In13.Cu")
	)
	(gr_line
		(start 70.273672 -399.031206)
		(end 70.669912 -398.871948)
		(stroke
			(width 0.07112)
			(type default)
		)
		(layer "In13.Cu")
	)
	(gr_line
		(start 70.522846 -434.038756)
		(end 70.51167 -434.038756)
		(stroke
			(width 0.07112)
			(type default)
		)
		(layer "In13.Cu")
	)
	(gr_line
		(start 70.62343 -402.077174)
		(end 71.279004 -401.827238)
		(stroke
			(width 0.07112)
			(type default)
		)
		(layer "In13.Cu")
	)
	(gr_line
		(start 70.649846 -434.48986)
		(end 70.649846 -434.165756)
		(stroke
			(width 0.07112)
			(type default)
		)
		(layer "In13.Cu")
	)
	(gr_line
		(start 70.649846 -434.165756)
		(end 70.522846 -434.038756)
		(stroke
			(width 0.07112)
			(type default)
		)
		(layer "In13.Cu")
	)
	(gr_line
		(start 70.649846 -433.61864)
		(end 70.51294 -433.755546)
		(stroke
			(width 0.07112)
			(type default)
		)
		(layer "In13.Cu")
	)
	(gr_line
		(start 70.649846 -433.289964)
		(end 70.649846 -433.61864)
		(stroke
			(width 0.07112)
			(type default)
		)
		(layer "In13.Cu")
	)
	(gr_line
		(start 70.669912 -398.871948)
		(end 70.745096 -398.694656)
		(stroke
			(width 0.07112)
			(type default)
		)
		(layer "In13.Cu")
	)
	(gr_line
		(start 70.725284 -402.341334)
		(end 70.900798 -402.420074)
		(stroke
			(width 0.07112)
			(type default)
		)
		(layer "In13.Cu")
	)
	(gr_line
		(start 70.900798 -402.420074)
		(end 71.299832 -402.268182)
		(stroke
			(width 0.07112)
			(type default)
		)
		(layer "In13.Cu")
	)
	(gr_line
		(start 71.299832 -402.268182)
		(end 71.378572 -402.092414)
		(stroke
			(width 0.07112)
			(type default)
		)
		(layer "In13.Cu")
	)
	(gr_line
		(start 71.341234 -411.92196)
		(end 71.341488 -411.922214)
		(stroke
			(width 0.07112)
			(type default)
		)
		(layer "In13.Cu")
	)
	(gr_line
		(start 71.67753 -401.6756)
		(end 72.33285 -401.425664)
		(stroke
			(width 0.07112)
			(type default)
		)
		(layer "In13.Cu")
	)
	(gr_line
		(start 71.689214 -417.263326)
		(end 71.689214 -416.602926)
		(stroke
			(width 0.07112)
			(type default)
		)
		(layer "In13.Cu")
	)
	(gr_line
		(start 71.689214 -416.216846)
		(end 71.689214 -415.556446)
		(stroke
			(width 0.07112)
			(type default)
		)
		(layer "In13.Cu")
	)
	(gr_line
		(start 71.689214 -415.170366)
		(end 71.689214 -414.509966)
		(stroke
			(width 0.07112)
			(type default)
		)
		(layer "In13.Cu")
	)
	(gr_line
		(start 71.730616 -397.9926)
		(end 72.38111 -397.730726)
		(stroke
			(width 0.07112)
			(type default)
		)
		(layer "In13.Cu")
	)
	(gr_line
		(start 71.779384 -401.93976)
		(end 71.954898 -402.0185)
		(stroke
			(width 0.07112)
			(type default)
		)
		(layer "In13.Cu")
	)
	(gr_line
		(start 71.837296 -398.254982)
		(end 72.014334 -398.33042)
		(stroke
			(width 0.07112)
			(type default)
		)
		(layer "In13.Cu")
	)
	(gr_line
		(start 71.954898 -402.0185)
		(end 72.353932 -401.866608)
		(stroke
			(width 0.07112)
			(type default)
		)
		(layer "In13.Cu")
	)
	(gr_line
		(start 71.972424 -417.262056)
		(end 72.108314 -417.126166)
		(stroke
			(width 0.07112)
			(type default)
		)
		(layer "In13.Cu")
	)
	(gr_line
		(start 71.972424 -416.215576)
		(end 72.108314 -416.079686)
		(stroke
			(width 0.07112)
			(type default)
		)
		(layer "In13.Cu")
	)
	(gr_line
		(start 71.972424 -415.169096)
		(end 72.108314 -415.033206)
		(stroke
			(width 0.07112)
			(type default)
		)
		(layer "In13.Cu")
	)
	(gr_line
		(start 72.014334 -398.33042)
		(end 72.410574 -398.170908)
		(stroke
			(width 0.07112)
			(type default)
		)
		(layer "In13.Cu")
	)
	(gr_line
		(start 72.108314 -417.126166)
		(end 72.108314 -416.740086)
		(stroke
			(width 0.07112)
			(type default)
		)
		(layer "In13.Cu")
	)
	(gr_line
		(start 72.108314 -416.740086)
		(end 71.972424 -416.604196)
		(stroke
			(width 0.07112)
			(type default)
		)
		(layer "In13.Cu")
	)
	(gr_line
		(start 72.108314 -416.079686)
		(end 72.108314 -415.693606)
		(stroke
			(width 0.07112)
			(type default)
		)
		(layer "In13.Cu")
	)
	(gr_line
		(start 72.108314 -415.693606)
		(end 71.972424 -415.557716)
		(stroke
			(width 0.07112)
			(type default)
		)
		(layer "In13.Cu")
	)
	(gr_line
		(start 72.108314 -415.033206)
		(end 72.108314 -414.647126)
		(stroke
			(width 0.07112)
			(type default)
		)
		(layer "In13.Cu")
	)
	(gr_line
		(start 72.108314 -414.647126)
		(end 71.972424 -414.511236)
		(stroke
			(width 0.07112)
			(type default)
		)
		(layer "In13.Cu")
	)
	(gr_line
		(start 72.353932 -401.866608)
		(end 72.432672 -401.69084)
		(stroke
			(width 0.07112)
			(type default)
		)
		(layer "In13.Cu")
	)
	(gr_line
		(start 72.410574 -398.170908)
		(end 72.485758 -397.99387)
		(stroke
			(width 0.07112)
			(type default)
		)
		(layer "In13.Cu")
	)
	(gr_line
		(start 72.522842 -435.038754)
		(end 72.511666 -435.038754)
		(stroke
			(width 0.07112)
			(type default)
		)
		(layer "In13.Cu")
	)
	(gr_line
		(start 72.590914 -409.53944)
		(end 72.590914 -408.8384)
		(stroke
			(width 0.07112)
			(type default)
		)
		(layer "In13.Cu")
	)
	(gr_line
		(start 72.590914 -408.41168)
		(end 72.590914 -407.71064)
		(stroke
			(width 0.07112)
			(type default)
		)
		(layer "In13.Cu")
	)
	(gr_line
		(start 72.594978 -402.7551)
		(end 73.239376 -402.479002)
		(stroke
			(width 0.07112)
			(type default)
		)
		(layer "In13.Cu")
	)
	(gr_line
		(start 72.649842 -435.489858)
		(end 72.649842 -435.165754)
		(stroke
			(width 0.07112)
			(type default)
		)
		(layer "In13.Cu")
	)
	(gr_line
		(start 72.649842 -435.165754)
		(end 72.522842 -435.038754)
		(stroke
			(width 0.07112)
			(type default)
		)
		(layer "In13.Cu")
	)
	(gr_line
		(start 72.649842 -434.618638)
		(end 72.512936 -434.755544)
		(stroke
			(width 0.07112)
			(type default)
		)
		(layer "In13.Cu")
	)
	(gr_line
		(start 72.649842 -434.289962)
		(end 72.649842 -434.618638)
		(stroke
			(width 0.07112)
			(type default)
		)
		(layer "In13.Cu")
	)
	(gr_line
		(start 72.706992 -403.015196)
		(end 72.886062 -403.08657)
		(stroke
			(width 0.07112)
			(type default)
		)
		(layer "In13.Cu")
	)
	(gr_line
		(start 72.73163 -401.273772)
		(end 73.38695 -401.02409)
		(stroke
			(width 0.07112)
			(type default)
		)
		(layer "In13.Cu")
	)
	(gr_line
		(start 72.833484 -401.538186)
		(end 73.008998 -401.616926)
		(stroke
			(width 0.07112)
			(type default)
		)
		(layer "In13.Cu")
	)
	(gr_line
		(start 72.874124 -409.53817)
		(end 73.010014 -409.40228)
		(stroke
			(width 0.07112)
			(type default)
		)
		(layer "In13.Cu")
	)
	(gr_line
		(start 72.874124 -408.41041)
		(end 73.010014 -408.27452)
		(stroke
			(width 0.07112)
			(type default)
		)
		(layer "In13.Cu")
	)
	(gr_line
		(start 72.886062 -403.08657)
		(end 73.278492 -402.918676)
		(stroke
			(width 0.07112)
			(type default)
		)
		(layer "In13.Cu")
	)
	(gr_line
		(start 73.008998 -401.616926)
		(end 73.408032 -401.465034)
		(stroke
			(width 0.07112)
			(type default)
		)
		(layer "In13.Cu")
	)
	(gr_line
		(start 73.010014 -409.40228)
		(end 73.010014 -408.97556)
		(stroke
			(width 0.07112)
			(type default)
		)
		(layer "In13.Cu")
	)
	(gr_line
		(start 73.010014 -408.97556)
		(end 72.874124 -408.83967)
		(stroke
			(width 0.07112)
			(type default)
		)
		(layer "In13.Cu")
	)
	(gr_line
		(start 73.010014 -408.27452)
		(end 73.010014 -407.8478)
		(stroke
			(width 0.07112)
			(type default)
		)
		(layer "In13.Cu")
	)
	(gr_line
		(start 73.010014 -407.8478)
		(end 72.874124 -407.71191)
		(stroke
			(width 0.07112)
			(type default)
		)
		(layer "In13.Cu")
	)
	(gr_line
		(start 73.278492 -402.918676)
		(end 73.349612 -402.739606)
		(stroke
			(width 0.07112)
			(type default)
		)
		(layer "In13.Cu")
	)
	(gr_line
		(start 73.343516 -399.728436)
		(end 74.00925 -399.507964)
		(stroke
			(width 0.07112)
			(type default)
		)
		(layer "In13.Cu")
	)
	(gr_line
		(start 73.408032 -401.465034)
		(end 73.487026 -401.289266)
		(stroke
			(width 0.07112)
			(type default)
		)
		(layer "In13.Cu")
	)
	(gr_line
		(start 73.433686 -399.996914)
		(end 73.60539 -400.083274)
		(stroke
			(width 0.07112)
			(type default)
		)
		(layer "In13.Cu")
	)
	(gr_line
		(start 73.60539 -400.083274)
		(end 74.010774 -399.949162)
		(stroke
			(width 0.07112)
			(type default)
		)
		(layer "In13.Cu")
	)
	(gr_line
		(start 73.631552 -402.310854)
		(end 74.276204 -402.034502)
		(stroke
			(width 0.07112)
			(type default)
		)
		(layer "In13.Cu")
	)
	(gr_line
		(start 73.744074 -402.570696)
		(end 73.922636 -402.64207)
		(stroke
			(width 0.07112)
			(type default)
		)
		(layer "In13.Cu")
	)
	(gr_line
		(start 73.785476 -400.872198)
		(end 74.44105 -400.622516)
		(stroke
			(width 0.07112)
			(type default)
		)
		(layer "In13.Cu")
	)
	(gr_line
		(start 73.887584 -401.136612)
		(end 74.063098 -401.215352)
		(stroke
			(width 0.07112)
			(type default)
		)
		(layer "In13.Cu")
	)
	(gr_line
		(start 73.922636 -402.64207)
		(end 74.315066 -402.474176)
		(stroke
			(width 0.07112)
			(type default)
		)
		(layer "In13.Cu")
	)
	(gr_line
		(start 74.010774 -399.949162)
		(end 74.097134 -399.777204)
		(stroke
			(width 0.07112)
			(type default)
		)
		(layer "In13.Cu")
	)
	(gr_line
		(start 74.026776 -398.439386)
		(end 74.694034 -398.223486)
		(stroke
			(width 0.07112)
			(type default)
		)
		(layer "In13.Cu")
	)
	(gr_line
		(start 74.063098 -401.215352)
		(end 74.462132 -401.06346)
		(stroke
			(width 0.07112)
			(type default)
		)
		(layer "In13.Cu")
	)
	(gr_line
		(start 74.115168 -398.708626)
		(end 74.1934 -398.748758)
		(stroke
			(width 0.07112)
			(type default)
		)
		(layer "In13.Cu")
	)
	(gr_line
		(start 74.122534 -424.292522)
		(end 74.122534 -423.591482)
		(stroke
			(width 0.07112)
			(type default)
		)
		(layer "In13.Cu")
	)
	(gr_line
		(start 74.122534 -423.164762)
		(end 74.122534 -422.463722)
		(stroke
			(width 0.07112)
			(type default)
		)
		(layer "In13.Cu")
	)
	(gr_line
		(start 74.122534 -422.037002)
		(end 74.122534 -421.335962)
		(stroke
			(width 0.07112)
			(type default)
		)
		(layer "In13.Cu")
	)
	(gr_line
		(start 74.122534 -420.949882)
		(end 74.122534 -420.289482)
		(stroke
			(width 0.07112)
			(type default)
		)
		(layer "In13.Cu")
	)
	(gr_line
		(start 74.122534 -419.903402)
		(end 74.122534 -419.243002)
		(stroke
			(width 0.07112)
			(type default)
		)
		(layer "In13.Cu")
	)
	(gr_line
		(start 74.1934 -398.748758)
		(end 74.740008 -398.571974)
		(stroke
			(width 0.07112)
			(type default)
		)
		(layer "In13.Cu")
	)
	(gr_line
		(start 74.315066 -402.474176)
		(end 74.386694 -402.29536)
		(stroke
			(width 0.07112)
			(type default)
		)
		(layer "In13.Cu")
	)
	(gr_line
		(start 74.405744 -424.291252)
		(end 74.541634 -424.155362)
		(stroke
			(width 0.07112)
			(type default)
		)
		(layer "In13.Cu")
	)
	(gr_line
		(start 74.405744 -423.163492)
		(end 74.541634 -423.027602)
		(stroke
			(width 0.07112)
			(type default)
		)
		(layer "In13.Cu")
	)
	(gr_line
		(start 74.405744 -422.035732)
		(end 74.541634 -421.899842)
		(stroke
			(width 0.07112)
			(type default)
		)
		(layer "In13.Cu")
	)
	(gr_line
		(start 74.405744 -420.948612)
		(end 74.541634 -420.812722)
		(stroke
			(width 0.07112)
			(type default)
		)
		(layer "In13.Cu")
	)
	(gr_line
		(start 74.405744 -419.902132)
		(end 74.541634 -419.766242)
		(stroke
			(width 0.07112)
			(type default)
		)
		(layer "In13.Cu")
	)
	(gr_line
		(start 74.462132 -401.06346)
		(end 74.541126 -400.887438)
		(stroke
			(width 0.07112)
			(type default)
		)
		(layer "In13.Cu")
	)
	(gr_line
		(start 74.541634 -424.155362)
		(end 74.541634 -423.728642)
		(stroke
			(width 0.07112)
			(type default)
		)
		(layer "In13.Cu")
	)
	(gr_line
		(start 74.541634 -423.728642)
		(end 74.405744 -423.592752)
		(stroke
			(width 0.07112)
			(type default)
		)
		(layer "In13.Cu")
	)
	(gr_line
		(start 74.541634 -423.027602)
		(end 74.541634 -422.600882)
		(stroke
			(width 0.07112)
			(type default)
		)
		(layer "In13.Cu")
	)
	(gr_line
		(start 74.541634 -422.600882)
		(end 74.405744 -422.464992)
		(stroke
			(width 0.07112)
			(type default)
		)
		(layer "In13.Cu")
	)
	(gr_line
		(start 74.541634 -421.899842)
		(end 74.541634 -421.473122)
		(stroke
			(width 0.07112)
			(type default)
		)
		(layer "In13.Cu")
	)
	(gr_line
		(start 74.541634 -421.473122)
		(end 74.405744 -421.337232)
		(stroke
			(width 0.07112)
			(type default)
		)
		(layer "In13.Cu")
	)
	(gr_line
		(start 74.541634 -420.812722)
		(end 74.541634 -420.426642)
		(stroke
			(width 0.07112)
			(type default)
		)
		(layer "In13.Cu")
	)
	(gr_line
		(start 74.541634 -420.426642)
		(end 74.405744 -420.290752)
		(stroke
			(width 0.07112)
			(type default)
		)
		(layer "In13.Cu")
	)
	(gr_line
		(start 74.541634 -419.766242)
		(end 74.541634 -419.380162)
		(stroke
			(width 0.07112)
			(type default)
		)
		(layer "In13.Cu")
	)
	(gr_line
		(start 74.541634 -419.380162)
		(end 74.405744 -419.244272)
		(stroke
			(width 0.07112)
			(type default)
		)
		(layer "In13.Cu")
	)
	(gr_line
		(start 74.66838 -401.866608)
		(end 75.312778 -401.590256)
		(stroke
			(width 0.07112)
			(type default)
		)
		(layer "In13.Cu")
	)
	(gr_line
		(start 74.740008 -398.571974)
		(end 74.78014 -398.493488)
		(stroke
			(width 0.07112)
			(type default)
		)
		(layer "In13.Cu")
	)
	(gr_line
		(start 74.780648 -402.12645)
		(end 74.959464 -402.197824)
		(stroke
			(width 0.07112)
			(type default)
		)
		(layer "In13.Cu")
	)
	(gr_line
		(start 74.839576 -400.470624)
		(end 75.49515 -400.220942)
		(stroke
			(width 0.07112)
			(type default)
		)
		(layer "In13.Cu")
	)
	(gr_line
		(start 74.941684 -400.735038)
		(end 75.117198 -400.813778)
		(stroke
			(width 0.07112)
			(type default)
		)
		(layer "In13.Cu")
	)
	(gr_line
		(start 74.959464 -402.197824)
		(end 75.351894 -402.02993)
		(stroke
			(width 0.07112)
			(type default)
		)
		(layer "In13.Cu")
	)
	(gr_line
		(start 75.108816 -396.84706)
		(end 75.78598 -396.664942)
		(stroke
			(width 0.07112)
			(type default)
		)
		(layer "In13.Cu")
	)
	(gr_line
		(start 75.117198 -400.813778)
		(end 75.516232 -400.661886)
		(stroke
			(width 0.07112)
			(type default)
		)
		(layer "In13.Cu")
	)
	(gr_line
		(start 75.183238 -397.120364)
		(end 75.350116 -397.216376)
		(stroke
			(width 0.07112)
			(type default)
		)
		(layer "In13.Cu")
	)
	(gr_line
		(start 75.350116 -397.216376)
		(end 75.762358 -397.105632)
		(stroke
			(width 0.07112)
			(type default)
		)
		(layer "In13.Cu")
	)
	(gr_line
		(start 75.351894 -402.02993)
		(end 75.423522 -401.85086)
		(stroke
			(width 0.07112)
			(type default)
		)
		(layer "In13.Cu")
	)
	(gr_line
		(start 75.49515 -400.220942)
		(end 75.49515 -400.221196)
		(stroke
			(width 0.07112)
			(type default)
		)
		(layer "In13.Cu")
	)
	(gr_line
		(start 75.516232 -400.661886)
		(end 75.595226 -400.485864)
		(stroke
			(width 0.07112)
			(type default)
		)
		(layer "In13.Cu")
	)
	(gr_line
		(start 75.52309 -434.038756)
		(end 75.511914 -434.038756)
		(stroke
			(width 0.07112)
			(type default)
		)
		(layer "In13.Cu")
	)
	(gr_line
		(start 75.65009 -434.48986)
		(end 75.65009 -434.165756)
		(stroke
			(width 0.07112)
			(type default)
		)
		(layer "In13.Cu")
	)
	(gr_line
		(start 75.65009 -434.165756)
		(end 75.52309 -434.038756)
		(stroke
			(width 0.07112)
			(type default)
		)
		(layer "In13.Cu")
	)
	(gr_line
		(start 75.65009 -433.61864)
		(end 75.513184 -433.755546)
		(stroke
			(width 0.07112)
			(type default)
		)
		(layer "In13.Cu")
	)
	(gr_line
		(start 75.65009 -433.289964)
		(end 75.65009 -433.61864)
		(stroke
			(width 0.07112)
			(type default)
		)
		(layer "In13.Cu")
	)
	(gr_line
		(start 75.654154 -409.569158)
		(end 75.654154 -408.868118)
		(stroke
			(width 0.07112)
			(type default)
		)
		(layer "In13.Cu")
	)
	(gr_line
		(start 75.654154 -408.441398)
		(end 75.654154 -407.740358)
		(stroke
			(width 0.07112)
			(type default)
		)
		(layer "In13.Cu")
	)
	(gr_line
		(start 75.654916 -402.632926)
		(end 76.260452 -402.368766)
		(stroke
			(width 0.07112)
			(type default)
		)
		(layer "In13.Cu")
	)
	(gr_line
		(start 75.7555 -401.400518)
		(end 76.400406 -401.124166)
		(stroke
			(width 0.07112)
			(type default)
		)
		(layer "In13.Cu")
	)
	(gr_line
		(start 75.762358 -397.105632)
		(end 75.858116 -396.938754)
		(stroke
			(width 0.07112)
			(type default)
		)
		(layer "In13.Cu")
	)
	(gr_line
		(start 75.768962 -402.892006)
		(end 75.948286 -402.962364)
		(stroke
			(width 0.07112)
			(type default)
		)
		(layer "In13.Cu")
	)
	(gr_line
		(start 75.868022 -401.66036)
		(end 76.046838 -401.731988)
		(stroke
			(width 0.07112)
			(type default)
		)
		(layer "In13.Cu")
	)
	(gr_line
		(start 75.910186 -400.063208)
		(end 76.565506 -399.813272)
		(stroke
			(width 0.07112)
			(type default)
		)
		(layer "In13.Cu")
	)
	(gr_line
		(start 75.937364 -409.567888)
		(end 76.073254 -409.431998)
		(stroke
			(width 0.07112)
			(type default)
		)
		(layer "In13.Cu")
	)
	(gr_line
		(start 75.937364 -408.440128)
		(end 76.073254 -408.304238)
		(stroke
			(width 0.07112)
			(type default)
		)
		(layer "In13.Cu")
	)
	(gr_line
		(start 75.948286 -402.962364)
		(end 76.302362 -402.808186)
		(stroke
			(width 0.07112)
			(type default)
		)
		(layer "In13.Cu")
	)
	(gr_line
		(start 76.01204 -400.327368)
		(end 76.187554 -400.406108)
		(stroke
			(width 0.07112)
			(type default)
		)
		(layer "In13.Cu")
	)
	(gr_line
		(start 76.046838 -401.731988)
		(end 76.439268 -401.56384)
		(stroke
			(width 0.07112)
			(type default)
		)
		(layer "In13.Cu")
	)
	(gr_line
		(start 76.073254 -409.431998)
		(end 76.073254 -409.005278)
		(stroke
			(width 0.07112)
			(type default)
		)
		(layer "In13.Cu")
	)
	(gr_line
		(start 76.073254 -409.005278)
		(end 75.937364 -408.869388)
		(stroke
			(width 0.07112)
			(type default)
		)
		(layer "In13.Cu")
	)
	(gr_line
		(start 76.073254 -408.304238)
		(end 76.073254 -407.877518)
		(stroke
			(width 0.07112)
			(type default)
		)
		(layer "In13.Cu")
	)
	(gr_line
		(start 76.073254 -407.877518)
		(end 75.937364 -407.741628)
		(stroke
			(width 0.07112)
			(type default)
		)
		(layer "In13.Cu")
	)
	(gr_line
		(start 76.187554 -400.406108)
		(end 76.586588 -400.254216)
		(stroke
			(width 0.07112)
			(type default)
		)
		(layer "In13.Cu")
	)
	(gr_line
		(start 76.302362 -402.808186)
		(end 76.37272 -402.628862)
		(stroke
			(width 0.07112)
			(type default)
		)
		(layer "In13.Cu")
	)
	(gr_line
		(start 76.439268 -401.56384)
		(end 76.510896 -401.385024)
		(stroke
			(width 0.07112)
			(type default)
		)
		(layer "In13.Cu")
	)
	(gr_line
		(start 76.510642 -394.105892)
		(end 77.170026 -393.867386)
		(stroke
			(width 0.07112)
			(type default)
		)
		(layer "In13.Cu")
	)
	(gr_line
		(start 76.586588 -400.254216)
		(end 76.665074 -400.078448)
		(stroke
			(width 0.07112)
			(type default)
		)
		(layer "In13.Cu")
	)
	(gr_line
		(start 76.607924 -394.372084)
		(end 76.782168 -394.453872)
		(stroke
			(width 0.07112)
			(type default)
		)
		(layer "In13.Cu")
	)
	(gr_line
		(start 76.614274 -402.214588)
		(end 77.21981 -401.950428)
		(stroke
			(width 0.07112)
			(type default)
		)
		(layer "In13.Cu")
	)
	(gr_line
		(start 76.689204 -419.88486)
		(end 76.689204 -419.22446)
		(stroke
			(width 0.07112)
			(type default)
		)
		(layer "In13.Cu")
	)
	(gr_line
		(start 76.689204 -418.83838)
		(end 76.689204 -418.17798)
		(stroke
			(width 0.07112)
			(type default)
		)
		(layer "In13.Cu")
	)
	(gr_line
		(start 76.689204 -417.7919)
		(end 76.689204 -417.09086)
		(stroke
			(width 0.07112)
			(type default)
		)
		(layer "In13.Cu")
	)
	(gr_line
		(start 76.72832 -402.473668)
		(end 76.907644 -402.544026)
		(stroke
			(width 0.07112)
			(type default)
		)
		(layer "In13.Cu")
	)
	(gr_line
		(start 76.782168 -394.453872)
		(end 77.183742 -394.308584)
		(stroke
			(width 0.07112)
			(type default)
		)
		(layer "In13.Cu")
	)
	(gr_line
		(start 76.792582 -400.956018)
		(end 77.43698 -400.67992)
		(stroke
			(width 0.07112)
			(type default)
		)
		(layer "In13.Cu")
	)
	(gr_line
		(start 76.90485 -401.216114)
		(end 77.083666 -401.287488)
		(stroke
			(width 0.07112)
			(type default)
		)
		(layer "In13.Cu")
	)
	(gr_line
		(start 76.907644 -402.544026)
		(end 77.26172 -402.389848)
		(stroke
			(width 0.07112)
			(type default)
		)
		(layer "In13.Cu")
	)
	(gr_line
		(start 76.972414 -419.88359)
		(end 77.108304 -419.7477)
		(stroke
			(width 0.07112)
			(type default)
		)
		(layer "In13.Cu")
	)
	(gr_line
		(start 76.972414 -418.83711)
		(end 77.108304 -418.70122)
		(stroke
			(width 0.07112)
			(type default)
		)
		(layer "In13.Cu")
	)
	(gr_line
		(start 76.972414 -417.79063)
		(end 77.108304 -417.65474)
		(stroke
			(width 0.07112)
			(type default)
		)
		(layer "In13.Cu")
	)
	(gr_line
		(start 77.083666 -401.287488)
		(end 77.476096 -401.119594)
		(stroke
			(width 0.07112)
			(type default)
		)
		(layer "In13.Cu")
	)
	(gr_line
		(start 77.108304 -419.7477)
		(end 77.108304 -419.36162)
		(stroke
			(width 0.07112)
			(type default)
		)
		(layer "In13.Cu")
	)
	(gr_line
		(start 77.108304 -419.36162)
		(end 76.972414 -419.22573)
		(stroke
			(width 0.07112)
			(type default)
		)
		(layer "In13.Cu")
	)
	(gr_line
		(start 77.108304 -418.70122)
		(end 77.108304 -418.31514)
		(stroke
			(width 0.07112)
			(type default)
		)
		(layer "In13.Cu")
	)
	(gr_line
		(start 77.108304 -418.31514)
		(end 76.972414 -418.17925)
		(stroke
			(width 0.07112)
			(type default)
		)
		(layer "In13.Cu")
	)
	(gr_line
		(start 77.108304 -417.65474)
		(end 77.108304 -417.22802)
		(stroke
			(width 0.07112)
			(type default)
		)
		(layer "In13.Cu")
	)
	(gr_line
		(start 77.108304 -417.22802)
		(end 76.972414 -417.09213)
		(stroke
			(width 0.07112)
			(type default)
		)
		(layer "In13.Cu")
	)
	(gr_line
		(start 77.183742 -394.308584)
		(end 77.26553 -394.134086)
		(stroke
			(width 0.07112)
			(type default)
		)
		(layer "In13.Cu")
	)
	(gr_line
		(start 77.26172 -402.389848)
		(end 77.332078 -402.210524)
		(stroke
			(width 0.07112)
			(type default)
		)
		(layer "In13.Cu")
	)
	(gr_line
		(start 77.43698 -400.67992)
		(end 77.43698 -400.680174)
		(stroke
			(width 0.07112)
			(type default)
		)
		(layer "In13.Cu")
	)
	(gr_line
		(start 77.476096 -401.119594)
		(end 77.547724 -400.940524)
		(stroke
			(width 0.07112)
			(type default)
		)
		(layer "In13.Cu")
	)
	(gr_line
		(start 77.523086 -435.038754)
		(end 77.51191 -435.038754)
		(stroke
			(width 0.07112)
			(type default)
		)
		(layer "In13.Cu")
	)
	(gr_line
		(start 77.573632 -401.79625)
		(end 78.179168 -401.53209)
		(stroke
			(width 0.07112)
			(type default)
		)
		(layer "In13.Cu")
	)
	(gr_line
		(start 77.650086 -435.489858)
		(end 77.650086 -435.165754)
		(stroke
			(width 0.07112)
			(type default)
		)
		(layer "In13.Cu")
	)
	(gr_line
		(start 77.650086 -435.165754)
		(end 77.523086 -435.038754)
		(stroke
			(width 0.07112)
			(type default)
		)
		(layer "In13.Cu")
	)
	(gr_line
		(start 77.650086 -434.618638)
		(end 77.51318 -434.755544)
		(stroke
			(width 0.07112)
			(type default)
		)
		(layer "In13.Cu")
	)
	(gr_line
		(start 77.650086 -434.289962)
		(end 77.650086 -434.618638)
		(stroke
			(width 0.07112)
			(type default)
		)
		(layer "In13.Cu")
	)
	(gr_line
		(start 77.687678 -402.05533)
		(end 77.867002 -402.125688)
		(stroke
			(width 0.07112)
			(type default)
		)
		(layer "In13.Cu")
	)
	(gr_line
		(start 77.867002 -402.125688)
		(end 78.221078 -401.97151)
		(stroke
			(width 0.07112)
			(type default)
		)
		(layer "In13.Cu")
	)
	(gr_line
		(start 78.221078 -401.97151)
		(end 78.291436 -401.792186)
		(stroke
			(width 0.07112)
			(type default)
		)
		(layer "In13.Cu")
	)
	(gr_arc
		(start 78.436978 -400.56181)
		(mid 78.438121 -400.561429)
		(end 78.439264 -400.561048)
		(stroke
			(width 0.07112)
			(type default)
		)
		(layer "In13.Cu")
	)
	(gr_line
		(start 78.53299 -401.377912)
		(end 79.138526 -401.113752)
		(stroke
			(width 0.07112)
			(type default)
		)
		(layer "In13.Cu")
	)
	(gr_line
		(start 78.64729 -401.636992)
		(end 78.82636 -401.70735)
		(stroke
			(width 0.07112)
			(type default)
		)
		(layer "In13.Cu")
	)
	(gr_line
		(start 78.717394 -409.360878)
		(end 78.717394 -408.659838)
		(stroke
			(width 0.07112)
			(type default)
		)
		(layer "In13.Cu")
	)
	(gr_line
		(start 78.717394 -408.233118)
		(end 78.717394 -407.532078)
		(stroke
			(width 0.07112)
			(type default)
		)
		(layer "In13.Cu")
	)
	(gr_line
		(start 78.82636 -401.70735)
		(end 79.180436 -401.553172)
		(stroke
			(width 0.07112)
			(type default)
		)
		(layer "In13.Cu")
	)
	(gr_line
		(start 78.881478 -422.61536)
		(end 78.881478 -421.95496)
		(stroke
			(width 0.07112)
			(type default)
		)
		(layer "In13.Cu")
	)
	(gr_line
		(start 78.881478 -421.51681)
		(end 78.881478 -420.85641)
		(stroke
			(width 0.07112)
			(type default)
		)
		(layer "In13.Cu")
	)
	(gr_line
		(start 78.881478 -420.47033)
		(end 78.881478 -419.76929)
		(stroke
			(width 0.07112)
			(type default)
		)
		(layer "In13.Cu")
	)
	(gr_line
		(start 78.881478 -419.34257)
		(end 78.881478 -418.64153)
		(stroke
			(width 0.07112)
			(type default)
		)
		(layer "In13.Cu")
	)
	(gr_line
		(start 79.000604 -409.359608)
		(end 79.136494 -409.223718)
		(stroke
			(width 0.07112)
			(type default)
		)
		(layer "In13.Cu")
	)
	(gr_line
		(start 79.000604 -408.231848)
		(end 79.136494 -408.095958)
		(stroke
			(width 0.07112)
			(type default)
		)
		(layer "In13.Cu")
	)
	(gr_line
		(start 79.136494 -409.223718)
		(end 79.136494 -408.796998)
		(stroke
			(width 0.07112)
			(type default)
		)
		(layer "In13.Cu")
	)
	(gr_line
		(start 79.136494 -408.796998)
		(end 79.000604 -408.661108)
		(stroke
			(width 0.07112)
			(type default)
		)
		(layer "In13.Cu")
	)
	(gr_line
		(start 79.136494 -408.095958)
		(end 79.136494 -407.669238)
		(stroke
			(width 0.07112)
			(type default)
		)
		(layer "In13.Cu")
	)
	(gr_line
		(start 79.136494 -407.669238)
		(end 79.000604 -407.533348)
		(stroke
			(width 0.07112)
			(type default)
		)
		(layer "In13.Cu")
	)
	(gr_line
		(start 79.164688 -422.61409)
		(end 79.300578 -422.4782)
		(stroke
			(width 0.07112)
			(type default)
		)
		(layer "In13.Cu")
	)
	(gr_line
		(start 79.164688 -421.51554)
		(end 79.300578 -421.37965)
		(stroke
			(width 0.07112)
			(type default)
		)
		(layer "In13.Cu")
	)
	(gr_line
		(start 79.164688 -420.46906)
		(end 79.300578 -420.33317)
		(stroke
			(width 0.07112)
			(type default)
		)
		(layer "In13.Cu")
	)
	(gr_line
		(start 79.164688 -419.3413)
		(end 79.300578 -419.20541)
		(stroke
			(width 0.07112)
			(type default)
		)
		(layer "In13.Cu")
	)
	(gr_line
		(start 79.180436 -401.553172)
		(end 79.250794 -401.373848)
		(stroke
			(width 0.07112)
			(type default)
		)
		(layer "In13.Cu")
	)
	(gr_line
		(start 79.300578 -422.4782)
		(end 79.300578 -422.09212)
		(stroke
			(width 0.07112)
			(type default)
		)
		(layer "In13.Cu")
	)
	(gr_line
		(start 79.300578 -422.09212)
		(end 79.164688 -421.95623)
		(stroke
			(width 0.07112)
			(type default)
		)
		(layer "In13.Cu")
	)
	(gr_line
		(start 79.300578 -421.37965)
		(end 79.300578 -420.99357)
		(stroke
			(width 0.07112)
			(type default)
		)
		(layer "In13.Cu")
	)
	(gr_line
		(start 79.300578 -420.99357)
		(end 79.164688 -420.85768)
		(stroke
			(width 0.07112)
			(type default)
		)
		(layer "In13.Cu")
	)
	(gr_line
		(start 79.300578 -420.33317)
		(end 79.300578 -419.90645)
		(stroke
			(width 0.07112)
			(type default)
		)
		(layer "In13.Cu")
	)
	(gr_line
		(start 79.300578 -419.90645)
		(end 79.164688 -419.77056)
		(stroke
			(width 0.07112)
			(type default)
		)
		(layer "In13.Cu")
	)
	(gr_line
		(start 79.300578 -419.20541)
		(end 79.300578 -418.77869)
		(stroke
			(width 0.07112)
			(type default)
		)
		(layer "In13.Cu")
	)
	(gr_line
		(start 79.300578 -418.77869)
		(end 79.164688 -418.6428)
		(stroke
			(width 0.07112)
			(type default)
		)
		(layer "In13.Cu")
	)
	(gr_line
		(start 79.411322 -402.310092)
		(end 80.059022 -402.041614)
		(stroke
			(width 0.07112)
			(type default)
		)
		(layer "In13.Cu")
	)
	(gr_line
		(start 79.492348 -400.959574)
		(end 80.097884 -400.695414)
		(stroke
			(width 0.07112)
			(type default)
		)
		(layer "In13.Cu")
	)
	(gr_line
		(start 79.520796 -402.571204)
		(end 79.698342 -402.645118)
		(stroke
			(width 0.07112)
			(type default)
		)
		(layer "In13.Cu")
	)
	(gr_line
		(start 79.535782 -433.73294)
		(end 79.499206 -433.73294)
		(stroke
			(width 0.07112)
			(type default)
		)
		(layer "In13.Cu")
	)
	(gr_line
		(start 79.606648 -401.218654)
		(end 79.785718 -401.289012)
		(stroke
			(width 0.07112)
			(type default)
		)
		(layer "In13.Cu")
	)
	(gr_line
		(start 79.650082 -434.48986)
		(end 79.650082 -434.165756)
		(stroke
			(width 0.07112)
			(type default)
		)
		(layer "In13.Cu")
	)
	(gr_line
		(start 79.650082 -434.165756)
		(end 79.500476 -434.01615)
		(stroke
			(width 0.07112)
			(type default)
		)
		(layer "In13.Cu")
	)
	(gr_line
		(start 79.650082 -433.61864)
		(end 79.535782 -433.73294)
		(stroke
			(width 0.07112)
			(type default)
		)
		(layer "In13.Cu")
	)
	(gr_line
		(start 79.650082 -433.289964)
		(end 79.650082 -433.61864)
		(stroke
			(width 0.07112)
			(type default)
		)
		(layer "In13.Cu")
	)
	(gr_line
		(start 79.698342 -402.645118)
		(end 80.092804 -402.481542)
		(stroke
			(width 0.07112)
			(type default)
		)
		(layer "In13.Cu")
	)
	(gr_line
		(start 79.785718 -401.289012)
		(end 80.139794 -401.134834)
		(stroke
			(width 0.07112)
			(type default)
		)
		(layer "In13.Cu")
	)
	(gr_line
		(start 80.053434 -393.002008)
		(end 80.344264 -393.292838)
		(stroke
			(width 0.07112)
			(type default)
		)
		(layer "In13.Cu")
	)
	(gr_line
		(start 80.053434 -392.720068)
		(end 80.344264 -392.429238)
		(stroke
			(width 0.07112)
			(type default)
		)
		(layer "In13.Cu")
	)
	(gr_line
		(start 80.092804 -402.481542)
		(end 80.16621 -402.303742)
		(stroke
			(width 0.07112)
			(type default)
		)
		(layer "In13.Cu")
	)
	(gr_line
		(start 80.139794 -401.134834)
		(end 80.210152 -400.95551)
		(stroke
			(width 0.07112)
			(type default)
		)
		(layer "In13.Cu")
	)
	(gr_line
		(start 80.521302 -401.850098)
		(end 81.169002 -401.58162)
		(stroke
			(width 0.07112)
			(type default)
		)
		(layer "In13.Cu")
	)
	(gr_line
		(start 80.630776 -402.11121)
		(end 80.808322 -402.185124)
		(stroke
			(width 0.07112)
			(type default)
		)
		(layer "In13.Cu")
	)
	(gr_line
		(start 80.689196 -419.956488)
		(end 80.689196 -419.296088)
		(stroke
			(width 0.07112)
			(type default)
		)
		(layer "In13.Cu")
	)
	(gr_line
		(start 80.689196 -418.910008)
		(end 80.689196 -418.249608)
		(stroke
			(width 0.07112)
			(type default)
		)
		(layer "In13.Cu")
	)
	(gr_line
		(start 80.808322 -402.185124)
		(end 81.202784 -402.021548)
		(stroke
			(width 0.07112)
			(type default)
		)
		(layer "In13.Cu")
	)
	(gr_line
		(start 80.972406 -419.955218)
		(end 81.108296 -419.819328)
		(stroke
			(width 0.07112)
			(type default)
		)
		(layer "In13.Cu")
	)
	(gr_line
		(start 80.972406 -418.908738)
		(end 81.108296 -418.772848)
		(stroke
			(width 0.07112)
			(type default)
		)
		(layer "In13.Cu")
	)
	(gr_line
		(start 81.108296 -419.819328)
		(end 81.108296 -419.433248)
		(stroke
			(width 0.07112)
			(type default)
		)
		(layer "In13.Cu")
	)
	(gr_line
		(start 81.108296 -419.433248)
		(end 80.972406 -419.297358)
		(stroke
			(width 0.07112)
			(type default)
		)
		(layer "In13.Cu")
	)
	(gr_line
		(start 81.108296 -418.772848)
		(end 81.108296 -418.386768)
		(stroke
			(width 0.07112)
			(type default)
		)
		(layer "In13.Cu")
	)
	(gr_line
		(start 81.108296 -418.386768)
		(end 80.972406 -418.250878)
		(stroke
			(width 0.07112)
			(type default)
		)
		(layer "In13.Cu")
	)
	(gr_line
		(start 81.169002 -401.58162)
		(end 81.169256 -401.58162)
		(stroke
			(width 0.07112)
			(type default)
		)
		(layer "In13.Cu")
	)
	(gr_line
		(start 81.202784 -402.021548)
		(end 81.276444 -401.843748)
		(stroke
			(width 0.07112)
			(type default)
		)
		(layer "In13.Cu")
	)
	(gr_line
		(start 81.33334 -416.612832)
		(end 81.829402 -416.11677)
		(stroke
			(width 0.07112)
			(type default)
		)
		(layer "In13.Cu")
	)
	(gr_line
		(start 81.40573 -393.017756)
		(end 81.41716 -393.017756)
		(stroke
			(width 0.07112)
			(type default)
		)
		(layer "In13.Cu")
	)
	(gr_line
		(start 81.407 -392.734546)
		(end 81.54416 -392.597386)
		(stroke
			(width 0.07112)
			(type default)
		)
		(layer "In13.Cu")
	)
	(gr_line
		(start 81.41716 -393.017756)
		(end 81.54416 -393.144756)
		(stroke
			(width 0.07112)
			(type default)
		)
		(layer "In13.Cu")
	)
	(gr_line
		(start 81.5213 -434.747416)
		(end 81.51368 -434.747416)
		(stroke
			(width 0.07112)
			(type default)
		)
		(layer "In13.Cu")
	)
	(gr_line
		(start 81.534508 -416.812222)
		(end 81.726786 -416.812222)
		(stroke
			(width 0.07112)
			(type default)
		)
		(layer "In13.Cu")
	)
	(gr_line
		(start 81.54416 -393.144756)
		(end 81.54416 -393.292838)
		(stroke
			(width 0.07112)
			(type default)
		)
		(layer "In13.Cu")
	)
	(gr_line
		(start 81.54416 -392.597386)
		(end 81.54416 -392.429238)
		(stroke
			(width 0.07112)
			(type default)
		)
		(layer "In13.Cu")
	)
	(gr_line
		(start 81.650078 -435.489858)
		(end 81.650078 -435.165754)
		(stroke
			(width 0.07112)
			(type default)
		)
		(layer "In13.Cu")
	)
	(gr_line
		(start 81.650078 -435.165754)
		(end 81.51495 -435.030626)
		(stroke
			(width 0.07112)
			(type default)
		)
		(layer "In13.Cu")
	)
	(gr_line
		(start 81.650078 -434.618638)
		(end 81.5213 -434.747416)
		(stroke
			(width 0.07112)
			(type default)
		)
		(layer "In13.Cu")
	)
	(gr_line
		(start 81.650078 -434.289962)
		(end 81.650078 -434.618638)
		(stroke
			(width 0.07112)
			(type default)
		)
		(layer "In13.Cu")
	)
	(gr_line
		(start 81.726786 -416.812222)
		(end 82.028792 -416.510216)
		(stroke
			(width 0.07112)
			(type default)
		)
		(layer "In13.Cu")
	)
	(gr_line
		(start 81.780634 -409.415234)
		(end 81.780634 -408.714194)
		(stroke
			(width 0.07112)
			(type default)
		)
		(layer "In13.Cu")
	)
	(gr_line
		(start 81.780634 -408.287474)
		(end 81.780634 -407.586434)
		(stroke
			(width 0.07112)
			(type default)
		)
		(layer "In13.Cu")
	)
	(gr_line
		(start 81.94167 -398.967706)
		(end 82.59953 -398.724882)
		(stroke
			(width 0.07112)
			(type default)
		)
		(layer "In13.Cu")
	)
	(gr_line
		(start 82.012028 -402.410676)
		(end 82.659728 -402.142198)
		(stroke
			(width 0.07112)
			(type default)
		)
		(layer "In13.Cu")
	)
	(gr_line
		(start 82.028792 -416.510216)
		(end 82.028792 -416.317938)
		(stroke
			(width 0.07112)
			(type default)
		)
		(layer "In13.Cu")
	)
	(gr_line
		(start 82.04073 -399.233136)
		(end 82.215482 -399.313654)
		(stroke
			(width 0.07112)
			(type default)
		)
		(layer "In13.Cu")
	)
	(gr_line
		(start 82.063844 -409.413964)
		(end 82.199734 -409.278074)
		(stroke
			(width 0.07112)
			(type default)
		)
		(layer "In13.Cu")
	)
	(gr_line
		(start 82.063844 -408.286204)
		(end 82.199734 -408.150314)
		(stroke
			(width 0.07112)
			(type default)
		)
		(layer "In13.Cu")
	)
	(gr_line
		(start 82.121502 -402.671788)
		(end 82.299048 -402.745702)
		(stroke
			(width 0.07112)
			(type default)
		)
		(layer "In13.Cu")
	)
	(gr_line
		(start 82.1309 -415.815272)
		(end 82.626962 -415.31921)
		(stroke
			(width 0.07112)
			(type default)
		)
		(layer "In13.Cu")
	)
	(gr_line
		(start 82.199734 -409.278074)
		(end 82.199734 -408.851354)
		(stroke
			(width 0.07112)
			(type default)
		)
		(layer "In13.Cu")
	)
	(gr_line
		(start 82.199734 -408.851354)
		(end 82.063844 -408.715464)
		(stroke
			(width 0.07112)
			(type default)
		)
		(layer "In13.Cu")
	)
	(gr_line
		(start 82.199734 -408.150314)
		(end 82.199734 -407.723594)
		(stroke
			(width 0.07112)
			(type default)
		)
		(layer "In13.Cu")
	)
	(gr_line
		(start 82.199734 -407.723594)
		(end 82.063844 -407.587704)
		(stroke
			(width 0.07112)
			(type default)
		)
		(layer "In13.Cu")
	)
	(gr_line
		(start 82.215482 -399.313654)
		(end 82.61604 -399.165826)
		(stroke
			(width 0.07112)
			(type default)
		)
		(layer "In13.Cu")
	)
	(gr_line
		(start 82.299048 -402.745702)
		(end 82.69351 -402.58238)
		(stroke
			(width 0.07112)
			(type default)
		)
		(layer "In13.Cu")
	)
	(gr_line
		(start 82.332068 -416.014662)
		(end 82.524346 -416.014662)
		(stroke
			(width 0.07112)
			(type default)
		)
		(layer "In13.Cu")
	)
	(gr_line
		(start 82.524346 -416.014662)
		(end 82.826352 -415.712656)
		(stroke
			(width 0.07112)
			(type default)
		)
		(layer "In13.Cu")
	)
	(gr_line
		(start 82.60588 -393.017756)
		(end 82.61731 -393.017756)
		(stroke
			(width 0.07112)
			(type default)
		)
		(layer "In13.Cu")
	)
	(gr_line
		(start 82.60715 -392.734546)
		(end 82.74431 -392.597386)
		(stroke
			(width 0.07112)
			(type default)
		)
		(layer "In13.Cu")
	)
	(gr_line
		(start 82.61604 -399.165826)
		(end 82.696558 -398.991074)
		(stroke
			(width 0.07112)
			(type default)
		)
		(layer "In13.Cu")
	)
	(gr_line
		(start 82.61731 -393.017756)
		(end 82.74431 -393.144756)
		(stroke
			(width 0.07112)
			(type default)
		)
		(layer "In13.Cu")
	)
	(gr_line
		(start 82.639154 -399.875756)
		(end 83.287362 -399.607532)
		(stroke
			(width 0.07112)
			(type default)
		)
		(layer "In13.Cu")
	)
	(gr_line
		(start 82.689192 -420.523162)
		(end 82.689192 -419.822122)
		(stroke
			(width 0.07112)
			(type default)
		)
		(layer "In13.Cu")
	)
	(gr_line
		(start 82.689192 -419.395402)
		(end 82.689192 -418.735002)
		(stroke
			(width 0.07112)
			(type default)
		)
		(layer "In13.Cu")
	)
	(gr_line
		(start 82.69351 -402.58238)
		(end 82.766916 -402.404326)
		(stroke
			(width 0.07112)
			(type default)
		)
		(layer "In13.Cu")
	)
	(gr_line
		(start 82.74431 -393.144756)
		(end 82.74431 -393.292838)
		(stroke
			(width 0.07112)
			(type default)
		)
		(layer "In13.Cu")
	)
	(gr_line
		(start 82.74431 -392.597386)
		(end 82.74431 -392.429238)
		(stroke
			(width 0.07112)
			(type default)
		)
		(layer "In13.Cu")
	)
	(gr_line
		(start 82.748628 -400.136868)
		(end 82.926428 -400.210782)
		(stroke
			(width 0.07112)
			(type default)
		)
		(layer "In13.Cu")
	)
	(gr_line
		(start 82.826352 -415.712656)
		(end 82.826352 -415.520378)
		(stroke
			(width 0.07112)
			(type default)
		)
		(layer "In13.Cu")
	)
	(gr_line
		(start 82.926428 -400.210782)
		(end 83.32089 -400.047714)
		(stroke
			(width 0.07112)
			(type default)
		)
		(layer "In13.Cu")
	)
	(gr_line
		(start 82.972402 -420.521892)
		(end 83.108292 -420.386002)
		(stroke
			(width 0.07112)
			(type default)
		)
		(layer "In13.Cu")
	)
	(gr_line
		(start 82.972402 -419.394132)
		(end 83.108292 -419.258242)
		(stroke
			(width 0.07112)
			(type default)
		)
		(layer "In13.Cu")
	)
	(gr_line
		(start 83.083654 -401.966684)
		(end 83.731354 -401.698206)
		(stroke
			(width 0.07112)
			(type default)
		)
		(layer "In13.Cu")
	)
	(gr_line
		(start 83.108292 -420.386002)
		(end 83.108292 -419.959282)
		(stroke
			(width 0.07112)
			(type default)
		)
		(layer "In13.Cu")
	)
	(gr_line
		(start 83.108292 -419.959282)
		(end 82.972402 -419.823392)
		(stroke
			(width 0.07112)
			(type default)
		)
		(layer "In13.Cu")
	)
	(gr_line
		(start 83.108292 -419.258242)
		(end 83.108292 -418.872162)
		(stroke
			(width 0.07112)
			(type default)
		)
		(layer "In13.Cu")
	)
	(gr_line
		(start 83.108292 -418.872162)
		(end 82.972402 -418.736272)
		(stroke
			(width 0.07112)
			(type default)
		)
		(layer "In13.Cu")
	)
	(gr_line
		(start 83.193128 -402.227796)
		(end 83.370674 -402.301456)
		(stroke
			(width 0.07112)
			(type default)
		)
		(layer "In13.Cu")
	)
	(gr_line
		(start 83.32089 -400.047714)
		(end 83.394804 -399.86966)
		(stroke
			(width 0.07112)
			(type default)
		)
		(layer "In13.Cu")
	)
	(gr_line
		(start 83.339686 -417.029646)
		(end 83.835748 -416.533584)
		(stroke
			(width 0.07112)
			(type default)
		)
		(layer "In13.Cu")
	)
	(gr_line
		(start 83.370674 -402.301456)
		(end 83.765136 -402.138134)
		(stroke
			(width 0.07112)
			(type default)
		)
		(layer "In13.Cu")
	)
	(gr_line
		(start 83.53171 -434.047392)
		(end 83.503262 -434.047392)
		(stroke
			(width 0.07112)
			(type default)
		)
		(layer "In13.Cu")
	)
	(gr_line
		(start 83.540854 -417.229036)
		(end 83.733132 -417.229036)
		(stroke
			(width 0.07112)
			(type default)
		)
		(layer "In13.Cu")
	)
	(gr_line
		(start 83.650074 -434.48986)
		(end 83.650074 -434.165756)
		(stroke
			(width 0.07112)
			(type default)
		)
		(layer "In13.Cu")
	)
	(gr_line
		(start 83.650074 -434.165756)
		(end 83.53171 -434.047392)
		(stroke
			(width 0.07112)
			(type default)
		)
		(layer "In13.Cu")
	)
	(gr_line
		(start 83.650074 -433.61864)
		(end 83.504532 -433.764182)
		(stroke
			(width 0.07112)
			(type default)
		)
		(layer "In13.Cu")
	)
	(gr_line
		(start 83.650074 -433.289964)
		(end 83.650074 -433.61864)
		(stroke
			(width 0.07112)
			(type default)
		)
		(layer "In13.Cu")
	)
	(gr_line
		(start 83.733132 -417.229036)
		(end 84.035138 -416.92703)
		(stroke
			(width 0.07112)
			(type default)
		)
		(layer "In13.Cu")
	)
	(gr_line
		(start 83.765136 -402.138134)
		(end 83.838542 -401.960334)
		(stroke
			(width 0.07112)
			(type default)
		)
		(layer "In13.Cu")
	)
	(gr_line
		(start 83.805776 -393.017756)
		(end 83.817206 -393.017756)
		(stroke
			(width 0.07112)
			(type default)
		)
		(layer "In13.Cu")
	)
	(gr_line
		(start 83.807046 -392.734546)
		(end 83.944206 -392.597386)
		(stroke
			(width 0.07112)
			(type default)
		)
		(layer "In13.Cu")
	)
	(gr_line
		(start 83.817206 -393.017756)
		(end 83.944206 -393.144756)
		(stroke
			(width 0.07112)
			(type default)
		)
		(layer "In13.Cu")
	)
	(gr_line
		(start 83.944206 -393.144756)
		(end 83.944206 -393.292838)
		(stroke
			(width 0.07112)
			(type default)
		)
		(layer "In13.Cu")
	)
	(gr_line
		(start 83.944206 -392.597386)
		(end 83.944206 -392.429238)
		(stroke
			(width 0.07112)
			(type default)
		)
		(layer "In13.Cu")
	)
	(gr_line
		(start 84.035138 -416.92703)
		(end 84.035138 -416.734752)
		(stroke
			(width 0.07112)
			(type default)
		)
		(layer "In13.Cu")
	)
	(gr_line
		(start 84.137246 -416.232086)
		(end 84.633308 -415.736024)
		(stroke
			(width 0.07112)
			(type default)
		)
		(layer "In13.Cu")
	)
	(gr_line
		(start 84.338414 -416.431476)
		(end 84.530692 -416.431476)
		(stroke
			(width 0.07112)
			(type default)
		)
		(layer "In13.Cu")
	)
	(gr_line
		(start 84.530692 -416.431476)
		(end 84.832698 -416.12947)
		(stroke
			(width 0.07112)
			(type default)
		)
		(layer "In13.Cu")
	)
	(gr_line
		(start 84.832698 -416.12947)
		(end 84.832698 -415.937192)
		(stroke
			(width 0.07112)
			(type default)
		)
		(layer "In13.Cu")
	)
	(gr_line
		(start 84.843874 -409.387294)
		(end 84.843874 -408.686254)
		(stroke
			(width 0.07112)
			(type default)
		)
		(layer "In13.Cu")
	)
	(gr_line
		(start 84.843874 -408.259534)
		(end 84.843874 -407.558494)
		(stroke
			(width 0.07112)
			(type default)
		)
		(layer "In13.Cu")
	)
	(gr_line
		(start 84.934806 -415.434526)
		(end 85.430868 -414.938464)
		(stroke
			(width 0.07112)
			(type default)
		)
		(layer "In13.Cu")
	)
	(gr_line
		(start 85.005926 -393.017756)
		(end 85.017356 -393.017756)
		(stroke
			(width 0.07112)
			(type default)
		)
		(layer "In13.Cu")
	)
	(gr_line
		(start 85.007196 -392.734546)
		(end 85.144356 -392.597386)
		(stroke
			(width 0.07112)
			(type default)
		)
		(layer "In13.Cu")
	)
	(gr_line
		(start 85.017356 -393.017756)
		(end 85.144356 -393.144756)
		(stroke
			(width 0.07112)
			(type default)
		)
		(layer "In13.Cu")
	)
	(gr_line
		(start 85.034628 -395.792198)
		(end 85.034882 -395.792198)
		(stroke
			(width 0.07112)
			(type default)
		)
		(layer "In13.Cu")
	)
	(gr_arc
		(start 85.04428 -401.077176)
		(mid 85.045169 -401.076542)
		(end 85.046058 -401.075906)
		(stroke
			(width 0.07112)
			(type default)
		)
		(layer "In13.Cu")
	)
	(gr_line
		(start 85.127084 -409.386024)
		(end 85.262974 -409.250134)
		(stroke
			(width 0.07112)
			(type default)
		)
		(layer "In13.Cu")
	)
	(gr_line
		(start 85.127084 -408.258264)
		(end 85.262974 -408.122374)
		(stroke
			(width 0.07112)
			(type default)
		)
		(layer "In13.Cu")
	)
	(gr_line
		(start 85.135974 -415.633916)
		(end 85.328252 -415.633916)
		(stroke
			(width 0.07112)
			(type default)
		)
		(layer "In13.Cu")
	)
	(gr_line
		(start 85.144356 -393.144756)
		(end 85.144356 -393.292838)
		(stroke
			(width 0.07112)
			(type default)
		)
		(layer "In13.Cu")
	)
	(gr_line
		(start 85.144356 -392.597386)
		(end 85.144356 -392.429238)
		(stroke
			(width 0.07112)
			(type default)
		)
		(layer "In13.Cu")
	)
	(gr_line
		(start 85.179916 -399.740882)
		(end 85.719412 -399.292572)
		(stroke
			(width 0.07112)
			(type default)
		)
		(layer "In13.Cu")
	)
	(gr_arc
		(start 85.234272 -395.991588)
		(mid 85.234145 -395.991715)
		(end 85.234018 -395.991842)
		(stroke
			(width 0.07112)
			(type default)
		)
		(layer "In13.Cu")
	)
	(gr_line
		(start 85.262974 -409.250134)
		(end 85.262974 -408.823414)
		(stroke
			(width 0.07112)
			(type default)
		)
		(layer "In13.Cu")
	)
	(gr_line
		(start 85.262974 -408.823414)
		(end 85.127084 -408.687524)
		(stroke
			(width 0.07112)
			(type default)
		)
		(layer "In13.Cu")
	)
	(gr_line
		(start 85.262974 -408.122374)
		(end 85.262974 -407.695654)
		(stroke
			(width 0.07112)
			(type default)
		)
		(layer "In13.Cu")
	)
	(gr_line
		(start 85.262974 -407.695654)
		(end 85.127084 -407.559764)
		(stroke
			(width 0.07112)
			(type default)
		)
		(layer "In13.Cu")
	)
	(gr_line
		(start 85.328252 -415.633916)
		(end 85.630258 -415.33191)
		(stroke
			(width 0.07112)
			(type default)
		)
		(layer "In13.Cu")
	)
	(gr_line
		(start 85.36178 -399.958052)
		(end 85.445854 -399.965672)
		(stroke
			(width 0.07112)
			(type default)
		)
		(layer "In13.Cu")
	)
	(gr_line
		(start 85.445854 -399.965672)
		(end 85.891878 -399.594832)
		(stroke
			(width 0.07112)
			(type default)
		)
		(layer "In13.Cu")
	)
	(gr_line
		(start 85.528912 -434.739796)
		(end 85.506052 -434.739796)
		(stroke
			(width 0.07112)
			(type default)
		)
		(layer "In13.Cu")
	)
	(gr_line
		(start 85.630258 -415.33191)
		(end 85.630258 -415.139632)
		(stroke
			(width 0.07112)
			(type default)
		)
		(layer "In13.Cu")
	)
	(gr_line
		(start 85.65007 -435.489858)
		(end 85.65007 -435.165754)
		(stroke
			(width 0.07112)
			(type default)
		)
		(layer "In13.Cu")
	)
	(gr_line
		(start 85.65007 -435.165754)
		(end 85.507322 -435.023006)
		(stroke
			(width 0.07112)
			(type default)
		)
		(layer "In13.Cu")
	)
	(gr_line
		(start 85.65007 -434.618638)
		(end 85.528912 -434.739796)
		(stroke
			(width 0.07112)
			(type default)
		)
		(layer "In13.Cu")
	)
	(gr_line
		(start 85.65007 -434.289962)
		(end 85.65007 -434.618638)
		(stroke
			(width 0.07112)
			(type default)
		)
		(layer "In13.Cu")
	)
	(gr_line
		(start 85.724238 -417.808918)
		(end 86.2203 -417.312856)
		(stroke
			(width 0.07112)
			(type default)
		)
		(layer "In13.Cu")
	)
	(gr_line
		(start 85.891878 -399.594832)
		(end 85.899498 -399.510758)
		(stroke
			(width 0.07112)
			(type default)
		)
		(layer "In13.Cu")
	)
	(gr_line
		(start 85.925406 -418.008308)
		(end 86.117684 -418.008308)
		(stroke
			(width 0.07112)
			(type default)
		)
		(layer "In13.Cu")
	)
	(gr_line
		(start 86.040976 -401.638008)
		(end 86.62035 -401.242276)
		(stroke
			(width 0.07112)
			(type default)
		)
		(layer "In13.Cu")
	)
	(gr_line
		(start 86.117684 -418.008308)
		(end 86.41969 -417.706302)
		(stroke
			(width 0.07112)
			(type default)
		)
		(layer "In13.Cu")
	)
	(gr_line
		(start 86.201758 -401.87118)
		(end 86.390988 -401.90674)
		(stroke
			(width 0.07112)
			(type default)
		)
		(layer "In13.Cu")
	)
	(gr_line
		(start 86.205822 -393.017756)
		(end 86.217252 -393.017756)
		(stroke
			(width 0.07112)
			(type default)
		)
		(layer "In13.Cu")
	)
	(gr_line
		(start 86.207092 -392.734546)
		(end 86.344252 -392.597386)
		(stroke
			(width 0.07112)
			(type default)
		)
		(layer "In13.Cu")
	)
	(gr_line
		(start 86.217252 -393.017756)
		(end 86.344252 -393.144756)
		(stroke
			(width 0.07112)
			(type default)
		)
		(layer "In13.Cu")
	)
	(gr_line
		(start 86.344252 -393.144756)
		(end 86.344252 -393.292838)
		(stroke
			(width 0.07112)
			(type default)
		)
		(layer "In13.Cu")
	)
	(gr_line
		(start 86.344252 -392.597386)
		(end 86.344252 -392.429238)
		(stroke
			(width 0.07112)
			(type default)
		)
		(layer "In13.Cu")
	)
	(gr_line
		(start 86.390988 -401.90674)
		(end 86.74354 -401.665694)
		(stroke
			(width 0.07112)
			(type default)
		)
		(layer "In13.Cu")
	)
	(gr_line
		(start 86.41969 -417.706302)
		(end 86.41969 -417.514024)
		(stroke
			(width 0.07112)
			(type default)
		)
		(layer "In13.Cu")
	)
	(gr_line
		(start 86.493096 -417.04006)
		(end 86.960456 -416.5727)
		(stroke
			(width 0.07112)
			(type default)
		)
		(layer "In13.Cu")
	)
	(gr_line
		(start 86.514432 -399.913094)
		(end 87.010494 -399.417286)
		(stroke
			(width 0.07112)
			(type default)
		)
		(layer "In13.Cu")
	)
	(gr_line
		(start 86.694264 -417.23945)
		(end 86.886542 -417.23945)
		(stroke
			(width 0.07112)
			(type default)
		)
		(layer "In13.Cu")
	)
	(gr_line
		(start 86.715346 -400.112738)
		(end 86.907624 -400.112738)
		(stroke
			(width 0.07112)
			(type default)
		)
		(layer "In13.Cu")
	)
	(gr_line
		(start 86.74354 -401.665694)
		(end 86.7791 -401.476718)
		(stroke
			(width 0.07112)
			(type default)
		)
		(layer "In13.Cu")
	)
	(gr_line
		(start 86.886542 -417.23945)
		(end 87.159846 -416.966146)
		(stroke
			(width 0.07112)
			(type default)
		)
		(layer "In13.Cu")
	)
	(gr_line
		(start 86.907624 -400.112738)
		(end 87.209884 -399.810732)
		(stroke
			(width 0.07112)
			(type default)
		)
		(layer "In13.Cu")
	)
	(gr_line
		(start 86.948772 -402.951696)
		(end 87.419942 -402.432012)
		(stroke
			(width 0.07112)
			(type default)
		)
		(layer "In13.Cu")
	)
	(gr_line
		(start 87.085424 -395.024102)
		(end 87.085424 -395.025118)
		(stroke
			(width 0.07112)
			(type default)
		)
		(layer "In13.Cu")
	)
	(gr_line
		(start 87.159592 -403.14118)
		(end 87.351616 -403.131528)
		(stroke
			(width 0.07112)
			(type default)
		)
		(layer "In13.Cu")
	)
	(gr_line
		(start 87.159846 -416.966146)
		(end 87.159846 -416.773868)
		(stroke
			(width 0.07112)
			(type default)
		)
		(layer "In13.Cu")
	)
	(gr_line
		(start 87.209884 -399.810732)
		(end 87.209884 -399.618454)
		(stroke
			(width 0.07112)
			(type default)
		)
		(layer "In13.Cu")
	)
	(gr_line
		(start 87.233252 -416.299904)
		(end 87.700612 -415.832544)
		(stroke
			(width 0.07112)
			(type default)
		)
		(layer "In13.Cu")
	)
	(gr_line
		(start 87.311992 -400.679666)
		(end 87.8078 -400.183858)
		(stroke
			(width 0.07112)
			(type default)
		)
		(layer "In13.Cu")
	)
	(gr_line
		(start 87.311992 -399.115788)
		(end 87.808054 -398.61998)
		(stroke
			(width 0.07112)
			(type default)
		)
		(layer "In13.Cu")
	)
	(gr_line
		(start 87.330026 -420.050976)
		(end 87.826088 -419.554914)
		(stroke
			(width 0.07112)
			(type default)
		)
		(layer "In13.Cu")
	)
	(gr_line
		(start 87.351616 -403.131528)
		(end 87.638382 -402.815044)
		(stroke
			(width 0.07112)
			(type default)
		)
		(layer "In13.Cu")
	)
	(gr_line
		(start 87.405972 -393.017756)
		(end 87.417402 -393.017756)
		(stroke
			(width 0.07112)
			(type default)
		)
		(layer "In13.Cu")
	)
	(gr_line
		(start 87.407242 -392.734546)
		(end 87.544402 -392.597386)
		(stroke
			(width 0.07112)
			(type default)
		)
		(layer "In13.Cu")
	)
	(gr_line
		(start 87.417402 -393.017756)
		(end 87.544402 -393.144756)
		(stroke
			(width 0.07112)
			(type default)
		)
		(layer "In13.Cu")
	)
	(gr_line
		(start 87.43442 -416.499294)
		(end 87.626698 -416.499294)
		(stroke
			(width 0.07112)
			(type default)
		)
		(layer "In13.Cu")
	)
	(gr_line
		(start 87.512906 -400.87931)
		(end 87.705184 -400.87931)
		(stroke
			(width 0.07112)
			(type default)
		)
		(layer "In13.Cu")
	)
	(gr_line
		(start 87.512906 -399.315432)
		(end 87.705438 -399.315432)
		(stroke
			(width 0.07112)
			(type default)
		)
		(layer "In13.Cu")
	)
	(gr_line
		(start 87.519764 -433.748942)
		(end 87.515192 -433.748942)
		(stroke
			(width 0.07112)
			(type default)
		)
		(layer "In13.Cu")
	)
	(gr_line
		(start 87.531194 -420.250366)
		(end 87.723472 -420.250366)
		(stroke
			(width 0.07112)
			(type default)
		)
		(layer "In13.Cu")
	)
	(gr_line
		(start 87.544402 -393.144756)
		(end 87.544402 -393.292838)
		(stroke
			(width 0.07112)
			(type default)
		)
		(layer "In13.Cu")
	)
	(gr_line
		(start 87.544402 -392.597386)
		(end 87.544402 -392.429238)
		(stroke
			(width 0.07112)
			(type default)
		)
		(layer "In13.Cu")
	)
	(gr_line
		(start 87.626698 -416.499294)
		(end 87.900002 -416.22599)
		(stroke
			(width 0.07112)
			(type default)
		)
		(layer "In13.Cu")
	)
	(gr_line
		(start 87.638382 -402.815044)
		(end 87.62873 -402.623274)
		(stroke
			(width 0.07112)
			(type default)
		)
		(layer "In13.Cu")
	)
	(gr_line
		(start 87.650066 -434.48986)
		(end 87.650066 -434.165756)
		(stroke
			(width 0.07112)
			(type default)
		)
		(layer "In13.Cu")
	)
	(gr_line
		(start 87.650066 -434.165756)
		(end 87.516462 -434.032152)
		(stroke
			(width 0.07112)
			(type default)
		)
		(layer "In13.Cu")
	)
	(gr_line
		(start 87.650066 -433.61864)
		(end 87.519764 -433.748942)
		(stroke
			(width 0.07112)
			(type default)
		)
		(layer "In13.Cu")
	)
	(gr_line
		(start 87.650066 -433.289964)
		(end 87.650066 -433.61864)
		(stroke
			(width 0.07112)
			(type default)
		)
		(layer "In13.Cu")
	)
	(gr_line
		(start 87.705184 -400.87931)
		(end 88.00719 -400.577304)
		(stroke
			(width 0.07112)
			(type default)
		)
		(layer "In13.Cu")
	)
	(gr_line
		(start 87.705438 -399.315432)
		(end 88.007444 -399.013426)
		(stroke
			(width 0.07112)
			(type default)
		)
		(layer "In13.Cu")
	)
	(gr_line
		(start 87.7062 -402.116036)
		(end 88.17737 -401.596352)
		(stroke
			(width 0.07112)
			(type default)
		)
		(layer "In13.Cu")
	)
	(gr_line
		(start 87.723472 -420.250366)
		(end 88.025478 -419.94836)
		(stroke
			(width 0.07112)
			(type default)
		)
		(layer "In13.Cu")
	)
	(gr_line
		(start 87.900002 -416.22599)
		(end 87.900002 -416.033712)
		(stroke
			(width 0.07112)
			(type default)
		)
		(layer "In13.Cu")
	)
	(gr_line
		(start 87.907114 -409.640024)
		(end 87.907114 -408.938984)
		(stroke
			(width 0.07112)
			(type default)
		)
		(layer "In13.Cu")
	)
	(gr_line
		(start 87.907114 -408.512264)
		(end 87.907114 -407.811224)
		(stroke
			(width 0.07112)
			(type default)
		)
		(layer "In13.Cu")
	)
	(gr_line
		(start 87.916766 -402.30552)
		(end 88.10879 -402.295868)
		(stroke
			(width 0.07112)
			(type default)
		)
		(layer "In13.Cu")
	)
	(gr_line
		(start 88.00719 -400.577304)
		(end 88.00719 -400.385026)
		(stroke
			(width 0.07112)
			(type default)
		)
		(layer "In13.Cu")
	)
	(gr_line
		(start 88.007444 -399.013426)
		(end 88.007444 -398.820894)
		(stroke
			(width 0.07112)
			(type default)
		)
		(layer "In13.Cu")
	)
	(gr_line
		(start 88.025478 -419.94836)
		(end 88.025478 -419.756082)
		(stroke
			(width 0.07112)
			(type default)
		)
		(layer "In13.Cu")
	)
	(gr_line
		(start 88.10879 -402.295868)
		(end 88.39581 -401.979384)
		(stroke
			(width 0.07112)
			(type default)
		)
		(layer "In13.Cu")
	)
	(gr_line
		(start 88.109552 -399.882106)
		(end 88.60536 -399.386298)
		(stroke
			(width 0.07112)
			(type default)
		)
		(layer "In13.Cu")
	)
	(gr_line
		(start 88.127586 -419.253416)
		(end 88.623648 -418.757354)
		(stroke
			(width 0.07112)
			(type default)
		)
		(layer "In13.Cu")
	)
	(gr_line
		(start 88.190324 -409.638754)
		(end 88.326214 -409.502864)
		(stroke
			(width 0.07112)
			(type default)
		)
		(layer "In13.Cu")
	)
	(gr_line
		(start 88.190324 -408.510994)
		(end 88.326214 -408.375104)
		(stroke
			(width 0.07112)
			(type default)
		)
		(layer "In13.Cu")
	)
	(gr_line
		(start 88.310466 -400.08175)
		(end 88.502744 -400.08175)
		(stroke
			(width 0.07112)
			(type default)
		)
		(layer "In13.Cu")
	)
	(gr_line
		(start 88.326214 -409.502864)
		(end 88.326214 -409.076144)
		(stroke
			(width 0.07112)
			(type default)
		)
		(layer "In13.Cu")
	)
	(gr_line
		(start 88.326214 -409.076144)
		(end 88.190324 -408.940254)
		(stroke
			(width 0.07112)
			(type default)
		)
		(layer "In13.Cu")
	)
	(gr_line
		(start 88.326214 -408.375104)
		(end 88.326214 -407.948384)
		(stroke
			(width 0.07112)
			(type default)
		)
		(layer "In13.Cu")
	)
	(gr_line
		(start 88.326214 -407.948384)
		(end 88.190324 -407.812494)
		(stroke
			(width 0.07112)
			(type default)
		)
		(layer "In13.Cu")
	)
	(gr_line
		(start 88.328754 -419.452806)
		(end 88.521032 -419.452806)
		(stroke
			(width 0.07112)
			(type default)
		)
		(layer "In13.Cu")
	)
	(gr_line
		(start 88.39581 -401.979384)
		(end 88.386158 -401.787614)
		(stroke
			(width 0.07112)
			(type default)
		)
		(layer "In13.Cu")
	)
	(gr_line
		(start 88.463628 -401.280376)
		(end 88.934798 -400.760692)
		(stroke
			(width 0.07112)
			(type default)
		)
		(layer "In13.Cu")
	)
	(gr_line
		(start 88.478106 -397.892778)
		(end 88.923368 -397.350488)
		(stroke
			(width 0.07112)
			(type default)
		)
		(layer "In13.Cu")
	)
	(gr_line
		(start 88.502744 -400.08175)
		(end 88.80475 -399.779744)
		(stroke
			(width 0.07112)
			(type default)
		)
		(layer "In13.Cu")
	)
	(gr_line
		(start 88.521032 -419.452806)
		(end 88.823038 -419.1508)
		(stroke
			(width 0.07112)
			(type default)
		)
		(layer "In13.Cu")
	)
	(gr_line
		(start 88.60536 -396.015972)
		(end 89.00922 -395.44244)
		(stroke
			(width 0.07112)
			(type default)
		)
		(layer "In13.Cu")
	)
	(gr_line
		(start 88.605868 -393.017756)
		(end 88.617298 -393.017756)
		(stroke
			(width 0.07112)
			(type default)
		)
		(layer "In13.Cu")
	)
	(gr_line
		(start 88.607138 -392.734546)
		(end 88.744298 -392.597386)
		(stroke
			(width 0.07112)
			(type default)
		)
		(layer "In13.Cu")
	)
	(gr_line
		(start 88.617298 -393.017756)
		(end 88.744298 -393.144756)
		(stroke
			(width 0.07112)
			(type default)
		)
		(layer "In13.Cu")
	)
	(gr_line
		(start 88.674194 -401.46986)
		(end 88.866218 -401.460208)
		(stroke
			(width 0.07112)
			(type default)
		)
		(layer "In13.Cu")
	)
	(gr_line
		(start 88.697816 -398.07134)
		(end 88.889332 -398.052544)
		(stroke
			(width 0.07112)
			(type default)
		)
		(layer "In13.Cu")
	)
	(gr_line
		(start 88.744298 -393.144756)
		(end 88.744298 -393.292838)
		(stroke
			(width 0.07112)
			(type default)
		)
		(layer "In13.Cu")
	)
	(gr_line
		(start 88.744298 -392.597386)
		(end 88.744298 -392.429238)
		(stroke
			(width 0.07112)
			(type default)
		)
		(layer "In13.Cu")
	)
	(gr_line
		(start 88.80475 -399.779744)
		(end 88.80475 -399.587466)
		(stroke
			(width 0.07112)
			(type default)
		)
		(layer "In13.Cu")
	)
	(gr_line
		(start 88.823038 -419.1508)
		(end 88.823038 -418.958522)
		(stroke
			(width 0.07112)
			(type default)
		)
		(layer "In13.Cu")
	)
	(gr_line
		(start 88.83777 -396.178024)
		(end 89.027254 -396.145004)
		(stroke
			(width 0.07112)
			(type default)
		)
		(layer "In13.Cu")
	)
	(gr_line
		(start 88.866218 -401.460208)
		(end 89.153238 -401.143724)
		(stroke
			(width 0.07112)
			(type default)
		)
		(layer "In13.Cu")
	)
	(gr_line
		(start 88.889332 -398.052544)
		(end 89.16035 -397.722598)
		(stroke
			(width 0.07112)
			(type default)
		)
		(layer "In13.Cu")
	)
	(gr_line
		(start 88.896444 -418.484558)
		(end 89.363804 -418.017198)
		(stroke
			(width 0.07112)
			(type default)
		)
		(layer "In13.Cu")
	)
	(gr_line
		(start 89.00922 -395.44244)
		(end 89.009474 -395.442186)
		(stroke
			(width 0.07112)
			(type default)
		)
		(layer "In13.Cu")
	)
	(gr_line
		(start 89.027254 -396.145004)
		(end 89.273126 -395.796008)
		(stroke
			(width 0.07112)
			(type default)
		)
		(layer "In13.Cu")
	)
	(gr_line
		(start 89.097612 -418.683948)
		(end 89.28989 -418.683948)
		(stroke
			(width 0.07112)
			(type default)
		)
		(layer "In13.Cu")
	)
	(gr_line
		(start 89.153238 -401.143724)
		(end 89.143586 -400.951954)
		(stroke
			(width 0.07112)
			(type default)
		)
		(layer "In13.Cu")
	)
	(gr_line
		(start 89.16035 -397.722598)
		(end 89.141554 -397.530828)
		(stroke
			(width 0.07112)
			(type default)
		)
		(layer "In13.Cu")
	)
	(gr_line
		(start 89.193116 -420.587678)
		(end 89.689178 -420.091616)
		(stroke
			(width 0.07112)
			(type default)
		)
		(layer "In13.Cu")
	)
	(gr_line
		(start 89.221056 -400.444716)
		(end 89.691972 -399.925032)
		(stroke
			(width 0.07112)
			(type default)
		)
		(layer "In13.Cu")
	)
	(gr_line
		(start 89.273126 -395.796008)
		(end 89.240106 -395.606524)
		(stroke
			(width 0.07112)
			(type default)
		)
		(layer "In13.Cu")
	)
	(gr_line
		(start 89.28989 -418.683948)
		(end 89.563194 -418.410644)
		(stroke
			(width 0.07112)
			(type default)
		)
		(layer "In13.Cu")
	)
	(gr_line
		(start 89.394284 -420.787068)
		(end 89.586562 -420.787068)
		(stroke
			(width 0.07112)
			(type default)
		)
		(layer "In13.Cu")
	)
	(gr_line
		(start 89.431622 -400.6342)
		(end 89.623646 -400.624548)
		(stroke
			(width 0.07112)
			(type default)
		)
		(layer "In13.Cu")
	)
	(gr_arc
		(start 89.48547 -395.12621)
		(mid 89.48547 -395.126464)
		(end 89.48547 -395.126718)
		(stroke
			(width 0.07112)
			(type default)
		)
		(layer "In13.Cu")
	)
	(gr_line
		(start 89.529158 -434.739542)
		(end 89.50579 -434.739542)
		(stroke
			(width 0.07112)
			(type default)
		)
		(layer "In13.Cu")
	)
	(gr_line
		(start 89.563194 -418.410644)
		(end 89.563194 -418.218366)
		(stroke
			(width 0.07112)
			(type default)
		)
		(layer "In13.Cu")
	)
	(gr_line
		(start 89.586562 -420.787068)
		(end 89.888568 -420.485062)
		(stroke
			(width 0.07112)
			(type default)
		)
		(layer "In13.Cu")
	)
	(gr_line
		(start 89.623646 -400.624548)
		(end 89.910666 -400.308064)
		(stroke
			(width 0.07112)
			(type default)
		)
		(layer "In13.Cu")
	)
	(gr_line
		(start 89.650062 -435.489858)
		(end 89.650062 -435.165754)
		(stroke
			(width 0.07112)
			(type default)
		)
		(layer "In13.Cu")
	)
	(gr_line
		(start 89.650062 -435.165754)
		(end 89.50706 -435.022752)
		(stroke
			(width 0.07112)
			(type default)
		)
		(layer "In13.Cu")
	)
	(gr_line
		(start 89.650062 -434.618638)
		(end 89.529158 -434.739542)
		(stroke
			(width 0.07112)
			(type default)
		)
		(layer "In13.Cu")
	)
	(gr_line
		(start 89.650062 -434.289962)
		(end 89.650062 -434.618638)
		(stroke
			(width 0.07112)
			(type default)
		)
		(layer "In13.Cu")
	)
	(gr_line
		(start 89.665302 -417.7157)
		(end 90.161364 -417.219638)
		(stroke
			(width 0.07112)
			(type default)
		)
		(layer "In13.Cu")
	)
	(gr_line
		(start 89.700354 -398.193006)
		(end 90.104214 -397.61922)
		(stroke
			(width 0.07112)
			(type default)
		)
		(layer "In13.Cu")
	)
	(gr_line
		(start 89.806018 -393.017756)
		(end 89.817448 -393.017756)
		(stroke
			(width 0.07112)
			(type default)
		)
		(layer "In13.Cu")
	)
	(gr_line
		(start 89.807288 -392.734546)
		(end 89.944448 -392.597386)
		(stroke
			(width 0.07112)
			(type default)
		)
		(layer "In13.Cu")
	)
	(gr_line
		(start 89.812114 -402.796502)
		(end 90.172794 -402.194776)
		(stroke
			(width 0.07112)
			(type default)
		)
		(layer "In13.Cu")
	)
	(gr_line
		(start 89.817448 -393.017756)
		(end 89.944448 -393.144756)
		(stroke
			(width 0.07112)
			(type default)
		)
		(layer "In13.Cu")
	)
	(gr_line
		(start 89.86647 -417.91509)
		(end 90.058748 -417.91509)
		(stroke
			(width 0.07112)
			(type default)
		)
		(layer "In13.Cu")
	)
	(gr_line
		(start 89.888568 -420.485062)
		(end 89.888568 -420.292784)
		(stroke
			(width 0.07112)
			(type default)
		)
		(layer "In13.Cu")
	)
	(gr_line
		(start 89.910666 -400.308064)
		(end 89.901014 -400.116294)
		(stroke
			(width 0.07112)
			(type default)
		)
		(layer "In13.Cu")
	)
	(gr_line
		(start 89.93251 -398.355058)
		(end 90.122248 -398.322038)
		(stroke
			(width 0.07112)
			(type default)
		)
		(layer "In13.Cu")
	)
	(gr_line
		(start 89.944448 -393.144756)
		(end 89.944448 -393.292838)
		(stroke
			(width 0.07112)
			(type default)
		)
		(layer "In13.Cu")
	)
	(gr_line
		(start 89.944448 -392.597386)
		(end 89.944448 -392.429238)
		(stroke
			(width 0.07112)
			(type default)
		)
		(layer "In13.Cu")
	)
	(gr_line
		(start 89.990676 -419.790118)
		(end 90.486738 -419.294056)
		(stroke
			(width 0.07112)
			(type default)
		)
		(layer "In13.Cu")
	)
	(gr_line
		(start 90.0557 -402.941028)
		(end 90.24239 -402.894292)
		(stroke
			(width 0.07112)
			(type default)
		)
		(layer "In13.Cu")
	)
	(gr_line
		(start 90.058748 -417.91509)
		(end 90.360754 -417.613084)
		(stroke
			(width 0.07112)
			(type default)
		)
		(layer "In13.Cu")
	)
	(gr_line
		(start 90.122248 -398.322038)
		(end 90.36812 -397.972788)
		(stroke
			(width 0.07112)
			(type default)
		)
		(layer "In13.Cu")
	)
	(gr_line
		(start 90.191844 -419.989508)
		(end 90.384122 -419.989508)
		(stroke
			(width 0.07112)
			(type default)
		)
		(layer "In13.Cu")
	)
	(gr_line
		(start 90.24239 -402.894292)
		(end 90.461846 -402.528024)
		(stroke
			(width 0.07112)
			(type default)
		)
		(layer "In13.Cu")
	)
	(gr_line
		(start 90.349832 -397.270478)
		(end 90.753946 -396.696692)
		(stroke
			(width 0.07112)
			(type default)
		)
		(layer "In13.Cu")
	)
	(gr_line
		(start 90.360754 -417.613084)
		(end 90.360754 -417.420806)
		(stroke
			(width 0.07112)
			(type default)
		)
		(layer "In13.Cu")
	)
	(gr_line
		(start 90.36812 -397.972788)
		(end 90.335354 -397.78305)
		(stroke
			(width 0.07112)
			(type default)
		)
		(layer "In13.Cu")
	)
	(gr_line
		(start 90.384122 -419.989508)
		(end 90.686128 -419.687502)
		(stroke
			(width 0.07112)
			(type default)
		)
		(layer "In13.Cu")
	)
	(gr_line
		(start 90.461846 -402.528024)
		(end 90.41511 -402.341588)
		(stroke
			(width 0.07112)
			(type default)
		)
		(layer "In13.Cu")
	)
	(gr_line
		(start 90.551508 -401.563078)
		(end 90.912188 -400.961352)
		(stroke
			(width 0.07112)
			(type default)
		)
		(layer "In13.Cu")
	)
	(gr_line
		(start 90.581988 -397.432784)
		(end 90.771726 -397.399764)
		(stroke
			(width 0.07112)
			(type default)
		)
		(layer "In13.Cu")
	)
	(gr_arc
		(start 90.685366 -395.41323)
		(mid 90.685366 -395.413484)
		(end 90.685366 -395.413738)
		(stroke
			(width 0.07112)
			(type default)
		)
		(layer "In13.Cu")
	)
	(gr_line
		(start 90.686128 -419.687502)
		(end 90.686128 -419.495224)
		(stroke
			(width 0.07112)
			(type default)
		)
		(layer "In13.Cu")
	)
	(gr_line
		(start 90.771726 -397.399764)
		(end 91.017598 -397.050768)
		(stroke
			(width 0.07112)
			(type default)
		)
		(layer "In13.Cu")
	)
	(gr_line
		(start 90.788236 -418.992558)
		(end 91.284298 -418.496496)
		(stroke
			(width 0.07112)
			(type default)
		)
		(layer "In13.Cu")
	)
	(gr_line
		(start 90.79484 -401.707604)
		(end 90.981784 -401.660868)
		(stroke
			(width 0.07112)
			(type default)
		)
		(layer "In13.Cu")
	)
	(gr_line
		(start 90.970354 -409.548584)
		(end 90.970354 -408.847544)
		(stroke
			(width 0.07112)
			(type default)
		)
		(layer "In13.Cu")
	)
	(gr_line
		(start 90.970354 -408.420824)
		(end 90.970354 -407.719784)
		(stroke
			(width 0.07112)
			(type default)
		)
		(layer "In13.Cu")
	)
	(gr_line
		(start 90.981784 -401.660868)
		(end 91.200986 -401.2946)
		(stroke
			(width 0.07112)
			(type default)
		)
		(layer "In13.Cu")
	)
	(gr_line
		(start 90.984578 -396.859506)
		(end 90.984578 -396.859252)
		(stroke
			(width 0.07112)
			(type default)
		)
		(layer "In13.Cu")
	)
	(gr_line
		(start 90.989404 -419.191948)
		(end 91.181682 -419.191948)
		(stroke
			(width 0.07112)
			(type default)
		)
		(layer "In13.Cu")
	)
	(gr_line
		(start 91.005914 -393.017756)
		(end 91.017344 -393.017756)
		(stroke
			(width 0.07112)
			(type default)
		)
		(layer "In13.Cu")
	)
	(gr_line
		(start 91.007184 -392.734546)
		(end 91.144344 -392.597386)
		(stroke
			(width 0.07112)
			(type default)
		)
		(layer "In13.Cu")
	)
	(gr_line
		(start 91.017344 -393.017756)
		(end 91.144344 -393.144756)
		(stroke
			(width 0.07112)
			(type default)
		)
		(layer "In13.Cu")
	)
	(gr_line
		(start 91.017598 -397.050768)
		(end 90.984832 -396.860776)
		(stroke
			(width 0.07112)
			(type default)
		)
		(layer "In13.Cu")
	)
	(gr_line
		(start 91.13139 -400.595592)
		(end 91.49207 -399.993866)
		(stroke
			(width 0.07112)
			(type default)
		)
		(layer "In13.Cu")
	)
	(gr_line
		(start 91.144344 -393.144756)
		(end 91.144344 -393.292838)
		(stroke
			(width 0.07112)
			(type default)
		)
		(layer "In13.Cu")
	)
	(gr_line
		(start 91.144344 -392.597386)
		(end 91.144344 -392.429238)
		(stroke
			(width 0.07112)
			(type default)
		)
		(layer "In13.Cu")
	)
	(gr_line
		(start 91.181682 -419.191948)
		(end 91.483688 -418.889942)
		(stroke
			(width 0.07112)
			(type default)
		)
		(layer "In13.Cu")
	)
	(gr_line
		(start 91.200986 -401.2946)
		(end 91.154504 -401.10791)
		(stroke
			(width 0.07112)
			(type default)
		)
		(layer "In13.Cu")
	)
	(gr_line
		(start 91.253564 -409.547314)
		(end 91.389454 -409.411424)
		(stroke
			(width 0.07112)
			(type default)
		)
		(layer "In13.Cu")
	)
	(gr_line
		(start 91.253564 -408.419554)
		(end 91.389454 -408.283664)
		(stroke
			(width 0.07112)
			(type default)
		)
		(layer "In13.Cu")
	)
	(gr_line
		(start 91.374722 -400.740118)
		(end 91.561666 -400.693382)
		(stroke
			(width 0.07112)
			(type default)
		)
		(layer "In13.Cu")
	)
	(gr_line
		(start 91.389454 -409.411424)
		(end 91.389454 -408.984704)
		(stroke
			(width 0.07112)
			(type default)
		)
		(layer "In13.Cu")
	)
	(gr_line
		(start 91.389454 -408.984704)
		(end 91.253564 -408.848814)
		(stroke
			(width 0.07112)
			(type default)
		)
		(layer "In13.Cu")
	)
	(gr_line
		(start 91.389454 -408.283664)
		(end 91.389454 -407.856944)
		(stroke
			(width 0.07112)
			(type default)
		)
		(layer "In13.Cu")
	)
	(gr_line
		(start 91.389454 -407.856944)
		(end 91.253564 -407.721054)
		(stroke
			(width 0.07112)
			(type default)
		)
		(layer "In13.Cu")
	)
	(gr_line
		(start 91.483688 -418.889942)
		(end 91.483688 -418.697664)
		(stroke
			(width 0.07112)
			(type default)
		)
		(layer "In13.Cu")
	)
	(gr_line
		(start 91.561666 -400.693382)
		(end 91.781122 -400.327114)
		(stroke
			(width 0.07112)
			(type default)
		)
		(layer "In13.Cu")
	)
	(gr_line
		(start 91.585796 -418.194998)
		(end 92.081858 -417.698936)
		(stroke
			(width 0.07112)
			(type default)
		)
		(layer "In13.Cu")
	)
	(gr_line
		(start 91.781122 -400.327114)
		(end 91.734386 -400.140424)
		(stroke
			(width 0.07112)
			(type default)
		)
		(layer "In13.Cu")
	)
	(gr_line
		(start 91.786964 -418.394388)
		(end 91.979242 -418.394388)
		(stroke
			(width 0.07112)
			(type default)
		)
		(layer "In13.Cu")
	)
	(gr_line
		(start 91.979242 -418.394388)
		(end 92.281248 -418.092382)
		(stroke
			(width 0.07112)
			(type default)
		)
		(layer "In13.Cu")
	)
	(gr_line
		(start 92.206064 -393.017756)
		(end 92.217494 -393.017756)
		(stroke
			(width 0.07112)
			(type default)
		)
		(layer "In13.Cu")
	)
	(gr_line
		(start 92.207334 -392.734546)
		(end 92.344494 -392.597386)
		(stroke
			(width 0.07112)
			(type default)
		)
		(layer "In13.Cu")
	)
	(gr_line
		(start 92.217494 -393.017756)
		(end 92.344494 -393.144756)
		(stroke
			(width 0.07112)
			(type default)
		)
		(layer "In13.Cu")
	)
	(gr_line
		(start 92.281248 -418.092382)
		(end 92.281248 -417.900104)
		(stroke
			(width 0.07112)
			(type default)
		)
		(layer "In13.Cu")
	)
	(gr_line
		(start 92.344494 -393.144756)
		(end 92.344494 -393.292838)
		(stroke
			(width 0.07112)
			(type default)
		)
		(layer "In13.Cu")
	)
	(gr_line
		(start 92.344494 -392.597386)
		(end 92.344494 -392.429238)
		(stroke
			(width 0.07112)
			(type default)
		)
		(layer "In13.Cu")
	)
	(gr_line
		(start 92.354654 -417.42614)
		(end 92.822014 -416.95878)
		(stroke
			(width 0.07112)
			(type default)
		)
		(layer "In13.Cu")
	)
	(gr_line
		(start 92.555822 -417.62553)
		(end 92.7481 -417.62553)
		(stroke
			(width 0.07112)
			(type default)
		)
		(layer "In13.Cu")
	)
	(gr_line
		(start 92.587318 -398.111472)
		(end 92.917772 -397.493236)
		(stroke
			(width 0.07112)
			(type default)
		)
		(layer "In13.Cu")
	)
	(gr_line
		(start 92.656406 -402.97862)
		(end 92.793312 -402.290534)
		(stroke
			(width 0.07112)
			(type default)
		)
		(layer "In13.Cu")
	)
	(gr_line
		(start 92.7481 -417.62553)
		(end 93.021404 -417.352226)
		(stroke
			(width 0.07112)
			(type default)
		)
		(layer "In13.Cu")
	)
	(gr_line
		(start 92.837254 -398.244568)
		(end 93.021912 -398.188434)
		(stroke
			(width 0.07112)
			(type default)
		)
		(layer "In13.Cu")
	)
	(gr_line
		(start 92.917772 -397.493236)
		(end 92.918026 -397.493236)
		(stroke
			(width 0.07112)
			(type default)
		)
		(layer "In13.Cu")
	)
	(gr_line
		(start 92.934536 -403.032468)
		(end 93.094556 -402.925788)
		(stroke
			(width 0.07112)
			(type default)
		)
		(layer "In13.Cu")
	)
	(gr_line
		(start 93.021404 -417.352226)
		(end 93.021404 -417.159948)
		(stroke
			(width 0.07112)
			(type default)
		)
		(layer "In13.Cu")
	)
	(gr_line
		(start 93.021912 -398.188434)
		(end 93.22308 -397.811752)
		(stroke
			(width 0.07112)
			(type default)
		)
		(layer "In13.Cu")
	)
	(gr_line
		(start 93.094556 -402.925788)
		(end 93.177614 -402.506942)
		(stroke
			(width 0.07112)
			(type default)
		)
		(layer "In13.Cu")
	)
	(gr_line
		(start 93.09481 -416.685984)
		(end 93.56217 -416.218624)
		(stroke
			(width 0.07112)
			(type default)
		)
		(layer "In13.Cu")
	)
	(gr_line
		(start 93.177614 -402.506942)
		(end 93.070934 -402.346922)
		(stroke
			(width 0.07112)
			(type default)
		)
		(layer "In13.Cu")
	)
	(gr_line
		(start 93.22308 -397.811752)
		(end 93.1672 -397.627602)
		(stroke
			(width 0.07112)
			(type default)
		)
		(layer "In13.Cu")
	)
	(gr_line
		(start 93.245178 -400.402298)
		(end 93.481398 -399.742152)
		(stroke
			(width 0.07112)
			(type default)
		)
		(layer "In13.Cu")
	)
	(gr_line
		(start 93.295978 -416.885374)
		(end 93.488256 -416.885374)
		(stroke
			(width 0.07112)
			(type default)
		)
		(layer "In13.Cu")
	)
	(gr_line
		(start 93.40596 -393.017756)
		(end 93.41739 -393.017756)
		(stroke
			(width 0.07112)
			(type default)
		)
		(layer "In13.Cu")
	)
	(gr_line
		(start 93.40723 -392.734546)
		(end 93.54439 -392.597386)
		(stroke
			(width 0.07112)
			(type default)
		)
		(layer "In13.Cu")
	)
	(gr_line
		(start 93.41739 -393.017756)
		(end 93.54439 -393.144756)
		(stroke
			(width 0.07112)
			(type default)
		)
		(layer "In13.Cu")
	)
	(gr_line
		(start 93.488256 -416.885374)
		(end 93.76156 -416.61207)
		(stroke
			(width 0.07112)
			(type default)
		)
		(layer "In13.Cu")
	)
	(gr_line
		(start 93.512132 -400.49704)
		(end 93.686376 -400.41449)
		(stroke
			(width 0.07112)
			(type default)
		)
		(layer "In13.Cu")
	)
	(gr_line
		(start 93.54439 -393.144756)
		(end 93.54439 -393.292838)
		(stroke
			(width 0.07112)
			(type default)
		)
		(layer "In13.Cu")
	)
	(gr_line
		(start 93.54439 -392.597386)
		(end 93.54439 -392.429238)
		(stroke
			(width 0.07112)
			(type default)
		)
		(layer "In13.Cu")
	)
	(gr_line
		(start 93.625162 -399.340578)
		(end 93.861382 -398.680178)
		(stroke
			(width 0.07112)
			(type default)
		)
		(layer "In13.Cu")
	)
	(gr_line
		(start 93.686376 -400.41449)
		(end 93.83014 -400.012408)
		(stroke
			(width 0.07112)
			(type default)
		)
		(layer "In13.Cu")
	)
	(gr_line
		(start 93.76156 -416.61207)
		(end 93.76156 -416.419792)
		(stroke
			(width 0.07112)
			(type default)
		)
		(layer "In13.Cu")
	)
	(gr_line
		(start 93.83014 -400.012408)
		(end 93.747844 -399.838418)
		(stroke
			(width 0.07112)
			(type default)
		)
		(layer "In13.Cu")
	)
	(gr_line
		(start 93.892116 -399.435066)
		(end 94.06636 -399.352516)
		(stroke
			(width 0.07112)
			(type default)
		)
		(layer "In13.Cu")
	)
	(gr_line
		(start 94.005146 -398.278604)
		(end 94.241366 -397.618204)
		(stroke
			(width 0.07112)
			(type default)
		)
		(layer "In13.Cu")
	)
	(gr_line
		(start 94.033594 -409.45308)
		(end 94.033594 -408.75204)
		(stroke
			(width 0.07112)
			(type default)
		)
		(layer "In13.Cu")
	)
	(gr_line
		(start 94.033594 -408.32532)
		(end 94.033594 -407.62428)
		(stroke
			(width 0.07112)
			(type default)
		)
		(layer "In13.Cu")
	)
	(gr_line
		(start 94.06636 -399.352516)
		(end 94.210124 -398.950434)
		(stroke
			(width 0.07112)
			(type default)
		)
		(layer "In13.Cu")
	)
	(gr_line
		(start 94.210124 -398.950434)
		(end 94.127828 -398.776698)
		(stroke
			(width 0.07112)
			(type default)
		)
		(layer "In13.Cu")
	)
	(gr_line
		(start 94.2721 -398.373092)
		(end 94.446344 -398.290542)
		(stroke
			(width 0.07112)
			(type default)
		)
		(layer "In13.Cu")
	)
	(gr_line
		(start 94.316804 -409.45181)
		(end 94.452694 -409.31592)
		(stroke
			(width 0.07112)
			(type default)
		)
		(layer "In13.Cu")
	)
	(gr_line
		(start 94.316804 -408.32405)
		(end 94.452694 -408.18816)
		(stroke
			(width 0.07112)
			(type default)
		)
		(layer "In13.Cu")
	)
	(gr_line
		(start 94.38513 -397.21663)
		(end 94.619318 -396.561818)
		(stroke
			(width 0.07112)
			(type default)
		)
		(layer "In13.Cu")
	)
	(gr_line
		(start 94.446344 -398.290542)
		(end 94.590108 -397.88846)
		(stroke
			(width 0.07112)
			(type default)
		)
		(layer "In13.Cu")
	)
	(gr_line
		(start 94.452694 -409.31592)
		(end 94.452694 -408.8892)
		(stroke
			(width 0.07112)
			(type default)
		)
		(layer "In13.Cu")
	)
	(gr_line
		(start 94.452694 -408.8892)
		(end 94.316804 -408.75331)
		(stroke
			(width 0.07112)
			(type default)
		)
		(layer "In13.Cu")
	)
	(gr_line
		(start 94.452694 -408.18816)
		(end 94.452694 -407.76144)
		(stroke
			(width 0.07112)
			(type default)
		)
		(layer "In13.Cu")
	)
	(gr_line
		(start 94.452694 -407.76144)
		(end 94.316804 -407.62555)
		(stroke
			(width 0.07112)
			(type default)
		)
		(layer "In13.Cu")
	)
	(gr_line
		(start 94.590108 -397.88846)
		(end 94.507812 -397.714724)
		(stroke
			(width 0.07112)
			(type default)
		)
		(layer "In13.Cu")
	)
	(gr_line
		(start 94.605856 -393.017756)
		(end 94.617286 -393.017756)
		(stroke
			(width 0.07112)
			(type default)
		)
		(layer "In13.Cu")
	)
	(gr_line
		(start 94.607126 -392.734546)
		(end 94.744286 -392.597386)
		(stroke
			(width 0.07112)
			(type default)
		)
		(layer "In13.Cu")
	)
	(gr_line
		(start 94.617286 -393.017756)
		(end 94.744286 -393.144756)
		(stroke
			(width 0.07112)
			(type default)
		)
		(layer "In13.Cu")
	)
	(gr_line
		(start 94.619826 -396.560294)
		(end 94.62135 -396.556484)
		(stroke
			(width 0.07112)
			(type default)
		)
		(layer "In13.Cu")
	)
	(gr_line
		(start 94.62135 -396.556484)
		(end 94.622112 -396.554706)
		(stroke
			(width 0.07112)
			(type default)
		)
		(layer "In13.Cu")
	)
	(gr_line
		(start 94.652084 -397.310864)
		(end 94.826328 -397.228568)
		(stroke
			(width 0.07112)
			(type default)
		)
		(layer "In13.Cu")
	)
	(gr_line
		(start 94.744286 -393.144756)
		(end 94.744286 -393.292838)
		(stroke
			(width 0.07112)
			(type default)
		)
		(layer "In13.Cu")
	)
	(gr_line
		(start 94.744286 -392.597386)
		(end 94.744286 -392.429238)
		(stroke
			(width 0.07112)
			(type default)
		)
		(layer "In13.Cu")
	)
	(gr_line
		(start 94.826328 -397.228568)
		(end 94.970092 -396.82674)
		(stroke
			(width 0.07112)
			(type default)
		)
		(layer "In13.Cu")
	)
	(gr_line
		(start 94.970092 -396.82674)
		(end 94.887796 -396.652496)
		(stroke
			(width 0.07112)
			(type default)
		)
		(layer "In13.Cu")
	)
	(gr_line
		(start 95.585026 -404.718012)
		(end 95.597472 -404.589234)
		(stroke
			(width 0.07112)
			(type default)
		)
		(layer "In13.Cu")
	)
	(gr_line
		(start 95.597472 -404.589234)
		(end 95.666306 -403.890988)
		(stroke
			(width 0.07112)
			(type default)
		)
		(layer "In13.Cu")
	)
	(gr_line
		(start 95.708216 -403.466808)
		(end 95.776796 -402.768562)
		(stroke
			(width 0.07112)
			(type default)
		)
		(layer "In13.Cu")
	)
	(gr_line
		(start 95.805752 -393.017756)
		(end 95.817182 -393.017756)
		(stroke
			(width 0.07112)
			(type default)
		)
		(layer "In13.Cu")
	)
	(gr_line
		(start 95.807022 -392.734546)
		(end 95.944182 -392.597386)
		(stroke
			(width 0.07112)
			(type default)
		)
		(layer "In13.Cu")
	)
	(gr_line
		(start 95.817182 -393.017756)
		(end 95.944182 -393.144756)
		(stroke
			(width 0.07112)
			(type default)
		)
		(layer "In13.Cu")
	)
	(gr_line
		(start 95.818706 -402.344382)
		(end 95.887286 -401.646136)
		(stroke
			(width 0.07112)
			(type default)
		)
		(layer "In13.Cu")
	)
	(gr_line
		(start 95.865442 -404.745698)
		(end 95.878142 -404.616666)
		(stroke
			(width 0.07112)
			(type default)
		)
		(layer "In13.Cu")
	)
	(gr_line
		(start 95.879666 -404.615396)
		(end 96.028256 -404.493476)
		(stroke
			(width 0.07112)
			(type default)
		)
		(layer "In13.Cu")
	)
	(gr_line
		(start 95.929196 -401.221956)
		(end 95.997776 -400.52371)
		(stroke
			(width 0.07112)
			(type default)
		)
		(layer "In13.Cu")
	)
	(gr_line
		(start 95.944182 -393.144756)
		(end 95.944182 -393.292838)
		(stroke
			(width 0.07112)
			(type default)
		)
		(layer "In13.Cu")
	)
	(gr_line
		(start 95.944182 -392.597386)
		(end 95.944182 -392.429238)
		(stroke
			(width 0.07112)
			(type default)
		)
		(layer "In13.Cu")
	)
	(gr_line
		(start 95.990156 -403.493224)
		(end 96.139 -403.37105)
		(stroke
			(width 0.07112)
			(type default)
		)
		(layer "In13.Cu")
	)
	(gr_line
		(start 96.028256 -404.493476)
		(end 96.070166 -404.068534)
		(stroke
			(width 0.07112)
			(type default)
		)
		(layer "In13.Cu")
	)
	(gr_line
		(start 96.039686 -400.09953)
		(end 96.108266 -399.401284)
		(stroke
			(width 0.07112)
			(type default)
		)
		(layer "In13.Cu")
	)
	(gr_line
		(start 96.070166 -404.068534)
		(end 95.947992 -403.91969)
		(stroke
			(width 0.07112)
			(type default)
		)
		(layer "In13.Cu")
	)
	(gr_line
		(start 96.100646 -402.370798)
		(end 96.24949 -402.248624)
		(stroke
			(width 0.07112)
			(type default)
		)
		(layer "In13.Cu")
	)
	(gr_line
		(start 96.139 -403.37105)
		(end 96.18091 -402.946108)
		(stroke
			(width 0.07112)
			(type default)
		)
		(layer "In13.Cu")
	)
	(gr_line
		(start 96.18091 -402.946108)
		(end 96.058482 -402.797264)
		(stroke
			(width 0.07112)
			(type default)
		)
		(layer "In13.Cu")
	)
	(gr_line
		(start 96.211136 -401.248372)
		(end 96.35998 -401.126198)
		(stroke
			(width 0.07112)
			(type default)
		)
		(layer "In13.Cu")
	)
	(gr_line
		(start 96.24949 -402.248624)
		(end 96.2914 -401.823682)
		(stroke
			(width 0.07112)
			(type default)
		)
		(layer "In13.Cu")
	)
	(gr_line
		(start 96.2914 -401.823682)
		(end 96.169226 -401.674838)
		(stroke
			(width 0.07112)
			(type default)
		)
		(layer "In13.Cu")
	)
	(gr_line
		(start 96.321626 -400.125946)
		(end 96.47047 -400.003772)
		(stroke
			(width 0.07112)
			(type default)
		)
		(layer "In13.Cu")
	)
	(gr_line
		(start 96.35998 -401.126198)
		(end 96.40189 -400.701256)
		(stroke
			(width 0.07112)
			(type default)
		)
		(layer "In13.Cu")
	)
	(gr_line
		(start 96.40189 -400.701256)
		(end 96.279716 -400.552412)
		(stroke
			(width 0.07112)
			(type default)
		)
		(layer "In13.Cu")
	)
	(gr_line
		(start 96.430084 -296.422318)
		(end 96.430084 -296.39387)
		(stroke
			(width 0.05715)
			(type default)
		)
		(layer "In13.Cu")
	)
	(gr_line
		(start 96.430084 -296.39387)
		(end 96.475804 -296.34815)
		(stroke
			(width 0.05715)
			(type default)
		)
		(layer "In13.Cu")
	)
	(gr_line
		(start 96.47047 -400.003772)
		(end 96.51238 -399.57883)
		(stroke
			(width 0.07112)
			(type default)
		)
		(layer "In13.Cu")
	)
	(gr_line
		(start 96.51238 -399.57883)
		(end 96.390206 -399.429986)
		(stroke
			(width 0.07112)
			(type default)
		)
		(layer "In13.Cu")
	)
	(gr_line
		(start 96.712024 -296.422318)
		(end 96.712024 -296.39387)
		(stroke
			(width 0.05715)
			(type default)
		)
		(layer "In13.Cu")
	)
	(gr_line
		(start 96.712024 -296.39387)
		(end 96.666304 -296.34815)
		(stroke
			(width 0.05715)
			(type default)
		)
		(layer "In13.Cu")
	)
	(gr_line
		(start 96.761808 -411.329886)
		(end 96.809052 -411.222952)
		(stroke
			(width 0.07112)
			(type default)
		)
		(layer "In13.Cu")
	)
	(gr_line
		(start 96.809306 -411.222952)
		(end 96.809052 -411.222952)
		(stroke
			(width 0.07112)
			(type default)
		)
		(layer "In13.Cu")
	)
	(gr_line
		(start 96.809306 -411.222952)
		(end 97.046034 -410.688536)
		(stroke
			(width 0.07112)
			(type default)
		)
		(layer "In13.Cu")
	)
	(gr_line
		(start 97.005902 -393.017756)
		(end 97.017332 -393.017756)
		(stroke
			(width 0.07112)
			(type default)
		)
		(layer "In13.Cu")
	)
	(gr_line
		(start 97.007172 -392.734546)
		(end 97.144332 -392.597386)
		(stroke
			(width 0.07112)
			(type default)
		)
		(layer "In13.Cu")
	)
	(gr_line
		(start 97.017332 -393.017756)
		(end 97.144332 -393.144756)
		(stroke
			(width 0.07112)
			(type default)
		)
		(layer "In13.Cu")
	)
	(gr_line
		(start 97.021142 -411.443678)
		(end 97.200974 -411.374336)
		(stroke
			(width 0.07112)
			(type default)
		)
		(layer "In13.Cu")
	)
	(gr_line
		(start 97.136458 -295.145968)
		(end 97.136712 -295.146222)
		(stroke
			(width 0.05715)
			(type default)
		)
		(layer "In13.Cu")
	)
	(gr_line
		(start 97.144332 -393.144756)
		(end 97.144332 -393.292838)
		(stroke
			(width 0.07112)
			(type default)
		)
		(layer "In13.Cu")
	)
	(gr_line
		(start 97.144332 -392.597386)
		(end 97.144332 -392.429238)
		(stroke
			(width 0.07112)
			(type default)
		)
		(layer "In13.Cu")
	)
	(gr_arc
		(start 97.185734 -286.583882)
		(mid 97.182679 -286.586031)
		(end 97.179638 -286.5882)
		(stroke
			(width 0.05715)
			(type default)
		)
		(layer "In13.Cu")
	)
	(gr_line
		(start 97.200974 -411.374336)
		(end 97.373694 -410.983938)
		(stroke
			(width 0.07112)
			(type default)
		)
		(layer "In13.Cu")
	)
	(gr_line
		(start 97.370138 -296.422318)
		(end 97.370138 -296.40784)
		(stroke
			(width 0.05715)
			(type default)
		)
		(layer "In13.Cu")
	)
	(gr_line
		(start 97.370138 -296.40784)
		(end 97.415858 -296.36212)
		(stroke
			(width 0.05715)
			(type default)
		)
		(layer "In13.Cu")
	)
	(gr_line
		(start 97.373694 -410.983938)
		(end 97.304606 -410.804614)
		(stroke
			(width 0.07112)
			(type default)
		)
		(layer "In13.Cu")
	)
	(gr_line
		(start 97.60331 -408.810714)
		(end 97.60331 -408.109674)
		(stroke
			(width 0.07112)
			(type default)
		)
		(layer "In13.Cu")
	)
	(gr_line
		(start 97.60331 -407.682954)
		(end 97.60331 -406.981914)
		(stroke
			(width 0.07112)
			(type default)
		)
		(layer "In13.Cu")
	)
	(gr_line
		(start 97.60331 -406.555194)
		(end 97.60331 -405.854154)
		(stroke
			(width 0.07112)
			(type default)
		)
		(layer "In13.Cu")
	)
	(gr_line
		(start 97.652078 -296.422318)
		(end 97.652078 -296.40784)
		(stroke
			(width 0.05715)
			(type default)
		)
		(layer "In13.Cu")
	)
	(gr_line
		(start 97.652078 -296.40784)
		(end 97.606358 -296.36212)
		(stroke
			(width 0.05715)
			(type default)
		)
		(layer "In13.Cu")
	)
	(gr_line
		(start 97.691956 -272.792444)
		(end 97.698052 -272.788888)
		(stroke
			(width 0.05715)
			(type default)
		)
		(layer "In13.Cu")
	)
	(gr_line
		(start 97.698052 -272.788888)
		(end 97.698814 -272.78838)
		(stroke
			(width 0.05715)
			(type default)
		)
		(layer "In13.Cu")
	)
	(gr_line
		(start 97.794318 -272.953734)
		(end 97.79508 -272.953226)
		(stroke
			(width 0.05715)
			(type default)
		)
		(layer "In13.Cu")
	)
	(gr_line
		(start 97.88652 -408.809444)
		(end 98.02241 -408.673554)
		(stroke
			(width 0.07112)
			(type default)
		)
		(layer "In13.Cu")
	)
	(gr_line
		(start 97.88652 -407.681684)
		(end 98.02241 -407.545794)
		(stroke
			(width 0.07112)
			(type default)
		)
		(layer "In13.Cu")
	)
	(gr_line
		(start 97.88652 -406.553924)
		(end 98.02241 -406.418034)
		(stroke
			(width 0.07112)
			(type default)
		)
		(layer "In13.Cu")
	)
	(gr_line
		(start 97.894394 -295.279572)
		(end 97.894648 -295.279826)
		(stroke
			(width 0.05715)
			(type default)
		)
		(layer "In13.Cu")
	)
	(gr_line
		(start 98.02241 -408.673554)
		(end 98.02241 -408.246834)
		(stroke
			(width 0.07112)
			(type default)
		)
		(layer "In13.Cu")
	)
	(gr_line
		(start 98.02241 -408.246834)
		(end 97.88652 -408.110944)
		(stroke
			(width 0.07112)
			(type default)
		)
		(layer "In13.Cu")
	)
	(gr_line
		(start 98.02241 -407.545794)
		(end 98.02241 -407.119074)
		(stroke
			(width 0.07112)
			(type default)
		)
		(layer "In13.Cu")
	)
	(gr_line
		(start 98.02241 -407.119074)
		(end 97.88652 -406.983184)
		(stroke
			(width 0.07112)
			(type default)
		)
		(layer "In13.Cu")
	)
	(gr_line
		(start 98.02241 -406.418034)
		(end 98.02241 -405.991314)
		(stroke
			(width 0.07112)
			(type default)
		)
		(layer "In13.Cu")
	)
	(gr_line
		(start 98.02241 -405.991314)
		(end 97.88652 -405.855424)
		(stroke
			(width 0.07112)
			(type default)
		)
		(layer "In13.Cu")
	)
	(gr_line
		(start 98.205798 -393.017756)
		(end 98.217228 -393.017756)
		(stroke
			(width 0.07112)
			(type default)
		)
		(layer "In13.Cu")
	)
	(gr_line
		(start 98.207068 -392.734546)
		(end 98.344228 -392.597386)
		(stroke
			(width 0.07112)
			(type default)
		)
		(layer "In13.Cu")
	)
	(gr_line
		(start 98.217228 -393.017756)
		(end 98.344228 -393.144756)
		(stroke
			(width 0.07112)
			(type default)
		)
		(layer "In13.Cu")
	)
	(gr_line
		(start 98.27895 -273.276314)
		(end 97.981008 -273.276314)
		(stroke
			(width 0.05715)
			(type default)
		)
		(layer "In13.Cu")
	)
	(gr_line
		(start 98.27895 -271.656302)
		(end 97.981008 -271.656302)
		(stroke
			(width 0.05715)
			(type default)
		)
		(layer "In13.Cu")
	)
	(gr_line
		(start 98.27895 -270.03629)
		(end 97.981008 -270.03629)
		(stroke
			(width 0.05715)
			(type default)
		)
		(layer "In13.Cu")
	)
	(gr_line
		(start 98.310192 -296.422318)
		(end 98.310192 -296.39387)
		(stroke
			(width 0.05715)
			(type default)
		)
		(layer "In13.Cu")
	)
	(gr_line
		(start 98.310192 -296.39387)
		(end 98.351848 -296.343324)
		(stroke
			(width 0.05715)
			(type default)
		)
		(layer "In13.Cu")
	)
	(gr_line
		(start 98.344228 -393.144756)
		(end 98.344228 -393.292838)
		(stroke
			(width 0.07112)
			(type default)
		)
		(layer "In13.Cu")
	)
	(gr_line
		(start 98.344228 -392.597386)
		(end 98.344228 -392.429238)
		(stroke
			(width 0.07112)
			(type default)
		)
		(layer "In13.Cu")
	)
	(gr_line
		(start 98.348292 -273.345656)
		(end 98.27895 -273.276314)
		(stroke
			(width 0.05715)
			(type default)
		)
		(layer "In13.Cu")
	)
	(gr_line
		(start 98.348292 -271.725644)
		(end 98.27895 -271.656302)
		(stroke
			(width 0.05715)
			(type default)
		)
		(layer "In13.Cu")
	)
	(gr_line
		(start 98.351848 -296.343324)
		(end 98.351848 -296.324782)
		(stroke
			(width 0.05715)
			(type default)
		)
		(layer "In13.Cu")
	)
	(gr_line
		(start 98.361754 -270.119094)
		(end 98.27895 -270.03629)
		(stroke
			(width 0.05715)
			(type default)
		)
		(layer "In13.Cu")
	)
	(gr_arc
		(start 98.361754 -270.119094)
		(mid 98.363547 -270.130416)
		(end 98.365564 -270.1417)
		(stroke
			(width 0.05715)
			(type default)
		)
		(layer "In13.Cu")
	)
	(gr_arc
		(start 98.536506 -273.381978)
		(mid 98.538529 -273.370568)
		(end 98.540316 -273.359118)
		(stroke
			(width 0.05715)
			(type default)
		)
		(layer "In13.Cu")
	)
	(gr_arc
		(start 98.536506 -271.761966)
		(mid 98.538529 -271.750556)
		(end 98.540316 -271.739106)
		(stroke
			(width 0.05715)
			(type default)
		)
		(layer "In13.Cu")
	)
	(gr_line
		(start 98.540316 -273.359118)
		(end 98.62312 -273.276314)
		(stroke
			(width 0.05715)
			(type default)
		)
		(layer "In13.Cu")
	)
	(gr_line
		(start 98.540316 -271.739106)
		(end 98.62312 -271.656302)
		(stroke
			(width 0.05715)
			(type default)
		)
		(layer "In13.Cu")
	)
	(gr_line
		(start 98.553778 -270.105632)
		(end 98.62312 -270.03629)
		(stroke
			(width 0.05715)
			(type default)
		)
		(layer "In13.Cu")
	)
	(gr_arc
		(start 98.590862 -270.495268)
		(mid 98.594914 -270.49808)
		(end 98.59899 -270.500856)
		(stroke
			(width 0.05715)
			(type default)
		)
		(layer "In13.Cu")
	)
	(gr_line
		(start 98.592132 -296.422318)
		(end 98.592132 -296.365422)
		(stroke
			(width 0.05715)
			(type default)
		)
		(layer "In13.Cu")
	)
	(gr_line
		(start 98.592132 -296.365422)
		(end 98.543618 -296.325798)
		(stroke
			(width 0.05715)
			(type default)
		)
		(layer "In13.Cu")
	)
	(gr_line
		(start 98.601784 -270.502888)
		(end 98.59899 -270.500856)
		(stroke
			(width 0.05715)
			(type default)
		)
		(layer "In13.Cu")
	)
	(gr_line
		(start 98.606102 -270.505428)
		(end 98.601784 -270.502888)
		(stroke
			(width 0.05715)
			(type default)
		)
		(layer "In13.Cu")
	)
	(gr_line
		(start 98.622104 -270.514572)
		(end 98.621596 -270.514318)
		(stroke
			(width 0.05715)
			(type default)
		)
		(layer "In13.Cu")
	)
	(gr_line
		(start 98.62312 -273.276314)
		(end 98.921062 -273.276314)
		(stroke
			(width 0.05715)
			(type default)
		)
		(layer "In13.Cu")
	)
	(gr_line
		(start 98.62312 -271.656302)
		(end 98.921062 -271.656302)
		(stroke
			(width 0.05715)
			(type default)
		)
		(layer "In13.Cu")
	)
	(gr_line
		(start 98.62312 -270.03629)
		(end 98.921062 -270.03629)
		(stroke
			(width 0.05715)
			(type default)
		)
		(layer "In13.Cu")
	)
	(gr_line
		(start 98.825812 -270.8529)
		(end 98.825812 -270.849598)
		(stroke
			(width 0.05715)
			(type default)
		)
		(layer "In13.Cu")
	)
	(gr_arc
		(start 98.825812 -270.8529)
		(mid 98.825935 -270.855059)
		(end 98.826066 -270.857218)
		(stroke
			(width 0.05715)
			(type default)
		)
		(layer "In13.Cu")
	)
	(gr_line
		(start 98.84156 -361.131612)
		(end 98.840544 -361.131612)
		(stroke
			(width 0.07112)
			(type default)
		)
		(layer "In13.Cu")
	)
	(gr_line
		(start 99.010978 -295.151556)
		(end 99.011232 -295.15181)
		(stroke
			(width 0.05715)
			(type default)
		)
		(layer "In13.Cu")
	)
	(gr_arc
		(start 99.071684 -273.619976)
		(mid 99.06402 -273.625247)
		(end 99.056444 -273.630644)
		(stroke
			(width 0.05715)
			(type default)
		)
		(layer "In13.Cu")
	)
	(gr_line
		(start 99.071684 -273.619976)
		(end 99.073208 -273.61896)
		(stroke
			(width 0.05715)
			(type default)
		)
		(layer "In13.Cu")
	)
	(gr_arc
		(start 99.071684 -271.999964)
		(mid 99.064534 -272.004863)
		(end 99.05746 -272.00987)
		(stroke
			(width 0.05715)
			(type default)
		)
		(layer "In13.Cu")
	)
	(gr_line
		(start 99.071684 -271.999964)
		(end 99.073208 -271.998948)
		(stroke
			(width 0.05715)
			(type default)
		)
		(layer "In13.Cu")
	)
	(gr_line
		(start 99.072954 -287.510474)
		(end 99.059746 -287.497012)
		(stroke
			(width 0.05715)
			(type default)
		)
		(layer "In13.Cu")
	)
	(gr_line
		(start 99.073208 -273.61896)
		(end 99.077272 -273.616674)
		(stroke
			(width 0.05715)
			(type default)
		)
		(layer "In13.Cu")
	)
	(gr_line
		(start 99.073208 -271.998948)
		(end 99.077272 -271.996662)
		(stroke
			(width 0.05715)
			(type default)
		)
		(layer "In13.Cu")
	)
	(gr_line
		(start 99.081844 -287.516316)
		(end 99.072954 -287.510474)
		(stroke
			(width 0.05715)
			(type default)
		)
		(layer "In13.Cu")
	)
	(gr_arc
		(start 99.088194 -292.381432)
		(mid 99.092373 -292.384117)
		(end 99.096576 -292.386766)
		(stroke
			(width 0.05715)
			(type default)
		)
		(layer "In13.Cu")
	)
	(gr_line
		(start 99.09175 -287.523174)
		(end 99.09048 -287.522412)
		(stroke
			(width 0.05715)
			(type default)
		)
		(layer "In13.Cu")
	)
	(gr_line
		(start 99.094544 -287.524952)
		(end 99.094798 -287.525206)
		(stroke
			(width 0.05715)
			(type default)
		)
		(layer "In13.Cu")
	)
	(gr_line
		(start 99.094798 -288.186368)
		(end 99.097084 -288.185098)
		(stroke
			(width 0.05715)
			(type default)
		)
		(layer "In13.Cu")
	)
	(gr_line
		(start 99.094798 -287.525206)
		(end 99.09175 -287.523174)
		(stroke
			(width 0.05715)
			(type default)
		)
		(layer "In13.Cu")
	)
	(gr_line
		(start 99.095306 -287.52546)
		(end 99.094544 -287.524952)
		(stroke
			(width 0.05715)
			(type default)
		)
		(layer "In13.Cu")
	)
	(gr_line
		(start 99.096322 -287.525968)
		(end 99.095306 -287.52546)
		(stroke
			(width 0.05715)
			(type default)
		)
		(layer "In13.Cu")
	)
	(gr_line
		(start 99.099116 -287.527746)
		(end 99.097592 -287.52673)
		(stroke
			(width 0.05715)
			(type default)
		)
		(layer "In13.Cu")
	)
	(gr_line
		(start 99.10064 -290.76904)
		(end 99.096576 -290.766754)
		(stroke
			(width 0.05715)
			(type default)
		)
		(layer "In13.Cu")
	)
	(gr_line
		(start 99.101656 -289.150044)
		(end 99.100386 -289.149282)
		(stroke
			(width 0.05715)
			(type default)
		)
		(layer "In13.Cu")
	)
	(gr_line
		(start 99.103688 -294.010842)
		(end 99.096576 -294.006778)
		(stroke
			(width 0.05715)
			(type default)
		)
		(layer "In13.Cu")
	)
	(gr_line
		(start 99.103942 -289.151568)
		(end 99.101656 -289.150044)
		(stroke
			(width 0.05715)
			(type default)
		)
		(layer "In13.Cu")
	)
	(gr_line
		(start 99.104958 -289.15233)
		(end 99.103942 -289.151568)
		(stroke
			(width 0.05715)
			(type default)
		)
		(layer "In13.Cu")
	)
	(gr_line
		(start 99.106482 -289.153092)
		(end 99.105466 -289.152584)
		(stroke
			(width 0.05715)
			(type default)
		)
		(layer "In13.Cu")
	)
	(gr_arc
		(start 99.107498 -293.039038)
		(mid 99.095081 -293.0465)
		(end 99.08286 -293.054278)
		(stroke
			(width 0.05715)
			(type default)
		)
		(layer "In13.Cu")
	)
	(gr_line
		(start 99.107498 -293.039038)
		(end 99.128834 -293.026592)
		(stroke
			(width 0.05715)
			(type default)
		)
		(layer "In13.Cu")
	)
	(gr_line
		(start 99.107752 -289.799014)
		(end 99.1108 -289.797236)
		(stroke
			(width 0.05715)
			(type default)
		)
		(layer "In13.Cu")
	)
	(gr_line
		(start 99.108006 -284.938978)
		(end 99.108514 -284.938724)
		(stroke
			(width 0.05715)
			(type default)
		)
		(layer "In13.Cu")
	)
	(gr_line
		(start 99.108006 -281.053794)
		(end 99.108006 -281.05354)
		(stroke
			(width 0.05715)
			(type default)
		)
		(layer "In13.Cu")
	)
	(gr_line
		(start 99.108006 -273.598894)
		(end 99.108514 -273.59864)
		(stroke
			(width 0.05715)
			(type default)
		)
		(layer "In13.Cu")
	)
	(gr_line
		(start 99.108006 -271.978882)
		(end 99.108514 -271.978628)
		(stroke
			(width 0.05715)
			(type default)
		)
		(layer "In13.Cu")
	)
	(gr_line
		(start 99.10826 -275.218906)
		(end 99.10953 -275.218144)
		(stroke
			(width 0.05715)
			(type default)
		)
		(layer "In13.Cu")
	)
	(gr_line
		(start 99.108514 -281.054048)
		(end 99.108006 -281.053794)
		(stroke
			(width 0.05715)
			(type default)
		)
		(layer "In13.Cu")
	)
	(gr_line
		(start 99.108514 -272.953988)
		(end 99.108006 -272.953734)
		(stroke
			(width 0.05715)
			(type default)
		)
		(layer "In13.Cu")
	)
	(gr_line
		(start 99.108768 -285.914338)
		(end 99.108006 -285.91383)
		(stroke
			(width 0.05715)
			(type default)
		)
		(layer "In13.Cu")
	)
	(gr_line
		(start 99.108768 -284.294326)
		(end 99.108006 -284.293818)
		(stroke
			(width 0.05715)
			(type default)
		)
		(layer "In13.Cu")
	)
	(gr_line
		(start 99.108768 -282.674314)
		(end 99.108006 -282.673806)
		(stroke
			(width 0.05715)
			(type default)
		)
		(layer "In13.Cu")
	)
	(gr_line
		(start 99.108768 -279.43429)
		(end 99.108006 -279.433782)
		(stroke
			(width 0.05715)
			(type default)
		)
		(layer "In13.Cu")
	)
	(gr_line
		(start 99.108768 -277.814278)
		(end 99.108006 -277.81377)
		(stroke
			(width 0.05715)
			(type default)
		)
		(layer "In13.Cu")
	)
	(gr_line
		(start 99.108768 -276.194266)
		(end 99.108006 -276.193758)
		(stroke
			(width 0.05715)
			(type default)
		)
		(layer "In13.Cu")
	)
	(gr_line
		(start 99.108768 -274.574254)
		(end 99.108006 -274.573746)
		(stroke
			(width 0.05715)
			(type default)
		)
		(layer "In13.Cu")
	)
	(gr_line
		(start 99.108768 -271.33423)
		(end 99.108006 -271.333722)
		(stroke
			(width 0.05715)
			(type default)
		)
		(layer "In13.Cu")
	)
	(gr_line
		(start 99.109276 -286.561784)
		(end 99.109022 -286.56153)
		(stroke
			(width 0.05715)
			(type default)
		)
		(layer "In13.Cu")
	)
	(gr_line
		(start 99.10953 -294.657526)
		(end 99.113594 -294.655494)
		(stroke
			(width 0.05715)
			(type default)
		)
		(layer "In13.Cu")
	)
	(gr_line
		(start 99.10953 -275.218144)
		(end 99.110292 -275.217636)
		(stroke
			(width 0.05715)
			(type default)
		)
		(layer "In13.Cu")
	)
	(gr_line
		(start 99.110038 -285.9151)
		(end 99.108768 -285.914338)
		(stroke
			(width 0.05715)
			(type default)
		)
		(layer "In13.Cu")
	)
	(gr_line
		(start 99.110038 -284.295088)
		(end 99.108768 -284.294326)
		(stroke
			(width 0.05715)
			(type default)
		)
		(layer "In13.Cu")
	)
	(gr_line
		(start 99.110038 -282.675076)
		(end 99.108768 -282.674314)
		(stroke
			(width 0.05715)
			(type default)
		)
		(layer "In13.Cu")
	)
	(gr_line
		(start 99.110038 -279.435052)
		(end 99.108768 -279.43429)
		(stroke
			(width 0.05715)
			(type default)
		)
		(layer "In13.Cu")
	)
	(gr_line
		(start 99.110038 -277.81504)
		(end 99.108768 -277.814278)
		(stroke
			(width 0.05715)
			(type default)
		)
		(layer "In13.Cu")
	)
	(gr_line
		(start 99.110038 -276.195028)
		(end 99.108768 -276.194266)
		(stroke
			(width 0.05715)
			(type default)
		)
		(layer "In13.Cu")
	)
	(gr_line
		(start 99.110038 -274.575016)
		(end 99.108768 -274.574254)
		(stroke
			(width 0.05715)
			(type default)
		)
		(layer "In13.Cu")
	)
	(gr_line
		(start 99.110292 -276.837648)
		(end 99.111308 -276.83714)
		(stroke
			(width 0.05715)
			(type default)
		)
		(layer "In13.Cu")
	)
	(gr_line
		(start 99.111308 -276.83714)
		(end 99.11207 -276.836632)
		(stroke
			(width 0.05715)
			(type default)
		)
		(layer "In13.Cu")
	)
	(gr_line
		(start 99.111562 -292.39591)
		(end 99.096576 -292.386766)
		(stroke
			(width 0.05715)
			(type default)
		)
		(layer "In13.Cu")
	)
	(gr_line
		(start 99.11207 -276.836632)
		(end 99.113086 -276.836124)
		(stroke
			(width 0.05715)
			(type default)
		)
		(layer "In13.Cu")
	)
	(gr_line
		(start 99.11207 -275.21662)
		(end 99.11461 -275.21535)
		(stroke
			(width 0.05715)
			(type default)
		)
		(layer "In13.Cu")
	)
	(gr_line
		(start 99.113086 -276.836124)
		(end 99.113848 -276.835616)
		(stroke
			(width 0.05715)
			(type default)
		)
		(layer "In13.Cu")
	)
	(gr_line
		(start 99.11334 -292.39718)
		(end 99.111562 -292.39591)
		(stroke
			(width 0.05715)
			(type default)
		)
		(layer "In13.Cu")
	)
	(gr_line
		(start 99.114102 -285.917386)
		(end 99.112578 -285.91637)
		(stroke
			(width 0.05715)
			(type default)
		)
		(layer "In13.Cu")
	)
	(gr_line
		(start 99.114102 -284.297374)
		(end 99.112578 -284.296358)
		(stroke
			(width 0.05715)
			(type default)
		)
		(layer "In13.Cu")
	)
	(gr_line
		(start 99.114102 -282.677362)
		(end 99.112578 -282.676346)
		(stroke
			(width 0.05715)
			(type default)
		)
		(layer "In13.Cu")
	)
	(gr_line
		(start 99.114102 -279.437338)
		(end 99.112578 -279.436322)
		(stroke
			(width 0.05715)
			(type default)
		)
		(layer "In13.Cu")
	)
	(gr_line
		(start 99.114102 -277.817326)
		(end 99.112578 -277.81631)
		(stroke
			(width 0.05715)
			(type default)
		)
		(layer "In13.Cu")
	)
	(gr_line
		(start 99.114102 -276.197314)
		(end 99.112578 -276.196298)
		(stroke
			(width 0.05715)
			(type default)
		)
		(layer "In13.Cu")
	)
	(gr_line
		(start 99.114102 -274.577302)
		(end 99.112578 -274.576286)
		(stroke
			(width 0.05715)
			(type default)
		)
		(layer "In13.Cu")
	)
	(gr_line
		(start 99.11461 -275.21535)
		(end 99.115372 -275.214842)
		(stroke
			(width 0.05715)
			(type default)
		)
		(layer "In13.Cu")
	)
	(gr_line
		(start 99.115118 -285.917894)
		(end 99.114102 -285.917386)
		(stroke
			(width 0.05715)
			(type default)
		)
		(layer "In13.Cu")
	)
	(gr_line
		(start 99.115118 -284.297882)
		(end 99.114102 -284.297374)
		(stroke
			(width 0.05715)
			(type default)
		)
		(layer "In13.Cu")
	)
	(gr_line
		(start 99.115118 -282.67787)
		(end 99.114102 -282.677362)
		(stroke
			(width 0.05715)
			(type default)
		)
		(layer "In13.Cu")
	)
	(gr_line
		(start 99.115118 -279.437846)
		(end 99.114102 -279.437338)
		(stroke
			(width 0.05715)
			(type default)
		)
		(layer "In13.Cu")
	)
	(gr_line
		(start 99.115118 -277.817834)
		(end 99.114102 -277.817326)
		(stroke
			(width 0.05715)
			(type default)
		)
		(layer "In13.Cu")
	)
	(gr_line
		(start 99.115118 -276.197822)
		(end 99.114102 -276.197314)
		(stroke
			(width 0.05715)
			(type default)
		)
		(layer "In13.Cu")
	)
	(gr_line
		(start 99.115118 -274.57781)
		(end 99.114102 -274.577302)
		(stroke
			(width 0.05715)
			(type default)
		)
		(layer "In13.Cu")
	)
	(gr_line
		(start 99.115372 -275.214842)
		(end 99.116388 -275.214334)
		(stroke
			(width 0.05715)
			(type default)
		)
		(layer "In13.Cu")
	)
	(gr_line
		(start 99.115626 -285.918148)
		(end 99.115118 -285.917894)
		(stroke
			(width 0.05715)
			(type default)
		)
		(layer "In13.Cu")
	)
	(gr_line
		(start 99.115626 -284.298136)
		(end 99.115118 -284.297882)
		(stroke
			(width 0.05715)
			(type default)
		)
		(layer "In13.Cu")
	)
	(gr_line
		(start 99.115626 -282.678124)
		(end 99.115118 -282.67787)
		(stroke
			(width 0.05715)
			(type default)
		)
		(layer "In13.Cu")
	)
	(gr_line
		(start 99.115626 -279.4381)
		(end 99.115118 -279.437846)
		(stroke
			(width 0.05715)
			(type default)
		)
		(layer "In13.Cu")
	)
	(gr_line
		(start 99.115626 -277.818088)
		(end 99.115118 -277.817834)
		(stroke
			(width 0.05715)
			(type default)
		)
		(layer "In13.Cu")
	)
	(gr_line
		(start 99.115626 -276.198076)
		(end 99.115118 -276.197822)
		(stroke
			(width 0.05715)
			(type default)
		)
		(layer "In13.Cu")
	)
	(gr_line
		(start 99.115626 -274.578064)
		(end 99.115118 -274.57781)
		(stroke
			(width 0.05715)
			(type default)
		)
		(layer "In13.Cu")
	)
	(gr_line
		(start 99.116896 -294.018716)
		(end 99.114356 -294.017192)
		(stroke
			(width 0.05715)
			(type default)
		)
		(layer "In13.Cu")
	)
	(gr_line
		(start 99.123246 -292.402006)
		(end 99.11334 -292.39718)
		(stroke
			(width 0.05715)
			(type default)
		)
		(layer "In13.Cu")
	)
	(gr_line
		(start 99.134676 -292.40861)
		(end 99.123246 -292.402006)
		(stroke
			(width 0.05715)
			(type default)
		)
		(layer "In13.Cu")
	)
	(gr_line
		(start 99.19081 -288.351214)
		(end 99.191064 -288.35096)
		(stroke
			(width 0.05715)
			(type default)
		)
		(layer "In13.Cu")
	)
	(gr_arc
		(start 99.191064 -293.212774)
		(mid 99.217924 -293.197239)
		(end 99.243896 -293.180262)
		(stroke
			(width 0.05715)
			(type default)
		)
		(layer "In13.Cu")
	)
	(gr_line
		(start 99.194874 -292.22065)
		(end 99.192588 -292.22065)
		(stroke
			(width 0.05715)
			(type default)
		)
		(layer "In13.Cu")
	)
	(gr_line
		(start 99.196144 -288.984436)
		(end 99.194112 -288.983166)
		(stroke
			(width 0.05715)
			(type default)
		)
		(layer "In13.Cu")
	)
	(gr_line
		(start 99.196906 -288.984944)
		(end 99.196144 -288.984436)
		(stroke
			(width 0.05715)
			(type default)
		)
		(layer "In13.Cu")
	)
	(gr_line
		(start 99.197414 -290.604956)
		(end 99.196144 -290.604194)
		(stroke
			(width 0.05715)
			(type default)
		)
		(layer "In13.Cu")
	)
	(gr_line
		(start 99.198176 -288.985706)
		(end 99.196906 -288.984944)
		(stroke
			(width 0.05715)
			(type default)
		)
		(layer "In13.Cu")
	)
	(gr_line
		(start 99.200716 -288.98723)
		(end 99.1997 -288.986468)
		(stroke
			(width 0.05715)
			(type default)
		)
		(layer "In13.Cu")
	)
	(gr_line
		(start 99.201986 -294.824912)
		(end 99.203256 -294.82415)
		(stroke
			(width 0.05715)
			(type default)
		)
		(layer "In13.Cu")
	)
	(gr_line
		(start 99.203256 -284.128464)
		(end 99.200462 -284.12694)
		(stroke
			(width 0.05715)
			(type default)
		)
		(layer "In13.Cu")
	)
	(gr_line
		(start 99.203256 -282.508452)
		(end 99.200462 -282.506928)
		(stroke
			(width 0.05715)
			(type default)
		)
		(layer "In13.Cu")
	)
	(gr_line
		(start 99.203256 -280.88844)
		(end 99.202494 -280.887932)
		(stroke
			(width 0.05715)
			(type default)
		)
		(layer "In13.Cu")
	)
	(gr_line
		(start 99.203256 -279.268428)
		(end 99.200462 -279.266904)
		(stroke
			(width 0.05715)
			(type default)
		)
		(layer "In13.Cu")
	)
	(gr_line
		(start 99.203256 -277.648416)
		(end 99.200462 -277.646892)
		(stroke
			(width 0.05715)
			(type default)
		)
		(layer "In13.Cu")
	)
	(gr_line
		(start 99.203256 -276.028404)
		(end 99.200462 -276.02688)
		(stroke
			(width 0.05715)
			(type default)
		)
		(layer "In13.Cu")
	)
	(gr_line
		(start 99.204018 -284.128972)
		(end 99.203256 -284.128464)
		(stroke
			(width 0.05715)
			(type default)
		)
		(layer "In13.Cu")
	)
	(gr_line
		(start 99.204018 -282.50896)
		(end 99.203256 -282.508452)
		(stroke
			(width 0.05715)
			(type default)
		)
		(layer "In13.Cu")
	)
	(gr_line
		(start 99.204018 -279.268936)
		(end 99.203256 -279.268428)
		(stroke
			(width 0.05715)
			(type default)
		)
		(layer "In13.Cu")
	)
	(gr_line
		(start 99.204018 -277.648924)
		(end 99.203256 -277.648416)
		(stroke
			(width 0.05715)
			(type default)
		)
		(layer "In13.Cu")
	)
	(gr_line
		(start 99.204018 -276.028912)
		(end 99.203256 -276.028404)
		(stroke
			(width 0.05715)
			(type default)
		)
		(layer "In13.Cu")
	)
	(gr_line
		(start 99.204272 -294.823388)
		(end 99.205034 -294.823134)
		(stroke
			(width 0.05715)
			(type default)
		)
		(layer "In13.Cu")
	)
	(gr_line
		(start 99.205034 -294.823134)
		(end 99.209352 -294.820848)
		(stroke
			(width 0.05715)
			(type default)
		)
		(layer "In13.Cu")
	)
	(gr_line
		(start 99.205034 -284.12948)
		(end 99.204018 -284.128972)
		(stroke
			(width 0.05715)
			(type default)
		)
		(layer "In13.Cu")
	)
	(gr_line
		(start 99.205034 -283.483304)
		(end 99.212654 -283.478986)
		(stroke
			(width 0.05715)
			(type default)
		)
		(layer "In13.Cu")
	)
	(gr_line
		(start 99.205034 -282.509468)
		(end 99.204018 -282.50896)
		(stroke
			(width 0.05715)
			(type default)
		)
		(layer "In13.Cu")
	)
	(gr_line
		(start 99.205034 -281.863292)
		(end 99.212654 -281.858974)
		(stroke
			(width 0.05715)
			(type default)
		)
		(layer "In13.Cu")
	)
	(gr_line
		(start 99.205034 -279.269444)
		(end 99.204018 -279.268936)
		(stroke
			(width 0.05715)
			(type default)
		)
		(layer "In13.Cu")
	)
	(gr_line
		(start 99.205034 -278.623268)
		(end 99.212654 -278.61895)
		(stroke
			(width 0.05715)
			(type default)
		)
		(layer "In13.Cu")
	)
	(gr_line
		(start 99.205034 -277.649432)
		(end 99.204018 -277.648924)
		(stroke
			(width 0.05715)
			(type default)
		)
		(layer "In13.Cu")
	)
	(gr_line
		(start 99.205034 -277.003256)
		(end 99.209606 -277.000462)
		(stroke
			(width 0.05715)
			(type default)
		)
		(layer "In13.Cu")
	)
	(gr_line
		(start 99.205034 -276.02942)
		(end 99.204018 -276.028912)
		(stroke
			(width 0.05715)
			(type default)
		)
		(layer "In13.Cu")
	)
	(gr_line
		(start 99.205034 -275.383244)
		(end 99.206812 -275.382228)
		(stroke
			(width 0.05715)
			(type default)
		)
		(layer "In13.Cu")
	)
	(gr_line
		(start 99.206812 -284.130496)
		(end 99.205034 -284.12948)
		(stroke
			(width 0.05715)
			(type default)
		)
		(layer "In13.Cu")
	)
	(gr_line
		(start 99.206812 -282.510484)
		(end 99.205034 -282.509468)
		(stroke
			(width 0.05715)
			(type default)
		)
		(layer "In13.Cu")
	)
	(gr_line
		(start 99.206812 -279.27046)
		(end 99.205034 -279.269444)
		(stroke
			(width 0.05715)
			(type default)
		)
		(layer "In13.Cu")
	)
	(gr_line
		(start 99.206812 -277.650448)
		(end 99.205034 -277.649432)
		(stroke
			(width 0.05715)
			(type default)
		)
		(layer "In13.Cu")
	)
	(gr_line
		(start 99.206812 -276.030436)
		(end 99.205034 -276.02942)
		(stroke
			(width 0.05715)
			(type default)
		)
		(layer "In13.Cu")
	)
	(gr_line
		(start 99.206812 -275.382228)
		(end 99.207828 -275.38172)
		(stroke
			(width 0.05715)
			(type default)
		)
		(layer "In13.Cu")
	)
	(gr_line
		(start 99.207828 -275.38172)
		(end 99.210622 -275.380196)
		(stroke
			(width 0.05715)
			(type default)
		)
		(layer "In13.Cu")
	)
	(gr_line
		(start 99.209352 -285.752032)
		(end 99.208336 -285.751524)
		(stroke
			(width 0.05715)
			(type default)
		)
		(layer "In13.Cu")
	)
	(gr_line
		(start 99.209352 -274.411948)
		(end 99.208336 -274.41144)
		(stroke
			(width 0.05715)
			(type default)
		)
		(layer "In13.Cu")
	)
	(gr_line
		(start 99.209606 -271.171924)
		(end 99.208336 -271.171162)
		(stroke
			(width 0.05715)
			(type default)
		)
		(layer "In13.Cu")
	)
	(gr_line
		(start 99.210368 -285.752794)
		(end 99.209352 -285.752032)
		(stroke
			(width 0.05715)
			(type default)
		)
		(layer "In13.Cu")
	)
	(gr_line
		(start 99.210368 -274.41271)
		(end 99.209352 -274.411948)
		(stroke
			(width 0.05715)
			(type default)
		)
		(layer "In13.Cu")
	)
	(gr_line
		(start 99.210622 -275.380196)
		(end 99.211638 -275.379688)
		(stroke
			(width 0.05715)
			(type default)
		)
		(layer "In13.Cu")
	)
	(gr_line
		(start 99.210876 -294.819832)
		(end 99.212908 -294.818816)
		(stroke
			(width 0.05715)
			(type default)
		)
		(layer "In13.Cu")
	)
	(gr_line
		(start 99.212908 -294.818816)
		(end 99.213924 -294.818308)
		(stroke
			(width 0.05715)
			(type default)
		)
		(layer "In13.Cu")
	)
	(gr_line
		(start 99.21494 -294.817546)
		(end 99.215702 -294.817038)
		(stroke
			(width 0.05715)
			(type default)
		)
		(layer "In13.Cu")
	)
	(gr_line
		(start 99.215702 -294.817038)
		(end 99.21621 -294.816784)
		(stroke
			(width 0.05715)
			(type default)
		)
		(layer "In13.Cu")
	)
	(gr_line
		(start 99.223068 -291.572442)
		(end 99.224084 -291.571934)
		(stroke
			(width 0.05715)
			(type default)
		)
		(layer "In13.Cu")
	)
	(gr_line
		(start 99.223068 -289.95243)
		(end 99.226116 -289.950652)
		(stroke
			(width 0.05715)
			(type default)
		)
		(layer "In13.Cu")
	)
	(gr_line
		(start 99.224084 -291.571934)
		(end 99.2251 -291.571426)
		(stroke
			(width 0.05715)
			(type default)
		)
		(layer "In13.Cu")
	)
	(gr_line
		(start 99.2251 -291.571426)
		(end 99.226116 -291.570918)
		(stroke
			(width 0.05715)
			(type default)
		)
		(layer "In13.Cu")
	)
	(gr_line
		(start 99.235514 -285.767272)
		(end 99.23018 -285.764224)
		(stroke
			(width 0.05715)
			(type default)
		)
		(layer "In13.Cu")
	)
	(gr_line
		(start 99.235514 -284.14726)
		(end 99.235006 -284.147006)
		(stroke
			(width 0.05715)
			(type default)
		)
		(layer "In13.Cu")
	)
	(gr_line
		(start 99.235514 -282.527248)
		(end 99.235006 -282.526994)
		(stroke
			(width 0.05715)
			(type default)
		)
		(layer "In13.Cu")
	)
	(gr_line
		(start 99.235514 -279.287224)
		(end 99.235006 -279.28697)
		(stroke
			(width 0.05715)
			(type default)
		)
		(layer "In13.Cu")
	)
	(gr_line
		(start 99.235514 -277.667212)
		(end 99.235006 -277.666958)
		(stroke
			(width 0.05715)
			(type default)
		)
		(layer "In13.Cu")
	)
	(gr_line
		(start 99.235514 -276.0472)
		(end 99.235006 -276.046946)
		(stroke
			(width 0.05715)
			(type default)
		)
		(layer "In13.Cu")
	)
	(gr_line
		(start 99.235514 -274.427188)
		(end 99.235006 -274.426934)
		(stroke
			(width 0.05715)
			(type default)
		)
		(layer "In13.Cu")
	)
	(gr_line
		(start 99.235514 -271.187164)
		(end 99.234244 -271.186402)
		(stroke
			(width 0.05715)
			(type default)
		)
		(layer "In13.Cu")
	)
	(gr_line
		(start 99.236276 -284.147768)
		(end 99.235514 -284.14726)
		(stroke
			(width 0.05715)
			(type default)
		)
		(layer "In13.Cu")
	)
	(gr_line
		(start 99.236276 -282.527756)
		(end 99.235514 -282.527248)
		(stroke
			(width 0.05715)
			(type default)
		)
		(layer "In13.Cu")
	)
	(gr_line
		(start 99.236276 -279.287732)
		(end 99.235514 -279.287224)
		(stroke
			(width 0.05715)
			(type default)
		)
		(layer "In13.Cu")
	)
	(gr_line
		(start 99.236276 -277.66772)
		(end 99.235514 -277.667212)
		(stroke
			(width 0.05715)
			(type default)
		)
		(layer "In13.Cu")
	)
	(gr_line
		(start 99.236276 -276.047708)
		(end 99.235514 -276.0472)
		(stroke
			(width 0.05715)
			(type default)
		)
		(layer "In13.Cu")
	)
	(gr_line
		(start 99.236276 -274.427696)
		(end 99.235514 -274.427188)
		(stroke
			(width 0.05715)
			(type default)
		)
		(layer "In13.Cu")
	)
	(gr_line
		(start 99.236276 -271.187672)
		(end 99.235514 -271.187164)
		(stroke
			(width 0.05715)
			(type default)
		)
		(layer "In13.Cu")
	)
	(gr_line
		(start 99.24161 -290.63061)
		(end 99.235768 -290.627308)
		(stroke
			(width 0.05715)
			(type default)
		)
		(layer "In13.Cu")
	)
	(gr_arc
		(start 99.24161 -290.63061)
		(mid 99.242372 -290.631118)
		(end 99.243134 -290.631626)
		(stroke
			(width 0.05715)
			(type default)
		)
		(layer "In13.Cu")
	)
	(gr_line
		(start 99.242372 -293.871142)
		(end 99.235768 -293.867332)
		(stroke
			(width 0.05715)
			(type default)
		)
		(layer "In13.Cu")
	)
	(gr_arc
		(start 99.242372 -293.871142)
		(mid 99.242753 -293.871396)
		(end 99.243134 -293.87165)
		(stroke
			(width 0.05715)
			(type default)
		)
		(layer "In13.Cu")
	)
	(gr_line
		(start 99.242372 -287.391348)
		(end 99.241102 -287.390586)
		(stroke
			(width 0.05715)
			(type default)
		)
		(layer "In13.Cu")
	)
	(gr_line
		(start 99.242372 -287.391094)
		(end 99.242372 -287.391348)
		(stroke
			(width 0.05715)
			(type default)
		)
		(layer "In13.Cu")
	)
	(gr_line
		(start 99.242372 -285.771844)
		(end 99.235514 -285.767272)
		(stroke
			(width 0.05715)
			(type default)
		)
		(layer "In13.Cu")
	)
	(gr_line
		(start 99.243134 -284.151832)
		(end 99.236276 -284.147768)
		(stroke
			(width 0.05715)
			(type default)
		)
		(layer "In13.Cu")
	)
	(gr_line
		(start 99.243134 -282.53182)
		(end 99.236276 -282.527756)
		(stroke
			(width 0.05715)
			(type default)
		)
		(layer "In13.Cu")
	)
	(gr_line
		(start 99.243134 -279.291796)
		(end 99.236276 -279.287732)
		(stroke
			(width 0.05715)
			(type default)
		)
		(layer "In13.Cu")
	)
	(gr_line
		(start 99.243134 -277.671784)
		(end 99.236276 -277.66772)
		(stroke
			(width 0.05715)
			(type default)
		)
		(layer "In13.Cu")
	)
	(gr_line
		(start 99.243134 -276.051772)
		(end 99.236276 -276.047708)
		(stroke
			(width 0.05715)
			(type default)
		)
		(layer "In13.Cu")
	)
	(gr_line
		(start 99.243134 -274.43176)
		(end 99.236276 -274.427696)
		(stroke
			(width 0.05715)
			(type default)
		)
		(layer "In13.Cu")
	)
	(gr_line
		(start 99.243134 -271.191736)
		(end 99.236276 -271.187672)
		(stroke
			(width 0.05715)
			(type default)
		)
		(layer "In13.Cu")
	)
	(gr_arc
		(start 99.24415 -285.773114)
		(mid 99.243262 -285.772478)
		(end 99.242372 -285.771844)
		(stroke
			(width 0.05715)
			(type default)
		)
		(layer "In13.Cu")
	)
	(gr_arc
		(start 99.245674 -288.31921)
		(mid 99.25103 -288.315303)
		(end 99.256342 -288.311336)
		(stroke
			(width 0.05715)
			(type default)
		)
		(layer "In13.Cu")
	)
	(gr_arc
		(start 99.248214 -287.395158)
		(mid 99.245299 -287.393117)
		(end 99.242372 -287.391094)
		(stroke
			(width 0.05715)
			(type default)
		)
		(layer "In13.Cu")
	)
	(gr_arc
		(start 99.249992 -290.636452)
		(mid 99.246572 -290.634026)
		(end 99.243134 -290.631626)
		(stroke
			(width 0.05715)
			(type default)
		)
		(layer "In13.Cu")
	)
	(gr_arc
		(start 99.251008 -293.877238)
		(mid 99.247083 -293.874427)
		(end 99.243134 -293.87165)
		(stroke
			(width 0.05715)
			(type default)
		)
		(layer "In13.Cu")
	)
	(gr_arc
		(start 99.251008 -284.15742)
		(mid 99.247083 -284.154609)
		(end 99.243134 -284.151832)
		(stroke
			(width 0.05715)
			(type default)
		)
		(layer "In13.Cu")
	)
	(gr_arc
		(start 99.251008 -282.537408)
		(mid 99.247083 -282.534597)
		(end 99.243134 -282.53182)
		(stroke
			(width 0.05715)
			(type default)
		)
		(layer "In13.Cu")
	)
	(gr_arc
		(start 99.251008 -279.297384)
		(mid 99.247083 -279.294573)
		(end 99.243134 -279.291796)
		(stroke
			(width 0.05715)
			(type default)
		)
		(layer "In13.Cu")
	)
	(gr_arc
		(start 99.251008 -277.677372)
		(mid 99.247083 -277.674561)
		(end 99.243134 -277.671784)
		(stroke
			(width 0.05715)
			(type default)
		)
		(layer "In13.Cu")
	)
	(gr_arc
		(start 99.251008 -276.05736)
		(mid 99.247083 -276.054549)
		(end 99.243134 -276.051772)
		(stroke
			(width 0.05715)
			(type default)
		)
		(layer "In13.Cu")
	)
	(gr_arc
		(start 99.251008 -274.437348)
		(mid 99.247083 -274.434537)
		(end 99.243134 -274.43176)
		(stroke
			(width 0.05715)
			(type default)
		)
		(layer "In13.Cu")
	)
	(gr_arc
		(start 99.251008 -271.197324)
		(mid 99.247083 -271.194513)
		(end 99.243134 -271.191736)
		(stroke
			(width 0.05715)
			(type default)
		)
		(layer "In13.Cu")
	)
	(gr_arc
		(start 99.251262 -292.25621)
		(mid 99.223588 -292.237605)
		(end 99.194874 -292.22065)
		(stroke
			(width 0.05715)
			(type default)
		)
		(layer "In13.Cu")
	)
	(gr_arc
		(start 99.256088 -287.400746)
		(mid 99.252541 -287.398193)
		(end 99.248976 -287.395666)
		(stroke
			(width 0.05715)
			(type default)
		)
		(layer "In13.Cu")
	)
	(gr_line
		(start 99.564444 3.382264)
		(end 99.273614 3.091434)
		(stroke
			(width 0.07112)
			(type default)
		)
		(layer "In13.Cu")
	)
	(gr_line
		(start 99.564444 3.664204)
		(end 99.273614 3.955034)
		(stroke
			(width 0.07112)
			(type default)
		)
		(layer "In13.Cu")
	)
	(gr_line
		(start 99.599242 -296.612564)
		(end 99.599242 -296.584116)
		(stroke
			(width 0.05715)
			(type default)
		)
		(layer "In13.Cu")
	)
	(gr_line
		(start 99.599242 -296.584116)
		(end 99.644962 -296.538396)
		(stroke
			(width 0.05715)
			(type default)
		)
		(layer "In13.Cu")
	)
	(gr_line
		(start 99.881182 -296.612564)
		(end 99.881182 -296.584116)
		(stroke
			(width 0.05715)
			(type default)
		)
		(layer "In13.Cu")
	)
	(gr_line
		(start 99.881182 -296.584116)
		(end 99.835462 -296.538396)
		(stroke
			(width 0.05715)
			(type default)
		)
		(layer "In13.Cu")
	)
	(gr_line
		(start 100.510848 -272.793206)
		(end 100.514658 -272.79092)
		(stroke
			(width 0.05715)
			(type default)
		)
		(layer "In13.Cu")
	)
	(gr_line
		(start 100.514658 -272.79092)
		(end 100.515674 -272.790412)
		(stroke
			(width 0.05715)
			(type default)
		)
		(layer "In13.Cu")
	)
	(gr_line
		(start 100.517706 -272.789142)
		(end 100.518214 -272.788888)
		(stroke
			(width 0.05715)
			(type default)
		)
		(layer "In13.Cu")
	)
	(gr_line
		(start 100.518214 -272.788888)
		(end 100.518976 -272.78838)
		(stroke
			(width 0.05715)
			(type default)
		)
		(layer "In13.Cu")
	)
	(gr_line
		(start 100.604066 -272.959576)
		(end 100.604828 -272.959068)
		(stroke
			(width 0.05715)
			(type default)
		)
		(layer "In13.Cu")
	)
	(gr_line
		(start 100.61194 -272.955004)
		(end 100.613464 -272.954242)
		(stroke
			(width 0.05715)
			(type default)
		)
		(layer "In13.Cu")
	)
	(gr_line
		(start 100.613464 -272.954242)
		(end 100.614226 -272.953734)
		(stroke
			(width 0.05715)
			(type default)
		)
		(layer "In13.Cu")
	)
	(gr_line
		(start 100.614226 -272.953734)
		(end 100.615242 -272.953226)
		(stroke
			(width 0.05715)
			(type default)
		)
		(layer "In13.Cu")
	)
	(gr_line
		(start 100.615242 -272.953226)
		(end 100.616766 -272.95221)
		(stroke
			(width 0.05715)
			(type default)
		)
		(layer "In13.Cu")
	)
	(gr_line
		(start 100.618544 -272.951194)
		(end 100.6221 -272.949162)
		(stroke
			(width 0.05715)
			(type default)
		)
		(layer "In13.Cu")
	)
	(gr_line
		(start 100.6602 -296.422318)
		(end 100.6602 -296.39387)
		(stroke
			(width 0.05715)
			(type default)
		)
		(layer "In13.Cu")
	)
	(gr_line
		(start 100.6602 -296.39387)
		(end 100.70592 -296.34815)
		(stroke
			(width 0.05715)
			(type default)
		)
		(layer "In13.Cu")
	)
	(gr_arc
		(start 100.939854 -286.5882)
		(mid 100.937691 -286.589846)
		(end 100.935536 -286.591502)
		(stroke
			(width 0.05715)
			(type default)
		)
		(layer "In13.Cu")
	)
	(gr_line
		(start 100.939854 -286.5882)
		(end 100.940108 -286.587946)
		(stroke
			(width 0.05715)
			(type default)
		)
		(layer "In13.Cu")
	)
	(gr_line
		(start 100.940108 -286.587946)
		(end 100.944934 -286.584644)
		(stroke
			(width 0.05715)
			(type default)
		)
		(layer "In13.Cu")
	)
	(gr_line
		(start 100.94214 -296.422318)
		(end 100.94214 -296.39387)
		(stroke
			(width 0.05715)
			(type default)
		)
		(layer "In13.Cu")
	)
	(gr_line
		(start 100.94214 -296.39387)
		(end 100.89642 -296.34815)
		(stroke
			(width 0.05715)
			(type default)
		)
		(layer "In13.Cu")
	)
	(gr_line
		(start 100.947474 -286.58312)
		(end 100.947982 -286.582612)
		(stroke
			(width 0.05715)
			(type default)
		)
		(layer "In13.Cu")
	)
	(gr_line
		(start 100.947982 -286.582612)
		(end 100.950522 -286.580834)
		(stroke
			(width 0.05715)
			(type default)
		)
		(layer "In13.Cu")
	)
	(gr_line
		(start 100.950522 -286.580834)
		(end 100.951284 -286.58058)
		(stroke
			(width 0.05715)
			(type default)
		)
		(layer "In13.Cu")
	)
	(gr_line
		(start 100.954078 -286.578548)
		(end 100.955348 -286.57804)
		(stroke
			(width 0.05715)
			(type default)
		)
		(layer "In13.Cu")
	)
	(gr_line
		(start 100.958904 -286.576008)
		(end 100.960428 -286.574992)
		(stroke
			(width 0.05715)
			(type default)
		)
		(layer "In13.Cu")
	)
	(gr_line
		(start 100.964746 -286.571944)
		(end 100.965508 -286.571436)
		(stroke
			(width 0.05715)
			(type default)
		)
		(layer "In13.Cu")
	)
	(gr_line
		(start 100.965508 -286.571436)
		(end 100.972366 -286.567372)
		(stroke
			(width 0.05715)
			(type default)
		)
		(layer "In13.Cu")
	)
	(gr_line
		(start 100.972366 -286.567372)
		(end 100.973382 -286.566864)
		(stroke
			(width 0.05715)
			(type default)
		)
		(layer "In13.Cu")
	)
	(gr_line
		(start 100.973382 -286.566864)
		(end 100.974652 -286.566102)
		(stroke
			(width 0.05715)
			(type default)
		)
		(layer "In13.Cu")
	)
	(gr_line
		(start 100.974652 -286.566102)
		(end 100.975668 -286.565594)
		(stroke
			(width 0.05715)
			(type default)
		)
		(layer "In13.Cu")
	)
	(gr_line
		(start 101.053138 -286.74187)
		(end 101.054408 -286.741108)
		(stroke
			(width 0.05715)
			(type default)
		)
		(layer "In13.Cu")
	)
	(gr_line
		(start 101.054408 -286.741108)
		(end 101.055424 -286.7406)
		(stroke
			(width 0.05715)
			(type default)
		)
		(layer "In13.Cu")
	)
	(gr_line
		(start 101.055424 -286.7406)
		(end 101.056694 -286.739838)
		(stroke
			(width 0.05715)
			(type default)
		)
		(layer "In13.Cu")
	)
	(gr_line
		(start 101.056694 -286.739838)
		(end 101.05771 -286.739076)
		(stroke
			(width 0.05715)
			(type default)
		)
		(layer "In13.Cu")
	)
	(gr_line
		(start 101.069902 -286.731202)
		(end 101.07041 -286.730948)
		(stroke
			(width 0.05715)
			(type default)
		)
		(layer "In13.Cu")
	)
	(gr_line
		(start 101.084126 -286.723074)
		(end 101.084888 -286.722566)
		(stroke
			(width 0.05715)
			(type default)
		)
		(layer "In13.Cu")
	)
	(gr_line
		(start 101.099112 -273.276314)
		(end 100.80117 -273.276314)
		(stroke
			(width 0.05715)
			(type default)
		)
		(layer "In13.Cu")
	)
	(gr_line
		(start 101.099112 -271.656302)
		(end 100.80117 -271.656302)
		(stroke
			(width 0.05715)
			(type default)
		)
		(layer "In13.Cu")
	)
	(gr_line
		(start 101.099112 -270.03629)
		(end 100.80117 -270.03629)
		(stroke
			(width 0.05715)
			(type default)
		)
		(layer "In13.Cu")
	)
	(gr_line
		(start 101.168454 -273.345656)
		(end 101.099112 -273.276314)
		(stroke
			(width 0.05715)
			(type default)
		)
		(layer "In13.Cu")
	)
	(gr_line
		(start 101.168454 -271.725644)
		(end 101.099112 -271.656302)
		(stroke
			(width 0.05715)
			(type default)
		)
		(layer "In13.Cu")
	)
	(gr_line
		(start 101.181916 -270.119094)
		(end 101.099112 -270.03629)
		(stroke
			(width 0.05715)
			(type default)
		)
		(layer "In13.Cu")
	)
	(gr_arc
		(start 101.181916 -270.119094)
		(mid 101.183707 -270.130416)
		(end 101.185726 -270.1417)
		(stroke
			(width 0.05715)
			(type default)
		)
		(layer "In13.Cu")
	)
	(gr_arc
		(start 101.356668 -273.381978)
		(mid 101.358691 -273.370568)
		(end 101.360478 -273.359118)
		(stroke
			(width 0.05715)
			(type default)
		)
		(layer "In13.Cu")
	)
	(gr_arc
		(start 101.356668 -271.761966)
		(mid 101.35869 -271.750556)
		(end 101.360478 -271.739106)
		(stroke
			(width 0.05715)
			(type default)
		)
		(layer "In13.Cu")
	)
	(gr_line
		(start 101.360478 -273.359118)
		(end 101.443282 -273.276314)
		(stroke
			(width 0.05715)
			(type default)
		)
		(layer "In13.Cu")
	)
	(gr_line
		(start 101.360478 -271.739106)
		(end 101.443282 -271.656302)
		(stroke
			(width 0.05715)
			(type default)
		)
		(layer "In13.Cu")
	)
	(gr_line
		(start 101.37394 -270.105378)
		(end 101.443028 -270.03629)
		(stroke
			(width 0.05715)
			(type default)
		)
		(layer "In13.Cu")
	)
	(gr_line
		(start 101.443028 -270.03629)
		(end 101.74097 -270.03629)
		(stroke
			(width 0.05715)
			(type default)
		)
		(layer "In13.Cu")
	)
	(gr_line
		(start 101.443282 -273.276314)
		(end 101.74097 -273.276314)
		(stroke
			(width 0.05715)
			(type default)
		)
		(layer "In13.Cu")
	)
	(gr_line
		(start 101.443282 -271.656302)
		(end 101.74097 -271.656302)
		(stroke
			(width 0.05715)
			(type default)
		)
		(layer "In13.Cu")
	)
	(gr_line
		(start 101.459538 -270.526002)
		(end 101.457506 -270.524732)
		(stroke
			(width 0.05715)
			(type default)
		)
		(layer "In13.Cu")
	)
	(gr_line
		(start 101.553518 -270.359886)
		(end 101.553264 -270.359632)
		(stroke
			(width 0.05715)
			(type default)
		)
		(layer "In13.Cu")
	)
	(gr_line
		(start 101.557836 -270.362172)
		(end 101.555296 -270.360902)
		(stroke
			(width 0.05715)
			(type default)
		)
		(layer "In13.Cu")
	)
	(gr_arc
		(start 101.560884 -270.364204)
		(mid 101.560122 -270.363695)
		(end 101.55936 -270.363188)
		(stroke
			(width 0.05715)
			(type default)
		)
		(layer "In13.Cu")
	)
	(gr_line
		(start 101.6381 -295.122092)
		(end 101.6381 -295.121584)
		(stroke
			(width 0.05715)
			(type default)
		)
		(layer "In13.Cu")
	)
	(gr_line
		(start 101.934518 -294.65524)
		(end 101.935026 -294.654732)
		(stroke
			(width 0.05715)
			(type default)
		)
		(layer "In13.Cu")
	)
	(gr_line
		(start 102.052882 -294.806878)
		(end 102.053644 -294.80637)
		(stroke
			(width 0.05715)
			(type default)
		)
		(layer "In13.Cu")
	)
	(gr_line
		(start 102.054914 -294.805608)
		(end 102.05593 -294.8051)
		(stroke
			(width 0.05715)
			(type default)
		)
		(layer "In13.Cu")
	)
	(gr_line
		(start 102.05593 -294.8051)
		(end 102.056692 -294.804592)
		(stroke
			(width 0.05715)
			(type default)
		)
		(layer "In13.Cu")
	)
	(gr_line
		(start 102.056692 -294.804592)
		(end 102.060756 -294.802052)
		(stroke
			(width 0.05715)
			(type default)
		)
		(layer "In13.Cu")
	)
	(gr_line
		(start 102.061518 -294.801798)
		(end 102.063042 -294.800782)
		(stroke
			(width 0.05715)
			(type default)
		)
		(layer "In13.Cu")
	)
	(gr_arc
		(start 102.06355 -294.800528)
		(mid 102.064567 -294.799767)
		(end 102.065582 -294.799004)
		(stroke
			(width 0.05715)
			(type default)
		)
		(layer "In13.Cu")
	)
	(gr_arc
		(start 102.066344 -294.798496)
		(mid 102.069399 -294.796347)
		(end 102.07244 -294.794178)
		(stroke
			(width 0.05715)
			(type default)
		)
		(layer "In13.Cu")
	)
	(gr_line
		(start 102.070154 -296.436288)
		(end 102.070154 -296.40784)
		(stroke
			(width 0.05715)
			(type default)
		)
		(layer "In13.Cu")
	)
	(gr_line
		(start 102.070154 -296.40784)
		(end 102.115874 -296.36212)
		(stroke
			(width 0.05715)
			(type default)
		)
		(layer "In13.Cu")
	)
	(gr_line
		(start 102.299008 -358.047544)
		(end 102.299262 -358.047544)
		(stroke
			(width 0.07112)
			(type default)
		)
		(layer "In13.Cu")
	)
	(gr_line
		(start 102.352094 -296.436288)
		(end 102.352094 -296.40784)
		(stroke
			(width 0.05715)
			(type default)
		)
		(layer "In13.Cu")
	)
	(gr_line
		(start 102.352094 -296.40784)
		(end 102.306374 -296.36212)
		(stroke
			(width 0.05715)
			(type default)
		)
		(layer "In13.Cu")
	)
	(gr_arc
		(start 102.718362 -294.780462)
		(mid 102.718616 -294.780208)
		(end 102.71887 -294.779954)
		(stroke
			(width 0.05715)
			(type default)
		)
		(layer "In13.Cu")
	)
	(gr_line
		(start 102.776274 -295.13276)
		(end 102.776528 -295.133014)
		(stroke
			(width 0.05715)
			(type default)
		)
		(layer "In13.Cu")
	)
	(gr_arc
		(start 102.827836 -293.062914)
		(mid 102.825419 -293.064559)
		(end 102.82301 -293.066216)
		(stroke
			(width 0.05715)
			(type default)
		)
		(layer "In13.Cu")
	)
	(gr_arc
		(start 102.828598 -293.062152)
		(mid 102.82936 -293.061644)
		(end 102.830122 -293.061136)
		(stroke
			(width 0.05715)
			(type default)
		)
		(layer "In13.Cu")
	)
	(gr_line
		(start 102.830122 -293.061136)
		(end 102.83698 -293.057072)
		(stroke
			(width 0.05715)
			(type default)
		)
		(layer "In13.Cu")
	)
	(gr_line
		(start 102.83698 -293.057072)
		(end 102.837742 -293.056564)
		(stroke
			(width 0.05715)
			(type default)
		)
		(layer "In13.Cu")
	)
	(gr_line
		(start 102.837742 -293.056564)
		(end 102.838504 -293.056056)
		(stroke
			(width 0.05715)
			(type default)
		)
		(layer "In13.Cu")
	)
	(gr_line
		(start 102.9335 -280.870914)
		(end 102.9335 -280.871168)
		(stroke
			(width 0.05715)
			(type default)
		)
		(layer "In13.Cu")
	)
	(gr_line
		(start 103.077264 -296.612564)
		(end 103.077264 -296.584116)
		(stroke
			(width 0.05715)
			(type default)
		)
		(layer "In13.Cu")
	)
	(gr_line
		(start 103.077264 -296.584116)
		(end 103.121714 -296.539666)
		(stroke
			(width 0.05715)
			(type default)
		)
		(layer "In13.Cu")
	)
	(gr_line
		(start 103.313484 -296.552366)
		(end 103.313484 -296.538396)
		(stroke
			(width 0.05715)
			(type default)
		)
		(layer "In13.Cu")
	)
	(gr_line
		(start 103.32339 -272.79727)
		(end 103.324406 -272.796762)
		(stroke
			(width 0.05715)
			(type default)
		)
		(layer "In13.Cu")
	)
	(gr_line
		(start 103.329232 -272.793714)
		(end 103.330248 -272.793206)
		(stroke
			(width 0.05715)
			(type default)
		)
		(layer "In13.Cu")
	)
	(gr_line
		(start 103.330248 -272.793206)
		(end 103.331518 -272.792444)
		(stroke
			(width 0.05715)
			(type default)
		)
		(layer "In13.Cu")
	)
	(gr_line
		(start 103.33609 -272.789904)
		(end 103.339138 -272.788126)
		(stroke
			(width 0.05715)
			(type default)
		)
		(layer "In13.Cu")
	)
	(gr_line
		(start 103.340662 -272.78711)
		(end 103.343964 -272.785332)
		(stroke
			(width 0.05715)
			(type default)
		)
		(layer "In13.Cu")
	)
	(gr_line
		(start 103.343964 -272.785332)
		(end 103.344218 -272.785332)
		(stroke
			(width 0.05715)
			(type default)
		)
		(layer "In13.Cu")
	)
	(gr_line
		(start 103.344218 -272.785332)
		(end 103.346758 -272.784062)
		(stroke
			(width 0.05715)
			(type default)
		)
		(layer "In13.Cu")
	)
	(gr_line
		(start 103.359204 -296.612564)
		(end 103.359204 -296.598086)
		(stroke
			(width 0.05715)
			(type default)
		)
		(layer "In13.Cu")
	)
	(gr_line
		(start 103.359204 -296.598086)
		(end 103.313484 -296.552366)
		(stroke
			(width 0.05715)
			(type default)
		)
		(layer "In13.Cu")
	)
	(gr_line
		(start 103.419656 -272.961862)
		(end 103.420164 -272.961608)
		(stroke
			(width 0.05715)
			(type default)
		)
		(layer "In13.Cu")
	)
	(gr_line
		(start 103.420164 -272.961608)
		(end 103.420926 -272.961354)
		(stroke
			(width 0.05715)
			(type default)
		)
		(layer "In13.Cu")
	)
	(gr_line
		(start 103.420926 -272.961354)
		(end 103.422704 -272.960338)
		(stroke
			(width 0.05715)
			(type default)
		)
		(layer "In13.Cu")
	)
	(gr_line
		(start 103.422704 -272.960338)
		(end 103.423974 -272.959576)
		(stroke
			(width 0.05715)
			(type default)
		)
		(layer "In13.Cu")
	)
	(gr_line
		(start 103.423974 -272.959576)
		(end 103.424736 -272.959068)
		(stroke
			(width 0.05715)
			(type default)
		)
		(layer "In13.Cu")
	)
	(gr_line
		(start 103.424736 -272.959068)
		(end 103.425244 -272.958814)
		(stroke
			(width 0.05715)
			(type default)
		)
		(layer "In13.Cu")
	)
	(gr_line
		(start 103.42753 -272.957544)
		(end 103.427784 -272.957544)
		(stroke
			(width 0.05715)
			(type default)
		)
		(layer "In13.Cu")
	)
	(gr_line
		(start 103.428292 -272.958306)
		(end 103.429054 -272.957798)
		(stroke
			(width 0.05715)
			(type default)
		)
		(layer "In13.Cu")
	)
	(gr_line
		(start 103.429054 -272.957798)
		(end 103.430832 -272.956782)
		(stroke
			(width 0.05715)
			(type default)
		)
		(layer "In13.Cu")
	)
	(gr_line
		(start 103.430832 -272.956782)
		(end 103.431594 -272.956274)
		(stroke
			(width 0.05715)
			(type default)
		)
		(layer "In13.Cu")
	)
	(gr_line
		(start 103.431594 -272.956274)
		(end 103.43261 -272.955512)
		(stroke
			(width 0.05715)
			(type default)
		)
		(layer "In13.Cu")
	)
	(gr_line
		(start 103.43896 -272.95094)
		(end 103.442262 -272.948908)
		(stroke
			(width 0.05715)
			(type default)
		)
		(layer "In13.Cu")
	)
	(gr_line
		(start 103.442262 -272.948908)
		(end 103.44277 -272.948654)
		(stroke
			(width 0.05715)
			(type default)
		)
		(layer "In13.Cu")
	)
	(gr_line
		(start 103.69169 -294.75938)
		(end 103.69169 -294.759126)
		(stroke
			(width 0.05715)
			(type default)
		)
		(layer "In13.Cu")
	)
	(gr_arc
		(start 103.76916 -286.581596)
		(mid 103.764443 -286.584873)
		(end 103.759762 -286.5882)
		(stroke
			(width 0.05715)
			(type default)
		)
		(layer "In13.Cu")
	)
	(gr_line
		(start 103.76916 -286.581596)
		(end 103.771192 -286.580072)
		(stroke
			(width 0.05715)
			(type default)
		)
		(layer "In13.Cu")
	)
	(gr_line
		(start 103.771192 -286.580072)
		(end 103.776018 -286.577278)
		(stroke
			(width 0.05715)
			(type default)
		)
		(layer "In13.Cu")
	)
	(gr_line
		(start 103.903526 -286.72409)
		(end 103.904034 -286.723836)
		(stroke
			(width 0.05715)
			(type default)
		)
		(layer "In13.Cu")
	)
	(gr_line
		(start 103.91902 -273.276314)
		(end 103.621078 -273.276314)
		(stroke
			(width 0.05715)
			(type default)
		)
		(layer "In13.Cu")
	)
	(gr_line
		(start 103.91902 -271.656302)
		(end 103.621078 -271.656302)
		(stroke
			(width 0.05715)
			(type default)
		)
		(layer "In13.Cu")
	)
	(gr_line
		(start 103.988362 -273.345656)
		(end 103.91902 -273.276314)
		(stroke
			(width 0.05715)
			(type default)
		)
		(layer "In13.Cu")
	)
	(gr_line
		(start 103.988362 -271.725644)
		(end 103.91902 -271.656302)
		(stroke
			(width 0.05715)
			(type default)
		)
		(layer "In13.Cu")
	)
	(gr_line
		(start 104.165908 -296.502582)
		(end 104.165908 -296.474134)
		(stroke
			(width 0.05715)
			(type default)
		)
		(layer "In13.Cu")
	)
	(gr_line
		(start 104.165908 -296.474134)
		(end 104.211628 -296.428414)
		(stroke
			(width 0.05715)
			(type default)
		)
		(layer "In13.Cu")
	)
	(gr_arc
		(start 104.176576 -273.381978)
		(mid 104.178599 -273.370568)
		(end 104.180386 -273.359118)
		(stroke
			(width 0.05715)
			(type default)
		)
		(layer "In13.Cu")
	)
	(gr_arc
		(start 104.176576 -271.761966)
		(mid 104.178598 -271.750556)
		(end 104.180386 -271.739106)
		(stroke
			(width 0.05715)
			(type default)
		)
		(layer "In13.Cu")
	)
	(gr_line
		(start 104.180386 -273.359118)
		(end 104.26319 -273.276314)
		(stroke
			(width 0.05715)
			(type default)
		)
		(layer "In13.Cu")
	)
	(gr_line
		(start 104.180386 -271.739106)
		(end 104.26319 -271.656302)
		(stroke
			(width 0.05715)
			(type default)
		)
		(layer "In13.Cu")
	)
	(gr_line
		(start 104.26319 -273.276314)
		(end 104.561132 -273.276314)
		(stroke
			(width 0.05715)
			(type default)
		)
		(layer "In13.Cu")
	)
	(gr_line
		(start 104.26319 -271.656302)
		(end 104.561132 -271.656302)
		(stroke
			(width 0.05715)
			(type default)
		)
		(layer "In13.Cu")
	)
	(gr_line
		(start 104.447848 -296.502582)
		(end 104.447848 -296.474134)
		(stroke
			(width 0.05715)
			(type default)
		)
		(layer "In13.Cu")
	)
	(gr_line
		(start 104.447848 -296.474134)
		(end 104.402128 -296.428414)
		(stroke
			(width 0.05715)
			(type default)
		)
		(layer "In13.Cu")
	)
	(gr_line
		(start 105.495852 -363.398816)
		(end 105.495852 -363.206538)
		(stroke
			(width 0.07112)
			(type default)
		)
		(layer "In13.Cu")
	)
	(gr_line
		(start 105.495852 -363.206538)
		(end 105.797858 -362.904532)
		(stroke
			(width 0.07112)
			(type default)
		)
		(layer "In13.Cu")
	)
	(gr_line
		(start 105.58018 -365.04245)
		(end 106.28122 -365.04245)
		(stroke
			(width 0.07112)
			(type default)
		)
		(layer "In13.Cu")
	)
	(gr_line
		(start 105.58145 -364.75924)
		(end 105.71734 -364.62335)
		(stroke
			(width 0.07112)
			(type default)
		)
		(layer "In13.Cu")
	)
	(gr_line
		(start 105.695242 -363.599984)
		(end 106.191304 -363.103922)
		(stroke
			(width 0.07112)
			(type default)
		)
		(layer "In13.Cu")
	)
	(gr_line
		(start 105.71734 -364.62335)
		(end 106.14406 -364.62335)
		(stroke
			(width 0.07112)
			(type default)
		)
		(layer "In13.Cu")
	)
	(gr_line
		(start 105.797858 -362.904532)
		(end 105.990136 -362.904532)
		(stroke
			(width 0.07112)
			(type default)
		)
		(layer "In13.Cu")
	)
	(gr_line
		(start 106.14406 -364.62335)
		(end 106.27995 -364.75924)
		(stroke
			(width 0.07112)
			(type default)
		)
		(layer "In13.Cu")
	)
	(gr_line
		(start 106.166666 -361.3912)
		(end 106.198416 -361.201462)
		(stroke
			(width 0.07112)
			(type default)
		)
		(layer "In13.Cu")
	)
	(gr_line
		(start 106.198416 -361.201462)
		(end 106.546142 -360.953558)
		(stroke
			(width 0.07112)
			(type default)
		)
		(layer "In13.Cu")
	)
	(gr_line
		(start 106.330242 -361.62234)
		(end 106.901234 -361.215178)
		(stroke
			(width 0.07112)
			(type default)
		)
		(layer "In13.Cu")
	)
	(gr_line
		(start 106.546142 -360.953558)
		(end 106.73588 -360.985308)
		(stroke
			(width 0.07112)
			(type default)
		)
		(layer "In13.Cu")
	)
	(gr_line
		(start 106.70794 -365.04245)
		(end 107.40898 -365.04245)
		(stroke
			(width 0.07112)
			(type default)
		)
		(layer "In13.Cu")
	)
	(gr_line
		(start 106.70921 -364.75924)
		(end 106.8451 -364.62335)
		(stroke
			(width 0.07112)
			(type default)
		)
		(layer "In13.Cu")
	)
	(gr_line
		(start 106.8451 -364.62335)
		(end 107.27182 -364.62335)
		(stroke
			(width 0.07112)
			(type default)
		)
		(layer "In13.Cu")
	)
	(gr_line
		(start 107.27182 -364.62335)
		(end 107.40771 -364.75924)
		(stroke
			(width 0.07112)
			(type default)
		)
		(layer "In13.Cu")
	)
	(gr_line
		(start 107.75696 -362.510324)
		(end 108.458 -362.510324)
		(stroke
			(width 0.07112)
			(type default)
		)
		(layer "In13.Cu")
	)
	(gr_line
		(start 107.75823 -362.227114)
		(end 107.89412 -362.091224)
		(stroke
			(width 0.07112)
			(type default)
		)
		(layer "In13.Cu")
	)
	(gr_line
		(start 107.87634 -365.04245)
		(end 108.57738 -365.04245)
		(stroke
			(width 0.07112)
			(type default)
		)
		(layer "In13.Cu")
	)
	(gr_line
		(start 107.87761 -364.75924)
		(end 108.0135 -364.62335)
		(stroke
			(width 0.07112)
			(type default)
		)
		(layer "In13.Cu")
	)
	(gr_line
		(start 107.89412 -362.091224)
		(end 108.32084 -362.091224)
		(stroke
			(width 0.07112)
			(type default)
		)
		(layer "In13.Cu")
	)
	(gr_line
		(start 108.0135 -364.62335)
		(end 108.44022 -364.62335)
		(stroke
			(width 0.07112)
			(type default)
		)
		(layer "In13.Cu")
	)
	(gr_line
		(start 108.32084 -362.091224)
		(end 108.45673 -362.227114)
		(stroke
			(width 0.07112)
			(type default)
		)
		(layer "In13.Cu")
	)
	(gr_line
		(start 108.44022 -364.62335)
		(end 108.57611 -364.75924)
		(stroke
			(width 0.07112)
			(type default)
		)
		(layer "In13.Cu")
	)
	(gr_line
		(start 108.443522 -353.001834)
		(end 108.462064 -352.810572)
		(stroke
			(width 0.07112)
			(type default)
		)
		(layer "In13.Cu")
	)
	(gr_line
		(start 108.462064 -352.810572)
		(end 108.792264 -352.539554)
		(stroke
			(width 0.07112)
			(type default)
		)
		(layer "In13.Cu")
	)
	(gr_line
		(start 108.622084 -353.221544)
		(end 109.164374 -352.776536)
		(stroke
			(width 0.07112)
			(type default)
		)
		(layer "In13.Cu")
	)
	(gr_line
		(start 108.792264 -352.539554)
		(end 108.984034 -352.558096)
		(stroke
			(width 0.07112)
			(type default)
		)
		(layer "In13.Cu")
	)
	(gr_line
		(start 109.27334 -362.510324)
		(end 109.97438 -362.510324)
		(stroke
			(width 0.07112)
			(type default)
		)
		(layer "In13.Cu")
	)
	(gr_line
		(start 109.27461 -362.227114)
		(end 109.4105 -362.091224)
		(stroke
			(width 0.07112)
			(type default)
		)
		(layer "In13.Cu")
	)
	(gr_line
		(start 109.4105 -362.091224)
		(end 109.83722 -362.091224)
		(stroke
			(width 0.07112)
			(type default)
		)
		(layer "In13.Cu")
	)
	(gr_line
		(start 109.83722 -362.091224)
		(end 109.97311 -362.227114)
		(stroke
			(width 0.07112)
			(type default)
		)
		(layer "In13.Cu")
	)
	(gr_line
		(start 110.589568 -353.859592)
		(end 110.589568 -353.859338)
		(stroke
			(width 0.07112)
			(type default)
		)
		(layer "In13.Cu")
	)
	(gr_line
		(start 110.589568 -353.859338)
		(end 110.66399 -353.950016)
		(stroke
			(width 0.07112)
			(type default)
		)
		(layer "In13.Cu")
	)
	(gr_line
		(start 110.66399 -353.950016)
		(end 110.652306 -354.066602)
		(stroke
			(width 0.07112)
			(type default)
		)
		(layer "In13.Cu")
	)
	(gr_line
		(start 112.913922 -271.846548)
		(end 112.913414 -271.847056)
		(stroke
			(width 0.07112)
			(type default)
		)
		(layer "In13.Cu")
	)
	(gr_line
		(start 112.933988 -271.826482)
		(end 112.913922 -271.846548)
		(stroke
			(width 0.05715)
			(type default)
		)
		(layer "In13.Cu")
	)
	(gr_line
		(start 112.997742 -271.826482)
		(end 112.933988 -271.826482)
		(stroke
			(width 0.05715)
			(type default)
		)
		(layer "In13.Cu")
	)
	(gr_line
		(start 113.113058 -272.045938)
		(end 113.113312 -272.045938)
		(stroke
			(width 0.07112)
			(type default)
		)
		(layer "In13.Cu")
	)
	(gr_line
		(start 113.133124 -272.025872)
		(end 113.113058 -272.045938)
		(stroke
			(width 0.05715)
			(type default)
		)
		(layer "In13.Cu")
	)
	(gr_line
		(start 113.133124 -271.961864)
		(end 113.133124 -272.025872)
		(stroke
			(width 0.05715)
			(type default)
		)
		(layer "In13.Cu")
	)
	(gr_line
		(start 113.133886 -271.961356)
		(end 113.133124 -271.961864)
		(stroke
			(width 0.05715)
			(type default)
		)
		(layer "In13.Cu")
	)
	(gr_line
		(start 113.38941 -286.23641)
		(end 113.389664 -286.23641)
		(stroke
			(width 0.05715)
			(type default)
		)
		(layer "In13.Cu")
	)
	(gr_arc
		(start 113.389918 -286.215582)
		(mid 113.389779 -286.219138)
		(end 113.389664 -286.222694)
		(stroke
			(width 0.05715)
			(type default)
		)
		(layer "In13.Cu")
	)
	(gr_arc
		(start 113.659158 -285.096458)
		(mid 113.661188 -285.097605)
		(end 113.663222 -285.098744)
		(stroke
			(width 0.05715)
			(type default)
		)
		(layer "In13.Cu")
	)
	(gr_arc
		(start 113.662714 -293.19855)
		(mid 113.663603 -293.199059)
		(end 113.664492 -293.199566)
		(stroke
			(width 0.05715)
			(type default)
		)
		(layer "In13.Cu")
	)
	(gr_arc
		(start 113.664492 -292.232842)
		(mid 113.663602 -292.233349)
		(end 113.662714 -292.233858)
		(stroke
			(width 0.05715)
			(type default)
		)
		(layer "In13.Cu")
	)
	(gr_line
		(start 113.668048 -283.481526)
		(end 113.67262 -283.48432)
		(stroke
			(width 0.05715)
			(type default)
		)
		(layer "In13.Cu")
	)
	(gr_line
		(start 113.668048 -281.861514)
		(end 113.67262 -281.864308)
		(stroke
			(width 0.05715)
			(type default)
		)
		(layer "In13.Cu")
	)
	(gr_line
		(start 113.67135 -280.889202)
		(end 113.668048 -280.891234)
		(stroke
			(width 0.05715)
			(type default)
		)
		(layer "In13.Cu")
	)
	(gr_line
		(start 113.671604 -285.103824)
		(end 113.671858 -285.103824)
		(stroke
			(width 0.05715)
			(type default)
		)
		(layer "In13.Cu")
	)
	(gr_line
		(start 113.671858 -284.128972)
		(end 113.671604 -284.129226)
		(stroke
			(width 0.05715)
			(type default)
		)
		(layer "In13.Cu")
	)
	(gr_line
		(start 113.671858 -282.50896)
		(end 113.668048 -282.511246)
		(stroke
			(width 0.05715)
			(type default)
		)
		(layer "In13.Cu")
	)
	(gr_line
		(start 113.67262 -283.48432)
		(end 113.673128 -283.484574)
		(stroke
			(width 0.05715)
			(type default)
		)
		(layer "In13.Cu")
	)
	(gr_line
		(start 113.67262 -281.864308)
		(end 113.673128 -281.864562)
		(stroke
			(width 0.05715)
			(type default)
		)
		(layer "In13.Cu")
	)
	(gr_line
		(start 113.672874 -282.508452)
		(end 113.671858 -282.50896)
		(stroke
			(width 0.05715)
			(type default)
		)
		(layer "In13.Cu")
	)
	(gr_arc
		(start 113.674652 -304.89271)
		(mid 113.674018 -304.892074)
		(end 113.673382 -304.89144)
		(stroke
			(width 0.07112)
			(type default)
		)
		(layer "In13.Cu")
	)
	(gr_line
		(start 113.686082 -288.980118)
		(end 113.683034 -288.98215)
		(stroke
			(width 0.05715)
			(type default)
		)
		(layer "In13.Cu")
	)
	(gr_line
		(start 113.702338 -280.261822)
		(end 113.702338 -280.261568)
		(stroke
			(width 0.05715)
			(type default)
		)
		(layer "In13.Cu")
	)
	(gr_line
		(start 113.76533 -293.037514)
		(end 113.770664 -293.040562)
		(stroke
			(width 0.05715)
			(type default)
		)
		(layer "In13.Cu")
	)
	(gr_line
		(start 113.766092 -281.05481)
		(end 113.764314 -281.055826)
		(stroke
			(width 0.05715)
			(type default)
		)
		(layer "In13.Cu")
	)
	(gr_line
		(start 113.766346 -288.177986)
		(end 113.769394 -288.179764)
		(stroke
			(width 0.05715)
			(type default)
		)
		(layer "In13.Cu")
	)
	(gr_line
		(start 113.768632 -284.29331)
		(end 113.76787 -284.293818)
		(stroke
			(width 0.05715)
			(type default)
		)
		(layer "In13.Cu")
	)
	(gr_line
		(start 113.77041 -292.391846)
		(end 113.76533 -292.394894)
		(stroke
			(width 0.05715)
			(type default)
		)
		(layer "In13.Cu")
	)
	(gr_line
		(start 113.770664 -293.040562)
		(end 113.771426 -293.04107)
		(stroke
			(width 0.05715)
			(type default)
		)
		(layer "In13.Cu")
	)
	(gr_line
		(start 113.772188 -289.15106)
		(end 113.767616 -289.1536)
		(stroke
			(width 0.05715)
			(type default)
		)
		(layer "In13.Cu")
	)
	(gr_line
		(start 113.787174 -289.141662)
		(end 113.786666 -289.141916)
		(stroke
			(width 0.05715)
			(type default)
		)
		(layer "In13.Cu")
	)
	(gr_line
		(start 113.798096 -283.336746)
		(end 113.805208 -283.34081)
		(stroke
			(width 0.05715)
			(type default)
		)
		(layer "In13.Cu")
	)
	(gr_line
		(start 113.798096 -281.716734)
		(end 113.805208 -281.720798)
		(stroke
			(width 0.05715)
			(type default)
		)
		(layer "In13.Cu")
	)
	(gr_line
		(start 113.79835 -284.956758)
		(end 113.805208 -284.960822)
		(stroke
			(width 0.05715)
			(type default)
		)
		(layer "In13.Cu")
	)
	(gr_line
		(start 113.798858 -293.057072)
		(end 113.80597 -293.061136)
		(stroke
			(width 0.05715)
			(type default)
		)
		(layer "In13.Cu")
	)
	(gr_arc
		(start 113.80597 -293.061136)
		(mid 113.806351 -293.06139)
		(end 113.806732 -293.061644)
		(stroke
			(width 0.05715)
			(type default)
		)
		(layer "In13.Cu")
	)
	(gr_arc
		(start 113.806732 -284.961838)
		(mid 113.80597 -284.961329)
		(end 113.805208 -284.960822)
		(stroke
			(width 0.05715)
			(type default)
		)
		(layer "In13.Cu")
	)
	(gr_arc
		(start 113.806732 -283.341826)
		(mid 113.80597 -283.341317)
		(end 113.805208 -283.34081)
		(stroke
			(width 0.05715)
			(type default)
		)
		(layer "In13.Cu")
	)
	(gr_arc
		(start 113.806732 -281.721814)
		(mid 113.80597 -281.721305)
		(end 113.805208 -281.720798)
		(stroke
			(width 0.05715)
			(type default)
		)
		(layer "In13.Cu")
	)
	(gr_arc
		(start 113.813082 -284.96641)
		(mid 113.809915 -284.964113)
		(end 113.806732 -284.961838)
		(stroke
			(width 0.05715)
			(type default)
		)
		(layer "In13.Cu")
	)
	(gr_arc
		(start 113.813082 -283.346398)
		(mid 113.809915 -283.344101)
		(end 113.806732 -283.341826)
		(stroke
			(width 0.05715)
			(type default)
		)
		(layer "In13.Cu")
	)
	(gr_arc
		(start 113.813082 -281.726386)
		(mid 113.809915 -281.724089)
		(end 113.806732 -281.721814)
		(stroke
			(width 0.05715)
			(type default)
		)
		(layer "In13.Cu")
	)
	(gr_arc
		(start 113.814606 -293.067232)
		(mid 113.810681 -293.064421)
		(end 113.806732 -293.061644)
		(stroke
			(width 0.05715)
			(type default)
		)
		(layer "In13.Cu")
	)
	(gr_line
		(start 113.871756 -403.092158)
		(end 114.04219 -402.411946)
		(stroke
			(width 0.07112)
			(type default)
		)
		(layer "In13.Cu")
	)
	(gr_line
		(start 114.135662 -271.982438)
		(end 114.134646 -271.9832)
		(stroke
			(width 0.05715)
			(type default)
		)
		(layer "In13.Cu")
	)
	(gr_line
		(start 114.138202 -271.980914)
		(end 114.135662 -271.982438)
		(stroke
			(width 0.05715)
			(type default)
		)
		(layer "In13.Cu")
	)
	(gr_line
		(start 114.139218 -271.980406)
		(end 114.138202 -271.980914)
		(stroke
			(width 0.05715)
			(type default)
		)
		(layer "In13.Cu")
	)
	(gr_line
		(start 114.140742 -271.97939)
		(end 114.139218 -271.980406)
		(stroke
			(width 0.05715)
			(type default)
		)
		(layer "In13.Cu")
	)
	(gr_line
		(start 114.141758 -271.978882)
		(end 114.140742 -271.97939)
		(stroke
			(width 0.05715)
			(type default)
		)
		(layer "In13.Cu")
	)
	(gr_line
		(start 114.14252 -270.358362)
		(end 114.141758 -270.35887)
		(stroke
			(width 0.05715)
			(type default)
		)
		(layer "In13.Cu")
	)
	(gr_line
		(start 114.146838 -403.159722)
		(end 114.311938 -403.06117)
		(stroke
			(width 0.07112)
			(type default)
		)
		(layer "In13.Cu")
	)
	(gr_line
		(start 114.17554 -401.25904)
		(end 114.17554 -400.558)
		(stroke
			(width 0.07112)
			(type default)
		)
		(layer "In13.Cu")
	)
	(gr_line
		(start 114.17554 -400.13128)
		(end 114.17554 -399.43024)
		(stroke
			(width 0.07112)
			(type default)
		)
		(layer "In13.Cu")
	)
	(gr_line
		(start 114.17554 -399.00352)
		(end 114.17554 -398.30248)
		(stroke
			(width 0.07112)
			(type default)
		)
		(layer "In13.Cu")
	)
	(gr_line
		(start 114.17554 -397.87576)
		(end 114.17554 -397.17472)
		(stroke
			(width 0.07112)
			(type default)
		)
		(layer "In13.Cu")
	)
	(gr_line
		(start 114.17554 -396.748)
		(end 114.17554 -396.04696)
		(stroke
			(width 0.07112)
			(type default)
		)
		(layer "In13.Cu")
	)
	(gr_line
		(start 114.17554 -395.62024)
		(end 114.17554 -394.9192)
		(stroke
			(width 0.07112)
			(type default)
		)
		(layer "In13.Cu")
	)
	(gr_line
		(start 114.231166 -272.147538)
		(end 114.23015 -272.148046)
		(stroke
			(width 0.05715)
			(type default)
		)
		(layer "In13.Cu")
	)
	(gr_line
		(start 114.231928 -272.14703)
		(end 114.231166 -272.147538)
		(stroke
			(width 0.05715)
			(type default)
		)
		(layer "In13.Cu")
	)
	(gr_line
		(start 114.233452 -272.146268)
		(end 114.231928 -272.14703)
		(stroke
			(width 0.05715)
			(type default)
		)
		(layer "In13.Cu")
	)
	(gr_line
		(start 114.234214 -272.14576)
		(end 114.233452 -272.146268)
		(stroke
			(width 0.05715)
			(type default)
		)
		(layer "In13.Cu")
	)
	(gr_line
		(start 114.237008 -272.144236)
		(end 114.2365 -272.14449)
		(stroke
			(width 0.05715)
			(type default)
		)
		(layer "In13.Cu")
	)
	(gr_line
		(start 114.237516 -272.143982)
		(end 114.237008 -272.144236)
		(stroke
			(width 0.05715)
			(type default)
		)
		(layer "In13.Cu")
	)
	(gr_line
		(start 114.238786 -270.522954)
		(end 114.23777 -270.523716)
		(stroke
			(width 0.05715)
			(type default)
		)
		(layer "In13.Cu")
	)
	(gr_line
		(start 114.283744 -296.29862)
		(end 114.283744 -296.327068)
		(stroke
			(width 0.05715)
			(type default)
		)
		(layer "In13.Cu")
	)
	(gr_line
		(start 114.311938 -403.06117)
		(end 114.41557 -402.646896)
		(stroke
			(width 0.07112)
			(type default)
		)
		(layer "In13.Cu")
	)
	(gr_line
		(start 114.329464 -296.2529)
		(end 114.283744 -296.29862)
		(stroke
			(width 0.05715)
			(type default)
		)
		(layer "In13.Cu")
	)
	(gr_arc
		(start 114.329972 -271.639538)
		(mid 114.329507 -271.645247)
		(end 114.32921 -271.650968)
		(stroke
			(width 0.05715)
			(type default)
		)
		(layer "In13.Cu")
	)
	(gr_line
		(start 114.41557 -402.646896)
		(end 114.316764 -402.481796)
		(stroke
			(width 0.07112)
			(type default)
		)
		(layer "In13.Cu")
	)
	(gr_line
		(start 114.424714 -274.08632)
		(end 114.722656 -274.08632)
		(stroke
			(width 0.05715)
			(type default)
		)
		(layer "In13.Cu")
	)
	(gr_line
		(start 114.424714 -272.466308)
		(end 114.722656 -272.466308)
		(stroke
			(width 0.05715)
			(type default)
		)
		(layer "In13.Cu")
	)
	(gr_line
		(start 114.424714 -270.846296)
		(end 114.722656 -270.846296)
		(stroke
			(width 0.05715)
			(type default)
		)
		(layer "In13.Cu")
	)
	(gr_line
		(start 114.424714 -269.226284)
		(end 114.722656 -269.226284)
		(stroke
			(width 0.05715)
			(type default)
		)
		(layer "In13.Cu")
	)
	(gr_line
		(start 114.45875 -401.25777)
		(end 114.59464 -401.12188)
		(stroke
			(width 0.07112)
			(type default)
		)
		(layer "In13.Cu")
	)
	(gr_line
		(start 114.45875 -400.13001)
		(end 114.59464 -399.99412)
		(stroke
			(width 0.07112)
			(type default)
		)
		(layer "In13.Cu")
	)
	(gr_line
		(start 114.45875 -399.00225)
		(end 114.59464 -398.86636)
		(stroke
			(width 0.07112)
			(type default)
		)
		(layer "In13.Cu")
	)
	(gr_line
		(start 114.45875 -397.87449)
		(end 114.59464 -397.7386)
		(stroke
			(width 0.07112)
			(type default)
		)
		(layer "In13.Cu")
	)
	(gr_line
		(start 114.45875 -396.74673)
		(end 114.59464 -396.61084)
		(stroke
			(width 0.07112)
			(type default)
		)
		(layer "In13.Cu")
	)
	(gr_line
		(start 114.45875 -395.61897)
		(end 114.59464 -395.48308)
		(stroke
			(width 0.07112)
			(type default)
		)
		(layer "In13.Cu")
	)
	(gr_arc
		(start 114.51971 -271.663668)
		(mid 114.519852 -271.659477)
		(end 114.519964 -271.655286)
		(stroke
			(width 0.05715)
			(type default)
		)
		(layer "In13.Cu")
	)
	(gr_line
		(start 114.519964 -296.2529)
		(end 114.565684 -296.29862)
		(stroke
			(width 0.05715)
			(type default)
		)
		(layer "In13.Cu")
	)
	(gr_arc
		(start 114.552476 -271.206722)
		(mid 114.550185 -271.208749)
		(end 114.547904 -271.210786)
		(stroke
			(width 0.05715)
			(type default)
		)
		(layer "In13.Cu")
	)
	(gr_arc
		(start 114.552476 -271.206722)
		(mid 114.552984 -271.206341)
		(end 114.553492 -271.20596)
		(stroke
			(width 0.05715)
			(type default)
		)
		(layer "In13.Cu")
	)
	(gr_arc
		(start 114.564668 -293.175182)
		(mid 114.568593 -293.177993)
		(end 114.572542 -293.18077)
		(stroke
			(width 0.05715)
			(type default)
		)
		(layer "In13.Cu")
	)
	(gr_line
		(start 114.565684 -296.29862)
		(end 114.565684 -296.327068)
		(stroke
			(width 0.05715)
			(type default)
		)
		(layer "In13.Cu")
	)
	(gr_line
		(start 114.572542 -293.18077)
		(end 114.5794 -293.184834)
		(stroke
			(width 0.05715)
			(type default)
		)
		(layer "In13.Cu")
	)
	(gr_line
		(start 114.5794 -293.184834)
		(end 114.580162 -293.185342)
		(stroke
			(width 0.05715)
			(type default)
		)
		(layer "In13.Cu")
	)
	(gr_line
		(start 114.580162 -293.185342)
		(end 114.580924 -293.18585)
		(stroke
			(width 0.05715)
			(type default)
		)
		(layer "In13.Cu")
	)
	(gr_line
		(start 114.59464 -401.12188)
		(end 114.59464 -400.69516)
		(stroke
			(width 0.07112)
			(type default)
		)
		(layer "In13.Cu")
	)
	(gr_line
		(start 114.59464 -400.69516)
		(end 114.45875 -400.55927)
		(stroke
			(width 0.07112)
			(type default)
		)
		(layer "In13.Cu")
	)
	(gr_line
		(start 114.59464 -399.99412)
		(end 114.59464 -399.5674)
		(stroke
			(width 0.07112)
			(type default)
		)
		(layer "In13.Cu")
	)
	(gr_line
		(start 114.59464 -399.5674)
		(end 114.45875 -399.43151)
		(stroke
			(width 0.07112)
			(type default)
		)
		(layer "In13.Cu")
	)
	(gr_line
		(start 114.59464 -398.86636)
		(end 114.59464 -398.43964)
		(stroke
			(width 0.07112)
			(type default)
		)
		(layer "In13.Cu")
	)
	(gr_line
		(start 114.59464 -398.43964)
		(end 114.45875 -398.30375)
		(stroke
			(width 0.07112)
			(type default)
		)
		(layer "In13.Cu")
	)
	(gr_line
		(start 114.59464 -397.7386)
		(end 114.59464 -397.31188)
		(stroke
			(width 0.07112)
			(type default)
		)
		(layer "In13.Cu")
	)
	(gr_line
		(start 114.59464 -397.31188)
		(end 114.45875 -397.17599)
		(stroke
			(width 0.07112)
			(type default)
		)
		(layer "In13.Cu")
	)
	(gr_line
		(start 114.59464 -396.61084)
		(end 114.59464 -396.18412)
		(stroke
			(width 0.07112)
			(type default)
		)
		(layer "In13.Cu")
	)
	(gr_line
		(start 114.59464 -396.18412)
		(end 114.45875 -396.04823)
		(stroke
			(width 0.07112)
			(type default)
		)
		(layer "In13.Cu")
	)
	(gr_line
		(start 114.59464 -395.48308)
		(end 114.59464 -395.05636)
		(stroke
			(width 0.07112)
			(type default)
		)
		(layer "In13.Cu")
	)
	(gr_line
		(start 114.59464 -395.05636)
		(end 114.45875 -394.92047)
		(stroke
			(width 0.07112)
			(type default)
		)
		(layer "In13.Cu")
	)
	(gr_line
		(start 114.59591 -293.845996)
		(end 114.594132 -293.847012)
		(stroke
			(width 0.05715)
			(type default)
		)
		(layer "In13.Cu")
	)
	(gr_arc
		(start 114.60099 -281.857704)
		(mid 114.600609 -281.85745)
		(end 114.600228 -281.857196)
		(stroke
			(width 0.05715)
			(type default)
		)
		(layer "In13.Cu")
	)
	(gr_arc
		(start 114.602768 -285.098744)
		(mid 114.604291 -285.099635)
		(end 114.605816 -285.100522)
		(stroke
			(width 0.05715)
			(type default)
		)
		(layer "In13.Cu")
	)
	(gr_arc
		(start 114.603022 -293.841424)
		(mid 114.599457 -293.843696)
		(end 114.59591 -293.845996)
		(stroke
			(width 0.05715)
			(type default)
		)
		(layer "In13.Cu")
	)
	(gr_arc
		(start 114.604546 -284.133036)
		(mid 114.603656 -284.133543)
		(end 114.602768 -284.134052)
		(stroke
			(width 0.05715)
			(type default)
		)
		(layer "In13.Cu")
	)
	(gr_line
		(start 114.604546 -283.479748)
		(end 114.606832 -283.481272)
		(stroke
			(width 0.05715)
			(type default)
		)
		(layer "In13.Cu")
	)
	(gr_line
		(start 114.60734 -292.231318)
		(end 114.605308 -292.232588)
		(stroke
			(width 0.05715)
			(type default)
		)
		(layer "In13.Cu")
	)
	(gr_line
		(start 114.608864 -293.837868)
		(end 114.608102 -293.838376)
		(stroke
			(width 0.05715)
			(type default)
		)
		(layer "In13.Cu")
	)
	(gr_arc
		(start 114.609372 -285.750254)
		(mid 114.608483 -285.750761)
		(end 114.607594 -285.75127)
		(stroke
			(width 0.05715)
			(type default)
		)
		(layer "In13.Cu")
	)
	(gr_line
		(start 114.609372 -285.75)
		(end 114.609372 -285.750254)
		(stroke
			(width 0.05715)
			(type default)
		)
		(layer "In13.Cu")
	)
	(gr_line
		(start 114.610134 -285.749492)
		(end 114.609372 -285.75)
		(stroke
			(width 0.05715)
			(type default)
		)
		(layer "In13.Cu")
	)
	(gr_line
		(start 114.610388 -293.837106)
		(end 114.608864 -293.837868)
		(stroke
			(width 0.05715)
			(type default)
		)
		(layer "In13.Cu")
	)
	(gr_line
		(start 114.610642 -292.229286)
		(end 114.609118 -292.230302)
		(stroke
			(width 0.05715)
			(type default)
		)
		(layer "In13.Cu")
	)
	(gr_line
		(start 114.611404 -293.836598)
		(end 114.610388 -293.837106)
		(stroke
			(width 0.05715)
			(type default)
		)
		(layer "In13.Cu")
	)
	(gr_line
		(start 114.611658 -292.228778)
		(end 114.610642 -292.229286)
		(stroke
			(width 0.05715)
			(type default)
		)
		(layer "In13.Cu")
	)
	(gr_line
		(start 114.611658 -280.243788)
		(end 114.612166 -280.244042)
		(stroke
			(width 0.05715)
			(type default)
		)
		(layer "In13.Cu")
	)
	(gr_line
		(start 114.611658 -271.168876)
		(end 114.61115 -271.16913)
		(stroke
			(width 0.05715)
			(type default)
		)
		(layer "In13.Cu")
	)
	(gr_line
		(start 114.611658 -269.548864)
		(end 114.609626 -269.550134)
		(stroke
			(width 0.05715)
			(type default)
		)
		(layer "In13.Cu")
	)
	(gr_line
		(start 114.611912 -293.203884)
		(end 114.61242 -293.204138)
		(stroke
			(width 0.05715)
			(type default)
		)
		(layer "In13.Cu")
	)
	(gr_line
		(start 114.611912 -288.343594)
		(end 114.611658 -288.343848)
		(stroke
			(width 0.05715)
			(type default)
		)
		(layer "In13.Cu")
	)
	(gr_line
		(start 114.61242 -293.204138)
		(end 114.612928 -293.204392)
		(stroke
			(width 0.05715)
			(type default)
		)
		(layer "In13.Cu")
	)
	(gr_line
		(start 114.61242 -292.22827)
		(end 114.611658 -292.228778)
		(stroke
			(width 0.05715)
			(type default)
		)
		(layer "In13.Cu")
	)
	(gr_line
		(start 114.61369 -292.227508)
		(end 114.61242 -292.22827)
		(stroke
			(width 0.05715)
			(type default)
		)
		(layer "In13.Cu")
	)
	(gr_line
		(start 114.614198 -283.485336)
		(end 114.61496 -283.485844)
		(stroke
			(width 0.05715)
			(type default)
		)
		(layer "In13.Cu")
	)
	(gr_line
		(start 114.615214 -293.205662)
		(end 114.615976 -293.20617)
		(stroke
			(width 0.05715)
			(type default)
		)
		(layer "In13.Cu")
	)
	(gr_line
		(start 114.615976 -293.20617)
		(end 114.6175 -293.206932)
		(stroke
			(width 0.05715)
			(type default)
		)
		(layer "In13.Cu")
	)
	(gr_line
		(start 114.6175 -293.206932)
		(end 114.618262 -293.20744)
		(stroke
			(width 0.05715)
			(type default)
		)
		(layer "In13.Cu")
	)
	(gr_line
		(start 114.618262 -293.20744)
		(end 114.619278 -293.207948)
		(stroke
			(width 0.05715)
			(type default)
		)
		(layer "In13.Cu")
	)
	(gr_line
		(start 114.619278 -293.207948)
		(end 114.620294 -293.208456)
		(stroke
			(width 0.05715)
			(type default)
		)
		(layer "In13.Cu")
	)
	(gr_line
		(start 114.643154 -289.981894)
		(end 114.643408 -289.981894)
		(stroke
			(width 0.05715)
			(type default)
		)
		(layer "In13.Cu")
	)
	(gr_line
		(start 114.699796 -283.314648)
		(end 114.700812 -283.315156)
		(stroke
			(width 0.05715)
			(type default)
		)
		(layer "In13.Cu")
	)
	(gr_line
		(start 114.702336 -292.396672)
		(end 114.701574 -292.39718)
		(stroke
			(width 0.05715)
			(type default)
		)
		(layer "In13.Cu")
	)
	(gr_line
		(start 114.703098 -283.316426)
		(end 114.70513 -283.317442)
		(stroke
			(width 0.05715)
			(type default)
		)
		(layer "In13.Cu")
	)
	(gr_line
		(start 114.703352 -292.396164)
		(end 114.702336 -292.396672)
		(stroke
			(width 0.05715)
			(type default)
		)
		(layer "In13.Cu")
	)
	(gr_line
		(start 114.704114 -292.395656)
		(end 114.703352 -292.396164)
		(stroke
			(width 0.05715)
			(type default)
		)
		(layer "In13.Cu")
	)
	(gr_line
		(start 114.705384 -284.937708)
		(end 114.708686 -284.939486)
		(stroke
			(width 0.05715)
			(type default)
		)
		(layer "In13.Cu")
	)
	(gr_line
		(start 114.705638 -292.394894)
		(end 114.704114 -292.395656)
		(stroke
			(width 0.05715)
			(type default)
		)
		(layer "In13.Cu")
	)
	(gr_line
		(start 114.706908 -292.394132)
		(end 114.705638 -292.394894)
		(stroke
			(width 0.05715)
			(type default)
		)
		(layer "In13.Cu")
	)
	(gr_line
		(start 114.706908 -281.054302)
		(end 114.7064 -281.054556)
		(stroke
			(width 0.05715)
			(type default)
		)
		(layer "In13.Cu")
	)
	(gr_line
		(start 114.706908 -269.714218)
		(end 114.705384 -269.71498)
		(stroke
			(width 0.05715)
			(type default)
		)
		(layer "In13.Cu")
	)
	(gr_line
		(start 114.70767 -293.038784)
		(end 114.708686 -293.039292)
		(stroke
			(width 0.05715)
			(type default)
		)
		(layer "In13.Cu")
	)
	(gr_line
		(start 114.70767 -292.393624)
		(end 114.706908 -292.394132)
		(stroke
			(width 0.05715)
			(type default)
		)
		(layer "In13.Cu")
	)
	(gr_line
		(start 114.70767 -271.333722)
		(end 114.707162 -271.333722)
		(stroke
			(width 0.05715)
			(type default)
		)
		(layer "In13.Cu")
	)
	(gr_line
		(start 114.708686 -293.039292)
		(end 114.71021 -293.040308)
		(stroke
			(width 0.05715)
			(type default)
		)
		(layer "In13.Cu")
	)
	(gr_line
		(start 114.708686 -292.393116)
		(end 114.70767 -292.393624)
		(stroke
			(width 0.05715)
			(type default)
		)
		(layer "In13.Cu")
	)
	(gr_line
		(start 114.709448 -283.319982)
		(end 114.710464 -283.320744)
		(stroke
			(width 0.05715)
			(type default)
		)
		(layer "In13.Cu")
	)
	(gr_line
		(start 114.71021 -293.040308)
		(end 114.711226 -293.040816)
		(stroke
			(width 0.05715)
			(type default)
		)
		(layer "In13.Cu")
	)
	(gr_line
		(start 114.710464 -284.292294)
		(end 114.705384 -284.295088)
		(stroke
			(width 0.05715)
			(type default)
		)
		(layer "In13.Cu")
	)
	(gr_line
		(start 114.711226 -293.040816)
		(end 114.713766 -293.04234)
		(stroke
			(width 0.05715)
			(type default)
		)
		(layer "In13.Cu")
	)
	(gr_line
		(start 114.713766 -293.04234)
		(end 114.714782 -293.043102)
		(stroke
			(width 0.05715)
			(type default)
		)
		(layer "In13.Cu")
	)
	(gr_line
		(start 114.722656 -274.08632)
		(end 114.791998 -274.155662)
		(stroke
			(width 0.05715)
			(type default)
		)
		(layer "In13.Cu")
	)
	(gr_line
		(start 114.722656 -272.466308)
		(end 114.80546 -272.549112)
		(stroke
			(width 0.05715)
			(type default)
		)
		(layer "In13.Cu")
	)
	(gr_line
		(start 114.722656 -270.846296)
		(end 114.791998 -270.915638)
		(stroke
			(width 0.05715)
			(type default)
		)
		(layer "In13.Cu")
	)
	(gr_line
		(start 114.722656 -269.226284)
		(end 114.791998 -269.295626)
		(stroke
			(width 0.05715)
			(type default)
		)
		(layer "In13.Cu")
	)
	(gr_line
		(start 114.736372 -294.67556)
		(end 114.746024 -294.681148)
		(stroke
			(width 0.05715)
			(type default)
		)
		(layer "In13.Cu")
	)
	(gr_line
		(start 114.737642 -283.336492)
		(end 114.738658 -283.337)
		(stroke
			(width 0.05715)
			(type default)
		)
		(layer "In13.Cu")
	)
	(gr_line
		(start 114.738404 -281.716988)
		(end 114.746024 -281.721306)
		(stroke
			(width 0.05715)
			(type default)
		)
		(layer "In13.Cu")
	)
	(gr_line
		(start 114.738658 -284.957012)
		(end 114.746024 -284.96133)
		(stroke
			(width 0.05715)
			(type default)
		)
		(layer "In13.Cu")
	)
	(gr_line
		(start 114.738658 -283.337)
		(end 114.73942 -283.337508)
		(stroke
			(width 0.05715)
			(type default)
		)
		(layer "In13.Cu")
	)
	(gr_line
		(start 114.73942 -283.337508)
		(end 114.746024 -283.341318)
		(stroke
			(width 0.05715)
			(type default)
		)
		(layer "In13.Cu")
	)
	(gr_line
		(start 114.741198 -286.578802)
		(end 114.748818 -286.58312)
		(stroke
			(width 0.05715)
			(type default)
		)
		(layer "In13.Cu")
	)
	(gr_arc
		(start 114.746024 -294.681148)
		(mid 114.746405 -294.681402)
		(end 114.746786 -294.681656)
		(stroke
			(width 0.05715)
			(type default)
		)
		(layer "In13.Cu")
	)
	(gr_arc
		(start 114.746024 -284.96133)
		(mid 114.746405 -284.961584)
		(end 114.746786 -284.961838)
		(stroke
			(width 0.05715)
			(type default)
		)
		(layer "In13.Cu")
	)
	(gr_arc
		(start 114.746024 -283.341318)
		(mid 114.746405 -283.341572)
		(end 114.746786 -283.341826)
		(stroke
			(width 0.05715)
			(type default)
		)
		(layer "In13.Cu")
	)
	(gr_arc
		(start 114.746024 -281.721306)
		(mid 114.746405 -281.72156)
		(end 114.746786 -281.721814)
		(stroke
			(width 0.05715)
			(type default)
		)
		(layer "In13.Cu")
	)
	(gr_line
		(start 114.746786 -284.961838)
		(end 114.748818 -284.963108)
		(stroke
			(width 0.05715)
			(type default)
		)
		(layer "In13.Cu")
	)
	(gr_line
		(start 114.748818 -286.58312)
		(end 114.748818 -286.582866)
		(stroke
			(width 0.05715)
			(type default)
		)
		(layer "In13.Cu")
	)
	(gr_arc
		(start 114.748818 -284.963108)
		(mid 114.749199 -284.963362)
		(end 114.74958 -284.963616)
		(stroke
			(width 0.05715)
			(type default)
		)
		(layer "In13.Cu")
	)
	(gr_arc
		(start 114.75466 -294.687244)
		(mid 114.750735 -294.684433)
		(end 114.746786 -294.681656)
		(stroke
			(width 0.05715)
			(type default)
		)
		(layer "In13.Cu")
	)
	(gr_line
		(start 114.75466 -287.50514)
		(end 114.754152 -287.505648)
		(stroke
			(width 0.05715)
			(type default)
		)
		(layer "In13.Cu")
	)
	(gr_arc
		(start 114.75466 -283.347414)
		(mid 114.750735 -283.344603)
		(end 114.746786 -283.341826)
		(stroke
			(width 0.05715)
			(type default)
		)
		(layer "In13.Cu")
	)
	(gr_arc
		(start 114.75466 -281.727402)
		(mid 114.750735 -281.724591)
		(end 114.746786 -281.721814)
		(stroke
			(width 0.05715)
			(type default)
		)
		(layer "In13.Cu")
	)
	(gr_arc
		(start 114.755422 -284.96768)
		(mid 114.752887 -284.965895)
		(end 114.750342 -284.964124)
		(stroke
			(width 0.05715)
			(type default)
		)
		(layer "In13.Cu")
	)
	(gr_arc
		(start 114.757454 -286.588962)
		(mid 114.753151 -286.585893)
		(end 114.748818 -286.582866)
		(stroke
			(width 0.05715)
			(type default)
		)
		(layer "In13.Cu")
	)
	(gr_line
		(start 114.777012 -392.707622)
		(end 114.789458 -392.707622)
		(stroke
			(width 0.07112)
			(type default)
		)
		(layer "In13.Cu")
	)
	(gr_line
		(start 114.778282 -392.990832)
		(end 114.916458 -393.129008)
		(stroke
			(width 0.07112)
			(type default)
		)
		(layer "In13.Cu")
	)
	(gr_line
		(start 114.789458 -392.707622)
		(end 114.916458 -392.580622)
		(stroke
			(width 0.07112)
			(type default)
		)
		(layer "In13.Cu")
	)
	(gr_arc
		(start 114.80546 -272.549112)
		(mid 114.807248 -272.560562)
		(end 114.80927 -272.571972)
		(stroke
			(width 0.05715)
			(type default)
		)
		(layer "In13.Cu")
	)
	(gr_line
		(start 114.916458 -393.129008)
		(end 114.916458 -393.292838)
		(stroke
			(width 0.07112)
			(type default)
		)
		(layer "In13.Cu")
	)
	(gr_line
		(start 114.916458 -392.580622)
		(end 114.916458 -392.429238)
		(stroke
			(width 0.07112)
			(type default)
		)
		(layer "In13.Cu")
	)
	(gr_arc
		(start 114.980212 -274.191984)
		(mid 114.982235 -274.180574)
		(end 114.984022 -274.169124)
		(stroke
			(width 0.05715)
			(type default)
		)
		(layer "In13.Cu")
	)
	(gr_arc
		(start 114.980212 -270.95196)
		(mid 114.982234 -270.94055)
		(end 114.984022 -270.9291)
		(stroke
			(width 0.05715)
			(type default)
		)
		(layer "In13.Cu")
	)
	(gr_arc
		(start 114.980212 -269.331948)
		(mid 114.982234 -269.320538)
		(end 114.984022 -269.309088)
		(stroke
			(width 0.05715)
			(type default)
		)
		(layer "In13.Cu")
	)
	(gr_line
		(start 115.066826 -274.08632)
		(end 114.984022 -274.169124)
		(stroke
			(width 0.05715)
			(type default)
		)
		(layer "In13.Cu")
	)
	(gr_line
		(start 115.066826 -272.466308)
		(end 114.997484 -272.53565)
		(stroke
			(width 0.05715)
			(type default)
		)
		(layer "In13.Cu")
	)
	(gr_line
		(start 115.066826 -270.846296)
		(end 114.984022 -270.9291)
		(stroke
			(width 0.05715)
			(type default)
		)
		(layer "In13.Cu")
	)
	(gr_line
		(start 115.066826 -269.226284)
		(end 114.984022 -269.309088)
		(stroke
			(width 0.05715)
			(type default)
		)
		(layer "In13.Cu")
	)
	(gr_line
		(start 115.184936 -409.254452)
		(end 115.184936 -408.553412)
		(stroke
			(width 0.07112)
			(type default)
		)
		(layer "In13.Cu")
	)
	(gr_line
		(start 115.184936 -408.126692)
		(end 115.184936 -407.425652)
		(stroke
			(width 0.07112)
			(type default)
		)
		(layer "In13.Cu")
	)
	(gr_line
		(start 115.223798 -296.29862)
		(end 115.223798 -296.327068)
		(stroke
			(width 0.05715)
			(type default)
		)
		(layer "In13.Cu")
	)
	(gr_line
		(start 115.269518 -296.2529)
		(end 115.223798 -296.29862)
		(stroke
			(width 0.05715)
			(type default)
		)
		(layer "In13.Cu")
	)
	(gr_line
		(start 115.364768 -274.08632)
		(end 115.066826 -274.08632)
		(stroke
			(width 0.05715)
			(type default)
		)
		(layer "In13.Cu")
	)
	(gr_line
		(start 115.364768 -272.466308)
		(end 115.066826 -272.466308)
		(stroke
			(width 0.05715)
			(type default)
		)
		(layer "In13.Cu")
	)
	(gr_line
		(start 115.364768 -270.846296)
		(end 115.066826 -270.846296)
		(stroke
			(width 0.05715)
			(type default)
		)
		(layer "In13.Cu")
	)
	(gr_line
		(start 115.364768 -269.226284)
		(end 115.066826 -269.226284)
		(stroke
			(width 0.05715)
			(type default)
		)
		(layer "In13.Cu")
	)
	(gr_line
		(start 115.375436 -399.53819)
		(end 115.375436 -398.83715)
		(stroke
			(width 0.07112)
			(type default)
		)
		(layer "In13.Cu")
	)
	(gr_line
		(start 115.375436 -398.41043)
		(end 115.375436 -397.70939)
		(stroke
			(width 0.07112)
			(type default)
		)
		(layer "In13.Cu")
	)
	(gr_line
		(start 115.375436 -397.28267)
		(end 115.375436 -396.58163)
		(stroke
			(width 0.07112)
			(type default)
		)
		(layer "In13.Cu")
	)
	(gr_line
		(start 115.375436 -396.15491)
		(end 115.375436 -395.45387)
		(stroke
			(width 0.07112)
			(type default)
		)
		(layer "In13.Cu")
	)
	(gr_line
		(start 115.375436 -395.02715)
		(end 115.375436 -394.32611)
		(stroke
			(width 0.07112)
			(type default)
		)
		(layer "In13.Cu")
	)
	(gr_line
		(start 115.460018 -296.2529)
		(end 115.505738 -296.29862)
		(stroke
			(width 0.05715)
			(type default)
		)
		(layer "In13.Cu")
	)
	(gr_line
		(start 115.468146 -409.253182)
		(end 115.604036 -409.117292)
		(stroke
			(width 0.07112)
			(type default)
		)
		(layer "In13.Cu")
	)
	(gr_line
		(start 115.468146 -408.125422)
		(end 115.604036 -407.989532)
		(stroke
			(width 0.07112)
			(type default)
		)
		(layer "In13.Cu")
	)
	(gr_arc
		(start 115.504722 -294.795194)
		(mid 115.508647 -294.798005)
		(end 115.512596 -294.800782)
		(stroke
			(width 0.05715)
			(type default)
		)
		(layer "In13.Cu")
	)
	(gr_arc
		(start 115.504722 -293.175182)
		(mid 115.508647 -293.177993)
		(end 115.512596 -293.18077)
		(stroke
			(width 0.05715)
			(type default)
		)
		(layer "In13.Cu")
	)
	(gr_arc
		(start 115.504722 -291.55517)
		(mid 115.508647 -291.557981)
		(end 115.512596 -291.560758)
		(stroke
			(width 0.05715)
			(type default)
		)
		(layer "In13.Cu")
	)
	(gr_arc
		(start 115.504722 -285.075376)
		(mid 115.508647 -285.078187)
		(end 115.512596 -285.080964)
		(stroke
			(width 0.05715)
			(type default)
		)
		(layer "In13.Cu")
	)
	(gr_arc
		(start 115.504722 -283.455364)
		(mid 115.508647 -283.458175)
		(end 115.512596 -283.460952)
		(stroke
			(width 0.05715)
			(type default)
		)
		(layer "In13.Cu")
	)
	(gr_arc
		(start 115.504722 -281.835352)
		(mid 115.508647 -281.838163)
		(end 115.512596 -281.84094)
		(stroke
			(width 0.05715)
			(type default)
		)
		(layer "In13.Cu")
	)
	(gr_arc
		(start 115.504722 -280.21534)
		(mid 115.508647 -280.218151)
		(end 115.512596 -280.220928)
		(stroke
			(width 0.05715)
			(type default)
		)
		(layer "In13.Cu")
	)
	(gr_arc
		(start 115.504722 -278.595328)
		(mid 115.508647 -278.598139)
		(end 115.512596 -278.600916)
		(stroke
			(width 0.05715)
			(type default)
		)
		(layer "In13.Cu")
	)
	(gr_arc
		(start 115.504722 -276.975316)
		(mid 115.508647 -276.978127)
		(end 115.512596 -276.980904)
		(stroke
			(width 0.05715)
			(type default)
		)
		(layer "In13.Cu")
	)
	(gr_arc
		(start 115.504722 -275.355304)
		(mid 115.508647 -275.358115)
		(end 115.512596 -275.360892)
		(stroke
			(width 0.05715)
			(type default)
		)
		(layer "In13.Cu")
	)
	(gr_arc
		(start 115.504722 -273.735292)
		(mid 115.508647 -273.738103)
		(end 115.512596 -273.74088)
		(stroke
			(width 0.05715)
			(type default)
		)
		(layer "In13.Cu")
	)
	(gr_line
		(start 115.505738 -296.29862)
		(end 115.505738 -296.327068)
		(stroke
			(width 0.05715)
			(type default)
		)
		(layer "In13.Cu")
	)
	(gr_line
		(start 115.512596 -294.800782)
		(end 115.519454 -294.804846)
		(stroke
			(width 0.05715)
			(type default)
		)
		(layer "In13.Cu")
	)
	(gr_line
		(start 115.512596 -293.18077)
		(end 115.519454 -293.184834)
		(stroke
			(width 0.05715)
			(type default)
		)
		(layer "In13.Cu")
	)
	(gr_line
		(start 115.512596 -291.560758)
		(end 115.519454 -291.564822)
		(stroke
			(width 0.05715)
			(type default)
		)
		(layer "In13.Cu")
	)
	(gr_line
		(start 115.512596 -285.080964)
		(end 115.519454 -285.085028)
		(stroke
			(width 0.05715)
			(type default)
		)
		(layer "In13.Cu")
	)
	(gr_line
		(start 115.512596 -283.460952)
		(end 115.519454 -283.465016)
		(stroke
			(width 0.05715)
			(type default)
		)
		(layer "In13.Cu")
	)
	(gr_line
		(start 115.512596 -281.84094)
		(end 115.519454 -281.845004)
		(stroke
			(width 0.05715)
			(type default)
		)
		(layer "In13.Cu")
	)
	(gr_arc
		(start 115.512596 -280.911808)
		(mid 115.508647 -280.914585)
		(end 115.504722 -280.917396)
		(stroke
			(width 0.05715)
			(type default)
		)
		(layer "In13.Cu")
	)
	(gr_line
		(start 115.512596 -280.220928)
		(end 115.519454 -280.224992)
		(stroke
			(width 0.05715)
			(type default)
		)
		(layer "In13.Cu")
	)
	(gr_line
		(start 115.512596 -278.600916)
		(end 115.519454 -278.60498)
		(stroke
			(width 0.05715)
			(type default)
		)
		(layer "In13.Cu")
	)
	(gr_line
		(start 115.512596 -276.980904)
		(end 115.519454 -276.984968)
		(stroke
			(width 0.05715)
			(type default)
		)
		(layer "In13.Cu")
	)
	(gr_line
		(start 115.512596 -275.360892)
		(end 115.519454 -275.364956)
		(stroke
			(width 0.05715)
			(type default)
		)
		(layer "In13.Cu")
	)
	(gr_line
		(start 115.512596 -273.74088)
		(end 115.519454 -273.744944)
		(stroke
			(width 0.05715)
			(type default)
		)
		(layer "In13.Cu")
	)
	(gr_line
		(start 115.51539 -280.909776)
		(end 115.512596 -280.911808)
		(stroke
			(width 0.05715)
			(type default)
		)
		(layer "In13.Cu")
	)
	(gr_line
		(start 115.519454 -294.804846)
		(end 115.520216 -294.805354)
		(stroke
			(width 0.05715)
			(type default)
		)
		(layer "In13.Cu")
	)
	(gr_line
		(start 115.519454 -293.184834)
		(end 115.520216 -293.185342)
		(stroke
			(width 0.05715)
			(type default)
		)
		(layer "In13.Cu")
	)
	(gr_line
		(start 115.519454 -291.564822)
		(end 115.520216 -291.56533)
		(stroke
			(width 0.05715)
			(type default)
		)
		(layer "In13.Cu")
	)
	(gr_line
		(start 115.519454 -285.085028)
		(end 115.520216 -285.085536)
		(stroke
			(width 0.05715)
			(type default)
		)
		(layer "In13.Cu")
	)
	(gr_line
		(start 115.519454 -283.465016)
		(end 115.520216 -283.465524)
		(stroke
			(width 0.05715)
			(type default)
		)
		(layer "In13.Cu")
	)
	(gr_line
		(start 115.519454 -281.845004)
		(end 115.520216 -281.845512)
		(stroke
			(width 0.05715)
			(type default)
		)
		(layer "In13.Cu")
	)
	(gr_line
		(start 115.519454 -280.224992)
		(end 115.520216 -280.2255)
		(stroke
			(width 0.05715)
			(type default)
		)
		(layer "In13.Cu")
	)
	(gr_line
		(start 115.519454 -278.60498)
		(end 115.520216 -278.605488)
		(stroke
			(width 0.05715)
			(type default)
		)
		(layer "In13.Cu")
	)
	(gr_line
		(start 115.519454 -276.984968)
		(end 115.520216 -276.985476)
		(stroke
			(width 0.05715)
			(type default)
		)
		(layer "In13.Cu")
	)
	(gr_line
		(start 115.519454 -275.364956)
		(end 115.520216 -275.365464)
		(stroke
			(width 0.05715)
			(type default)
		)
		(layer "In13.Cu")
	)
	(gr_line
		(start 115.519454 -273.744944)
		(end 115.520216 -273.745452)
		(stroke
			(width 0.05715)
			(type default)
		)
		(layer "In13.Cu")
	)
	(gr_line
		(start 115.520216 -294.805354)
		(end 115.520978 -294.805862)
		(stroke
			(width 0.05715)
			(type default)
		)
		(layer "In13.Cu")
	)
	(gr_line
		(start 115.520216 -293.185342)
		(end 115.520978 -293.18585)
		(stroke
			(width 0.05715)
			(type default)
		)
		(layer "In13.Cu")
	)
	(gr_line
		(start 115.520216 -291.56533)
		(end 115.520978 -291.565838)
		(stroke
			(width 0.05715)
			(type default)
		)
		(layer "In13.Cu")
	)
	(gr_line
		(start 115.520216 -285.085536)
		(end 115.520978 -285.086044)
		(stroke
			(width 0.05715)
			(type default)
		)
		(layer "In13.Cu")
	)
	(gr_line
		(start 115.520216 -283.465524)
		(end 115.520978 -283.466032)
		(stroke
			(width 0.05715)
			(type default)
		)
		(layer "In13.Cu")
	)
	(gr_line
		(start 115.520216 -281.845512)
		(end 115.520978 -281.84602)
		(stroke
			(width 0.05715)
			(type default)
		)
		(layer "In13.Cu")
	)
	(gr_line
		(start 115.520216 -280.2255)
		(end 115.520978 -280.226008)
		(stroke
			(width 0.05715)
			(type default)
		)
		(layer "In13.Cu")
	)
	(gr_line
		(start 115.520216 -278.605488)
		(end 115.520978 -278.605996)
		(stroke
			(width 0.05715)
			(type default)
		)
		(layer "In13.Cu")
	)
	(gr_line
		(start 115.520216 -276.985476)
		(end 115.520978 -276.985984)
		(stroke
			(width 0.05715)
			(type default)
		)
		(layer "In13.Cu")
	)
	(gr_line
		(start 115.520216 -275.365464)
		(end 115.520978 -275.365972)
		(stroke
			(width 0.05715)
			(type default)
		)
		(layer "In13.Cu")
	)
	(gr_line
		(start 115.520216 -273.745452)
		(end 115.520978 -273.74596)
		(stroke
			(width 0.05715)
			(type default)
		)
		(layer "In13.Cu")
	)
	(gr_line
		(start 115.520724 -280.906728)
		(end 115.51539 -280.909776)
		(stroke
			(width 0.05715)
			(type default)
		)
		(layer "In13.Cu")
	)
	(gr_line
		(start 115.551458 -279.268936)
		(end 115.550696 -279.269444)
		(stroke
			(width 0.05715)
			(type default)
		)
		(layer "In13.Cu")
	)
	(gr_line
		(start 115.551458 -277.648924)
		(end 115.550696 -277.649432)
		(stroke
			(width 0.05715)
			(type default)
		)
		(layer "In13.Cu")
	)
	(gr_line
		(start 115.551458 -276.028912)
		(end 115.550696 -276.02942)
		(stroke
			(width 0.05715)
			(type default)
		)
		(layer "In13.Cu")
	)
	(gr_line
		(start 115.551458 -274.4089)
		(end 115.550696 -274.409408)
		(stroke
			(width 0.05715)
			(type default)
		)
		(layer "In13.Cu")
	)
	(gr_line
		(start 115.551712 -293.84879)
		(end 115.550696 -293.849298)
		(stroke
			(width 0.05715)
			(type default)
		)
		(layer "In13.Cu")
	)
	(gr_line
		(start 115.551712 -292.228778)
		(end 115.550696 -292.229286)
		(stroke
			(width 0.05715)
			(type default)
		)
		(layer "In13.Cu")
	)
	(gr_line
		(start 115.551712 -290.608766)
		(end 115.550696 -290.609274)
		(stroke
			(width 0.05715)
			(type default)
		)
		(layer "In13.Cu")
	)
	(gr_line
		(start 115.551712 -288.988754)
		(end 115.550696 -288.989262)
		(stroke
			(width 0.05715)
			(type default)
		)
		(layer "In13.Cu")
	)
	(gr_line
		(start 115.551712 -285.748984)
		(end 115.550696 -285.749492)
		(stroke
			(width 0.05715)
			(type default)
		)
		(layer "In13.Cu")
	)
	(gr_line
		(start 115.551712 -284.128972)
		(end 115.550696 -284.12948)
		(stroke
			(width 0.05715)
			(type default)
		)
		(layer "In13.Cu")
	)
	(gr_line
		(start 115.551712 -282.50896)
		(end 115.550696 -282.509468)
		(stroke
			(width 0.05715)
			(type default)
		)
		(layer "In13.Cu")
	)
	(gr_line
		(start 115.551712 -280.243788)
		(end 115.55222 -280.244042)
		(stroke
			(width 0.05715)
			(type default)
		)
		(layer "In13.Cu")
	)
	(gr_line
		(start 115.551966 -294.823896)
		(end 115.552474 -294.82415)
		(stroke
			(width 0.05715)
			(type default)
		)
		(layer "In13.Cu")
	)
	(gr_line
		(start 115.551966 -293.203884)
		(end 115.552474 -293.204138)
		(stroke
			(width 0.05715)
			(type default)
		)
		(layer "In13.Cu")
	)
	(gr_line
		(start 115.551966 -291.583872)
		(end 115.552474 -291.584126)
		(stroke
			(width 0.05715)
			(type default)
		)
		(layer "In13.Cu")
	)
	(gr_line
		(start 115.551966 -285.104078)
		(end 115.552474 -285.104332)
		(stroke
			(width 0.05715)
			(type default)
		)
		(layer "In13.Cu")
	)
	(gr_line
		(start 115.551966 -283.484066)
		(end 115.552474 -283.48432)
		(stroke
			(width 0.05715)
			(type default)
		)
		(layer "In13.Cu")
	)
	(gr_line
		(start 115.551966 -281.864054)
		(end 115.552474 -281.864308)
		(stroke
			(width 0.05715)
			(type default)
		)
		(layer "In13.Cu")
	)
	(gr_line
		(start 115.551966 -278.62403)
		(end 115.552474 -278.624284)
		(stroke
			(width 0.05715)
			(type default)
		)
		(layer "In13.Cu")
	)
	(gr_line
		(start 115.551966 -277.004018)
		(end 115.552474 -277.004272)
		(stroke
			(width 0.05715)
			(type default)
		)
		(layer "In13.Cu")
	)
	(gr_line
		(start 115.551966 -275.384006)
		(end 115.552474 -275.38426)
		(stroke
			(width 0.05715)
			(type default)
		)
		(layer "In13.Cu")
	)
	(gr_line
		(start 115.551966 -273.763994)
		(end 115.552474 -273.764248)
		(stroke
			(width 0.05715)
			(type default)
		)
		(layer "In13.Cu")
	)
	(gr_line
		(start 115.552474 -294.82415)
		(end 115.553744 -294.824912)
		(stroke
			(width 0.05715)
			(type default)
		)
		(layer "In13.Cu")
	)
	(gr_line
		(start 115.552474 -293.848282)
		(end 115.551712 -293.84879)
		(stroke
			(width 0.05715)
			(type default)
		)
		(layer "In13.Cu")
	)
	(gr_line
		(start 115.552474 -293.204138)
		(end 115.553744 -293.2049)
		(stroke
			(width 0.05715)
			(type default)
		)
		(layer "In13.Cu")
	)
	(gr_line
		(start 115.552474 -292.22827)
		(end 115.551712 -292.228778)
		(stroke
			(width 0.05715)
			(type default)
		)
		(layer "In13.Cu")
	)
	(gr_line
		(start 115.552474 -291.584126)
		(end 115.553744 -291.584888)
		(stroke
			(width 0.05715)
			(type default)
		)
		(layer "In13.Cu")
	)
	(gr_line
		(start 115.552474 -290.608258)
		(end 115.551712 -290.608766)
		(stroke
			(width 0.05715)
			(type default)
		)
		(layer "In13.Cu")
	)
	(gr_line
		(start 115.552474 -289.964114)
		(end 115.553744 -289.964876)
		(stroke
			(width 0.05715)
			(type default)
		)
		(layer "In13.Cu")
	)
	(gr_line
		(start 115.552474 -288.988246)
		(end 115.551712 -288.988754)
		(stroke
			(width 0.05715)
			(type default)
		)
		(layer "In13.Cu")
	)
	(gr_line
		(start 115.552474 -285.748476)
		(end 115.551712 -285.748984)
		(stroke
			(width 0.05715)
			(type default)
		)
		(layer "In13.Cu")
	)
	(gr_line
		(start 115.552474 -285.104332)
		(end 115.553744 -285.105094)
		(stroke
			(width 0.05715)
			(type default)
		)
		(layer "In13.Cu")
	)
	(gr_line
		(start 115.552474 -284.128464)
		(end 115.551712 -284.128972)
		(stroke
			(width 0.05715)
			(type default)
		)
		(layer "In13.Cu")
	)
	(gr_line
		(start 115.552474 -283.48432)
		(end 115.553744 -283.485082)
		(stroke
			(width 0.05715)
			(type default)
		)
		(layer "In13.Cu")
	)
	(gr_line
		(start 115.552474 -282.508452)
		(end 115.551712 -282.50896)
		(stroke
			(width 0.05715)
			(type default)
		)
		(layer "In13.Cu")
	)
	(gr_line
		(start 115.552474 -281.864308)
		(end 115.553744 -281.86507)
		(stroke
			(width 0.05715)
			(type default)
		)
		(layer "In13.Cu")
	)
	(gr_line
		(start 115.552474 -278.624284)
		(end 115.553744 -278.625046)
		(stroke
			(width 0.05715)
			(type default)
		)
		(layer "In13.Cu")
	)
	(gr_line
		(start 115.552474 -277.004272)
		(end 115.553744 -277.005034)
		(stroke
			(width 0.05715)
			(type default)
		)
		(layer "In13.Cu")
	)
	(gr_line
		(start 115.552474 -275.38426)
		(end 115.553744 -275.385022)
		(stroke
			(width 0.05715)
			(type default)
		)
		(layer "In13.Cu")
	)
	(gr_line
		(start 115.552474 -273.764248)
		(end 115.553744 -273.76501)
		(stroke
			(width 0.05715)
			(type default)
		)
		(layer "In13.Cu")
	)
	(gr_line
		(start 115.553744 -293.84752)
		(end 115.552474 -293.848282)
		(stroke
			(width 0.05715)
			(type default)
		)
		(layer "In13.Cu")
	)
	(gr_line
		(start 115.553744 -292.227508)
		(end 115.552474 -292.22827)
		(stroke
			(width 0.05715)
			(type default)
		)
		(layer "In13.Cu")
	)
	(gr_line
		(start 115.553744 -290.607496)
		(end 115.552474 -290.608258)
		(stroke
			(width 0.05715)
			(type default)
		)
		(layer "In13.Cu")
	)
	(gr_line
		(start 115.553744 -288.987484)
		(end 115.552474 -288.988246)
		(stroke
			(width 0.05715)
			(type default)
		)
		(layer "In13.Cu")
	)
	(gr_line
		(start 115.553744 -285.747714)
		(end 115.552474 -285.748476)
		(stroke
			(width 0.05715)
			(type default)
		)
		(layer "In13.Cu")
	)
	(gr_line
		(start 115.553744 -284.127702)
		(end 115.552474 -284.128464)
		(stroke
			(width 0.05715)
			(type default)
		)
		(layer "In13.Cu")
	)
	(gr_line
		(start 115.553744 -282.50769)
		(end 115.552474 -282.508452)
		(stroke
			(width 0.05715)
			(type default)
		)
		(layer "In13.Cu")
	)
	(gr_line
		(start 115.560094 -400.839686)
		(end 115.55984 -400.839686)
		(stroke
			(width 0.07112)
			(type default)
		)
		(layer "In13.Cu")
	)
	(gr_line
		(start 115.604036 -409.117292)
		(end 115.604036 -408.690572)
		(stroke
			(width 0.07112)
			(type default)
		)
		(layer "In13.Cu")
	)
	(gr_line
		(start 115.604036 -408.690572)
		(end 115.468146 -408.554682)
		(stroke
			(width 0.07112)
			(type default)
		)
		(layer "In13.Cu")
	)
	(gr_line
		(start 115.604036 -407.989532)
		(end 115.604036 -407.562812)
		(stroke
			(width 0.07112)
			(type default)
		)
		(layer "In13.Cu")
	)
	(gr_line
		(start 115.604036 -407.562812)
		(end 115.468146 -407.426922)
		(stroke
			(width 0.07112)
			(type default)
		)
		(layer "In13.Cu")
	)
	(gr_line
		(start 115.646962 -294.014144)
		(end 115.645692 -294.014906)
		(stroke
			(width 0.05715)
			(type default)
		)
		(layer "In13.Cu")
	)
	(gr_line
		(start 115.646962 -292.394132)
		(end 115.645692 -292.394894)
		(stroke
			(width 0.05715)
			(type default)
		)
		(layer "In13.Cu")
	)
	(gr_line
		(start 115.646962 -290.77412)
		(end 115.645692 -290.774882)
		(stroke
			(width 0.05715)
			(type default)
		)
		(layer "In13.Cu")
	)
	(gr_line
		(start 115.646962 -289.154108)
		(end 115.645692 -289.15487)
		(stroke
			(width 0.05715)
			(type default)
		)
		(layer "In13.Cu")
	)
	(gr_line
		(start 115.646962 -285.914338)
		(end 115.645692 -285.9151)
		(stroke
			(width 0.05715)
			(type default)
		)
		(layer "In13.Cu")
	)
	(gr_line
		(start 115.646962 -284.294326)
		(end 115.645692 -284.295088)
		(stroke
			(width 0.05715)
			(type default)
		)
		(layer "In13.Cu")
	)
	(gr_line
		(start 115.646962 -282.674314)
		(end 115.645692 -282.675076)
		(stroke
			(width 0.05715)
			(type default)
		)
		(layer "In13.Cu")
	)
	(gr_line
		(start 115.646962 -279.43429)
		(end 115.645692 -279.435052)
		(stroke
			(width 0.05715)
			(type default)
		)
		(layer "In13.Cu")
	)
	(gr_line
		(start 115.646962 -277.814278)
		(end 115.645692 -277.81504)
		(stroke
			(width 0.05715)
			(type default)
		)
		(layer "In13.Cu")
	)
	(gr_line
		(start 115.646962 -276.194266)
		(end 115.645692 -276.195028)
		(stroke
			(width 0.05715)
			(type default)
		)
		(layer "In13.Cu")
	)
	(gr_line
		(start 115.646962 -274.574254)
		(end 115.645692 -274.575016)
		(stroke
			(width 0.05715)
			(type default)
		)
		(layer "In13.Cu")
	)
	(gr_line
		(start 115.647216 -289.798506)
		(end 115.647724 -289.79876)
		(stroke
			(width 0.05715)
			(type default)
		)
		(layer "In13.Cu")
	)
	(gr_line
		(start 115.64747 -279.434036)
		(end 115.646962 -279.43429)
		(stroke
			(width 0.05715)
			(type default)
		)
		(layer "In13.Cu")
	)
	(gr_line
		(start 115.64747 -277.814024)
		(end 115.646962 -277.814278)
		(stroke
			(width 0.05715)
			(type default)
		)
		(layer "In13.Cu")
	)
	(gr_line
		(start 115.64747 -276.194012)
		(end 115.646962 -276.194266)
		(stroke
			(width 0.05715)
			(type default)
		)
		(layer "In13.Cu")
	)
	(gr_line
		(start 115.64747 -274.574)
		(end 115.646962 -274.574254)
		(stroke
			(width 0.05715)
			(type default)
		)
		(layer "In13.Cu")
	)
	(gr_line
		(start 115.647724 -294.658796)
		(end 115.64874 -294.659304)
		(stroke
			(width 0.05715)
			(type default)
		)
		(layer "In13.Cu")
	)
	(gr_line
		(start 115.647724 -294.013636)
		(end 115.646962 -294.014144)
		(stroke
			(width 0.05715)
			(type default)
		)
		(layer "In13.Cu")
	)
	(gr_line
		(start 115.647724 -293.038784)
		(end 115.64874 -293.039292)
		(stroke
			(width 0.05715)
			(type default)
		)
		(layer "In13.Cu")
	)
	(gr_line
		(start 115.647724 -292.393624)
		(end 115.646962 -292.394132)
		(stroke
			(width 0.05715)
			(type default)
		)
		(layer "In13.Cu")
	)
	(gr_line
		(start 115.647724 -291.418772)
		(end 115.64874 -291.41928)
		(stroke
			(width 0.05715)
			(type default)
		)
		(layer "In13.Cu")
	)
	(gr_line
		(start 115.647724 -290.773612)
		(end 115.646962 -290.77412)
		(stroke
			(width 0.05715)
			(type default)
		)
		(layer "In13.Cu")
	)
	(gr_line
		(start 115.647724 -289.79876)
		(end 115.64874 -289.799268)
		(stroke
			(width 0.05715)
			(type default)
		)
		(layer "In13.Cu")
	)
	(gr_line
		(start 115.647724 -289.1536)
		(end 115.646962 -289.154108)
		(stroke
			(width 0.05715)
			(type default)
		)
		(layer "In13.Cu")
	)
	(gr_line
		(start 115.647724 -285.91383)
		(end 115.646962 -285.914338)
		(stroke
			(width 0.05715)
			(type default)
		)
		(layer "In13.Cu")
	)
	(gr_line
		(start 115.647724 -284.938978)
		(end 115.64874 -284.939486)
		(stroke
			(width 0.05715)
			(type default)
		)
		(layer "In13.Cu")
	)
	(gr_line
		(start 115.647724 -284.293818)
		(end 115.646962 -284.294326)
		(stroke
			(width 0.05715)
			(type default)
		)
		(layer "In13.Cu")
	)
	(gr_line
		(start 115.647724 -283.318966)
		(end 115.64874 -283.319474)
		(stroke
			(width 0.05715)
			(type default)
		)
		(layer "In13.Cu")
	)
	(gr_line
		(start 115.647724 -282.673806)
		(end 115.646962 -282.674314)
		(stroke
			(width 0.05715)
			(type default)
		)
		(layer "In13.Cu")
	)
	(gr_line
		(start 115.647724 -281.698954)
		(end 115.64874 -281.699462)
		(stroke
			(width 0.05715)
			(type default)
		)
		(layer "In13.Cu")
	)
	(gr_line
		(start 115.647724 -278.45893)
		(end 115.64874 -278.459438)
		(stroke
			(width 0.05715)
			(type default)
		)
		(layer "In13.Cu")
	)
	(gr_line
		(start 115.647724 -276.838918)
		(end 115.64874 -276.839426)
		(stroke
			(width 0.05715)
			(type default)
		)
		(layer "In13.Cu")
	)
	(gr_line
		(start 115.647724 -275.218906)
		(end 115.64874 -275.219414)
		(stroke
			(width 0.05715)
			(type default)
		)
		(layer "In13.Cu")
	)
	(gr_line
		(start 115.647724 -273.598894)
		(end 115.64874 -273.599402)
		(stroke
			(width 0.05715)
			(type default)
		)
		(layer "In13.Cu")
	)
	(gr_line
		(start 115.64874 -294.013128)
		(end 115.647724 -294.013636)
		(stroke
			(width 0.05715)
			(type default)
		)
		(layer "In13.Cu")
	)
	(gr_line
		(start 115.64874 -292.393116)
		(end 115.647724 -292.393624)
		(stroke
			(width 0.05715)
			(type default)
		)
		(layer "In13.Cu")
	)
	(gr_line
		(start 115.64874 -290.773104)
		(end 115.647724 -290.773612)
		(stroke
			(width 0.05715)
			(type default)
		)
		(layer "In13.Cu")
	)
	(gr_line
		(start 115.64874 -289.153092)
		(end 115.647724 -289.1536)
		(stroke
			(width 0.05715)
			(type default)
		)
		(layer "In13.Cu")
	)
	(gr_line
		(start 115.64874 -285.913322)
		(end 115.647724 -285.91383)
		(stroke
			(width 0.05715)
			(type default)
		)
		(layer "In13.Cu")
	)
	(gr_line
		(start 115.64874 -284.29331)
		(end 115.647724 -284.293818)
		(stroke
			(width 0.05715)
			(type default)
		)
		(layer "In13.Cu")
	)
	(gr_line
		(start 115.64874 -282.673298)
		(end 115.647724 -282.673806)
		(stroke
			(width 0.05715)
			(type default)
		)
		(layer "In13.Cu")
	)
	(gr_line
		(start 115.658646 -399.53692)
		(end 115.794536 -399.40103)
		(stroke
			(width 0.07112)
			(type default)
		)
		(layer "In13.Cu")
	)
	(gr_line
		(start 115.658646 -398.40916)
		(end 115.794536 -398.27327)
		(stroke
			(width 0.07112)
			(type default)
		)
		(layer "In13.Cu")
	)
	(gr_line
		(start 115.658646 -397.2814)
		(end 115.794536 -397.14551)
		(stroke
			(width 0.07112)
			(type default)
		)
		(layer "In13.Cu")
	)
	(gr_line
		(start 115.658646 -396.15364)
		(end 115.794536 -396.01775)
		(stroke
			(width 0.07112)
			(type default)
		)
		(layer "In13.Cu")
	)
	(gr_line
		(start 115.658646 -395.02588)
		(end 115.794536 -394.88999)
		(stroke
			(width 0.07112)
			(type default)
		)
		(layer "In13.Cu")
	)
	(gr_line
		(start 115.794536 -399.40103)
		(end 115.794536 -398.97431)
		(stroke
			(width 0.07112)
			(type default)
		)
		(layer "In13.Cu")
	)
	(gr_line
		(start 115.794536 -398.97431)
		(end 115.658646 -398.83842)
		(stroke
			(width 0.07112)
			(type default)
		)
		(layer "In13.Cu")
	)
	(gr_line
		(start 115.794536 -398.27327)
		(end 115.794536 -397.84655)
		(stroke
			(width 0.07112)
			(type default)
		)
		(layer "In13.Cu")
	)
	(gr_line
		(start 115.794536 -397.84655)
		(end 115.658646 -397.71066)
		(stroke
			(width 0.07112)
			(type default)
		)
		(layer "In13.Cu")
	)
	(gr_line
		(start 115.794536 -397.14551)
		(end 115.794536 -396.71879)
		(stroke
			(width 0.07112)
			(type default)
		)
		(layer "In13.Cu")
	)
	(gr_line
		(start 115.794536 -396.71879)
		(end 115.658646 -396.5829)
		(stroke
			(width 0.07112)
			(type default)
		)
		(layer "In13.Cu")
	)
	(gr_line
		(start 115.794536 -396.01775)
		(end 115.794536 -395.59103)
		(stroke
			(width 0.07112)
			(type default)
		)
		(layer "In13.Cu")
	)
	(gr_line
		(start 115.794536 -395.59103)
		(end 115.658646 -395.45514)
		(stroke
			(width 0.07112)
			(type default)
		)
		(layer "In13.Cu")
	)
	(gr_line
		(start 115.794536 -394.88999)
		(end 115.794536 -394.46327)
		(stroke
			(width 0.07112)
			(type default)
		)
		(layer "In13.Cu")
	)
	(gr_line
		(start 115.794536 -394.46327)
		(end 115.658646 -394.32738)
		(stroke
			(width 0.07112)
			(type default)
		)
		(layer "In13.Cu")
	)
	(gr_line
		(start 115.828572 -401.487894)
		(end 115.560094 -400.839686)
		(stroke
			(width 0.07112)
			(type default)
		)
		(layer "In13.Cu")
	)
	(gr_line
		(start 115.976908 -392.707622)
		(end 115.989354 -392.707622)
		(stroke
			(width 0.07112)
			(type default)
		)
		(layer "In13.Cu")
	)
	(gr_line
		(start 115.978178 -392.990832)
		(end 116.116354 -393.129008)
		(stroke
			(width 0.07112)
			(type default)
		)
		(layer "In13.Cu")
	)
	(gr_line
		(start 115.989354 -392.707622)
		(end 116.116354 -392.580622)
		(stroke
			(width 0.07112)
			(type default)
		)
		(layer "In13.Cu")
	)
	(gr_line
		(start 115.99164 -401.881848)
		(end 115.955064 -401.793202)
		(stroke
			(width 0.07112)
			(type default)
		)
		(layer "In13.Cu")
	)
	(gr_line
		(start 116.000022 -400.806158)
		(end 115.822476 -400.732752)
		(stroke
			(width 0.07112)
			(type default)
		)
		(layer "In13.Cu")
	)
	(gr_line
		(start 116.089684 -401.37842)
		(end 116.163344 -401.20062)
		(stroke
			(width 0.07112)
			(type default)
		)
		(layer "In13.Cu")
	)
	(gr_line
		(start 116.116354 -393.129008)
		(end 116.116354 -393.292838)
		(stroke
			(width 0.07112)
			(type default)
		)
		(layer "In13.Cu")
	)
	(gr_line
		(start 116.116354 -392.580622)
		(end 116.116354 -392.429238)
		(stroke
			(width 0.07112)
			(type default)
		)
		(layer "In13.Cu")
	)
	(gr_line
		(start 116.163344 -401.20062)
		(end 116.000022 -400.806158)
		(stroke
			(width 0.07112)
			(type default)
		)
		(layer "In13.Cu")
	)
	(gr_line
		(start 116.163852 -296.29862)
		(end 116.163852 -296.327068)
		(stroke
			(width 0.05715)
			(type default)
		)
		(layer "In13.Cu")
	)
	(gr_line
		(start 116.209572 -296.2529)
		(end 116.163852 -296.29862)
		(stroke
			(width 0.05715)
			(type default)
		)
		(layer "In13.Cu")
	)
	(gr_line
		(start 116.252244 -401.774152)
		(end 116.215414 -401.685506)
		(stroke
			(width 0.07112)
			(type default)
		)
		(layer "In13.Cu")
	)
	(gr_line
		(start 116.260118 -402.530056)
		(end 115.99164 -401.881848)
		(stroke
			(width 0.07112)
			(type default)
		)
		(layer "In13.Cu")
	)
	(gr_line
		(start 116.400072 -296.2529)
		(end 116.445792 -296.29862)
		(stroke
			(width 0.05715)
			(type default)
		)
		(layer "In13.Cu")
	)
	(gr_line
		(start 116.400072 -295.95572)
		(end 116.400072 -295.956228)
		(stroke
			(width 0.05715)
			(type default)
		)
		(layer "In13.Cu")
	)
	(gr_line
		(start 116.40185 -313.058556)
		(end 116.402104 -313.058556)
		(stroke
			(width 0.07112)
			(type default)
		)
		(layer "In13.Cu")
	)
	(gr_line
		(start 116.431822 -401.84832)
		(end 116.254022 -401.774914)
		(stroke
			(width 0.07112)
			(type default)
		)
		(layer "In13.Cu")
	)
	(gr_arc
		(start 116.444776 -293.175182)
		(mid 116.448701 -293.177993)
		(end 116.45265 -293.18077)
		(stroke
			(width 0.05715)
			(type default)
		)
		(layer "In13.Cu")
	)
	(gr_arc
		(start 116.444776 -291.55517)
		(mid 116.448701 -291.557981)
		(end 116.45265 -291.560758)
		(stroke
			(width 0.05715)
			(type default)
		)
		(layer "In13.Cu")
	)
	(gr_arc
		(start 116.444776 -289.935158)
		(mid 116.448701 -289.937969)
		(end 116.45265 -289.940746)
		(stroke
			(width 0.05715)
			(type default)
		)
		(layer "In13.Cu")
	)
	(gr_arc
		(start 116.444776 -281.835352)
		(mid 116.448701 -281.838163)
		(end 116.45265 -281.84094)
		(stroke
			(width 0.05715)
			(type default)
		)
		(layer "In13.Cu")
	)
	(gr_arc
		(start 116.444776 -280.21534)
		(mid 116.448701 -280.218151)
		(end 116.45265 -280.220928)
		(stroke
			(width 0.05715)
			(type default)
		)
		(layer "In13.Cu")
	)
	(gr_arc
		(start 116.444776 -276.975316)
		(mid 116.448701 -276.978127)
		(end 116.45265 -276.980904)
		(stroke
			(width 0.05715)
			(type default)
		)
		(layer "In13.Cu")
	)
	(gr_arc
		(start 116.444776 -275.355304)
		(mid 116.448701 -275.358115)
		(end 116.45265 -275.360892)
		(stroke
			(width 0.05715)
			(type default)
		)
		(layer "In13.Cu")
	)
	(gr_arc
		(start 116.444776 -273.735292)
		(mid 116.448701 -273.738103)
		(end 116.45265 -273.74088)
		(stroke
			(width 0.05715)
			(type default)
		)
		(layer "In13.Cu")
	)
	(gr_arc
		(start 116.444776 -272.11528)
		(mid 116.448701 -272.118091)
		(end 116.45265 -272.120868)
		(stroke
			(width 0.05715)
			(type default)
		)
		(layer "In13.Cu")
	)
	(gr_line
		(start 116.445792 -296.29862)
		(end 116.445792 -296.327068)
		(stroke
			(width 0.05715)
			(type default)
		)
		(layer "In13.Cu")
	)
	(gr_line
		(start 116.45265 -293.18077)
		(end 116.459508 -293.184834)
		(stroke
			(width 0.05715)
			(type default)
		)
		(layer "In13.Cu")
	)
	(gr_line
		(start 116.45265 -291.560758)
		(end 116.459508 -291.564822)
		(stroke
			(width 0.05715)
			(type default)
		)
		(layer "In13.Cu")
	)
	(gr_line
		(start 116.45265 -289.940746)
		(end 116.459508 -289.94481)
		(stroke
			(width 0.05715)
			(type default)
		)
		(layer "In13.Cu")
	)
	(gr_line
		(start 116.45265 -281.84094)
		(end 116.459508 -281.845004)
		(stroke
			(width 0.05715)
			(type default)
		)
		(layer "In13.Cu")
	)
	(gr_arc
		(start 116.45265 -280.911808)
		(mid 116.448701 -280.914585)
		(end 116.444776 -280.917396)
		(stroke
			(width 0.05715)
			(type default)
		)
		(layer "In13.Cu")
	)
	(gr_line
		(start 116.45265 -280.220928)
		(end 116.459508 -280.224992)
		(stroke
			(width 0.05715)
			(type default)
		)
		(layer "In13.Cu")
	)
	(gr_line
		(start 116.45265 -276.980904)
		(end 116.459508 -276.984968)
		(stroke
			(width 0.05715)
			(type default)
		)
		(layer "In13.Cu")
	)
	(gr_line
		(start 116.45265 -275.360892)
		(end 116.459508 -275.364956)
		(stroke
			(width 0.05715)
			(type default)
		)
		(layer "In13.Cu")
	)
	(gr_line
		(start 116.45265 -273.74088)
		(end 116.459508 -273.744944)
		(stroke
			(width 0.05715)
			(type default)
		)
		(layer "In13.Cu")
	)
	(gr_line
		(start 116.45265 -272.120868)
		(end 116.459508 -272.124932)
		(stroke
			(width 0.05715)
			(type default)
		)
		(layer "In13.Cu")
	)
	(gr_line
		(start 116.455444 -280.909776)
		(end 116.45265 -280.911808)
		(stroke
			(width 0.05715)
			(type default)
		)
		(layer "In13.Cu")
	)
	(gr_line
		(start 116.459508 -293.184834)
		(end 116.46027 -293.185342)
		(stroke
			(width 0.05715)
			(type default)
		)
		(layer "In13.Cu")
	)
	(gr_line
		(start 116.459508 -291.564822)
		(end 116.46027 -291.56533)
		(stroke
			(width 0.05715)
			(type default)
		)
		(layer "In13.Cu")
	)
	(gr_line
		(start 116.459508 -289.94481)
		(end 116.46027 -289.945318)
		(stroke
			(width 0.05715)
			(type default)
		)
		(layer "In13.Cu")
	)
	(gr_line
		(start 116.459508 -281.845004)
		(end 116.46027 -281.845512)
		(stroke
			(width 0.05715)
			(type default)
		)
		(layer "In13.Cu")
	)
	(gr_line
		(start 116.459508 -280.224992)
		(end 116.46027 -280.2255)
		(stroke
			(width 0.05715)
			(type default)
		)
		(layer "In13.Cu")
	)
	(gr_line
		(start 116.459508 -276.984968)
		(end 116.46027 -276.985476)
		(stroke
			(width 0.05715)
			(type default)
		)
		(layer "In13.Cu")
	)
	(gr_line
		(start 116.459508 -275.364956)
		(end 116.46027 -275.365464)
		(stroke
			(width 0.05715)
			(type default)
		)
		(layer "In13.Cu")
	)
	(gr_line
		(start 116.459508 -273.744944)
		(end 116.46027 -273.745452)
		(stroke
			(width 0.05715)
			(type default)
		)
		(layer "In13.Cu")
	)
	(gr_line
		(start 116.459508 -272.124932)
		(end 116.46027 -272.12544)
		(stroke
			(width 0.05715)
			(type default)
		)
		(layer "In13.Cu")
	)
	(gr_line
		(start 116.46027 -293.185342)
		(end 116.461032 -293.18585)
		(stroke
			(width 0.05715)
			(type default)
		)
		(layer "In13.Cu")
	)
	(gr_line
		(start 116.46027 -291.56533)
		(end 116.461032 -291.565838)
		(stroke
			(width 0.05715)
			(type default)
		)
		(layer "In13.Cu")
	)
	(gr_line
		(start 116.46027 -289.945318)
		(end 116.461032 -289.945826)
		(stroke
			(width 0.05715)
			(type default)
		)
		(layer "In13.Cu")
	)
	(gr_line
		(start 116.46027 -281.845512)
		(end 116.461032 -281.84602)
		(stroke
			(width 0.05715)
			(type default)
		)
		(layer "In13.Cu")
	)
	(gr_line
		(start 116.46027 -280.2255)
		(end 116.461032 -280.226008)
		(stroke
			(width 0.05715)
			(type default)
		)
		(layer "In13.Cu")
	)
	(gr_line
		(start 116.46027 -276.985476)
		(end 116.461032 -276.985984)
		(stroke
			(width 0.05715)
			(type default)
		)
		(layer "In13.Cu")
	)
	(gr_line
		(start 116.46027 -275.365464)
		(end 116.461032 -275.365972)
		(stroke
			(width 0.05715)
			(type default)
		)
		(layer "In13.Cu")
	)
	(gr_line
		(start 116.46027 -273.745452)
		(end 116.461032 -273.74596)
		(stroke
			(width 0.05715)
			(type default)
		)
		(layer "In13.Cu")
	)
	(gr_line
		(start 116.46027 -272.12544)
		(end 116.461032 -272.125948)
		(stroke
			(width 0.05715)
			(type default)
		)
		(layer "In13.Cu")
	)
	(gr_line
		(start 116.460524 -280.906728)
		(end 116.455444 -280.909776)
		(stroke
			(width 0.05715)
			(type default)
		)
		(layer "In13.Cu")
	)
	(gr_arc
		(start 116.477796 -285.095696)
		(mid 116.479572 -285.096715)
		(end 116.481352 -285.097728)
		(stroke
			(width 0.05715)
			(type default)
		)
		(layer "In13.Cu")
	)
	(gr_line
		(start 116.48567 -282.512516)
		(end 116.484908 -282.513024)
		(stroke
			(width 0.05715)
			(type default)
		)
		(layer "In13.Cu")
	)
	(gr_line
		(start 116.48694 -283.481018)
		(end 116.488718 -283.482034)
		(stroke
			(width 0.05715)
			(type default)
		)
		(layer "In13.Cu")
	)
	(gr_line
		(start 116.487194 -282.5115)
		(end 116.48567 -282.512516)
		(stroke
			(width 0.05715)
			(type default)
		)
		(layer "In13.Cu")
	)
	(gr_line
		(start 116.48821 -282.510992)
		(end 116.487194 -282.5115)
		(stroke
			(width 0.05715)
			(type default)
		)
		(layer "In13.Cu")
	)
	(gr_line
		(start 116.488718 -294.823134)
		(end 116.50218 -294.836596)
		(stroke
			(width 0.05715)
			(type default)
		)
		(layer "In13.Cu")
	)
	(gr_line
		(start 116.488718 -283.482034)
		(end 116.489734 -283.482542)
		(stroke
			(width 0.05715)
			(type default)
		)
		(layer "In13.Cu")
	)
	(gr_line
		(start 116.489226 -293.850314)
		(end 116.487956 -293.851076)
		(stroke
			(width 0.05715)
			(type default)
		)
		(layer "In13.Cu")
	)
	(gr_line
		(start 116.489734 -283.482542)
		(end 116.490496 -283.48305)
		(stroke
			(width 0.05715)
			(type default)
		)
		(layer "In13.Cu")
	)
	(gr_line
		(start 116.489988 -284.129988)
		(end 116.488464 -284.131004)
		(stroke
			(width 0.05715)
			(type default)
		)
		(layer "In13.Cu")
	)
	(gr_line
		(start 116.489988 -282.509976)
		(end 116.48821 -282.510992)
		(stroke
			(width 0.05715)
			(type default)
		)
		(layer "In13.Cu")
	)
	(gr_line
		(start 116.490496 -283.48305)
		(end 116.492274 -283.484066)
		(stroke
			(width 0.05715)
			(type default)
		)
		(layer "In13.Cu")
	)
	(gr_line
		(start 116.49075 -293.849298)
		(end 116.489226 -293.850314)
		(stroke
			(width 0.05715)
			(type default)
		)
		(layer "In13.Cu")
	)
	(gr_line
		(start 116.491766 -293.849044)
		(end 116.491766 -293.84879)
		(stroke
			(width 0.05715)
			(type default)
		)
		(layer "In13.Cu")
	)
	(gr_line
		(start 116.491766 -293.84879)
		(end 116.49075 -293.849298)
		(stroke
			(width 0.05715)
			(type default)
		)
		(layer "In13.Cu")
	)
	(gr_line
		(start 116.491766 -292.229032)
		(end 116.491766 -292.228778)
		(stroke
			(width 0.05715)
			(type default)
		)
		(layer "In13.Cu")
	)
	(gr_line
		(start 116.491766 -292.228778)
		(end 116.49075 -292.229286)
		(stroke
			(width 0.05715)
			(type default)
		)
		(layer "In13.Cu")
	)
	(gr_line
		(start 116.491766 -290.60902)
		(end 116.491766 -290.608766)
		(stroke
			(width 0.05715)
			(type default)
		)
		(layer "In13.Cu")
	)
	(gr_line
		(start 116.491766 -290.608766)
		(end 116.49075 -290.609274)
		(stroke
			(width 0.05715)
			(type default)
		)
		(layer "In13.Cu")
	)
	(gr_line
		(start 116.491766 -288.988754)
		(end 116.49075 -288.989262)
		(stroke
			(width 0.05715)
			(type default)
		)
		(layer "In13.Cu")
	)
	(gr_line
		(start 116.491766 -288.343594)
		(end 116.492782 -288.344102)
		(stroke
			(width 0.05715)
			(type default)
		)
		(layer "In13.Cu")
	)
	(gr_line
		(start 116.491766 -285.748984)
		(end 116.49075 -285.749492)
		(stroke
			(width 0.05715)
			(type default)
		)
		(layer "In13.Cu")
	)
	(gr_line
		(start 116.491766 -279.268936)
		(end 116.49075 -279.269444)
		(stroke
			(width 0.05715)
			(type default)
		)
		(layer "In13.Cu")
	)
	(gr_line
		(start 116.491766 -277.648924)
		(end 116.49075 -277.649432)
		(stroke
			(width 0.05715)
			(type default)
		)
		(layer "In13.Cu")
	)
	(gr_line
		(start 116.491766 -276.028912)
		(end 116.49075 -276.02942)
		(stroke
			(width 0.05715)
			(type default)
		)
		(layer "In13.Cu")
	)
	(gr_line
		(start 116.491766 -274.4089)
		(end 116.49075 -274.409408)
		(stroke
			(width 0.05715)
			(type default)
		)
		(layer "In13.Cu")
	)
	(gr_line
		(start 116.491766 -272.788888)
		(end 116.49075 -272.789396)
		(stroke
			(width 0.05715)
			(type default)
		)
		(layer "In13.Cu")
	)
	(gr_line
		(start 116.49202 -280.244042)
		(end 116.492528 -280.244296)
		(stroke
			(width 0.05715)
			(type default)
		)
		(layer "In13.Cu")
	)
	(gr_line
		(start 116.49202 -277.004018)
		(end 116.492528 -277.004272)
		(stroke
			(width 0.05715)
			(type default)
		)
		(layer "In13.Cu")
	)
	(gr_line
		(start 116.492274 -293.84879)
		(end 116.491766 -293.849044)
		(stroke
			(width 0.05715)
			(type default)
		)
		(layer "In13.Cu")
	)
	(gr_line
		(start 116.492274 -292.228778)
		(end 116.491766 -292.229032)
		(stroke
			(width 0.05715)
			(type default)
		)
		(layer "In13.Cu")
	)
	(gr_line
		(start 116.492274 -290.608766)
		(end 116.491766 -290.60902)
		(stroke
			(width 0.05715)
			(type default)
		)
		(layer "In13.Cu")
	)
	(gr_line
		(start 116.492274 -283.484066)
		(end 116.493036 -283.484574)
		(stroke
			(width 0.05715)
			(type default)
		)
		(layer "In13.Cu")
	)
	(gr_line
		(start 116.492528 -282.508706)
		(end 116.492528 -282.508452)
		(stroke
			(width 0.05715)
			(type default)
		)
		(layer "In13.Cu")
	)
	(gr_line
		(start 116.492528 -280.244296)
		(end 116.495322 -280.24582)
		(stroke
			(width 0.05715)
			(type default)
		)
		(layer "In13.Cu")
	)
	(gr_line
		(start 116.492528 -277.648416)
		(end 116.491766 -277.648924)
		(stroke
			(width 0.05715)
			(type default)
		)
		(layer "In13.Cu")
	)
	(gr_line
		(start 116.492528 -277.004272)
		(end 116.495322 -277.005796)
		(stroke
			(width 0.05715)
			(type default)
		)
		(layer "In13.Cu")
	)
	(gr_line
		(start 116.493036 -288.988246)
		(end 116.491766 -288.988754)
		(stroke
			(width 0.05715)
			(type default)
		)
		(layer "In13.Cu")
	)
	(gr_line
		(start 116.493798 -277.647654)
		(end 116.492528 -277.648416)
		(stroke
			(width 0.05715)
			(type default)
		)
		(layer "In13.Cu")
	)
	(gr_line
		(start 116.494052 -284.127956)
		(end 116.49075 -284.12948)
		(stroke
			(width 0.05715)
			(type default)
		)
		(layer "In13.Cu")
	)
	(gr_line
		(start 116.49456 -281.865578)
		(end 116.495068 -281.865578)
		(stroke
			(width 0.05715)
			(type default)
		)
		(layer "In13.Cu")
	)
	(gr_line
		(start 116.495322 -282.507182)
		(end 116.494814 -282.507182)
		(stroke
			(width 0.05715)
			(type default)
		)
		(layer "In13.Cu")
	)
	(gr_line
		(start 116.50218 -294.836596)
		(end 116.509546 -294.836596)
		(stroke
			(width 0.05715)
			(type default)
		)
		(layer "In13.Cu")
	)
	(gr_line
		(start 116.505228 -284.121352)
		(end 116.50472 -284.121606)
		(stroke
			(width 0.05715)
			(type default)
		)
		(layer "In13.Cu")
	)
	(gr_line
		(start 116.50599 -284.120844)
		(end 116.505228 -284.121352)
		(stroke
			(width 0.05715)
			(type default)
		)
		(layer "In13.Cu")
	)
	(gr_line
		(start 116.506752 -284.120336)
		(end 116.50599 -284.120844)
		(stroke
			(width 0.05715)
			(type default)
		)
		(layer "In13.Cu")
	)
	(gr_line
		(start 116.509292 -284.118812)
		(end 116.50853 -284.11932)
		(stroke
			(width 0.05715)
			(type default)
		)
		(layer "In13.Cu")
	)
	(gr_line
		(start 116.510054 -284.118304)
		(end 116.509292 -284.118812)
		(stroke
			(width 0.05715)
			(type default)
		)
		(layer "In13.Cu")
	)
	(gr_line
		(start 116.510054 -283.49448)
		(end 116.510308 -283.49448)
		(stroke
			(width 0.05715)
			(type default)
		)
		(layer "In13.Cu")
	)
	(gr_line
		(start 116.510562 -284.118304)
		(end 116.510054 -284.118304)
		(stroke
			(width 0.05715)
			(type default)
		)
		(layer "In13.Cu")
	)
	(gr_line
		(start 116.521484 -402.420582)
		(end 116.595144 -402.242782)
		(stroke
			(width 0.07112)
			(type default)
		)
		(layer "In13.Cu")
	)
	(gr_line
		(start 116.543328 -280.856436)
		(end 116.54282 -280.856944)
		(stroke
			(width 0.05715)
			(type default)
		)
		(layer "In13.Cu")
	)
	(gr_line
		(start 116.571268 -287.54324)
		(end 116.571268 -287.543494)
		(stroke
			(width 0.05715)
			(type default)
		)
		(layer "In13.Cu")
	)
	(gr_line
		(start 116.571776 -287.542986)
		(end 116.571268 -287.54324)
		(stroke
			(width 0.05715)
			(type default)
		)
		(layer "In13.Cu")
	)
	(gr_line
		(start 116.575586 -398.62887)
		(end 116.575586 -397.92783)
		(stroke
			(width 0.07112)
			(type default)
		)
		(layer "In13.Cu")
	)
	(gr_line
		(start 116.575586 -397.50111)
		(end 116.575586 -396.80007)
		(stroke
			(width 0.07112)
			(type default)
		)
		(layer "In13.Cu")
	)
	(gr_line
		(start 116.575586 -396.37335)
		(end 116.575586 -395.67231)
		(stroke
			(width 0.07112)
			(type default)
		)
		(layer "In13.Cu")
	)
	(gr_line
		(start 116.575586 -395.24559)
		(end 116.575586 -394.54455)
		(stroke
			(width 0.07112)
			(type default)
		)
		(layer "In13.Cu")
	)
	(gr_line
		(start 116.581174 -283.315156)
		(end 116.581936 -283.315664)
		(stroke
			(width 0.05715)
			(type default)
		)
		(layer "In13.Cu")
	)
	(gr_line
		(start 116.581936 -283.315664)
		(end 116.58346 -283.316426)
		(stroke
			(width 0.05715)
			(type default)
		)
		(layer "In13.Cu")
	)
	(gr_line
		(start 116.582698 -282.6766)
		(end 116.581174 -282.677362)
		(stroke
			(width 0.05715)
			(type default)
		)
		(layer "In13.Cu")
	)
	(gr_line
		(start 116.582952 -294.656256)
		(end 116.582444 -294.656002)
		(stroke
			(width 0.05715)
			(type default)
		)
		(layer "In13.Cu")
	)
	(gr_line
		(start 116.582952 -294.656256)
		(end 116.585492 -294.65778)
		(stroke
			(width 0.05715)
			(type default)
		)
		(layer "In13.Cu")
	)
	(gr_line
		(start 116.582952 -288.175954)
		(end 116.587778 -288.178748)
		(stroke
			(width 0.05715)
			(type default)
		)
		(layer "In13.Cu")
	)
	(gr_line
		(start 116.58346 -283.316426)
		(end 116.584222 -283.316934)
		(stroke
			(width 0.05715)
			(type default)
		)
		(layer "In13.Cu")
	)
	(gr_line
		(start 116.584222 -283.316934)
		(end 116.584984 -283.317442)
		(stroke
			(width 0.05715)
			(type default)
		)
		(layer "In13.Cu")
	)
	(gr_line
		(start 116.58473 -284.9372)
		(end 116.587778 -284.938978)
		(stroke
			(width 0.05715)
			(type default)
		)
		(layer "In13.Cu")
	)
	(gr_line
		(start 116.585492 -294.65778)
		(end 116.585746 -294.657526)
		(stroke
			(width 0.05715)
			(type default)
		)
		(layer "In13.Cu")
	)
	(gr_line
		(start 116.585746 -294.657526)
		(end 116.587016 -294.658288)
		(stroke
			(width 0.05715)
			(type default)
		)
		(layer "In13.Cu")
	)
	(gr_line
		(start 116.586 -294.014652)
		(end 116.584222 -294.015668)
		(stroke
			(width 0.05715)
			(type default)
		)
		(layer "In13.Cu")
	)
	(gr_line
		(start 116.587016 -294.658288)
		(end 116.587778 -294.658796)
		(stroke
			(width 0.05715)
			(type default)
		)
		(layer "In13.Cu")
	)
	(gr_line
		(start 116.587016 -292.394132)
		(end 116.585746 -292.394894)
		(stroke
			(width 0.05715)
			(type default)
		)
		(layer "In13.Cu")
	)
	(gr_line
		(start 116.587016 -290.77412)
		(end 116.585746 -290.774882)
		(stroke
			(width 0.05715)
			(type default)
		)
		(layer "In13.Cu")
	)
	(gr_line
		(start 116.587016 -289.154108)
		(end 116.585746 -289.15487)
		(stroke
			(width 0.05715)
			(type default)
		)
		(layer "In13.Cu")
	)
	(gr_line
		(start 116.587016 -285.914338)
		(end 116.585746 -285.9151)
		(stroke
			(width 0.05715)
			(type default)
		)
		(layer "In13.Cu")
	)
	(gr_line
		(start 116.587016 -283.318712)
		(end 116.587016 -283.318458)
		(stroke
			(width 0.05715)
			(type default)
		)
		(layer "In13.Cu")
	)
	(gr_line
		(start 116.587016 -283.318458)
		(end 116.587778 -283.318966)
		(stroke
			(width 0.05715)
			(type default)
		)
		(layer "In13.Cu")
	)
	(gr_line
		(start 116.587016 -279.43429)
		(end 116.585746 -279.435052)
		(stroke
			(width 0.05715)
			(type default)
		)
		(layer "In13.Cu")
	)
	(gr_line
		(start 116.587016 -277.814278)
		(end 116.585746 -277.81504)
		(stroke
			(width 0.05715)
			(type default)
		)
		(layer "In13.Cu")
	)
	(gr_line
		(start 116.587016 -276.194266)
		(end 116.585746 -276.195028)
		(stroke
			(width 0.05715)
			(type default)
		)
		(layer "In13.Cu")
	)
	(gr_line
		(start 116.587016 -274.574254)
		(end 116.585746 -274.575016)
		(stroke
			(width 0.05715)
			(type default)
		)
		(layer "In13.Cu")
	)
	(gr_line
		(start 116.587016 -272.954242)
		(end 116.585746 -272.955004)
		(stroke
			(width 0.05715)
			(type default)
		)
		(layer "In13.Cu")
	)
	(gr_line
		(start 116.58727 -278.458676)
		(end 116.587778 -278.45893)
		(stroke
			(width 0.05715)
			(type default)
		)
		(layer "In13.Cu")
	)
	(gr_line
		(start 116.587524 -285.914084)
		(end 116.587016 -285.914338)
		(stroke
			(width 0.05715)
			(type default)
		)
		(layer "In13.Cu")
	)
	(gr_line
		(start 116.587524 -282.67406)
		(end 116.586508 -282.674568)
		(stroke
			(width 0.05715)
			(type default)
		)
		(layer "In13.Cu")
	)
	(gr_line
		(start 116.587524 -279.434036)
		(end 116.587016 -279.43429)
		(stroke
			(width 0.05715)
			(type default)
		)
		(layer "In13.Cu")
	)
	(gr_line
		(start 116.587524 -277.814024)
		(end 116.587016 -277.814278)
		(stroke
			(width 0.05715)
			(type default)
		)
		(layer "In13.Cu")
	)
	(gr_line
		(start 116.587524 -276.194012)
		(end 116.587016 -276.194266)
		(stroke
			(width 0.05715)
			(type default)
		)
		(layer "In13.Cu")
	)
	(gr_line
		(start 116.587524 -274.574)
		(end 116.587016 -274.574254)
		(stroke
			(width 0.05715)
			(type default)
		)
		(layer "In13.Cu")
	)
	(gr_line
		(start 116.587524 -272.953988)
		(end 116.587016 -272.954242)
		(stroke
			(width 0.05715)
			(type default)
		)
		(layer "In13.Cu")
	)
	(gr_line
		(start 116.587778 -294.658796)
		(end 116.615718 -294.67683)
		(stroke
			(width 0.05715)
			(type default)
		)
		(layer "In13.Cu")
	)
	(gr_line
		(start 116.587778 -294.013636)
		(end 116.587016 -294.014144)
		(stroke
			(width 0.05715)
			(type default)
		)
		(layer "In13.Cu")
	)
	(gr_line
		(start 116.587778 -292.393624)
		(end 116.587016 -292.394132)
		(stroke
			(width 0.05715)
			(type default)
		)
		(layer "In13.Cu")
	)
	(gr_line
		(start 116.587778 -290.773612)
		(end 116.587016 -290.77412)
		(stroke
			(width 0.05715)
			(type default)
		)
		(layer "In13.Cu")
	)
	(gr_line
		(start 116.587778 -288.178748)
		(end 116.58854 -288.179256)
		(stroke
			(width 0.05715)
			(type default)
		)
		(layer "In13.Cu")
	)
	(gr_line
		(start 116.587778 -284.293818)
		(end 116.584476 -284.295596)
		(stroke
			(width 0.05715)
			(type default)
		)
		(layer "In13.Cu")
	)
	(gr_line
		(start 116.587778 -282.673806)
		(end 116.587524 -282.67406)
		(stroke
			(width 0.05715)
			(type default)
		)
		(layer "In13.Cu")
	)
	(gr_line
		(start 116.587778 -281.698954)
		(end 116.590826 -281.700732)
		(stroke
			(width 0.05715)
			(type default)
		)
		(layer "In13.Cu")
	)
	(gr_line
		(start 116.58854 -289.153092)
		(end 116.587016 -289.154108)
		(stroke
			(width 0.05715)
			(type default)
		)
		(layer "In13.Cu")
	)
	(gr_line
		(start 116.590064 -284.292548)
		(end 116.587778 -284.293818)
		(stroke
			(width 0.05715)
			(type default)
		)
		(layer "In13.Cu")
	)
	(gr_line
		(start 116.590826 -282.672028)
		(end 116.587778 -282.673806)
		(stroke
			(width 0.05715)
			(type default)
		)
		(layer "In13.Cu")
	)
	(gr_line
		(start 116.595144 -402.242782)
		(end 116.431822 -401.84832)
		(stroke
			(width 0.07112)
			(type default)
		)
		(layer "In13.Cu")
	)
	(gr_line
		(start 116.603272 -284.284928)
		(end 116.601494 -284.285944)
		(stroke
			(width 0.05715)
			(type default)
		)
		(layer "In13.Cu")
	)
	(gr_line
		(start 116.603526 -283.32811)
		(end 116.605304 -283.329126)
		(stroke
			(width 0.05715)
			(type default)
		)
		(layer "In13.Cu")
	)
	(gr_line
		(start 116.604034 -284.28442)
		(end 116.603272 -284.284928)
		(stroke
			(width 0.05715)
			(type default)
		)
		(layer "In13.Cu")
	)
	(gr_line
		(start 116.605304 -283.329126)
		(end 116.606066 -283.329634)
		(stroke
			(width 0.05715)
			(type default)
		)
		(layer "In13.Cu")
	)
	(gr_line
		(start 116.606066 -284.28315)
		(end 116.604034 -284.28442)
		(stroke
			(width 0.05715)
			(type default)
		)
		(layer "In13.Cu")
	)
	(gr_line
		(start 116.716556 -412.030418)
		(end 116.716302 -412.030672)
		(stroke
			(width 0.07112)
			(type default)
		)
		(layer "In13.Cu")
	)
	(gr_line
		(start 116.774722 -273.276314)
		(end 117.072664 -273.276314)
		(stroke
			(width 0.05715)
			(type default)
		)
		(layer "In13.Cu")
	)
	(gr_line
		(start 116.774722 -271.656302)
		(end 117.072664 -271.656302)
		(stroke
			(width 0.05715)
			(type default)
		)
		(layer "In13.Cu")
	)
	(gr_line
		(start 116.774722 -270.03629)
		(end 117.072664 -270.03629)
		(stroke
			(width 0.05715)
			(type default)
		)
		(layer "In13.Cu")
	)
	(gr_line
		(start 116.858796 -398.6276)
		(end 116.994686 -398.49171)
		(stroke
			(width 0.07112)
			(type default)
		)
		(layer "In13.Cu")
	)
	(gr_line
		(start 116.858796 -397.49984)
		(end 116.994686 -397.36395)
		(stroke
			(width 0.07112)
			(type default)
		)
		(layer "In13.Cu")
	)
	(gr_line
		(start 116.858796 -396.37208)
		(end 116.994686 -396.23619)
		(stroke
			(width 0.07112)
			(type default)
		)
		(layer "In13.Cu")
	)
	(gr_line
		(start 116.858796 -395.24432)
		(end 116.994686 -395.10843)
		(stroke
			(width 0.07112)
			(type default)
		)
		(layer "In13.Cu")
	)
	(gr_line
		(start 116.95176 -270.364712)
		(end 116.951252 -270.364966)
		(stroke
			(width 0.05715)
			(type default)
		)
		(layer "In13.Cu")
	)
	(gr_arc
		(start 116.967762 -413.93491)
		(mid 116.967508 -413.934529)
		(end 116.967254 -413.934148)
		(stroke
			(width 0.07112)
			(type default)
		)
		(layer "In13.Cu")
	)
	(gr_line
		(start 116.994686 -398.49171)
		(end 116.994686 -398.06499)
		(stroke
			(width 0.07112)
			(type default)
		)
		(layer "In13.Cu")
	)
	(gr_line
		(start 116.994686 -398.06499)
		(end 116.858796 -397.9291)
		(stroke
			(width 0.07112)
			(type default)
		)
		(layer "In13.Cu")
	)
	(gr_line
		(start 116.994686 -397.36395)
		(end 116.994686 -396.93723)
		(stroke
			(width 0.07112)
			(type default)
		)
		(layer "In13.Cu")
	)
	(gr_line
		(start 116.994686 -396.93723)
		(end 116.858796 -396.80134)
		(stroke
			(width 0.07112)
			(type default)
		)
		(layer "In13.Cu")
	)
	(gr_line
		(start 116.994686 -396.23619)
		(end 116.994686 -395.80947)
		(stroke
			(width 0.07112)
			(type default)
		)
		(layer "In13.Cu")
	)
	(gr_line
		(start 116.994686 -395.80947)
		(end 116.858796 -395.67358)
		(stroke
			(width 0.07112)
			(type default)
		)
		(layer "In13.Cu")
	)
	(gr_line
		(start 116.994686 -395.10843)
		(end 116.994686 -394.68171)
		(stroke
			(width 0.07112)
			(type default)
		)
		(layer "In13.Cu")
	)
	(gr_line
		(start 116.994686 -394.68171)
		(end 116.858796 -394.54582)
		(stroke
			(width 0.07112)
			(type default)
		)
		(layer "In13.Cu")
	)
	(gr_line
		(start 116.998496 -412.030672)
		(end 116.998242 -412.030418)
		(stroke
			(width 0.07112)
			(type default)
		)
		(layer "In13.Cu")
	)
	(gr_line
		(start 117.042692 -295.460166)
		(end 117.046248 -295.462198)
		(stroke
			(width 0.05715)
			(type default)
		)
		(layer "In13.Cu")
	)
	(gr_line
		(start 117.047264 -270.529558)
		(end 117.04701 -270.529812)
		(stroke
			(width 0.05715)
			(type default)
		)
		(layer "In13.Cu")
	)
	(gr_line
		(start 117.072664 -273.276314)
		(end 117.155468 -273.359118)
		(stroke
			(width 0.05715)
			(type default)
		)
		(layer "In13.Cu")
	)
	(gr_line
		(start 117.072664 -271.656302)
		(end 117.155468 -271.739106)
		(stroke
			(width 0.05715)
			(type default)
		)
		(layer "In13.Cu")
	)
	(gr_line
		(start 117.072664 -270.03629)
		(end 117.142006 -270.105632)
		(stroke
			(width 0.05715)
			(type default)
		)
		(layer "In13.Cu")
	)
	(gr_line
		(start 117.103906 -296.29862)
		(end 117.103906 -296.327068)
		(stroke
			(width 0.05715)
			(type default)
		)
		(layer "In13.Cu")
	)
	(gr_line
		(start 117.149626 -296.2529)
		(end 117.103906 -296.29862)
		(stroke
			(width 0.05715)
			(type default)
		)
		(layer "In13.Cu")
	)
	(gr_arc
		(start 117.155468 -273.359118)
		(mid 117.157256 -273.370568)
		(end 117.159278 -273.381978)
		(stroke
			(width 0.05715)
			(type default)
		)
		(layer "In13.Cu")
	)
	(gr_arc
		(start 117.155468 -271.739106)
		(mid 117.157256 -271.750556)
		(end 117.159278 -271.761966)
		(stroke
			(width 0.05715)
			(type default)
		)
		(layer "In13.Cu")
	)
	(gr_line
		(start 117.177058 -392.707622)
		(end 117.189504 -392.707622)
		(stroke
			(width 0.07112)
			(type default)
		)
		(layer "In13.Cu")
	)
	(gr_line
		(start 117.178328 -392.990832)
		(end 117.316504 -393.129008)
		(stroke
			(width 0.07112)
			(type default)
		)
		(layer "In13.Cu")
	)
	(gr_line
		(start 117.189504 -392.707622)
		(end 117.316504 -392.580622)
		(stroke
			(width 0.07112)
			(type default)
		)
		(layer "In13.Cu")
	)
	(gr_line
		(start 117.316504 -393.129008)
		(end 117.316504 -393.292838)
		(stroke
			(width 0.07112)
			(type default)
		)
		(layer "In13.Cu")
	)
	(gr_line
		(start 117.316504 -392.580622)
		(end 117.316504 -392.429238)
		(stroke
			(width 0.07112)
			(type default)
		)
		(layer "In13.Cu")
	)
	(gr_arc
		(start 117.33022 -270.1417)
		(mid 117.33224 -270.130416)
		(end 117.33403 -270.119094)
		(stroke
			(width 0.05715)
			(type default)
		)
		(layer "In13.Cu")
	)
	(gr_line
		(start 117.340126 -296.2529)
		(end 117.385846 -296.29862)
		(stroke
			(width 0.05715)
			(type default)
		)
		(layer "In13.Cu")
	)
	(gr_line
		(start 117.344952 -399.965164)
		(end 117.153436 -399.946368)
		(stroke
			(width 0.07112)
			(type default)
		)
		(layer "In13.Cu")
	)
	(gr_line
		(start 117.378734 -400.666966)
		(end 116.933726 -400.12493)
		(stroke
			(width 0.07112)
			(type default)
		)
		(layer "In13.Cu")
	)
	(gr_arc
		(start 117.382036 -288.313368)
		(mid 117.385202 -288.315666)
		(end 117.388386 -288.31794)
		(stroke
			(width 0.05715)
			(type default)
		)
		(layer "In13.Cu")
	)
	(gr_arc
		(start 117.38483 -283.455364)
		(mid 117.388755 -283.458175)
		(end 117.392704 -283.460952)
		(stroke
			(width 0.05715)
			(type default)
		)
		(layer "In13.Cu")
	)
	(gr_line
		(start 117.385846 -296.29862)
		(end 117.385846 -296.327068)
		(stroke
			(width 0.05715)
			(type default)
		)
		(layer "In13.Cu")
	)
	(gr_arc
		(start 117.389148 -288.318448)
		(mid 117.390924 -288.319721)
		(end 117.392704 -288.320988)
		(stroke
			(width 0.05715)
			(type default)
		)
		(layer "In13.Cu")
	)
	(gr_line
		(start 117.392704 -288.320988)
		(end 117.3988 -288.324544)
		(stroke
			(width 0.05715)
			(type default)
		)
		(layer "In13.Cu")
	)
	(gr_line
		(start 117.392704 -283.460952)
		(end 117.399562 -283.465016)
		(stroke
			(width 0.05715)
			(type default)
		)
		(layer "In13.Cu")
	)
	(gr_arc
		(start 117.392704 -280.911808)
		(mid 117.388755 -280.914585)
		(end 117.38483 -280.917396)
		(stroke
			(width 0.05715)
			(type default)
		)
		(layer "In13.Cu")
	)
	(gr_line
		(start 117.393212 -280.911554)
		(end 117.392704 -280.911808)
		(stroke
			(width 0.05715)
			(type default)
		)
		(layer "In13.Cu")
	)
	(gr_line
		(start 117.3988 -288.324544)
		(end 117.399054 -288.324544)
		(stroke
			(width 0.05715)
			(type default)
		)
		(layer "In13.Cu")
	)
	(gr_line
		(start 117.399562 -283.465016)
		(end 117.400324 -283.465524)
		(stroke
			(width 0.05715)
			(type default)
		)
		(layer "In13.Cu")
	)
	(gr_line
		(start 117.400324 -283.465524)
		(end 117.401086 -283.466032)
		(stroke
			(width 0.05715)
			(type default)
		)
		(layer "In13.Cu")
	)
	(gr_line
		(start 117.400324 -280.907236)
		(end 117.393212 -280.911554)
		(stroke
			(width 0.05715)
			(type default)
		)
		(layer "In13.Cu")
	)
	(gr_line
		(start 117.405658 -413.984948)
		(end 117.405404 -413.984694)
		(stroke
			(width 0.07112)
			(type default)
		)
		(layer "In13.Cu")
	)
	(gr_line
		(start 117.416834 -273.276314)
		(end 117.347492 -273.345656)
		(stroke
			(width 0.05715)
			(type default)
		)
		(layer "In13.Cu")
	)
	(gr_line
		(start 117.416834 -271.656302)
		(end 117.347492 -271.725644)
		(stroke
			(width 0.05715)
			(type default)
		)
		(layer "In13.Cu")
	)
	(gr_line
		(start 117.416834 -270.03629)
		(end 117.33403 -270.119094)
		(stroke
			(width 0.05715)
			(type default)
		)
		(layer "In13.Cu")
	)
	(gr_line
		(start 117.432582 -291.584126)
		(end 117.433852 -291.584888)
		(stroke
			(width 0.05715)
			(type default)
		)
		(layer "In13.Cu")
	)
	(gr_line
		(start 117.434614 -293.205408)
		(end 117.435122 -293.205408)
		(stroke
			(width 0.05715)
			(type default)
		)
		(layer "In13.Cu")
	)
	(gr_line
		(start 117.434614 -289.965384)
		(end 117.435122 -289.965384)
		(stroke
			(width 0.05715)
			(type default)
		)
		(layer "In13.Cu")
	)
	(gr_line
		(start 117.434614 -285.105602)
		(end 117.435122 -285.105602)
		(stroke
			(width 0.05715)
			(type default)
		)
		(layer "In13.Cu")
	)
	(gr_line
		(start 117.434614 -283.48559)
		(end 117.435122 -283.48559)
		(stroke
			(width 0.05715)
			(type default)
		)
		(layer "In13.Cu")
	)
	(gr_line
		(start 117.434614 -281.865578)
		(end 117.435122 -281.865578)
		(stroke
			(width 0.05715)
			(type default)
		)
		(layer "In13.Cu")
	)
	(gr_line
		(start 117.434868 -288.345372)
		(end 117.435122 -288.345372)
		(stroke
			(width 0.05715)
			(type default)
		)
		(layer "In13.Cu")
	)
	(gr_line
		(start 117.527324 -294.658542)
		(end 117.527832 -294.658796)
		(stroke
			(width 0.05715)
			(type default)
		)
		(layer "In13.Cu")
	)
	(gr_line
		(start 117.527324 -293.03853)
		(end 117.527832 -293.038784)
		(stroke
			(width 0.05715)
			(type default)
		)
		(layer "In13.Cu")
	)
	(gr_line
		(start 117.527324 -291.418518)
		(end 117.527832 -291.418772)
		(stroke
			(width 0.05715)
			(type default)
		)
		(layer "In13.Cu")
	)
	(gr_line
		(start 117.527324 -289.798506)
		(end 117.527832 -289.79876)
		(stroke
			(width 0.05715)
			(type default)
		)
		(layer "In13.Cu")
	)
	(gr_line
		(start 117.527324 -284.938724)
		(end 117.527832 -284.938978)
		(stroke
			(width 0.05715)
			(type default)
		)
		(layer "In13.Cu")
	)
	(gr_line
		(start 117.527324 -281.6987)
		(end 117.527832 -281.698954)
		(stroke
			(width 0.05715)
			(type default)
		)
		(layer "In13.Cu")
	)
	(gr_line
		(start 117.527578 -292.393878)
		(end 117.522244 -292.396926)
		(stroke
			(width 0.05715)
			(type default)
		)
		(layer "In13.Cu")
	)
	(gr_line
		(start 117.527832 -294.658796)
		(end 117.531896 -294.661336)
		(stroke
			(width 0.05715)
			(type default)
		)
		(layer "In13.Cu")
	)
	(gr_line
		(start 117.527832 -293.038784)
		(end 117.53088 -293.040562)
		(stroke
			(width 0.05715)
			(type default)
		)
		(layer "In13.Cu")
	)
	(gr_line
		(start 117.527832 -291.418772)
		(end 117.527832 -291.419026)
		(stroke
			(width 0.05715)
			(type default)
		)
		(layer "In13.Cu")
	)
	(gr_line
		(start 117.527832 -289.79876)
		(end 117.53088 -289.800538)
		(stroke
			(width 0.05715)
			(type default)
		)
		(layer "In13.Cu")
	)
	(gr_line
		(start 117.527832 -284.938978)
		(end 117.53088 -284.940756)
		(stroke
			(width 0.05715)
			(type default)
		)
		(layer "In13.Cu")
	)
	(gr_line
		(start 117.527832 -283.318966)
		(end 117.53088 -283.320744)
		(stroke
			(width 0.05715)
			(type default)
		)
		(layer "In13.Cu")
	)
	(gr_line
		(start 117.527832 -281.698954)
		(end 117.53088 -281.700732)
		(stroke
			(width 0.05715)
			(type default)
		)
		(layer "In13.Cu")
	)
	(gr_line
		(start 117.53088 -294.011858)
		(end 117.527324 -294.01389)
		(stroke
			(width 0.05715)
			(type default)
		)
		(layer "In13.Cu")
	)
	(gr_line
		(start 117.53088 -290.771834)
		(end 117.527324 -290.773866)
		(stroke
			(width 0.05715)
			(type default)
		)
		(layer "In13.Cu")
	)
	(gr_line
		(start 117.53088 -289.151822)
		(end 117.527324 -289.153854)
		(stroke
			(width 0.05715)
			(type default)
		)
		(layer "In13.Cu")
	)
	(gr_line
		(start 117.53088 -285.912052)
		(end 117.527324 -285.914084)
		(stroke
			(width 0.05715)
			(type default)
		)
		(layer "In13.Cu")
	)
	(gr_line
		(start 117.53088 -284.29204)
		(end 117.527324 -284.294072)
		(stroke
			(width 0.05715)
			(type default)
		)
		(layer "In13.Cu")
	)
	(gr_line
		(start 117.53088 -282.672028)
		(end 117.527324 -282.67406)
		(stroke
			(width 0.05715)
			(type default)
		)
		(layer "In13.Cu")
	)
	(gr_line
		(start 117.59692 -400.486626)
		(end 117.615716 -400.29511)
		(stroke
			(width 0.07112)
			(type default)
		)
		(layer "In13.Cu")
	)
	(gr_line
		(start 117.615716 -400.29511)
		(end 117.344952 -399.965164)
		(stroke
			(width 0.07112)
			(type default)
		)
		(layer "In13.Cu")
	)
	(gr_line
		(start 117.619526 -295.146222)
		(end 117.619272 -295.146222)
		(stroke
			(width 0.05715)
			(type default)
		)
		(layer "In13.Cu")
	)
	(gr_line
		(start 117.714776 -273.276314)
		(end 117.416834 -273.276314)
		(stroke
			(width 0.05715)
			(type default)
		)
		(layer "In13.Cu")
	)
	(gr_line
		(start 117.714776 -271.656302)
		(end 117.416834 -271.656302)
		(stroke
			(width 0.05715)
			(type default)
		)
		(layer "In13.Cu")
	)
	(gr_line
		(start 117.714776 -270.03629)
		(end 117.416834 -270.03629)
		(stroke
			(width 0.05715)
			(type default)
		)
		(layer "In13.Cu")
	)
	(gr_line
		(start 117.775482 -397.329406)
		(end 117.775482 -396.628366)
		(stroke
			(width 0.07112)
			(type default)
		)
		(layer "In13.Cu")
	)
	(gr_line
		(start 117.775482 -396.201646)
		(end 117.775482 -395.500606)
		(stroke
			(width 0.07112)
			(type default)
		)
		(layer "In13.Cu")
	)
	(gr_line
		(start 117.775482 -395.073886)
		(end 117.775482 -394.372846)
		(stroke
			(width 0.07112)
			(type default)
		)
		(layer "In13.Cu")
	)
	(gr_arc
		(start 117.85473 -272.925286)
		(mid 117.858655 -272.928097)
		(end 117.862604 -272.930874)
		(stroke
			(width 0.05715)
			(type default)
		)
		(layer "In13.Cu")
	)
	(gr_line
		(start 117.862604 -272.930874)
		(end 117.869462 -272.934938)
		(stroke
			(width 0.05715)
			(type default)
		)
		(layer "In13.Cu")
	)
	(gr_line
		(start 117.869462 -272.934938)
		(end 117.870224 -272.935446)
		(stroke
			(width 0.05715)
			(type default)
		)
		(layer "In13.Cu")
	)
	(gr_line
		(start 117.870224 -272.935446)
		(end 117.870986 -272.935954)
		(stroke
			(width 0.05715)
			(type default)
		)
		(layer "In13.Cu")
	)
	(gr_line
		(start 117.901974 -272.953988)
		(end 117.902482 -272.954242)
		(stroke
			(width 0.05715)
			(type default)
		)
		(layer "In13.Cu")
	)
	(gr_line
		(start 117.902482 -295.634156)
		(end 117.905276 -295.63568)
		(stroke
			(width 0.05715)
			(type default)
		)
		(layer "In13.Cu")
	)
	(gr_line
		(start 117.902482 -272.954242)
		(end 117.90299 -272.954496)
		(stroke
			(width 0.05715)
			(type default)
		)
		(layer "In13.Cu")
	)
	(gr_line
		(start 117.905276 -272.955766)
		(end 117.906038 -272.956274)
		(stroke
			(width 0.05715)
			(type default)
		)
		(layer "In13.Cu")
	)
	(gr_line
		(start 117.906038 -272.956274)
		(end 117.907562 -272.957036)
		(stroke
			(width 0.05715)
			(type default)
		)
		(layer "In13.Cu")
	)
	(gr_line
		(start 117.907562 -272.957036)
		(end 117.908324 -272.957544)
		(stroke
			(width 0.05715)
			(type default)
		)
		(layer "In13.Cu")
	)
	(gr_line
		(start 117.908324 -272.957544)
		(end 117.90934 -272.958052)
		(stroke
			(width 0.05715)
			(type default)
		)
		(layer "In13.Cu")
	)
	(gr_line
		(start 117.997224 -295.468548)
		(end 117.997732 -295.468802)
		(stroke
			(width 0.05715)
			(type default)
		)
		(layer "In13.Cu")
	)
	(gr_line
		(start 117.997732 -295.468802)
		(end 117.998748 -295.46931)
		(stroke
			(width 0.05715)
			(type default)
		)
		(layer "In13.Cu")
	)
	(gr_line
		(start 117.997732 -272.788888)
		(end 117.998748 -272.789396)
		(stroke
			(width 0.05715)
			(type default)
		)
		(layer "In13.Cu")
	)
	(gr_line
		(start 117.998748 -295.46931)
		(end 118.000272 -295.470326)
		(stroke
			(width 0.05715)
			(type default)
		)
		(layer "In13.Cu")
	)
	(gr_line
		(start 117.998748 -272.789396)
		(end 118.000272 -272.790412)
		(stroke
			(width 0.05715)
			(type default)
		)
		(layer "In13.Cu")
	)
	(gr_line
		(start 118.000272 -295.470326)
		(end 118.001288 -295.470834)
		(stroke
			(width 0.05715)
			(type default)
		)
		(layer "In13.Cu")
	)
	(gr_line
		(start 118.000272 -272.790412)
		(end 118.001288 -272.79092)
		(stroke
			(width 0.05715)
			(type default)
		)
		(layer "In13.Cu")
	)
	(gr_line
		(start 118.001288 -295.470834)
		(end 118.006368 -295.473882)
		(stroke
			(width 0.05715)
			(type default)
		)
		(layer "In13.Cu")
	)
	(gr_line
		(start 118.001288 -272.79092)
		(end 118.003828 -272.792444)
		(stroke
			(width 0.05715)
			(type default)
		)
		(layer "In13.Cu")
	)
	(gr_line
		(start 118.003828 -272.792444)
		(end 118.004844 -272.793206)
		(stroke
			(width 0.05715)
			(type default)
		)
		(layer "In13.Cu")
	)
	(gr_line
		(start 118.04396 -296.29862)
		(end 118.04396 -296.327068)
		(stroke
			(width 0.05715)
			(type default)
		)
		(layer "In13.Cu")
	)
	(gr_line
		(start 118.058692 -397.328136)
		(end 118.194582 -397.192246)
		(stroke
			(width 0.07112)
			(type default)
		)
		(layer "In13.Cu")
	)
	(gr_line
		(start 118.058692 -396.200376)
		(end 118.194582 -396.064486)
		(stroke
			(width 0.07112)
			(type default)
		)
		(layer "In13.Cu")
	)
	(gr_line
		(start 118.058692 -395.072616)
		(end 118.194582 -394.936726)
		(stroke
			(width 0.07112)
			(type default)
		)
		(layer "In13.Cu")
	)
	(gr_line
		(start 118.060216 -400.836892)
		(end 117.868954 -400.818096)
		(stroke
			(width 0.07112)
			(type default)
		)
		(layer "In13.Cu")
	)
	(gr_line
		(start 118.08968 -296.2529)
		(end 118.04396 -296.29862)
		(stroke
			(width 0.05715)
			(type default)
		)
		(layer "In13.Cu")
	)
	(gr_line
		(start 118.094252 -401.538948)
		(end 117.649244 -400.996658)
		(stroke
			(width 0.07112)
			(type default)
		)
		(layer "In13.Cu")
	)
	(gr_line
		(start 118.194582 -397.192246)
		(end 118.194582 -396.765526)
		(stroke
			(width 0.07112)
			(type default)
		)
		(layer "In13.Cu")
	)
	(gr_line
		(start 118.194582 -396.765526)
		(end 118.058692 -396.629636)
		(stroke
			(width 0.07112)
			(type default)
		)
		(layer "In13.Cu")
	)
	(gr_line
		(start 118.194582 -396.064486)
		(end 118.194582 -395.637766)
		(stroke
			(width 0.07112)
			(type default)
		)
		(layer "In13.Cu")
	)
	(gr_line
		(start 118.194582 -395.637766)
		(end 118.058692 -395.501876)
		(stroke
			(width 0.07112)
			(type default)
		)
		(layer "In13.Cu")
	)
	(gr_line
		(start 118.194582 -394.936726)
		(end 118.194582 -394.510006)
		(stroke
			(width 0.07112)
			(type default)
		)
		(layer "In13.Cu")
	)
	(gr_line
		(start 118.194582 -394.510006)
		(end 118.058692 -394.374116)
		(stroke
			(width 0.07112)
			(type default)
		)
		(layer "In13.Cu")
	)
	(gr_line
		(start 118.248176 -409.414218)
		(end 118.248176 -408.713178)
		(stroke
			(width 0.07112)
			(type default)
		)
		(layer "In13.Cu")
	)
	(gr_line
		(start 118.248176 -408.197304)
		(end 118.248176 -407.496264)
		(stroke
			(width 0.07112)
			(type default)
		)
		(layer "In13.Cu")
	)
	(gr_line
		(start 118.28018 -296.2529)
		(end 118.3259 -296.29862)
		(stroke
			(width 0.05715)
			(type default)
		)
		(layer "In13.Cu")
	)
	(gr_line
		(start 118.312438 -401.358354)
		(end 118.331234 -401.167092)
		(stroke
			(width 0.07112)
			(type default)
		)
		(layer "In13.Cu")
	)
	(gr_line
		(start 118.3259 -296.29862)
		(end 118.3259 -296.327068)
		(stroke
			(width 0.05715)
			(type default)
		)
		(layer "In13.Cu")
	)
	(gr_line
		(start 118.331234 -401.167092)
		(end 118.060216 -400.836892)
		(stroke
			(width 0.07112)
			(type default)
		)
		(layer "In13.Cu")
	)
	(gr_arc
		(start 118.332758 -280.911808)
		(mid 118.329575 -280.914083)
		(end 118.326408 -280.91638)
		(stroke
			(width 0.05715)
			(type default)
		)
		(layer "In13.Cu")
	)
	(gr_line
		(start 118.333266 -280.911554)
		(end 118.332758 -280.911808)
		(stroke
			(width 0.05715)
			(type default)
		)
		(layer "In13.Cu")
	)
	(gr_line
		(start 118.34114 -280.906982)
		(end 118.333266 -280.911554)
		(stroke
			(width 0.05715)
			(type default)
		)
		(layer "In13.Cu")
	)
	(gr_line
		(start 118.376954 -392.707622)
		(end 118.3894 -392.707622)
		(stroke
			(width 0.07112)
			(type default)
		)
		(layer "In13.Cu")
	)
	(gr_line
		(start 118.378224 -392.990832)
		(end 118.5164 -393.129008)
		(stroke
			(width 0.07112)
			(type default)
		)
		(layer "In13.Cu")
	)
	(gr_line
		(start 118.3894 -392.707622)
		(end 118.5164 -392.580622)
		(stroke
			(width 0.07112)
			(type default)
		)
		(layer "In13.Cu")
	)
	(gr_line
		(start 118.5164 -393.129008)
		(end 118.5164 -393.292838)
		(stroke
			(width 0.07112)
			(type default)
		)
		(layer "In13.Cu")
	)
	(gr_line
		(start 118.5164 -392.580622)
		(end 118.5164 -392.429238)
		(stroke
			(width 0.07112)
			(type default)
		)
		(layer "In13.Cu")
	)
	(gr_line
		(start 118.530116 -410.337508)
		(end 118.530116 -410.337)
		(stroke
			(width 0.07112)
			(type default)
		)
		(layer "In13.Cu")
	)
	(gr_line
		(start 118.531386 -409.412948)
		(end 118.667276 -409.277058)
		(stroke
			(width 0.07112)
			(type default)
		)
		(layer "In13.Cu")
	)
	(gr_line
		(start 118.531386 -408.196034)
		(end 118.667276 -408.060144)
		(stroke
			(width 0.07112)
			(type default)
		)
		(layer "In13.Cu")
	)
	(gr_line
		(start 118.552976 -399.033238)
		(end 118.360698 -399.033238)
		(stroke
			(width 0.07112)
			(type default)
		)
		(layer "In13.Cu")
	)
	(gr_line
		(start 118.655592 -399.72869)
		(end 118.15953 -399.232628)
		(stroke
			(width 0.07112)
			(type default)
		)
		(layer "In13.Cu")
	)
	(gr_line
		(start 118.667276 -409.277058)
		(end 118.667276 -408.850338)
		(stroke
			(width 0.07112)
			(type default)
		)
		(layer "In13.Cu")
	)
	(gr_line
		(start 118.667276 -408.850338)
		(end 118.531386 -408.714448)
		(stroke
			(width 0.07112)
			(type default)
		)
		(layer "In13.Cu")
	)
	(gr_line
		(start 118.667276 -408.060144)
		(end 118.667276 -407.633424)
		(stroke
			(width 0.07112)
			(type default)
		)
		(layer "In13.Cu")
	)
	(gr_line
		(start 118.667276 -407.633424)
		(end 118.531386 -407.497534)
		(stroke
			(width 0.07112)
			(type default)
		)
		(layer "In13.Cu")
	)
	(gr_line
		(start 118.842536 -295.634156)
		(end 118.843044 -295.63441)
		(stroke
			(width 0.05715)
			(type default)
		)
		(layer "In13.Cu")
	)
	(gr_line
		(start 118.84533 -295.63568)
		(end 118.846092 -295.636188)
		(stroke
			(width 0.05715)
			(type default)
		)
		(layer "In13.Cu")
	)
	(gr_line
		(start 118.846092 -295.636188)
		(end 118.847616 -295.63695)
		(stroke
			(width 0.05715)
			(type default)
		)
		(layer "In13.Cu")
	)
	(gr_line
		(start 118.847616 -295.63695)
		(end 118.848378 -295.637458)
		(stroke
			(width 0.05715)
			(type default)
		)
		(layer "In13.Cu")
	)
	(gr_line
		(start 118.848378 -295.637458)
		(end 118.849394 -295.637966)
		(stroke
			(width 0.05715)
			(type default)
		)
		(layer "In13.Cu")
	)
	(gr_line
		(start 118.854982 -399.527522)
		(end 118.854982 -399.335244)
		(stroke
			(width 0.07112)
			(type default)
		)
		(layer "In13.Cu")
	)
	(gr_line
		(start 118.854982 -399.335244)
		(end 118.552976 -399.033238)
		(stroke
			(width 0.07112)
			(type default)
		)
		(layer "In13.Cu")
	)
	(gr_line
		(start 118.937278 -295.468548)
		(end 118.937786 -295.468802)
		(stroke
			(width 0.05715)
			(type default)
		)
		(layer "In13.Cu")
	)
	(gr_line
		(start 118.937786 -295.468802)
		(end 118.938802 -295.46931)
		(stroke
			(width 0.05715)
			(type default)
		)
		(layer "In13.Cu")
	)
	(gr_line
		(start 118.938802 -295.46931)
		(end 118.940326 -295.470326)
		(stroke
			(width 0.05715)
			(type default)
		)
		(layer "In13.Cu")
	)
	(gr_line
		(start 118.940326 -295.470326)
		(end 118.941342 -295.470834)
		(stroke
			(width 0.05715)
			(type default)
		)
		(layer "In13.Cu")
	)
	(gr_line
		(start 118.941342 -295.470834)
		(end 118.943882 -295.472358)
		(stroke
			(width 0.05715)
			(type default)
		)
		(layer "In13.Cu")
	)
	(gr_line
		(start 118.943882 -295.472358)
		(end 118.944898 -295.47312)
		(stroke
			(width 0.05715)
			(type default)
		)
		(layer "In13.Cu")
	)
	(gr_line
		(start 118.975632 -397.298164)
		(end 118.975632 -396.597124)
		(stroke
			(width 0.07112)
			(type default)
		)
		(layer "In13.Cu")
	)
	(gr_line
		(start 118.975632 -396.170404)
		(end 118.975632 -395.469364)
		(stroke
			(width 0.07112)
			(type default)
		)
		(layer "In13.Cu")
	)
	(gr_line
		(start 118.975632 -395.042644)
		(end 118.975632 -394.341604)
		(stroke
			(width 0.07112)
			(type default)
		)
		(layer "In13.Cu")
	)
	(gr_line
		(start 118.984014 -296.97807)
		(end 118.984268 -296.978324)
		(stroke
			(width 0.07112)
			(type default)
		)
		(layer "In13.Cu")
	)
	(gr_line
		(start 118.984014 -296.29862)
		(end 118.984014 -296.327068)
		(stroke
			(width 0.05715)
			(type default)
		)
		(layer "In13.Cu")
	)
	(gr_line
		(start 119.029734 -296.2529)
		(end 118.984014 -296.29862)
		(stroke
			(width 0.05715)
			(type default)
		)
		(layer "In13.Cu")
	)
	(gr_line
		(start 119.034052 -402.023326)
		(end 118.842536 -402.00453)
		(stroke
			(width 0.07112)
			(type default)
		)
		(layer "In13.Cu")
	)
	(gr_line
		(start 119.068088 -402.725636)
		(end 118.62308 -402.183346)
		(stroke
			(width 0.07112)
			(type default)
		)
		(layer "In13.Cu")
	)
	(gr_line
		(start 119.220234 -296.2529)
		(end 119.265954 -296.29862)
		(stroke
			(width 0.05715)
			(type default)
		)
		(layer "In13.Cu")
	)
	(gr_line
		(start 119.258842 -397.296894)
		(end 119.394732 -397.161004)
		(stroke
			(width 0.07112)
			(type default)
		)
		(layer "In13.Cu")
	)
	(gr_line
		(start 119.258842 -396.169134)
		(end 119.394732 -396.033244)
		(stroke
			(width 0.07112)
			(type default)
		)
		(layer "In13.Cu")
	)
	(gr_line
		(start 119.258842 -395.041374)
		(end 119.394732 -394.905484)
		(stroke
			(width 0.07112)
			(type default)
		)
		(layer "In13.Cu")
	)
	(gr_line
		(start 119.265954 -296.907966)
		(end 119.266208 -296.907966)
		(stroke
			(width 0.07112)
			(type default)
		)
		(layer "In13.Cu")
	)
	(gr_line
		(start 119.265954 -296.29862)
		(end 119.265954 -296.327068)
		(stroke
			(width 0.05715)
			(type default)
		)
		(layer "In13.Cu")
	)
	(gr_line
		(start 119.286274 -402.545042)
		(end 119.30507 -402.353526)
		(stroke
			(width 0.07112)
			(type default)
		)
		(layer "In13.Cu")
	)
	(gr_arc
		(start 119.300244 -293.197026)
		(mid 119.3024 -293.198301)
		(end 119.304562 -293.199566)
		(stroke
			(width 0.05715)
			(type default)
		)
		(layer "In13.Cu")
	)
	(gr_line
		(start 119.30507 -402.353526)
		(end 119.034052 -402.023326)
		(stroke
			(width 0.07112)
			(type default)
		)
		(layer "In13.Cu")
	)
	(gr_line
		(start 119.307864 -286.72155)
		(end 119.307102 -286.721296)
		(stroke
			(width 0.05715)
			(type default)
		)
		(layer "In13.Cu")
	)
	(gr_arc
		(start 119.30888 -288.990278)
		(mid 119.307482 -288.991038)
		(end 119.306086 -288.991802)
		(stroke
			(width 0.05715)
			(type default)
		)
		(layer "In13.Cu")
	)
	(gr_arc
		(start 119.30888 -284.12821)
		(mid 119.306845 -284.129475)
		(end 119.304816 -284.13075)
		(stroke
			(width 0.05715)
			(type default)
		)
		(layer "In13.Cu")
	)
	(gr_arc
		(start 119.30888 -282.508198)
		(mid 119.306845 -282.509463)
		(end 119.304816 -282.510738)
		(stroke
			(width 0.05715)
			(type default)
		)
		(layer "In13.Cu")
	)
	(gr_line
		(start 119.309134 -285.750254)
		(end 119.309388 -285.750254)
		(stroke
			(width 0.05715)
			(type default)
		)
		(layer "In13.Cu")
	)
	(gr_line
		(start 119.309388 -286.722566)
		(end 119.311166 -286.723582)
		(stroke
			(width 0.05715)
			(type default)
		)
		(layer "In13.Cu")
	)
	(gr_arc
		(start 119.309388 -285.750254)
		(mid 119.308499 -285.750761)
		(end 119.30761 -285.75127)
		(stroke
			(width 0.05715)
			(type default)
		)
		(layer "In13.Cu")
	)
	(gr_line
		(start 119.309896 -285.749746)
		(end 119.309134 -285.750254)
		(stroke
			(width 0.05715)
			(type default)
		)
		(layer "In13.Cu")
	)
	(gr_line
		(start 119.31142 -293.20363)
		(end 119.311674 -293.20363)
		(stroke
			(width 0.05715)
			(type default)
		)
		(layer "In13.Cu")
	)
	(gr_line
		(start 119.311674 -291.583618)
		(end 119.312436 -291.584126)
		(stroke
			(width 0.05715)
			(type default)
		)
		(layer "In13.Cu")
	)
	(gr_line
		(start 119.311674 -280.243788)
		(end 119.312182 -280.244042)
		(stroke
			(width 0.05715)
			(type default)
		)
		(layer "In13.Cu")
	)
	(gr_line
		(start 119.312436 -291.584126)
		(end 119.313706 -291.584888)
		(stroke
			(width 0.05715)
			(type default)
		)
		(layer "In13.Cu")
	)
	(gr_line
		(start 119.312436 -280.88844)
		(end 119.310912 -280.889456)
		(stroke
			(width 0.05715)
			(type default)
		)
		(layer "In13.Cu")
	)
	(gr_line
		(start 119.313706 -280.887678)
		(end 119.312436 -280.88844)
		(stroke
			(width 0.05715)
			(type default)
		)
		(layer "In13.Cu")
	)
	(gr_line
		(start 119.315484 -287.36417)
		(end 119.310658 -287.366964)
		(stroke
			(width 0.05715)
			(type default)
		)
		(layer "In13.Cu")
	)
	(gr_line
		(start 119.319294 -322.427092)
		(end 119.31904 -322.427092)
		(stroke
			(width 0.07112)
			(type default)
		)
		(layer "In13.Cu")
	)
	(gr_line
		(start 119.319548 -293.208202)
		(end 119.32031 -293.208456)
		(stroke
			(width 0.05715)
			(type default)
		)
		(layer "In13.Cu")
	)
	(gr_line
		(start 119.350536 -399.830798)
		(end 119.158258 -399.830798)
		(stroke
			(width 0.07112)
			(type default)
		)
		(layer "In13.Cu")
	)
	(gr_line
		(start 119.394732 -397.161004)
		(end 119.394732 -396.734284)
		(stroke
			(width 0.07112)
			(type default)
		)
		(layer "In13.Cu")
	)
	(gr_line
		(start 119.394732 -396.734284)
		(end 119.258842 -396.598394)
		(stroke
			(width 0.07112)
			(type default)
		)
		(layer "In13.Cu")
	)
	(gr_line
		(start 119.394732 -396.033244)
		(end 119.394732 -395.606524)
		(stroke
			(width 0.07112)
			(type default)
		)
		(layer "In13.Cu")
	)
	(gr_line
		(start 119.394732 -395.606524)
		(end 119.258842 -395.470634)
		(stroke
			(width 0.07112)
			(type default)
		)
		(layer "In13.Cu")
	)
	(gr_line
		(start 119.394732 -394.905484)
		(end 119.394732 -394.478764)
		(stroke
			(width 0.07112)
			(type default)
		)
		(layer "In13.Cu")
	)
	(gr_line
		(start 119.394732 -394.478764)
		(end 119.258842 -394.342874)
		(stroke
			(width 0.07112)
			(type default)
		)
		(layer "In13.Cu")
	)
	(gr_line
		(start 119.404638 -289.796982)
		(end 119.407686 -289.79876)
		(stroke
			(width 0.05715)
			(type default)
		)
		(layer "In13.Cu")
	)
	(gr_line
		(start 119.405146 -286.55772)
		(end 119.405908 -286.558228)
		(stroke
			(width 0.05715)
			(type default)
		)
		(layer "In13.Cu")
	)
	(gr_line
		(start 119.405908 -286.558228)
		(end 119.407178 -286.55899)
		(stroke
			(width 0.05715)
			(type default)
		)
		(layer "In13.Cu")
	)
	(gr_line
		(start 119.407178 -293.03853)
		(end 119.414798 -293.042848)
		(stroke
			(width 0.05715)
			(type default)
		)
		(layer "In13.Cu")
	)
	(gr_line
		(start 119.407178 -291.418772)
		(end 119.407686 -291.418772)
		(stroke
			(width 0.05715)
			(type default)
		)
		(layer "In13.Cu")
	)
	(gr_line
		(start 119.407178 -286.55899)
		(end 119.407686 -286.559244)
		(stroke
			(width 0.05715)
			(type default)
		)
		(layer "In13.Cu")
	)
	(gr_arc
		(start 119.407178 -284.291786)
		(mid 119.406543 -284.292167)
		(end 119.405908 -284.292548)
		(stroke
			(width 0.05715)
			(type default)
		)
		(layer "In13.Cu")
	)
	(gr_line
		(start 119.407686 -291.418772)
		(end 119.408702 -291.41928)
		(stroke
			(width 0.05715)
			(type default)
		)
		(layer "In13.Cu")
	)
	(gr_line
		(start 119.407686 -289.79876)
		(end 119.408702 -289.799268)
		(stroke
			(width 0.05715)
			(type default)
		)
		(layer "In13.Cu")
	)
	(gr_line
		(start 119.407686 -281.053794)
		(end 119.406416 -281.054302)
		(stroke
			(width 0.05715)
			(type default)
		)
		(layer "In13.Cu")
	)
	(gr_line
		(start 119.408702 -281.053286)
		(end 119.407686 -281.053794)
		(stroke
			(width 0.05715)
			(type default)
		)
		(layer "In13.Cu")
	)
	(gr_line
		(start 119.41048 -289.151822)
		(end 119.404892 -289.155124)
		(stroke
			(width 0.05715)
			(type default)
		)
		(layer "In13.Cu")
	)
	(gr_line
		(start 119.414798 -293.042848)
		(end 119.416322 -293.043864)
		(stroke
			(width 0.05715)
			(type default)
		)
		(layer "In13.Cu")
	)
	(gr_line
		(start 119.42572 -322.614798)
		(end 119.319294 -322.427092)
		(stroke
			(width 0.07112)
			(type default)
		)
		(layer "In13.Cu")
	)
	(gr_line
		(start 119.438674 -294.67683)
		(end 119.44604 -294.681148)
		(stroke
			(width 0.05715)
			(type default)
		)
		(layer "In13.Cu")
	)
	(gr_line
		(start 119.439436 -293.057326)
		(end 119.44604 -293.061136)
		(stroke
			(width 0.05715)
			(type default)
		)
		(layer "In13.Cu")
	)
	(gr_arc
		(start 119.44604 -294.681148)
		(mid 119.446421 -294.681402)
		(end 119.446802 -294.681656)
		(stroke
			(width 0.05715)
			(type default)
		)
		(layer "In13.Cu")
	)
	(gr_arc
		(start 119.44604 -293.061136)
		(mid 119.446421 -293.06139)
		(end 119.446802 -293.061644)
		(stroke
			(width 0.05715)
			(type default)
		)
		(layer "In13.Cu")
	)
	(gr_line
		(start 119.453152 -400.52625)
		(end 118.95709 -400.030188)
		(stroke
			(width 0.07112)
			(type default)
		)
		(layer "In13.Cu")
	)
	(gr_arc
		(start 119.454676 -294.687244)
		(mid 119.450751 -294.684433)
		(end 119.446802 -294.681656)
		(stroke
			(width 0.05715)
			(type default)
		)
		(layer "In13.Cu")
	)
	(gr_arc
		(start 119.454676 -293.067232)
		(mid 119.450751 -293.064421)
		(end 119.446802 -293.061644)
		(stroke
			(width 0.05715)
			(type default)
		)
		(layer "In13.Cu")
	)
	(gr_line
		(start 119.49938 -295.146222)
		(end 119.499634 -295.146222)
		(stroke
			(width 0.05715)
			(type default)
		)
		(layer "In13.Cu")
	)
	(gr_line
		(start 119.577104 -392.707622)
		(end 119.58955 -392.707622)
		(stroke
			(width 0.07112)
			(type default)
		)
		(layer "In13.Cu")
	)
	(gr_line
		(start 119.578374 -392.990832)
		(end 119.71655 -393.129008)
		(stroke
			(width 0.07112)
			(type default)
		)
		(layer "In13.Cu")
	)
	(gr_line
		(start 119.58955 -392.707622)
		(end 119.71655 -392.580622)
		(stroke
			(width 0.07112)
			(type default)
		)
		(layer "In13.Cu")
	)
	(gr_line
		(start 119.59463 -273.276314)
		(end 119.892572 -273.276314)
		(stroke
			(width 0.05715)
			(type default)
		)
		(layer "In13.Cu")
	)
	(gr_line
		(start 119.59463 -271.656302)
		(end 119.892572 -271.656302)
		(stroke
			(width 0.05715)
			(type default)
		)
		(layer "In13.Cu")
	)
	(gr_line
		(start 119.59463 -270.03629)
		(end 119.892572 -270.03629)
		(stroke
			(width 0.05715)
			(type default)
		)
		(layer "In13.Cu")
	)
	(gr_line
		(start 119.652542 -400.325082)
		(end 119.652542 -400.132804)
		(stroke
			(width 0.07112)
			(type default)
		)
		(layer "In13.Cu")
	)
	(gr_line
		(start 119.652542 -400.132804)
		(end 119.350536 -399.830798)
		(stroke
			(width 0.07112)
			(type default)
		)
		(layer "In13.Cu")
	)
	(gr_line
		(start 119.67083 -322.475606)
		(end 119.564658 -322.288154)
		(stroke
			(width 0.07112)
			(type default)
		)
		(layer "In13.Cu")
	)
	(gr_line
		(start 119.71655 -393.129008)
		(end 119.71655 -393.292838)
		(stroke
			(width 0.07112)
			(type default)
		)
		(layer "In13.Cu")
	)
	(gr_line
		(start 119.71655 -392.580622)
		(end 119.71655 -392.429238)
		(stroke
			(width 0.07112)
			(type default)
		)
		(layer "In13.Cu")
	)
	(gr_arc
		(start 119.734838 -295.6052)
		(mid 119.738384 -295.607754)
		(end 119.74195 -295.61028)
		(stroke
			(width 0.05715)
			(type default)
		)
		(layer "In13.Cu")
	)
	(gr_line
		(start 119.74195 -295.61028)
		(end 119.745252 -295.612566)
		(stroke
			(width 0.05715)
			(type default)
		)
		(layer "In13.Cu")
	)
	(gr_line
		(start 119.745252 -295.612566)
		(end 119.750332 -295.615614)
		(stroke
			(width 0.05715)
			(type default)
		)
		(layer "In13.Cu")
	)
	(gr_line
		(start 119.753126 -398.7038)
		(end 119.560848 -398.7038)
		(stroke
			(width 0.07112)
			(type default)
		)
		(layer "In13.Cu")
	)
	(gr_line
		(start 119.855742 -399.399252)
		(end 119.35968 -398.90319)
		(stroke
			(width 0.07112)
			(type default)
		)
		(layer "In13.Cu")
	)
	(gr_line
		(start 119.892572 -273.276314)
		(end 119.975376 -273.359118)
		(stroke
			(width 0.05715)
			(type default)
		)
		(layer "In13.Cu")
	)
	(gr_line
		(start 119.892572 -271.656302)
		(end 119.975376 -271.739106)
		(stroke
			(width 0.05715)
			(type default)
		)
		(layer "In13.Cu")
	)
	(gr_line
		(start 119.892572 -270.03629)
		(end 119.961914 -270.105632)
		(stroke
			(width 0.05715)
			(type default)
		)
		(layer "In13.Cu")
	)
	(gr_line
		(start 119.923814 -296.29862)
		(end 119.923814 -296.327068)
		(stroke
			(width 0.05715)
			(type default)
		)
		(layer "In13.Cu")
	)
	(gr_line
		(start 119.969534 -296.2529)
		(end 119.923814 -296.29862)
		(stroke
			(width 0.05715)
			(type default)
		)
		(layer "In13.Cu")
	)
	(gr_arc
		(start 119.975376 -273.359118)
		(mid 119.977169 -273.37044)
		(end 119.979186 -273.381724)
		(stroke
			(width 0.05715)
			(type default)
		)
		(layer "In13.Cu")
	)
	(gr_arc
		(start 119.975376 -271.739106)
		(mid 119.977169 -271.750428)
		(end 119.979186 -271.761712)
		(stroke
			(width 0.05715)
			(type default)
		)
		(layer "In13.Cu")
	)
	(gr_line
		(start 120.055132 -399.198084)
		(end 120.055132 -399.005806)
		(stroke
			(width 0.07112)
			(type default)
		)
		(layer "In13.Cu")
	)
	(gr_line
		(start 120.055132 -399.005806)
		(end 119.753126 -398.7038)
		(stroke
			(width 0.07112)
			(type default)
		)
		(layer "In13.Cu")
	)
	(gr_line
		(start 120.148096 -400.628358)
		(end 119.955818 -400.628358)
		(stroke
			(width 0.07112)
			(type default)
		)
		(layer "In13.Cu")
	)
	(gr_arc
		(start 120.150128 -270.141954)
		(mid 120.15215 -270.130544)
		(end 120.153938 -270.119094)
		(stroke
			(width 0.05715)
			(type default)
		)
		(layer "In13.Cu")
	)
	(gr_line
		(start 120.160034 -296.2529)
		(end 120.205754 -296.29862)
		(stroke
			(width 0.05715)
			(type default)
		)
		(layer "In13.Cu")
	)
	(gr_line
		(start 120.175528 -396.689072)
		(end 120.175528 -395.988032)
		(stroke
			(width 0.07112)
			(type default)
		)
		(layer "In13.Cu")
	)
	(gr_line
		(start 120.175528 -395.487398)
		(end 120.175528 -394.786358)
		(stroke
			(width 0.07112)
			(type default)
		)
		(layer "In13.Cu")
	)
	(gr_arc
		(start 120.201944 -288.313368)
		(mid 120.20511 -288.315666)
		(end 120.208294 -288.31794)
		(stroke
			(width 0.05715)
			(type default)
		)
		(layer "In13.Cu")
	)
	(gr_arc
		(start 120.204484 -273.735292)
		(mid 120.208536 -273.738104)
		(end 120.212612 -273.74088)
		(stroke
			(width 0.05715)
			(type default)
		)
		(layer "In13.Cu")
	)
	(gr_arc
		(start 120.204484 -272.11528)
		(mid 120.208536 -272.118092)
		(end 120.212612 -272.120868)
		(stroke
			(width 0.05715)
			(type default)
		)
		(layer "In13.Cu")
	)
	(gr_arc
		(start 120.204738 -283.455364)
		(mid 120.208663 -283.458175)
		(end 120.212612 -283.460952)
		(stroke
			(width 0.05715)
			(type default)
		)
		(layer "In13.Cu")
	)
	(gr_arc
		(start 120.204738 -276.975316)
		(mid 120.208663 -276.978127)
		(end 120.212612 -276.980904)
		(stroke
			(width 0.05715)
			(type default)
		)
		(layer "In13.Cu")
	)
	(gr_arc
		(start 120.204738 -275.355304)
		(mid 120.208663 -275.358115)
		(end 120.212612 -275.360892)
		(stroke
			(width 0.05715)
			(type default)
		)
		(layer "In13.Cu")
	)
	(gr_line
		(start 120.205754 -296.29862)
		(end 120.205754 -296.327068)
		(stroke
			(width 0.05715)
			(type default)
		)
		(layer "In13.Cu")
	)
	(gr_arc
		(start 120.209056 -288.318448)
		(mid 120.210832 -288.319721)
		(end 120.212612 -288.320988)
		(stroke
			(width 0.05715)
			(type default)
		)
		(layer "In13.Cu")
	)
	(gr_line
		(start 120.212612 -288.320988)
		(end 120.218708 -288.324544)
		(stroke
			(width 0.05715)
			(type default)
		)
		(layer "In13.Cu")
	)
	(gr_line
		(start 120.212612 -283.460952)
		(end 120.21947 -283.465016)
		(stroke
			(width 0.05715)
			(type default)
		)
		(layer "In13.Cu")
	)
	(gr_arc
		(start 120.212612 -280.911808)
		(mid 120.208663 -280.914585)
		(end 120.204738 -280.917396)
		(stroke
			(width 0.05715)
			(type default)
		)
		(layer "In13.Cu")
	)
	(gr_line
		(start 120.212612 -276.980904)
		(end 120.21947 -276.984968)
		(stroke
			(width 0.05715)
			(type default)
		)
		(layer "In13.Cu")
	)
	(gr_line
		(start 120.212612 -275.360892)
		(end 120.21947 -275.364956)
		(stroke
			(width 0.05715)
			(type default)
		)
		(layer "In13.Cu")
	)
	(gr_line
		(start 120.212612 -273.74088)
		(end 120.21947 -273.744944)
		(stroke
			(width 0.05715)
			(type default)
		)
		(layer "In13.Cu")
	)
	(gr_line
		(start 120.212612 -272.120868)
		(end 120.21947 -272.124932)
		(stroke
			(width 0.05715)
			(type default)
		)
		(layer "In13.Cu")
	)
	(gr_line
		(start 120.215406 -280.909776)
		(end 120.212612 -280.911808)
		(stroke
			(width 0.05715)
			(type default)
		)
		(layer "In13.Cu")
	)
	(gr_line
		(start 120.218708 -288.324544)
		(end 120.218962 -288.324544)
		(stroke
			(width 0.05715)
			(type default)
		)
		(layer "In13.Cu")
	)
	(gr_line
		(start 120.21947 -283.465016)
		(end 120.220232 -283.465524)
		(stroke
			(width 0.05715)
			(type default)
		)
		(layer "In13.Cu")
	)
	(gr_line
		(start 120.21947 -276.984968)
		(end 120.220232 -276.985476)
		(stroke
			(width 0.05715)
			(type default)
		)
		(layer "In13.Cu")
	)
	(gr_line
		(start 120.21947 -275.364956)
		(end 120.220232 -275.365464)
		(stroke
			(width 0.05715)
			(type default)
		)
		(layer "In13.Cu")
	)
	(gr_line
		(start 120.21947 -273.744944)
		(end 120.220232 -273.745452)
		(stroke
			(width 0.05715)
			(type default)
		)
		(layer "In13.Cu")
	)
	(gr_line
		(start 120.21947 -272.124932)
		(end 120.220232 -272.12544)
		(stroke
			(width 0.05715)
			(type default)
		)
		(layer "In13.Cu")
	)
	(gr_line
		(start 120.220232 -283.465524)
		(end 120.220994 -283.466032)
		(stroke
			(width 0.05715)
			(type default)
		)
		(layer "In13.Cu")
	)
	(gr_line
		(start 120.220232 -276.985476)
		(end 120.220994 -276.985984)
		(stroke
			(width 0.05715)
			(type default)
		)
		(layer "In13.Cu")
	)
	(gr_line
		(start 120.220232 -275.365464)
		(end 120.220994 -275.365972)
		(stroke
			(width 0.05715)
			(type default)
		)
		(layer "In13.Cu")
	)
	(gr_line
		(start 120.220232 -273.745452)
		(end 120.220994 -273.74596)
		(stroke
			(width 0.05715)
			(type default)
		)
		(layer "In13.Cu")
	)
	(gr_line
		(start 120.220232 -272.12544)
		(end 120.220994 -272.125948)
		(stroke
			(width 0.05715)
			(type default)
		)
		(layer "In13.Cu")
	)
	(gr_line
		(start 120.22074 -280.906728)
		(end 120.215406 -280.909776)
		(stroke
			(width 0.05715)
			(type default)
		)
		(layer "In13.Cu")
	)
	(gr_line
		(start 120.236742 -273.276314)
		(end 120.1674 -273.345656)
		(stroke
			(width 0.05715)
			(type default)
		)
		(layer "In13.Cu")
	)
	(gr_line
		(start 120.236742 -271.656302)
		(end 120.1674 -271.725644)
		(stroke
			(width 0.05715)
			(type default)
		)
		(layer "In13.Cu")
	)
	(gr_line
		(start 120.236742 -270.03629)
		(end 120.153938 -270.119094)
		(stroke
			(width 0.05715)
			(type default)
		)
		(layer "In13.Cu")
	)
	(gr_line
		(start 120.24995 -280.242772)
		(end 120.250712 -280.24328)
		(stroke
			(width 0.05715)
			(type default)
		)
		(layer "In13.Cu")
	)
	(gr_line
		(start 120.250712 -401.32381)
		(end 119.75465 -400.827748)
		(stroke
			(width 0.07112)
			(type default)
		)
		(layer "In13.Cu")
	)
	(gr_line
		(start 120.250712 -280.24328)
		(end 120.251728 -280.243788)
		(stroke
			(width 0.05715)
			(type default)
		)
		(layer "In13.Cu")
	)
	(gr_line
		(start 120.251728 -280.243788)
		(end 120.252236 -280.244042)
		(stroke
			(width 0.05715)
			(type default)
		)
		(layer "In13.Cu")
	)
	(gr_line
		(start 120.251728 -279.268936)
		(end 120.250712 -279.269444)
		(stroke
			(width 0.05715)
			(type default)
		)
		(layer "In13.Cu")
	)
	(gr_line
		(start 120.251728 -277.648924)
		(end 120.250712 -277.649432)
		(stroke
			(width 0.05715)
			(type default)
		)
		(layer "In13.Cu")
	)
	(gr_line
		(start 120.251728 -276.028912)
		(end 120.250712 -276.02942)
		(stroke
			(width 0.05715)
			(type default)
		)
		(layer "In13.Cu")
	)
	(gr_line
		(start 120.251728 -274.4089)
		(end 120.250712 -274.409408)
		(stroke
			(width 0.05715)
			(type default)
		)
		(layer "In13.Cu")
	)
	(gr_line
		(start 120.251982 -277.004018)
		(end 120.25249 -277.004272)
		(stroke
			(width 0.05715)
			(type default)
		)
		(layer "In13.Cu")
	)
	(gr_line
		(start 120.251982 -275.384006)
		(end 120.25249 -275.38426)
		(stroke
			(width 0.05715)
			(type default)
		)
		(layer "In13.Cu")
	)
	(gr_line
		(start 120.251982 -273.763994)
		(end 120.25249 -273.764248)
		(stroke
			(width 0.05715)
			(type default)
		)
		(layer "In13.Cu")
	)
	(gr_line
		(start 120.251982 -272.143982)
		(end 120.25249 -272.144236)
		(stroke
			(width 0.05715)
			(type default)
		)
		(layer "In13.Cu")
	)
	(gr_line
		(start 120.252236 -279.268682)
		(end 120.251728 -279.268936)
		(stroke
			(width 0.05715)
			(type default)
		)
		(layer "In13.Cu")
	)
	(gr_line
		(start 120.252236 -277.64867)
		(end 120.251728 -277.648924)
		(stroke
			(width 0.05715)
			(type default)
		)
		(layer "In13.Cu")
	)
	(gr_line
		(start 120.252236 -276.028658)
		(end 120.251728 -276.028912)
		(stroke
			(width 0.05715)
			(type default)
		)
		(layer "In13.Cu")
	)
	(gr_line
		(start 120.252236 -274.408646)
		(end 120.251728 -274.4089)
		(stroke
			(width 0.05715)
			(type default)
		)
		(layer "In13.Cu")
	)
	(gr_line
		(start 120.25249 -291.584126)
		(end 120.25376 -291.584888)
		(stroke
			(width 0.05715)
			(type default)
		)
		(layer "In13.Cu")
	)
	(gr_line
		(start 120.25249 -278.624284)
		(end 120.25376 -278.625046)
		(stroke
			(width 0.05715)
			(type default)
		)
		(layer "In13.Cu")
	)
	(gr_line
		(start 120.25249 -277.004272)
		(end 120.25376 -277.005034)
		(stroke
			(width 0.05715)
			(type default)
		)
		(layer "In13.Cu")
	)
	(gr_line
		(start 120.25249 -275.38426)
		(end 120.25376 -275.385022)
		(stroke
			(width 0.05715)
			(type default)
		)
		(layer "In13.Cu")
	)
	(gr_line
		(start 120.25249 -273.764248)
		(end 120.25376 -273.76501)
		(stroke
			(width 0.05715)
			(type default)
		)
		(layer "In13.Cu")
	)
	(gr_line
		(start 120.25249 -272.144236)
		(end 120.252998 -272.14449)
		(stroke
			(width 0.05715)
			(type default)
		)
		(layer "In13.Cu")
	)
	(gr_line
		(start 120.254522 -293.205408)
		(end 120.25503 -293.205408)
		(stroke
			(width 0.05715)
			(type default)
		)
		(layer "In13.Cu")
	)
	(gr_line
		(start 120.254522 -289.965384)
		(end 120.25503 -289.965384)
		(stroke
			(width 0.05715)
			(type default)
		)
		(layer "In13.Cu")
	)
	(gr_line
		(start 120.254522 -285.105602)
		(end 120.25503 -285.105602)
		(stroke
			(width 0.05715)
			(type default)
		)
		(layer "In13.Cu")
	)
	(gr_line
		(start 120.254522 -283.48559)
		(end 120.25503 -283.48559)
		(stroke
			(width 0.05715)
			(type default)
		)
		(layer "In13.Cu")
	)
	(gr_line
		(start 120.254522 -281.865578)
		(end 120.25503 -281.865578)
		(stroke
			(width 0.05715)
			(type default)
		)
		(layer "In13.Cu")
	)
	(gr_line
		(start 120.254776 -288.345372)
		(end 120.25503 -288.345372)
		(stroke
			(width 0.05715)
			(type default)
		)
		(layer "In13.Cu")
	)
	(gr_line
		(start 120.255284 -272.14576)
		(end 120.256046 -272.146268)
		(stroke
			(width 0.05715)
			(type default)
		)
		(layer "In13.Cu")
	)
	(gr_line
		(start 120.256046 -272.146268)
		(end 120.25757 -272.14703)
		(stroke
			(width 0.05715)
			(type default)
		)
		(layer "In13.Cu")
	)
	(gr_line
		(start 120.25757 -272.14703)
		(end 120.258332 -272.147538)
		(stroke
			(width 0.05715)
			(type default)
		)
		(layer "In13.Cu")
	)
	(gr_line
		(start 120.258332 -272.147538)
		(end 120.259348 -272.148046)
		(stroke
			(width 0.05715)
			(type default)
		)
		(layer "In13.Cu")
	)
	(gr_line
		(start 120.346216 -280.077926)
		(end 120.346978 -280.078434)
		(stroke
			(width 0.05715)
			(type default)
		)
		(layer "In13.Cu")
	)
	(gr_line
		(start 120.346978 -279.43429)
		(end 120.345708 -279.435052)
		(stroke
			(width 0.05715)
			(type default)
		)
		(layer "In13.Cu")
	)
	(gr_line
		(start 120.346978 -277.814278)
		(end 120.345708 -277.81504)
		(stroke
			(width 0.05715)
			(type default)
		)
		(layer "In13.Cu")
	)
	(gr_line
		(start 120.346978 -276.194266)
		(end 120.345708 -276.195028)
		(stroke
			(width 0.05715)
			(type default)
		)
		(layer "In13.Cu")
	)
	(gr_line
		(start 120.346978 -274.574254)
		(end 120.345708 -274.575016)
		(stroke
			(width 0.05715)
			(type default)
		)
		(layer "In13.Cu")
	)
	(gr_line
		(start 120.347232 -294.658542)
		(end 120.34774 -294.658796)
		(stroke
			(width 0.05715)
			(type default)
		)
		(layer "In13.Cu")
	)
	(gr_line
		(start 120.347232 -293.03853)
		(end 120.34774 -293.038784)
		(stroke
			(width 0.05715)
			(type default)
		)
		(layer "In13.Cu")
	)
	(gr_line
		(start 120.347232 -291.418518)
		(end 120.34774 -291.418772)
		(stroke
			(width 0.05715)
			(type default)
		)
		(layer "In13.Cu")
	)
	(gr_line
		(start 120.347232 -289.798506)
		(end 120.34774 -289.79876)
		(stroke
			(width 0.05715)
			(type default)
		)
		(layer "In13.Cu")
	)
	(gr_line
		(start 120.347232 -284.938724)
		(end 120.34774 -284.938978)
		(stroke
			(width 0.05715)
			(type default)
		)
		(layer "In13.Cu")
	)
	(gr_line
		(start 120.347232 -281.6987)
		(end 120.34774 -281.698954)
		(stroke
			(width 0.05715)
			(type default)
		)
		(layer "In13.Cu")
	)
	(gr_line
		(start 120.347232 -278.458676)
		(end 120.34774 -278.45893)
		(stroke
			(width 0.05715)
			(type default)
		)
		(layer "In13.Cu")
	)
	(gr_line
		(start 120.347486 -292.393878)
		(end 120.342152 -292.396926)
		(stroke
			(width 0.05715)
			(type default)
		)
		(layer "In13.Cu")
	)
	(gr_line
		(start 120.347486 -279.434036)
		(end 120.346978 -279.43429)
		(stroke
			(width 0.05715)
			(type default)
		)
		(layer "In13.Cu")
	)
	(gr_line
		(start 120.347486 -277.814024)
		(end 120.346978 -277.814278)
		(stroke
			(width 0.05715)
			(type default)
		)
		(layer "In13.Cu")
	)
	(gr_line
		(start 120.347486 -276.194012)
		(end 120.346978 -276.194266)
		(stroke
			(width 0.05715)
			(type default)
		)
		(layer "In13.Cu")
	)
	(gr_line
		(start 120.347486 -274.574)
		(end 120.346978 -274.574254)
		(stroke
			(width 0.05715)
			(type default)
		)
		(layer "In13.Cu")
	)
	(gr_line
		(start 120.34774 -294.658796)
		(end 120.351804 -294.661336)
		(stroke
			(width 0.05715)
			(type default)
		)
		(layer "In13.Cu")
	)
	(gr_line
		(start 120.34774 -293.038784)
		(end 120.350788 -293.040562)
		(stroke
			(width 0.05715)
			(type default)
		)
		(layer "In13.Cu")
	)
	(gr_line
		(start 120.34774 -291.418772)
		(end 120.34774 -291.419026)
		(stroke
			(width 0.05715)
			(type default)
		)
		(layer "In13.Cu")
	)
	(gr_line
		(start 120.34774 -289.79876)
		(end 120.350788 -289.800538)
		(stroke
			(width 0.05715)
			(type default)
		)
		(layer "In13.Cu")
	)
	(gr_line
		(start 120.34774 -284.938978)
		(end 120.350788 -284.940756)
		(stroke
			(width 0.05715)
			(type default)
		)
		(layer "In13.Cu")
	)
	(gr_line
		(start 120.34774 -283.318966)
		(end 120.350788 -283.320744)
		(stroke
			(width 0.05715)
			(type default)
		)
		(layer "In13.Cu")
	)
	(gr_line
		(start 120.34774 -281.698954)
		(end 120.350788 -281.700732)
		(stroke
			(width 0.05715)
			(type default)
		)
		(layer "In13.Cu")
	)
	(gr_line
		(start 120.34774 -278.45893)
		(end 120.348756 -278.459438)
		(stroke
			(width 0.05715)
			(type default)
		)
		(layer "In13.Cu")
	)
	(gr_line
		(start 120.34774 -276.838918)
		(end 120.348756 -276.839426)
		(stroke
			(width 0.05715)
			(type default)
		)
		(layer "In13.Cu")
	)
	(gr_line
		(start 120.34774 -275.218906)
		(end 120.348756 -275.219414)
		(stroke
			(width 0.05715)
			(type default)
		)
		(layer "In13.Cu")
	)
	(gr_line
		(start 120.34774 -273.598894)
		(end 120.348756 -273.599402)
		(stroke
			(width 0.05715)
			(type default)
		)
		(layer "In13.Cu")
	)
	(gr_line
		(start 120.34774 -271.978882)
		(end 120.348756 -271.97939)
		(stroke
			(width 0.05715)
			(type default)
		)
		(layer "In13.Cu")
	)
	(gr_line
		(start 120.348756 -271.97939)
		(end 120.35028 -271.980406)
		(stroke
			(width 0.05715)
			(type default)
		)
		(layer "In13.Cu")
	)
	(gr_line
		(start 120.35028 -271.980406)
		(end 120.351296 -271.980914)
		(stroke
			(width 0.05715)
			(type default)
		)
		(layer "In13.Cu")
	)
	(gr_line
		(start 120.350788 -294.011858)
		(end 120.347232 -294.01389)
		(stroke
			(width 0.05715)
			(type default)
		)
		(layer "In13.Cu")
	)
	(gr_line
		(start 120.350788 -290.771834)
		(end 120.347232 -290.773866)
		(stroke
			(width 0.05715)
			(type default)
		)
		(layer "In13.Cu")
	)
	(gr_line
		(start 120.350788 -289.151822)
		(end 120.347232 -289.153854)
		(stroke
			(width 0.05715)
			(type default)
		)
		(layer "In13.Cu")
	)
	(gr_line
		(start 120.350788 -285.912052)
		(end 120.347232 -285.914084)
		(stroke
			(width 0.05715)
			(type default)
		)
		(layer "In13.Cu")
	)
	(gr_line
		(start 120.350788 -284.29204)
		(end 120.347232 -284.294072)
		(stroke
			(width 0.05715)
			(type default)
		)
		(layer "In13.Cu")
	)
	(gr_line
		(start 120.350788 -282.672028)
		(end 120.347232 -282.67406)
		(stroke
			(width 0.05715)
			(type default)
		)
		(layer "In13.Cu")
	)
	(gr_line
		(start 120.351296 -271.980914)
		(end 120.353836 -271.982438)
		(stroke
			(width 0.05715)
			(type default)
		)
		(layer "In13.Cu")
	)
	(gr_line
		(start 120.353836 -271.982438)
		(end 120.354852 -271.9832)
		(stroke
			(width 0.05715)
			(type default)
		)
		(layer "In13.Cu")
	)
	(gr_line
		(start 120.450102 -401.122642)
		(end 120.450102 -400.930364)
		(stroke
			(width 0.07112)
			(type default)
		)
		(layer "In13.Cu")
	)
	(gr_line
		(start 120.450102 -400.930364)
		(end 120.148096 -400.628358)
		(stroke
			(width 0.07112)
			(type default)
		)
		(layer "In13.Cu")
	)
	(gr_line
		(start 120.458738 -396.687802)
		(end 120.594628 -396.551912)
		(stroke
			(width 0.07112)
			(type default)
		)
		(layer "In13.Cu")
	)
	(gr_line
		(start 120.458738 -395.486128)
		(end 120.594628 -395.350238)
		(stroke
			(width 0.07112)
			(type default)
		)
		(layer "In13.Cu")
	)
	(gr_line
		(start 120.534684 -273.276314)
		(end 120.236742 -273.276314)
		(stroke
			(width 0.05715)
			(type default)
		)
		(layer "In13.Cu")
	)
	(gr_line
		(start 120.534684 -271.656302)
		(end 120.236742 -271.656302)
		(stroke
			(width 0.05715)
			(type default)
		)
		(layer "In13.Cu")
	)
	(gr_line
		(start 120.534684 -270.03629)
		(end 120.236742 -270.03629)
		(stroke
			(width 0.05715)
			(type default)
		)
		(layer "In13.Cu")
	)
	(gr_line
		(start 120.550686 -399.50136)
		(end 120.358408 -399.50136)
		(stroke
			(width 0.07112)
			(type default)
		)
		(layer "In13.Cu")
	)
	(gr_line
		(start 120.594628 -396.551912)
		(end 120.594628 -396.125192)
		(stroke
			(width 0.07112)
			(type default)
		)
		(layer "In13.Cu")
	)
	(gr_line
		(start 120.594628 -396.125192)
		(end 120.458738 -395.989302)
		(stroke
			(width 0.07112)
			(type default)
		)
		(layer "In13.Cu")
	)
	(gr_line
		(start 120.594628 -395.350238)
		(end 120.594628 -394.923518)
		(stroke
			(width 0.07112)
			(type default)
		)
		(layer "In13.Cu")
	)
	(gr_line
		(start 120.594628 -394.923518)
		(end 120.458738 -394.787628)
		(stroke
			(width 0.07112)
			(type default)
		)
		(layer "In13.Cu")
	)
	(gr_line
		(start 120.629934 -295.146222)
		(end 120.630188 -295.146222)
		(stroke
			(width 0.05715)
			(type default)
		)
		(layer "In13.Cu")
	)
	(gr_line
		(start 120.653302 -400.196812)
		(end 120.15724 -399.70075)
		(stroke
			(width 0.07112)
			(type default)
		)
		(layer "In13.Cu")
	)
	(gr_line
		(start 120.706134 -295.624504)
		(end 120.706388 -295.624504)
		(stroke
			(width 0.05715)
			(type default)
		)
		(layer "In13.Cu")
	)
	(gr_line
		(start 120.777 -392.707622)
		(end 120.789446 -392.707622)
		(stroke
			(width 0.07112)
			(type default)
		)
		(layer "In13.Cu")
	)
	(gr_line
		(start 120.77827 -392.990832)
		(end 120.916446 -393.129008)
		(stroke
			(width 0.07112)
			(type default)
		)
		(layer "In13.Cu")
	)
	(gr_line
		(start 120.789446 -392.707622)
		(end 120.916446 -392.580622)
		(stroke
			(width 0.07112)
			(type default)
		)
		(layer "In13.Cu")
	)
	(gr_line
		(start 120.802654 -295.460166)
		(end 120.803162 -295.46042)
		(stroke
			(width 0.05715)
			(type default)
		)
		(layer "In13.Cu")
	)
	(gr_line
		(start 120.816878 -415.24936)
		(end 120.639078 -415.32302)
		(stroke
			(width 0.07112)
			(type default)
		)
		(layer "In13.Cu")
	)
	(gr_line
		(start 120.852692 -399.995644)
		(end 120.852692 -399.803366)
		(stroke
			(width 0.07112)
			(type default)
		)
		(layer "In13.Cu")
	)
	(gr_line
		(start 120.852692 -399.803366)
		(end 120.550686 -399.50136)
		(stroke
			(width 0.07112)
			(type default)
		)
		(layer "In13.Cu")
	)
	(gr_line
		(start 120.909334 -295.956228)
		(end 120.909588 -295.955974)
		(stroke
			(width 0.05715)
			(type default)
		)
		(layer "In13.Cu")
	)
	(gr_line
		(start 120.916446 -393.129008)
		(end 120.916446 -393.292838)
		(stroke
			(width 0.07112)
			(type default)
		)
		(layer "In13.Cu")
	)
	(gr_line
		(start 120.916446 -392.580622)
		(end 120.916446 -392.429238)
		(stroke
			(width 0.07112)
			(type default)
		)
		(layer "In13.Cu")
	)
	(gr_line
		(start 120.940322 -296.612564)
		(end 120.940322 -296.613072)
		(stroke
			(width 0.07112)
			(type default)
		)
		(layer "In13.Cu")
	)
	(gr_line
		(start 120.940322 -296.584116)
		(end 120.940322 -296.612564)
		(stroke
			(width 0.05715)
			(type default)
		)
		(layer "In13.Cu")
	)
	(gr_line
		(start 120.945656 -401.425918)
		(end 120.753378 -401.425918)
		(stroke
			(width 0.07112)
			(type default)
		)
		(layer "In13.Cu")
	)
	(gr_line
		(start 120.953022 -398.273778)
		(end 120.760744 -398.273778)
		(stroke
			(width 0.07112)
			(type default)
		)
		(layer "In13.Cu")
	)
	(gr_line
		(start 120.986042 -296.538396)
		(end 120.940322 -296.584116)
		(stroke
			(width 0.05715)
			(type default)
		)
		(layer "In13.Cu")
	)
	(gr_line
		(start 121.048272 -402.12137)
		(end 120.55221 -401.625308)
		(stroke
			(width 0.07112)
			(type default)
		)
		(layer "In13.Cu")
	)
	(gr_line
		(start 121.055638 -398.96923)
		(end 120.559576 -398.473168)
		(stroke
			(width 0.07112)
			(type default)
		)
		(layer "In13.Cu")
	)
	(gr_arc
		(start 121.144792 -280.21534)
		(mid 121.148717 -280.218151)
		(end 121.152666 -280.220928)
		(stroke
			(width 0.05715)
			(type default)
		)
		(layer "In13.Cu")
	)
	(gr_arc
		(start 121.144792 -278.595328)
		(mid 121.148717 -278.598139)
		(end 121.152666 -278.600916)
		(stroke
			(width 0.05715)
			(type default)
		)
		(layer "In13.Cu")
	)
	(gr_arc
		(start 121.144792 -276.975316)
		(mid 121.148717 -276.978127)
		(end 121.152666 -276.980904)
		(stroke
			(width 0.05715)
			(type default)
		)
		(layer "In13.Cu")
	)
	(gr_arc
		(start 121.144792 -275.355304)
		(mid 121.148717 -275.358115)
		(end 121.152666 -275.360892)
		(stroke
			(width 0.05715)
			(type default)
		)
		(layer "In13.Cu")
	)
	(gr_arc
		(start 121.144792 -273.735292)
		(mid 121.148717 -273.738103)
		(end 121.152666 -273.74088)
		(stroke
			(width 0.05715)
			(type default)
		)
		(layer "In13.Cu")
	)
	(gr_arc
		(start 121.152666 -280.911808)
		(mid 121.150376 -280.913454)
		(end 121.148094 -280.91511)
		(stroke
			(width 0.05715)
			(type default)
		)
		(layer "In13.Cu")
	)
	(gr_line
		(start 121.152666 -280.220928)
		(end 121.159524 -280.224992)
		(stroke
			(width 0.05715)
			(type default)
		)
		(layer "In13.Cu")
	)
	(gr_line
		(start 121.152666 -278.600916)
		(end 121.159524 -278.60498)
		(stroke
			(width 0.05715)
			(type default)
		)
		(layer "In13.Cu")
	)
	(gr_line
		(start 121.152666 -276.980904)
		(end 121.159524 -276.984968)
		(stroke
			(width 0.05715)
			(type default)
		)
		(layer "In13.Cu")
	)
	(gr_line
		(start 121.152666 -275.360892)
		(end 121.159524 -275.364956)
		(stroke
			(width 0.05715)
			(type default)
		)
		(layer "In13.Cu")
	)
	(gr_line
		(start 121.152666 -273.74088)
		(end 121.159524 -273.744944)
		(stroke
			(width 0.05715)
			(type default)
		)
		(layer "In13.Cu")
	)
	(gr_line
		(start 121.15546 -280.909776)
		(end 121.152666 -280.911808)
		(stroke
			(width 0.05715)
			(type default)
		)
		(layer "In13.Cu")
	)
	(gr_line
		(start 121.159524 -280.224992)
		(end 121.160286 -280.2255)
		(stroke
			(width 0.05715)
			(type default)
		)
		(layer "In13.Cu")
	)
	(gr_line
		(start 121.159524 -278.60498)
		(end 121.160286 -278.605488)
		(stroke
			(width 0.05715)
			(type default)
		)
		(layer "In13.Cu")
	)
	(gr_line
		(start 121.159524 -276.984968)
		(end 121.160286 -276.985476)
		(stroke
			(width 0.05715)
			(type default)
		)
		(layer "In13.Cu")
	)
	(gr_line
		(start 121.159524 -275.364956)
		(end 121.160286 -275.365464)
		(stroke
			(width 0.05715)
			(type default)
		)
		(layer "In13.Cu")
	)
	(gr_line
		(start 121.159524 -273.744944)
		(end 121.160286 -273.745452)
		(stroke
			(width 0.05715)
			(type default)
		)
		(layer "In13.Cu")
	)
	(gr_line
		(start 121.160286 -280.2255)
		(end 121.161048 -280.226008)
		(stroke
			(width 0.05715)
			(type default)
		)
		(layer "In13.Cu")
	)
	(gr_line
		(start 121.160286 -278.605488)
		(end 121.161048 -278.605996)
		(stroke
			(width 0.05715)
			(type default)
		)
		(layer "In13.Cu")
	)
	(gr_line
		(start 121.160286 -276.985476)
		(end 121.161048 -276.985984)
		(stroke
			(width 0.05715)
			(type default)
		)
		(layer "In13.Cu")
	)
	(gr_line
		(start 121.160286 -275.365464)
		(end 121.161048 -275.365972)
		(stroke
			(width 0.05715)
			(type default)
		)
		(layer "In13.Cu")
	)
	(gr_line
		(start 121.160286 -273.745452)
		(end 121.161048 -273.74596)
		(stroke
			(width 0.05715)
			(type default)
		)
		(layer "In13.Cu")
	)
	(gr_line
		(start 121.163842 -280.90495)
		(end 121.15546 -280.909776)
		(stroke
			(width 0.05715)
			(type default)
		)
		(layer "In13.Cu")
	)
	(gr_line
		(start 121.176542 -296.538396)
		(end 121.222262 -296.584116)
		(stroke
			(width 0.05715)
			(type default)
		)
		(layer "In13.Cu")
	)
	(gr_line
		(start 121.177812 -415.85261)
		(end 120.529858 -415.584132)
		(stroke
			(width 0.07112)
			(type default)
		)
		(layer "In13.Cu")
	)
	(gr_line
		(start 121.191782 -279.268936)
		(end 121.190766 -279.269444)
		(stroke
			(width 0.05715)
			(type default)
		)
		(layer "In13.Cu")
	)
	(gr_line
		(start 121.191782 -277.648924)
		(end 121.190766 -277.649432)
		(stroke
			(width 0.05715)
			(type default)
		)
		(layer "In13.Cu")
	)
	(gr_line
		(start 121.191782 -276.028912)
		(end 121.190766 -276.02942)
		(stroke
			(width 0.05715)
			(type default)
		)
		(layer "In13.Cu")
	)
	(gr_line
		(start 121.191782 -274.4089)
		(end 121.190766 -274.409408)
		(stroke
			(width 0.05715)
			(type default)
		)
		(layer "In13.Cu")
	)
	(gr_line
		(start 121.192036 -280.244042)
		(end 121.192544 -280.244296)
		(stroke
			(width 0.05715)
			(type default)
		)
		(layer "In13.Cu")
	)
	(gr_line
		(start 121.192036 -278.62403)
		(end 121.192544 -278.624284)
		(stroke
			(width 0.05715)
			(type default)
		)
		(layer "In13.Cu")
	)
	(gr_line
		(start 121.192544 -280.244296)
		(end 121.195338 -280.24582)
		(stroke
			(width 0.05715)
			(type default)
		)
		(layer "In13.Cu")
	)
	(gr_line
		(start 121.192544 -279.268428)
		(end 121.191782 -279.268936)
		(stroke
			(width 0.05715)
			(type default)
		)
		(layer "In13.Cu")
	)
	(gr_line
		(start 121.192544 -278.624284)
		(end 121.195338 -278.625808)
		(stroke
			(width 0.05715)
			(type default)
		)
		(layer "In13.Cu")
	)
	(gr_line
		(start 121.193814 -279.267666)
		(end 121.192544 -279.268428)
		(stroke
			(width 0.05715)
			(type default)
		)
		(layer "In13.Cu")
	)
	(gr_line
		(start 121.21134 -415.412682)
		(end 120.816878 -415.24936)
		(stroke
			(width 0.07112)
			(type default)
		)
		(layer "In13.Cu")
	)
	(gr_line
		(start 121.222262 -296.584116)
		(end 121.222262 -296.612564)
		(stroke
			(width 0.05715)
			(type default)
		)
		(layer "In13.Cu")
	)
	(gr_line
		(start 121.22277 -296.837354)
		(end 121.22277 -296.837862)
		(stroke
			(width 0.07112)
			(type default)
		)
		(layer "In13.Cu")
	)
	(gr_line
		(start 121.243344 -280.856436)
		(end 121.242836 -280.856944)
		(stroke
			(width 0.05715)
			(type default)
		)
		(layer "In13.Cu")
	)
	(gr_line
		(start 121.247662 -401.920202)
		(end 121.247662 -401.727924)
		(stroke
			(width 0.07112)
			(type default)
		)
		(layer "In13.Cu")
	)
	(gr_line
		(start 121.247662 -401.727924)
		(end 120.945656 -401.425918)
		(stroke
			(width 0.07112)
			(type default)
		)
		(layer "In13.Cu")
	)
	(gr_line
		(start 121.255028 -398.768062)
		(end 121.255028 -398.575784)
		(stroke
			(width 0.07112)
			(type default)
		)
		(layer "In13.Cu")
	)
	(gr_line
		(start 121.255028 -398.575784)
		(end 120.953022 -398.273778)
		(stroke
			(width 0.07112)
			(type default)
		)
		(layer "In13.Cu")
	)
	(gr_line
		(start 121.285254 -415.590482)
		(end 121.21134 -415.412682)
		(stroke
			(width 0.07112)
			(type default)
		)
		(layer "In13.Cu")
	)
	(gr_line
		(start 121.287032 -279.43429)
		(end 121.285762 -279.435052)
		(stroke
			(width 0.05715)
			(type default)
		)
		(layer "In13.Cu")
	)
	(gr_line
		(start 121.287032 -277.814278)
		(end 121.285762 -277.81504)
		(stroke
			(width 0.05715)
			(type default)
		)
		(layer "In13.Cu")
	)
	(gr_line
		(start 121.287032 -276.194266)
		(end 121.285762 -276.195028)
		(stroke
			(width 0.05715)
			(type default)
		)
		(layer "In13.Cu")
	)
	(gr_line
		(start 121.287032 -274.574254)
		(end 121.285762 -274.575016)
		(stroke
			(width 0.05715)
			(type default)
		)
		(layer "In13.Cu")
	)
	(gr_line
		(start 121.28754 -279.434036)
		(end 121.287032 -279.43429)
		(stroke
			(width 0.05715)
			(type default)
		)
		(layer "In13.Cu")
	)
	(gr_line
		(start 121.28754 -277.814024)
		(end 121.287032 -277.814278)
		(stroke
			(width 0.05715)
			(type default)
		)
		(layer "In13.Cu")
	)
	(gr_line
		(start 121.28754 -276.194012)
		(end 121.287032 -276.194266)
		(stroke
			(width 0.05715)
			(type default)
		)
		(layer "In13.Cu")
	)
	(gr_line
		(start 121.28754 -274.574)
		(end 121.287032 -274.574254)
		(stroke
			(width 0.05715)
			(type default)
		)
		(layer "In13.Cu")
	)
	(gr_line
		(start 121.311416 -409.585922)
		(end 121.311416 -408.884882)
		(stroke
			(width 0.07112)
			(type default)
		)
		(layer "In13.Cu")
	)
	(gr_line
		(start 121.311416 -408.458162)
		(end 121.311416 -407.757122)
		(stroke
			(width 0.07112)
			(type default)
		)
		(layer "In13.Cu")
	)
	(gr_line
		(start 121.320306 -354.510086)
		(end 121.622312 -354.207826)
		(stroke
			(width 0.07112)
			(type default)
		)
		(layer "In13.Cu")
	)
	(gr_line
		(start 121.32056 -354.702364)
		(end 121.320306 -354.510086)
		(stroke
			(width 0.07112)
			(type default)
		)
		(layer "In13.Cu")
	)
	(gr_line
		(start 121.348246 -400.29892)
		(end 121.155968 -400.29892)
		(stroke
			(width 0.07112)
			(type default)
		)
		(layer "In13.Cu")
	)
	(gr_line
		(start 121.375678 -396.326614)
		(end 121.375678 -395.625574)
		(stroke
			(width 0.07112)
			(type default)
		)
		(layer "In13.Cu")
	)
	(gr_line
		(start 121.375678 -395.198854)
		(end 121.375678 -394.497814)
		(stroke
			(width 0.07112)
			(type default)
		)
		(layer "In13.Cu")
	)
	(gr_line
		(start 121.379234 -295.146222)
		(end 121.379488 -295.146222)
		(stroke
			(width 0.05715)
			(type default)
		)
		(layer "In13.Cu")
	)
	(gr_line
		(start 121.411238 -414.06953)
		(end 121.233184 -414.14319)
		(stroke
			(width 0.07112)
			(type default)
		)
		(layer "In13.Cu")
	)
	(gr_line
		(start 121.450862 -400.994372)
		(end 120.9548 -400.49831)
		(stroke
			(width 0.07112)
			(type default)
		)
		(layer "In13.Cu")
	)
	(gr_line
		(start 121.51995 -354.903532)
		(end 122.015758 -354.407216)
		(stroke
			(width 0.07112)
			(type default)
		)
		(layer "In13.Cu")
	)
	(gr_line
		(start 121.594626 -409.584652)
		(end 121.730516 -409.448762)
		(stroke
			(width 0.07112)
			(type default)
		)
		(layer "In13.Cu")
	)
	(gr_line
		(start 121.594626 -408.456892)
		(end 121.730516 -408.321002)
		(stroke
			(width 0.07112)
			(type default)
		)
		(layer "In13.Cu")
	)
	(gr_line
		(start 121.622312 -354.207826)
		(end 121.81459 -354.207826)
		(stroke
			(width 0.07112)
			(type default)
		)
		(layer "In13.Cu")
	)
	(gr_line
		(start 121.6279 -357.000048)
		(end 122.32894 -357.000048)
		(stroke
			(width 0.07112)
			(type default)
		)
		(layer "In13.Cu")
	)
	(gr_line
		(start 121.62917 -356.716838)
		(end 121.76506 -356.580948)
		(stroke
			(width 0.07112)
			(type default)
		)
		(layer "In13.Cu")
	)
	(gr_line
		(start 121.650252 -400.793204)
		(end 121.650252 -400.600926)
		(stroke
			(width 0.07112)
			(type default)
		)
		(layer "In13.Cu")
	)
	(gr_line
		(start 121.650252 -400.600926)
		(end 121.348246 -400.29892)
		(stroke
			(width 0.07112)
			(type default)
		)
		(layer "In13.Cu")
	)
	(gr_line
		(start 121.658888 -396.325344)
		(end 121.794778 -396.189454)
		(stroke
			(width 0.07112)
			(type default)
		)
		(layer "In13.Cu")
	)
	(gr_line
		(start 121.658888 -395.197584)
		(end 121.794778 -395.061694)
		(stroke
			(width 0.07112)
			(type default)
		)
		(layer "In13.Cu")
	)
	(gr_line
		(start 121.730516 -409.448762)
		(end 121.730516 -409.022042)
		(stroke
			(width 0.07112)
			(type default)
		)
		(layer "In13.Cu")
	)
	(gr_line
		(start 121.730516 -409.022042)
		(end 121.594626 -408.886152)
		(stroke
			(width 0.07112)
			(type default)
		)
		(layer "In13.Cu")
	)
	(gr_line
		(start 121.730516 -408.321002)
		(end 121.730516 -407.894282)
		(stroke
			(width 0.07112)
			(type default)
		)
		(layer "In13.Cu")
	)
	(gr_line
		(start 121.730516 -407.894282)
		(end 121.594626 -407.758392)
		(stroke
			(width 0.07112)
			(type default)
		)
		(layer "In13.Cu")
	)
	(gr_line
		(start 121.743216 -402.223478)
		(end 121.550938 -402.223478)
		(stroke
			(width 0.07112)
			(type default)
		)
		(layer "In13.Cu")
	)
	(gr_line
		(start 121.750582 -399.071338)
		(end 121.558304 -399.071338)
		(stroke
			(width 0.07112)
			(type default)
		)
		(layer "In13.Cu")
	)
	(gr_line
		(start 121.76506 -356.580948)
		(end 122.19178 -356.580948)
		(stroke
			(width 0.07112)
			(type default)
		)
		(layer "In13.Cu")
	)
	(gr_line
		(start 121.771918 -414.67278)
		(end 121.123964 -414.404556)
		(stroke
			(width 0.07112)
			(type default)
		)
		(layer "In13.Cu")
	)
	(gr_line
		(start 121.794778 -396.189454)
		(end 121.794778 -395.762734)
		(stroke
			(width 0.07112)
			(type default)
		)
		(layer "In13.Cu")
	)
	(gr_line
		(start 121.794778 -395.762734)
		(end 121.658888 -395.626844)
		(stroke
			(width 0.07112)
			(type default)
		)
		(layer "In13.Cu")
	)
	(gr_line
		(start 121.794778 -395.061694)
		(end 121.794778 -394.634974)
		(stroke
			(width 0.07112)
			(type default)
		)
		(layer "In13.Cu")
	)
	(gr_line
		(start 121.794778 -394.634974)
		(end 121.658888 -394.499084)
		(stroke
			(width 0.07112)
			(type default)
		)
		(layer "In13.Cu")
	)
	(gr_line
		(start 121.8057 -414.232598)
		(end 121.411238 -414.06953)
		(stroke
			(width 0.07112)
			(type default)
		)
		(layer "In13.Cu")
	)
	(gr_line
		(start 121.845832 -402.91893)
		(end 121.34977 -402.422868)
		(stroke
			(width 0.07112)
			(type default)
		)
		(layer "In13.Cu")
	)
	(gr_line
		(start 121.853198 -399.76679)
		(end 121.357136 -399.270728)
		(stroke
			(width 0.07112)
			(type default)
		)
		(layer "In13.Cu")
	)
	(gr_line
		(start 121.87936 -414.410652)
		(end 121.8057 -414.232598)
		(stroke
			(width 0.07112)
			(type default)
		)
		(layer "In13.Cu")
	)
	(gr_line
		(start 121.885456 -296.926254)
		(end 121.885456 -296.926762)
		(stroke
			(width 0.07112)
			(type default)
		)
		(layer "In13.Cu")
	)
	(gr_line
		(start 121.885456 -296.584116)
		(end 121.885456 -296.612564)
		(stroke
			(width 0.05715)
			(type default)
		)
		(layer "In13.Cu")
	)
	(gr_arc
		(start 121.911872 -295.598088)
		(mid 121.909468 -295.595286)
		(end 121.907046 -295.5925)
		(stroke
			(width 0.05715)
			(type default)
		)
		(layer "In13.Cu")
	)
	(gr_line
		(start 121.931176 -296.538396)
		(end 121.885456 -296.584116)
		(stroke
			(width 0.05715)
			(type default)
		)
		(layer "In13.Cu")
	)
	(gr_line
		(start 121.97715 -392.707622)
		(end 121.989596 -392.707622)
		(stroke
			(width 0.07112)
			(type default)
		)
		(layer "In13.Cu")
	)
	(gr_line
		(start 121.97842 -392.990832)
		(end 122.116596 -393.129008)
		(stroke
			(width 0.07112)
			(type default)
		)
		(layer "In13.Cu")
	)
	(gr_line
		(start 121.989596 -392.707622)
		(end 122.116596 -392.580622)
		(stroke
			(width 0.07112)
			(type default)
		)
		(layer "In13.Cu")
	)
	(gr_arc
		(start 122.040142 -295.956228)
		(mid 122.040157 -295.952291)
		(end 122.040142 -295.948354)
		(stroke
			(width 0.05715)
			(type default)
		)
		(layer "In13.Cu")
	)
	(gr_line
		(start 122.045222 -402.717762)
		(end 122.045222 -402.525484)
		(stroke
			(width 0.07112)
			(type default)
		)
		(layer "In13.Cu")
	)
	(gr_line
		(start 122.045222 -402.525484)
		(end 121.743216 -402.223478)
		(stroke
			(width 0.07112)
			(type default)
		)
		(layer "In13.Cu")
	)
	(gr_line
		(start 122.052588 -399.565622)
		(end 122.052588 -399.373344)
		(stroke
			(width 0.07112)
			(type default)
		)
		(layer "In13.Cu")
	)
	(gr_line
		(start 122.052588 -399.373344)
		(end 121.750582 -399.071338)
		(stroke
			(width 0.07112)
			(type default)
		)
		(layer "In13.Cu")
	)
	(gr_arc
		(start 122.084846 -294.795194)
		(mid 122.088771 -294.798005)
		(end 122.09272 -294.800782)
		(stroke
			(width 0.05715)
			(type default)
		)
		(layer "In13.Cu")
	)
	(gr_arc
		(start 122.084846 -293.175182)
		(mid 122.088771 -293.177993)
		(end 122.09272 -293.18077)
		(stroke
			(width 0.05715)
			(type default)
		)
		(layer "In13.Cu")
	)
	(gr_arc
		(start 122.084846 -289.935158)
		(mid 122.088771 -289.937969)
		(end 122.09272 -289.940746)
		(stroke
			(width 0.05715)
			(type default)
		)
		(layer "In13.Cu")
	)
	(gr_arc
		(start 122.084846 -281.835352)
		(mid 122.088771 -281.838163)
		(end 122.09272 -281.84094)
		(stroke
			(width 0.05715)
			(type default)
		)
		(layer "In13.Cu")
	)
	(gr_line
		(start 122.09272 -294.800782)
		(end 122.099578 -294.804846)
		(stroke
			(width 0.05715)
			(type default)
		)
		(layer "In13.Cu")
	)
	(gr_line
		(start 122.09272 -293.18077)
		(end 122.099578 -293.184834)
		(stroke
			(width 0.05715)
			(type default)
		)
		(layer "In13.Cu")
	)
	(gr_line
		(start 122.09272 -289.940746)
		(end 122.099578 -289.94481)
		(stroke
			(width 0.05715)
			(type default)
		)
		(layer "In13.Cu")
	)
	(gr_line
		(start 122.09272 -281.84094)
		(end 122.099578 -281.845004)
		(stroke
			(width 0.05715)
			(type default)
		)
		(layer "In13.Cu")
	)
	(gr_arc
		(start 122.09272 -280.911808)
		(mid 122.088771 -280.914585)
		(end 122.084846 -280.917396)
		(stroke
			(width 0.05715)
			(type default)
		)
		(layer "In13.Cu")
	)
	(gr_line
		(start 122.093228 -280.911554)
		(end 122.09272 -280.911808)
		(stroke
			(width 0.05715)
			(type default)
		)
		(layer "In13.Cu")
	)
	(gr_line
		(start 122.099578 -294.804846)
		(end 122.10034 -294.805354)
		(stroke
			(width 0.05715)
			(type default)
		)
		(layer "In13.Cu")
	)
	(gr_line
		(start 122.099578 -293.184834)
		(end 122.10034 -293.185342)
		(stroke
			(width 0.05715)
			(type default)
		)
		(layer "In13.Cu")
	)
	(gr_line
		(start 122.099578 -289.94481)
		(end 122.10034 -289.945318)
		(stroke
			(width 0.05715)
			(type default)
		)
		(layer "In13.Cu")
	)
	(gr_line
		(start 122.099578 -281.845004)
		(end 122.10034 -281.845512)
		(stroke
			(width 0.05715)
			(type default)
		)
		(layer "In13.Cu")
	)
	(gr_line
		(start 122.10034 -294.805354)
		(end 122.101102 -294.805862)
		(stroke
			(width 0.05715)
			(type default)
		)
		(layer "In13.Cu")
	)
	(gr_line
		(start 122.10034 -293.185342)
		(end 122.101102 -293.18585)
		(stroke
			(width 0.05715)
			(type default)
		)
		(layer "In13.Cu")
	)
	(gr_line
		(start 122.10034 -289.945318)
		(end 122.101102 -289.945826)
		(stroke
			(width 0.05715)
			(type default)
		)
		(layer "In13.Cu")
	)
	(gr_line
		(start 122.10034 -281.845512)
		(end 122.101102 -281.84602)
		(stroke
			(width 0.05715)
			(type default)
		)
		(layer "In13.Cu")
	)
	(gr_line
		(start 122.10034 -280.907236)
		(end 122.093228 -280.911554)
		(stroke
			(width 0.05715)
			(type default)
		)
		(layer "In13.Cu")
	)
	(gr_line
		(start 122.116596 -393.129008)
		(end 122.116596 -393.292838)
		(stroke
			(width 0.07112)
			(type default)
		)
		(layer "In13.Cu")
	)
	(gr_line
		(start 122.116596 -392.580622)
		(end 122.116596 -392.429238)
		(stroke
			(width 0.07112)
			(type default)
		)
		(layer "In13.Cu")
	)
	(gr_line
		(start 122.117358 -353.712018)
		(end 122.419364 -353.410012)
		(stroke
			(width 0.07112)
			(type default)
		)
		(layer "In13.Cu")
	)
	(gr_line
		(start 122.117612 -353.90455)
		(end 122.117358 -353.712018)
		(stroke
			(width 0.07112)
			(type default)
		)
		(layer "In13.Cu")
	)
	(gr_line
		(start 122.121676 -296.538396)
		(end 122.167396 -296.584116)
		(stroke
			(width 0.05715)
			(type default)
		)
		(layer "In13.Cu")
	)
	(gr_line
		(start 122.127518 -292.231318)
		(end 122.124978 -292.232842)
		(stroke
			(width 0.05715)
			(type default)
		)
		(layer "In13.Cu")
	)
	(gr_line
		(start 122.127518 -290.611306)
		(end 122.124978 -290.61283)
		(stroke
			(width 0.05715)
			(type default)
		)
		(layer "In13.Cu")
	)
	(gr_line
		(start 122.127518 -288.991294)
		(end 122.124978 -288.992818)
		(stroke
			(width 0.05715)
			(type default)
		)
		(layer "In13.Cu")
	)
	(gr_line
		(start 122.127518 -285.751524)
		(end 122.124978 -285.753048)
		(stroke
			(width 0.05715)
			(type default)
		)
		(layer "In13.Cu")
	)
	(gr_line
		(start 122.127518 -284.131512)
		(end 122.124978 -284.133036)
		(stroke
			(width 0.05715)
			(type default)
		)
		(layer "In13.Cu")
	)
	(gr_line
		(start 122.127518 -282.5115)
		(end 122.124978 -282.513024)
		(stroke
			(width 0.05715)
			(type default)
		)
		(layer "In13.Cu")
	)
	(gr_line
		(start 122.13082 -292.229286)
		(end 122.129296 -292.230302)
		(stroke
			(width 0.05715)
			(type default)
		)
		(layer "In13.Cu")
	)
	(gr_line
		(start 122.13082 -290.609274)
		(end 122.129296 -290.61029)
		(stroke
			(width 0.05715)
			(type default)
		)
		(layer "In13.Cu")
	)
	(gr_line
		(start 122.13082 -288.989262)
		(end 122.129296 -288.990278)
		(stroke
			(width 0.05715)
			(type default)
		)
		(layer "In13.Cu")
	)
	(gr_line
		(start 122.13082 -285.749492)
		(end 122.129296 -285.750508)
		(stroke
			(width 0.05715)
			(type default)
		)
		(layer "In13.Cu")
	)
	(gr_line
		(start 122.13082 -284.12948)
		(end 122.129296 -284.130496)
		(stroke
			(width 0.05715)
			(type default)
		)
		(layer "In13.Cu")
	)
	(gr_line
		(start 122.13082 -282.509468)
		(end 122.129296 -282.510484)
		(stroke
			(width 0.05715)
			(type default)
		)
		(layer "In13.Cu")
	)
	(gr_line
		(start 122.131836 -293.84879)
		(end 122.13082 -293.849298)
		(stroke
			(width 0.05715)
			(type default)
		)
		(layer "In13.Cu")
	)
	(gr_line
		(start 122.131836 -292.228778)
		(end 122.13082 -292.229286)
		(stroke
			(width 0.05715)
			(type default)
		)
		(layer "In13.Cu")
	)
	(gr_line
		(start 122.131836 -290.608766)
		(end 122.13082 -290.609274)
		(stroke
			(width 0.05715)
			(type default)
		)
		(layer "In13.Cu")
	)
	(gr_line
		(start 122.131836 -288.988754)
		(end 122.13082 -288.989262)
		(stroke
			(width 0.05715)
			(type default)
		)
		(layer "In13.Cu")
	)
	(gr_line
		(start 122.131836 -285.748984)
		(end 122.13082 -285.749492)
		(stroke
			(width 0.05715)
			(type default)
		)
		(layer "In13.Cu")
	)
	(gr_line
		(start 122.131836 -284.128972)
		(end 122.13082 -284.12948)
		(stroke
			(width 0.05715)
			(type default)
		)
		(layer "In13.Cu")
	)
	(gr_line
		(start 122.131836 -282.50896)
		(end 122.13082 -282.509468)
		(stroke
			(width 0.05715)
			(type default)
		)
		(layer "In13.Cu")
	)
	(gr_line
		(start 122.13209 -294.823896)
		(end 122.132598 -294.82415)
		(stroke
			(width 0.05715)
			(type default)
		)
		(layer "In13.Cu")
	)
	(gr_line
		(start 122.13209 -293.203884)
		(end 122.132598 -293.204138)
		(stroke
			(width 0.05715)
			(type default)
		)
		(layer "In13.Cu")
	)
	(gr_line
		(start 122.13209 -289.96386)
		(end 122.132598 -289.964114)
		(stroke
			(width 0.05715)
			(type default)
		)
		(layer "In13.Cu")
	)
	(gr_line
		(start 122.13209 -281.864054)
		(end 122.132598 -281.864308)
		(stroke
			(width 0.05715)
			(type default)
		)
		(layer "In13.Cu")
	)
	(gr_line
		(start 122.132344 -293.848536)
		(end 122.131836 -293.84879)
		(stroke
			(width 0.05715)
			(type default)
		)
		(layer "In13.Cu")
	)
	(gr_line
		(start 122.132598 -294.82415)
		(end 122.133868 -294.824912)
		(stroke
			(width 0.05715)
			(type default)
		)
		(layer "In13.Cu")
	)
	(gr_line
		(start 122.132598 -293.204138)
		(end 122.133868 -293.2049)
		(stroke
			(width 0.05715)
			(type default)
		)
		(layer "In13.Cu")
	)
	(gr_line
		(start 122.132598 -292.22827)
		(end 122.131836 -292.228778)
		(stroke
			(width 0.05715)
			(type default)
		)
		(layer "In13.Cu")
	)
	(gr_line
		(start 122.132598 -291.584126)
		(end 122.133868 -291.584888)
		(stroke
			(width 0.05715)
			(type default)
		)
		(layer "In13.Cu")
	)
	(gr_line
		(start 122.132598 -290.608258)
		(end 122.131836 -290.608766)
		(stroke
			(width 0.05715)
			(type default)
		)
		(layer "In13.Cu")
	)
	(gr_line
		(start 122.132598 -289.964114)
		(end 122.133868 -289.964876)
		(stroke
			(width 0.05715)
			(type default)
		)
		(layer "In13.Cu")
	)
	(gr_line
		(start 122.132598 -288.988246)
		(end 122.131836 -288.988754)
		(stroke
			(width 0.05715)
			(type default)
		)
		(layer "In13.Cu")
	)
	(gr_line
		(start 122.132598 -285.748476)
		(end 122.131836 -285.748984)
		(stroke
			(width 0.05715)
			(type default)
		)
		(layer "In13.Cu")
	)
	(gr_line
		(start 122.132598 -285.104332)
		(end 122.133868 -285.105094)
		(stroke
			(width 0.05715)
			(type default)
		)
		(layer "In13.Cu")
	)
	(gr_line
		(start 122.132598 -284.128464)
		(end 122.131836 -284.128972)
		(stroke
			(width 0.05715)
			(type default)
		)
		(layer "In13.Cu")
	)
	(gr_line
		(start 122.132598 -283.48432)
		(end 122.133868 -283.485082)
		(stroke
			(width 0.05715)
			(type default)
		)
		(layer "In13.Cu")
	)
	(gr_line
		(start 122.132598 -282.508452)
		(end 122.131836 -282.50896)
		(stroke
			(width 0.05715)
			(type default)
		)
		(layer "In13.Cu")
	)
	(gr_line
		(start 122.132598 -281.864308)
		(end 122.133868 -281.86507)
		(stroke
			(width 0.05715)
			(type default)
		)
		(layer "In13.Cu")
	)
	(gr_line
		(start 122.133868 -294.824912)
		(end 122.135392 -294.825674)
		(stroke
			(width 0.05715)
			(type default)
		)
		(layer "In13.Cu")
	)
	(gr_line
		(start 122.133868 -293.2049)
		(end 122.135392 -293.205662)
		(stroke
			(width 0.05715)
			(type default)
		)
		(layer "In13.Cu")
	)
	(gr_line
		(start 122.133868 -292.227508)
		(end 122.132598 -292.22827)
		(stroke
			(width 0.05715)
			(type default)
		)
		(layer "In13.Cu")
	)
	(gr_line
		(start 122.133868 -290.607496)
		(end 122.132598 -290.608258)
		(stroke
			(width 0.05715)
			(type default)
		)
		(layer "In13.Cu")
	)
	(gr_line
		(start 122.133868 -289.964876)
		(end 122.135392 -289.965638)
		(stroke
			(width 0.05715)
			(type default)
		)
		(layer "In13.Cu")
	)
	(gr_line
		(start 122.133868 -288.987484)
		(end 122.132598 -288.988246)
		(stroke
			(width 0.05715)
			(type default)
		)
		(layer "In13.Cu")
	)
	(gr_line
		(start 122.133868 -285.747714)
		(end 122.132598 -285.748476)
		(stroke
			(width 0.05715)
			(type default)
		)
		(layer "In13.Cu")
	)
	(gr_line
		(start 122.133868 -284.127702)
		(end 122.132598 -284.128464)
		(stroke
			(width 0.05715)
			(type default)
		)
		(layer "In13.Cu")
	)
	(gr_line
		(start 122.133868 -282.50769)
		(end 122.132598 -282.508452)
		(stroke
			(width 0.05715)
			(type default)
		)
		(layer "In13.Cu")
	)
	(gr_line
		(start 122.133868 -281.86507)
		(end 122.135392 -281.865832)
		(stroke
			(width 0.05715)
			(type default)
		)
		(layer "In13.Cu")
	)
	(gr_line
		(start 122.153172 -397.779748)
		(end 121.960894 -397.779748)
		(stroke
			(width 0.07112)
			(type default)
		)
		(layer "In13.Cu")
	)
	(gr_line
		(start 122.167396 -296.584116)
		(end 122.167396 -296.612564)
		(stroke
			(width 0.05715)
			(type default)
		)
		(layer "In13.Cu")
	)
	(gr_line
		(start 122.167904 -296.95521)
		(end 122.167904 -296.955718)
		(stroke
			(width 0.07112)
			(type default)
		)
		(layer "In13.Cu")
	)
	(gr_line
		(start 122.191272 -401.141946)
		(end 121.998994 -401.141946)
		(stroke
			(width 0.07112)
			(type default)
		)
		(layer "In13.Cu")
	)
	(gr_line
		(start 122.19178 -356.580948)
		(end 122.32767 -356.716838)
		(stroke
			(width 0.07112)
			(type default)
		)
		(layer "In13.Cu")
	)
	(gr_line
		(start 122.222006 -292.396926)
		(end 122.221244 -292.397434)
		(stroke
			(width 0.05715)
			(type default)
		)
		(layer "In13.Cu")
	)
	(gr_line
		(start 122.222006 -290.776914)
		(end 122.221244 -290.777422)
		(stroke
			(width 0.05715)
			(type default)
		)
		(layer "In13.Cu")
	)
	(gr_line
		(start 122.222006 -289.156902)
		(end 122.221244 -289.15741)
		(stroke
			(width 0.05715)
			(type default)
		)
		(layer "In13.Cu")
	)
	(gr_line
		(start 122.222006 -285.917132)
		(end 122.221244 -285.91764)
		(stroke
			(width 0.05715)
			(type default)
		)
		(layer "In13.Cu")
	)
	(gr_line
		(start 122.222006 -284.29712)
		(end 122.221244 -284.297628)
		(stroke
			(width 0.05715)
			(type default)
		)
		(layer "In13.Cu")
	)
	(gr_line
		(start 122.222006 -282.677108)
		(end 122.221244 -282.677616)
		(stroke
			(width 0.05715)
			(type default)
		)
		(layer "In13.Cu")
	)
	(gr_line
		(start 122.223022 -292.396418)
		(end 122.222006 -292.396926)
		(stroke
			(width 0.05715)
			(type default)
		)
		(layer "In13.Cu")
	)
	(gr_line
		(start 122.223022 -290.776406)
		(end 122.222006 -290.776914)
		(stroke
			(width 0.05715)
			(type default)
		)
		(layer "In13.Cu")
	)
	(gr_line
		(start 122.223022 -289.156394)
		(end 122.222006 -289.156902)
		(stroke
			(width 0.05715)
			(type default)
		)
		(layer "In13.Cu")
	)
	(gr_line
		(start 122.223022 -285.916624)
		(end 122.222006 -285.917132)
		(stroke
			(width 0.05715)
			(type default)
		)
		(layer "In13.Cu")
	)
	(gr_line
		(start 122.223022 -284.296612)
		(end 122.222006 -284.29712)
		(stroke
			(width 0.05715)
			(type default)
		)
		(layer "In13.Cu")
	)
	(gr_line
		(start 122.223022 -282.6766)
		(end 122.222006 -282.677108)
		(stroke
			(width 0.05715)
			(type default)
		)
		(layer "In13.Cu")
	)
	(gr_line
		(start 122.227086 -294.014144)
		(end 122.225816 -294.014906)
		(stroke
			(width 0.05715)
			(type default)
		)
		(layer "In13.Cu")
	)
	(gr_line
		(start 122.227086 -292.394132)
		(end 122.225816 -292.394894)
		(stroke
			(width 0.05715)
			(type default)
		)
		(layer "In13.Cu")
	)
	(gr_line
		(start 122.227086 -290.77412)
		(end 122.225816 -290.774882)
		(stroke
			(width 0.05715)
			(type default)
		)
		(layer "In13.Cu")
	)
	(gr_line
		(start 122.227086 -289.154108)
		(end 122.225816 -289.15487)
		(stroke
			(width 0.05715)
			(type default)
		)
		(layer "In13.Cu")
	)
	(gr_line
		(start 122.227086 -285.914338)
		(end 122.225816 -285.9151)
		(stroke
			(width 0.05715)
			(type default)
		)
		(layer "In13.Cu")
	)
	(gr_line
		(start 122.227086 -284.294326)
		(end 122.225816 -284.295088)
		(stroke
			(width 0.05715)
			(type default)
		)
		(layer "In13.Cu")
	)
	(gr_line
		(start 122.227086 -282.674314)
		(end 122.225816 -282.675076)
		(stroke
			(width 0.05715)
			(type default)
		)
		(layer "In13.Cu")
	)
	(gr_line
		(start 122.22734 -291.418518)
		(end 122.227848 -291.418772)
		(stroke
			(width 0.05715)
			(type default)
		)
		(layer "In13.Cu")
	)
	(gr_line
		(start 122.22734 -284.938724)
		(end 122.227848 -284.938978)
		(stroke
			(width 0.05715)
			(type default)
		)
		(layer "In13.Cu")
	)
	(gr_line
		(start 122.22734 -283.318712)
		(end 122.227848 -283.318966)
		(stroke
			(width 0.05715)
			(type default)
		)
		(layer "In13.Cu")
	)
	(gr_line
		(start 122.227848 -294.658796)
		(end 122.228864 -294.659304)
		(stroke
			(width 0.05715)
			(type default)
		)
		(layer "In13.Cu")
	)
	(gr_line
		(start 122.227848 -293.038784)
		(end 122.228864 -293.039292)
		(stroke
			(width 0.05715)
			(type default)
		)
		(layer "In13.Cu")
	)
	(gr_line
		(start 122.227848 -292.393624)
		(end 122.227086 -292.394132)
		(stroke
			(width 0.05715)
			(type default)
		)
		(layer "In13.Cu")
	)
	(gr_line
		(start 122.227848 -291.418772)
		(end 122.228864 -291.41928)
		(stroke
			(width 0.05715)
			(type default)
		)
		(layer "In13.Cu")
	)
	(gr_line
		(start 122.227848 -290.773612)
		(end 122.227086 -290.77412)
		(stroke
			(width 0.05715)
			(type default)
		)
		(layer "In13.Cu")
	)
	(gr_line
		(start 122.227848 -289.79876)
		(end 122.228864 -289.799268)
		(stroke
			(width 0.05715)
			(type default)
		)
		(layer "In13.Cu")
	)
	(gr_line
		(start 122.227848 -289.1536)
		(end 122.227086 -289.154108)
		(stroke
			(width 0.05715)
			(type default)
		)
		(layer "In13.Cu")
	)
	(gr_line
		(start 122.227848 -285.91383)
		(end 122.227086 -285.914338)
		(stroke
			(width 0.05715)
			(type default)
		)
		(layer "In13.Cu")
	)
	(gr_line
		(start 122.227848 -284.938978)
		(end 122.228864 -284.939486)
		(stroke
			(width 0.05715)
			(type default)
		)
		(layer "In13.Cu")
	)
	(gr_line
		(start 122.227848 -284.293818)
		(end 122.227086 -284.294326)
		(stroke
			(width 0.05715)
			(type default)
		)
		(layer "In13.Cu")
	)
	(gr_line
		(start 122.227848 -283.318966)
		(end 122.228864 -283.319474)
		(stroke
			(width 0.05715)
			(type default)
		)
		(layer "In13.Cu")
	)
	(gr_line
		(start 122.227848 -282.673806)
		(end 122.227086 -282.674314)
		(stroke
			(width 0.05715)
			(type default)
		)
		(layer "In13.Cu")
	)
	(gr_line
		(start 122.227848 -281.698954)
		(end 122.228864 -281.699462)
		(stroke
			(width 0.05715)
			(type default)
		)
		(layer "In13.Cu")
	)
	(gr_line
		(start 122.228864 -294.659304)
		(end 122.230388 -294.66032)
		(stroke
			(width 0.05715)
			(type default)
		)
		(layer "In13.Cu")
	)
	(gr_line
		(start 122.228864 -293.039292)
		(end 122.230388 -293.040308)
		(stroke
			(width 0.05715)
			(type default)
		)
		(layer "In13.Cu")
	)
	(gr_line
		(start 122.228864 -292.393116)
		(end 122.227848 -292.393624)
		(stroke
			(width 0.05715)
			(type default)
		)
		(layer "In13.Cu")
	)
	(gr_line
		(start 122.228864 -290.773104)
		(end 122.227848 -290.773612)
		(stroke
			(width 0.05715)
			(type default)
		)
		(layer "In13.Cu")
	)
	(gr_line
		(start 122.228864 -289.799268)
		(end 122.230388 -289.800284)
		(stroke
			(width 0.05715)
			(type default)
		)
		(layer "In13.Cu")
	)
	(gr_line
		(start 122.228864 -289.153092)
		(end 122.227848 -289.1536)
		(stroke
			(width 0.05715)
			(type default)
		)
		(layer "In13.Cu")
	)
	(gr_line
		(start 122.228864 -285.913322)
		(end 122.227848 -285.91383)
		(stroke
			(width 0.05715)
			(type default)
		)
		(layer "In13.Cu")
	)
	(gr_line
		(start 122.228864 -284.29331)
		(end 122.227848 -284.293818)
		(stroke
			(width 0.05715)
			(type default)
		)
		(layer "In13.Cu")
	)
	(gr_line
		(start 122.228864 -282.673298)
		(end 122.227848 -282.673806)
		(stroke
			(width 0.05715)
			(type default)
		)
		(layer "In13.Cu")
	)
	(gr_line
		(start 122.228864 -281.699462)
		(end 122.230388 -281.700478)
		(stroke
			(width 0.05715)
			(type default)
		)
		(layer "In13.Cu")
	)
	(gr_line
		(start 122.232166 -294.661336)
		(end 122.233436 -294.662098)
		(stroke
			(width 0.05715)
			(type default)
		)
		(layer "In13.Cu")
	)
	(gr_line
		(start 122.232166 -293.041324)
		(end 122.233436 -293.042086)
		(stroke
			(width 0.05715)
			(type default)
		)
		(layer "In13.Cu")
	)
	(gr_line
		(start 122.232166 -289.8013)
		(end 122.233436 -289.802062)
		(stroke
			(width 0.05715)
			(type default)
		)
		(layer "In13.Cu")
	)
	(gr_line
		(start 122.232166 -281.701494)
		(end 122.233436 -281.702256)
		(stroke
			(width 0.05715)
			(type default)
		)
		(layer "In13.Cu")
	)
	(gr_line
		(start 122.234706 -294.66286)
		(end 122.236484 -294.663876)
		(stroke
			(width 0.05715)
			(type default)
		)
		(layer "In13.Cu")
	)
	(gr_line
		(start 122.234706 -293.042848)
		(end 122.236484 -293.043864)
		(stroke
			(width 0.05715)
			(type default)
		)
		(layer "In13.Cu")
	)
	(gr_line
		(start 122.234706 -289.802824)
		(end 122.236484 -289.80384)
		(stroke
			(width 0.05715)
			(type default)
		)
		(layer "In13.Cu")
	)
	(gr_line
		(start 122.234706 -281.703018)
		(end 122.236484 -281.704034)
		(stroke
			(width 0.05715)
			(type default)
		)
		(layer "In13.Cu")
	)
	(gr_line
		(start 122.255788 -398.4752)
		(end 121.759726 -397.979138)
		(stroke
			(width 0.07112)
			(type default)
		)
		(layer "In13.Cu")
	)
	(gr_line
		(start 122.293888 -401.837398)
		(end 121.797826 -401.341336)
		(stroke
			(width 0.07112)
			(type default)
		)
		(layer "In13.Cu")
	)
	(gr_line
		(start 122.317256 -354.105464)
		(end 122.81281 -353.609148)
		(stroke
			(width 0.07112)
			(type default)
		)
		(layer "In13.Cu")
	)
	(gr_line
		(start 122.319542 -295.146222)
		(end 122.319288 -295.146222)
		(stroke
			(width 0.05715)
			(type default)
		)
		(layer "In13.Cu")
	)
	(gr_line
		(start 122.367548 -351.723706)
		(end 122.386598 -351.53219)
		(stroke
			(width 0.07112)
			(type default)
		)
		(layer "In13.Cu")
	)
	(gr_line
		(start 122.386598 -351.53219)
		(end 122.716798 -351.261426)
		(stroke
			(width 0.07112)
			(type default)
		)
		(layer "In13.Cu")
	)
	(gr_line
		(start 122.414792 -273.276314)
		(end 122.712734 -273.276314)
		(stroke
			(width 0.05715)
			(type default)
		)
		(layer "In13.Cu")
	)
	(gr_line
		(start 122.414792 -271.656302)
		(end 122.712734 -271.656302)
		(stroke
			(width 0.05715)
			(type default)
		)
		(layer "In13.Cu")
	)
	(gr_line
		(start 122.414792 -270.03629)
		(end 122.712734 -270.03629)
		(stroke
			(width 0.05715)
			(type default)
		)
		(layer "In13.Cu")
	)
	(gr_line
		(start 122.419364 -353.410012)
		(end 122.611642 -353.409758)
		(stroke
			(width 0.07112)
			(type default)
		)
		(layer "In13.Cu")
	)
	(gr_line
		(start 122.455178 -398.274032)
		(end 122.455178 -398.081754)
		(stroke
			(width 0.07112)
			(type default)
		)
		(layer "In13.Cu")
	)
	(gr_line
		(start 122.455178 -398.081754)
		(end 122.153172 -397.779748)
		(stroke
			(width 0.07112)
			(type default)
		)
		(layer "In13.Cu")
	)
	(gr_line
		(start 122.493278 -401.63623)
		(end 122.493278 -401.443952)
		(stroke
			(width 0.07112)
			(type default)
		)
		(layer "In13.Cu")
	)
	(gr_line
		(start 122.493278 -401.443952)
		(end 122.191272 -401.141946)
		(stroke
			(width 0.07112)
			(type default)
		)
		(layer "In13.Cu")
	)
	(gr_line
		(start 122.510296 -295.146222)
		(end 122.510042 -295.146222)
		(stroke
			(width 0.05715)
			(type default)
		)
		(layer "In13.Cu")
	)
	(gr_line
		(start 122.54611 -351.943416)
		(end 123.088654 -351.498662)
		(stroke
			(width 0.07112)
			(type default)
		)
		(layer "In13.Cu")
	)
	(gr_line
		(start 122.548142 -399.868898)
		(end 122.355864 -399.868898)
		(stroke
			(width 0.07112)
			(type default)
		)
		(layer "In13.Cu")
	)
	(gr_line
		(start 122.575574 -396.279624)
		(end 122.575574 -395.578584)
		(stroke
			(width 0.07112)
			(type default)
		)
		(layer "In13.Cu")
	)
	(gr_line
		(start 122.575574 -395.151864)
		(end 122.575574 -394.450824)
		(stroke
			(width 0.07112)
			(type default)
		)
		(layer "In13.Cu")
	)
	(gr_line
		(start 122.597418 -270.36141)
		(end 122.595386 -270.36268)
		(stroke
			(width 0.05715)
			(type default)
		)
		(layer "In13.Cu")
	)
	(gr_line
		(start 122.599196 -270.360394)
		(end 122.597418 -270.36141)
		(stroke
			(width 0.05715)
			(type default)
		)
		(layer "In13.Cu")
	)
	(gr_line
		(start 122.60072 -270.359378)
		(end 122.599196 -270.360394)
		(stroke
			(width 0.05715)
			(type default)
		)
		(layer "In13.Cu")
	)
	(gr_line
		(start 122.601482 -270.35887)
		(end 122.60072 -270.359378)
		(stroke
			(width 0.05715)
			(type default)
		)
		(layer "In13.Cu")
	)
	(gr_line
		(start 122.602498 -295.634156)
		(end 122.603006 -295.63441)
		(stroke
			(width 0.05715)
			(type default)
		)
		(layer "In13.Cu")
	)
	(gr_line
		(start 122.605292 -295.63568)
		(end 122.606054 -295.636188)
		(stroke
			(width 0.05715)
			(type default)
		)
		(layer "In13.Cu")
	)
	(gr_line
		(start 122.606054 -295.636188)
		(end 122.607578 -295.63695)
		(stroke
			(width 0.05715)
			(type default)
		)
		(layer "In13.Cu")
	)
	(gr_line
		(start 122.607578 -295.63695)
		(end 122.60834 -295.637458)
		(stroke
			(width 0.05715)
			(type default)
		)
		(layer "In13.Cu")
	)
	(gr_line
		(start 122.60834 -295.637458)
		(end 122.609864 -295.63822)
		(stroke
			(width 0.05715)
			(type default)
		)
		(layer "In13.Cu")
	)
	(gr_line
		(start 122.650758 -400.56435)
		(end 122.154696 -400.068288)
		(stroke
			(width 0.07112)
			(type default)
		)
		(layer "In13.Cu")
	)
	(gr_line
		(start 122.691906 -270.527018)
		(end 122.691398 -270.527272)
		(stroke
			(width 0.05715)
			(type default)
		)
		(layer "In13.Cu")
	)
	(gr_line
		(start 122.69724 -295.468548)
		(end 122.697748 -295.468802)
		(stroke
			(width 0.05715)
			(type default)
		)
		(layer "In13.Cu")
	)
	(gr_line
		(start 122.697748 -295.468802)
		(end 122.698764 -295.46931)
		(stroke
			(width 0.05715)
			(type default)
		)
		(layer "In13.Cu")
	)
	(gr_line
		(start 122.698764 -295.46931)
		(end 122.700288 -295.470326)
		(stroke
			(width 0.05715)
			(type default)
		)
		(layer "In13.Cu")
	)
	(gr_line
		(start 122.700288 -295.470326)
		(end 122.701304 -295.470834)
		(stroke
			(width 0.05715)
			(type default)
		)
		(layer "In13.Cu")
	)
	(gr_line
		(start 122.701304 -295.470834)
		(end 122.703844 -295.472358)
		(stroke
			(width 0.05715)
			(type default)
		)
		(layer "In13.Cu")
	)
	(gr_line
		(start 122.703844 -295.472358)
		(end 122.705368 -295.473374)
		(stroke
			(width 0.05715)
			(type default)
		)
		(layer "In13.Cu")
	)
	(gr_line
		(start 122.705368 -295.473374)
		(end 122.7074 -295.474644)
		(stroke
			(width 0.05715)
			(type default)
		)
		(layer "In13.Cu")
	)
	(gr_line
		(start 122.712734 -273.276314)
		(end 122.795538 -273.359118)
		(stroke
			(width 0.05715)
			(type default)
		)
		(layer "In13.Cu")
	)
	(gr_line
		(start 122.712734 -271.656302)
		(end 122.795538 -271.739106)
		(stroke
			(width 0.05715)
			(type default)
		)
		(layer "In13.Cu")
	)
	(gr_line
		(start 122.712734 -270.03629)
		(end 122.782076 -270.105632)
		(stroke
			(width 0.05715)
			(type default)
		)
		(layer "In13.Cu")
	)
	(gr_line
		(start 122.716798 -351.261426)
		(end 122.908314 -351.280222)
		(stroke
			(width 0.07112)
			(type default)
		)
		(layer "In13.Cu")
	)
	(gr_line
		(start 122.75566 -357.000048)
		(end 123.4567 -357.000048)
		(stroke
			(width 0.07112)
			(type default)
		)
		(layer "In13.Cu")
	)
	(gr_line
		(start 122.75693 -356.716838)
		(end 122.89282 -356.580948)
		(stroke
			(width 0.07112)
			(type default)
		)
		(layer "In13.Cu")
	)
	(gr_arc
		(start 122.795538 -273.359118)
		(mid 122.797326 -273.370568)
		(end 122.799348 -273.381978)
		(stroke
			(width 0.05715)
			(type default)
		)
		(layer "In13.Cu")
	)
	(gr_arc
		(start 122.795538 -271.739106)
		(mid 122.797325 -271.750556)
		(end 122.799348 -271.761966)
		(stroke
			(width 0.05715)
			(type default)
		)
		(layer "In13.Cu")
	)
	(gr_line
		(start 122.83059 -296.926254)
		(end 122.83059 -296.926762)
		(stroke
			(width 0.07112)
			(type default)
		)
		(layer "In13.Cu")
	)
	(gr_line
		(start 122.83059 -296.584116)
		(end 122.83059 -296.612564)
		(stroke
			(width 0.05715)
			(type default)
		)
		(layer "In13.Cu")
	)
	(gr_line
		(start 122.843036 -412.02864)
		(end 122.842782 -412.028894)
		(stroke
			(width 0.07112)
			(type default)
		)
		(layer "In13.Cu")
	)
	(gr_line
		(start 122.850148 -400.363182)
		(end 122.850148 -400.170904)
		(stroke
			(width 0.07112)
			(type default)
		)
		(layer "In13.Cu")
	)
	(gr_line
		(start 122.850148 -400.170904)
		(end 122.548142 -399.868898)
		(stroke
			(width 0.07112)
			(type default)
		)
		(layer "In13.Cu")
	)
	(gr_line
		(start 122.858784 -396.278354)
		(end 122.994674 -396.142464)
		(stroke
			(width 0.07112)
			(type default)
		)
		(layer "In13.Cu")
	)
	(gr_line
		(start 122.858784 -395.150594)
		(end 122.994674 -395.014704)
		(stroke
			(width 0.07112)
			(type default)
		)
		(layer "In13.Cu")
	)
	(gr_line
		(start 122.87631 -296.538396)
		(end 122.83059 -296.584116)
		(stroke
			(width 0.05715)
			(type default)
		)
		(layer "In13.Cu")
	)
	(gr_line
		(start 122.89282 -356.580948)
		(end 123.31954 -356.580948)
		(stroke
			(width 0.07112)
			(type default)
		)
		(layer "In13.Cu")
	)
	(gr_line
		(start 122.91441 -352.91395)
		(end 123.216416 -352.611944)
		(stroke
			(width 0.07112)
			(type default)
		)
		(layer "In13.Cu")
	)
	(gr_line
		(start 122.914664 -353.106482)
		(end 122.91441 -352.91395)
		(stroke
			(width 0.07112)
			(type default)
		)
		(layer "In13.Cu")
	)
	(gr_line
		(start 122.950732 -398.577308)
		(end 122.758454 -398.577308)
		(stroke
			(width 0.07112)
			(type default)
		)
		(layer "In13.Cu")
	)
	(gr_arc
		(start 122.97029 -270.141954)
		(mid 122.972312 -270.130544)
		(end 122.9741 -270.119094)
		(stroke
			(width 0.05715)
			(type default)
		)
		(layer "In13.Cu")
	)
	(gr_line
		(start 122.988832 -401.939506)
		(end 122.796554 -401.939506)
		(stroke
			(width 0.07112)
			(type default)
		)
		(layer "In13.Cu")
	)
	(gr_line
		(start 122.994674 -396.142464)
		(end 122.994674 -395.715744)
		(stroke
			(width 0.07112)
			(type default)
		)
		(layer "In13.Cu")
	)
	(gr_line
		(start 122.994674 -395.715744)
		(end 122.858784 -395.579854)
		(stroke
			(width 0.07112)
			(type default)
		)
		(layer "In13.Cu")
	)
	(gr_line
		(start 122.994674 -395.014704)
		(end 122.994674 -394.587984)
		(stroke
			(width 0.07112)
			(type default)
		)
		(layer "In13.Cu")
	)
	(gr_line
		(start 122.994674 -394.587984)
		(end 122.858784 -394.452094)
		(stroke
			(width 0.07112)
			(type default)
		)
		(layer "In13.Cu")
	)
	(gr_arc
		(start 123.022106 -288.313368)
		(mid 123.025272 -288.315666)
		(end 123.028456 -288.31794)
		(stroke
			(width 0.05715)
			(type default)
		)
		(layer "In13.Cu")
	)
	(gr_arc
		(start 123.0249 -283.455364)
		(mid 123.028825 -283.458175)
		(end 123.032774 -283.460952)
		(stroke
			(width 0.05715)
			(type default)
		)
		(layer "In13.Cu")
	)
	(gr_arc
		(start 123.029218 -288.318448)
		(mid 123.030994 -288.319721)
		(end 123.032774 -288.320988)
		(stroke
			(width 0.05715)
			(type default)
		)
		(layer "In13.Cu")
	)
	(gr_line
		(start 123.032774 -288.320988)
		(end 123.03887 -288.324544)
		(stroke
			(width 0.05715)
			(type default)
		)
		(layer "In13.Cu")
	)
	(gr_line
		(start 123.032774 -283.460952)
		(end 123.039632 -283.465016)
		(stroke
			(width 0.05715)
			(type default)
		)
		(layer "In13.Cu")
	)
	(gr_arc
		(start 123.032774 -280.911808)
		(mid 123.028825 -280.914585)
		(end 123.0249 -280.917396)
		(stroke
			(width 0.05715)
			(type default)
		)
		(layer "In13.Cu")
	)
	(gr_line
		(start 123.033282 -280.911554)
		(end 123.032774 -280.911808)
		(stroke
			(width 0.05715)
			(type default)
		)
		(layer "In13.Cu")
	)
	(gr_line
		(start 123.03887 -288.324544)
		(end 123.039124 -288.324544)
		(stroke
			(width 0.05715)
			(type default)
		)
		(layer "In13.Cu")
	)
	(gr_line
		(start 123.039632 -283.465016)
		(end 123.040394 -283.465524)
		(stroke
			(width 0.05715)
			(type default)
		)
		(layer "In13.Cu")
	)
	(gr_line
		(start 123.040394 -283.465524)
		(end 123.041156 -283.466032)
		(stroke
			(width 0.05715)
			(type default)
		)
		(layer "In13.Cu")
	)
	(gr_line
		(start 123.040394 -280.907236)
		(end 123.033282 -280.911554)
		(stroke
			(width 0.05715)
			(type default)
		)
		(layer "In13.Cu")
	)
	(gr_line
		(start 123.053348 -399.27276)
		(end 122.557286 -398.776698)
		(stroke
			(width 0.07112)
			(type default)
		)
		(layer "In13.Cu")
	)
	(gr_line
		(start 123.056904 -273.276314)
		(end 122.987562 -273.345656)
		(stroke
			(width 0.05715)
			(type default)
		)
		(layer "In13.Cu")
	)
	(gr_line
		(start 123.056904 -271.656302)
		(end 122.987562 -271.725644)
		(stroke
			(width 0.05715)
			(type default)
		)
		(layer "In13.Cu")
	)
	(gr_line
		(start 123.056904 -270.03629)
		(end 122.9741 -270.119094)
		(stroke
			(width 0.05715)
			(type default)
		)
		(layer "In13.Cu")
	)
	(gr_line
		(start 123.06681 -296.538396)
		(end 123.11253 -296.584116)
		(stroke
			(width 0.05715)
			(type default)
		)
		(layer "In13.Cu")
	)
	(gr_line
		(start 123.072652 -291.584126)
		(end 123.073922 -291.584888)
		(stroke
			(width 0.05715)
			(type default)
		)
		(layer "In13.Cu")
	)
	(gr_line
		(start 123.074684 -293.205408)
		(end 123.075192 -293.205408)
		(stroke
			(width 0.05715)
			(type default)
		)
		(layer "In13.Cu")
	)
	(gr_line
		(start 123.074684 -289.965384)
		(end 123.075192 -289.965384)
		(stroke
			(width 0.05715)
			(type default)
		)
		(layer "In13.Cu")
	)
	(gr_line
		(start 123.074684 -285.105602)
		(end 123.075192 -285.105602)
		(stroke
			(width 0.05715)
			(type default)
		)
		(layer "In13.Cu")
	)
	(gr_line
		(start 123.074684 -283.48559)
		(end 123.075192 -283.48559)
		(stroke
			(width 0.05715)
			(type default)
		)
		(layer "In13.Cu")
	)
	(gr_line
		(start 123.074684 -281.865578)
		(end 123.075192 -281.865578)
		(stroke
			(width 0.05715)
			(type default)
		)
		(layer "In13.Cu")
	)
	(gr_line
		(start 123.074938 -288.345372)
		(end 123.075192 -288.345372)
		(stroke
			(width 0.05715)
			(type default)
		)
		(layer "In13.Cu")
	)
	(gr_line
		(start 123.091448 -402.634958)
		(end 122.595386 -402.138896)
		(stroke
			(width 0.07112)
			(type default)
		)
		(layer "In13.Cu")
	)
	(gr_arc
		(start 123.093988 -411.87243)
		(mid 123.094242 -411.873065)
		(end 123.094496 -411.8737)
		(stroke
			(width 0.07112)
			(type default)
		)
		(layer "In13.Cu")
	)
	(gr_line
		(start 123.11253 -296.584116)
		(end 123.11253 -296.612564)
		(stroke
			(width 0.05715)
			(type default)
		)
		(layer "In13.Cu")
	)
	(gr_line
		(start 123.113038 -296.98442)
		(end 123.113038 -296.984928)
		(stroke
			(width 0.07112)
			(type default)
		)
		(layer "In13.Cu")
	)
	(gr_line
		(start 123.114308 -353.307396)
		(end 123.609862 -352.81108)
		(stroke
			(width 0.07112)
			(type default)
		)
		(layer "In13.Cu")
	)
	(gr_line
		(start 123.167394 -294.658542)
		(end 123.167902 -294.658796)
		(stroke
			(width 0.05715)
			(type default)
		)
		(layer "In13.Cu")
	)
	(gr_line
		(start 123.167394 -293.03853)
		(end 123.167902 -293.038784)
		(stroke
			(width 0.05715)
			(type default)
		)
		(layer "In13.Cu")
	)
	(gr_line
		(start 123.167394 -291.418518)
		(end 123.167902 -291.418772)
		(stroke
			(width 0.05715)
			(type default)
		)
		(layer "In13.Cu")
	)
	(gr_line
		(start 123.167394 -289.798506)
		(end 123.167902 -289.79876)
		(stroke
			(width 0.05715)
			(type default)
		)
		(layer "In13.Cu")
	)
	(gr_line
		(start 123.167394 -284.938724)
		(end 123.167902 -284.938978)
		(stroke
			(width 0.05715)
			(type default)
		)
		(layer "In13.Cu")
	)
	(gr_line
		(start 123.167394 -281.6987)
		(end 123.167902 -281.698954)
		(stroke
			(width 0.05715)
			(type default)
		)
		(layer "In13.Cu")
	)
	(gr_line
		(start 123.167648 -292.393878)
		(end 123.162314 -292.396926)
		(stroke
			(width 0.05715)
			(type default)
		)
		(layer "In13.Cu")
	)
	(gr_line
		(start 123.167902 -294.658796)
		(end 123.171966 -294.661336)
		(stroke
			(width 0.05715)
			(type default)
		)
		(layer "In13.Cu")
	)
	(gr_line
		(start 123.167902 -293.038784)
		(end 123.17095 -293.040562)
		(stroke
			(width 0.05715)
			(type default)
		)
		(layer "In13.Cu")
	)
	(gr_line
		(start 123.167902 -291.418772)
		(end 123.167902 -291.419026)
		(stroke
			(width 0.05715)
			(type default)
		)
		(layer "In13.Cu")
	)
	(gr_line
		(start 123.167902 -289.79876)
		(end 123.17095 -289.800538)
		(stroke
			(width 0.05715)
			(type default)
		)
		(layer "In13.Cu")
	)
	(gr_line
		(start 123.167902 -284.938978)
		(end 123.17095 -284.940756)
		(stroke
			(width 0.05715)
			(type default)
		)
		(layer "In13.Cu")
	)
	(gr_line
		(start 123.167902 -283.318966)
		(end 123.17095 -283.320744)
		(stroke
			(width 0.05715)
			(type default)
		)
		(layer "In13.Cu")
	)
	(gr_line
		(start 123.167902 -281.698954)
		(end 123.17095 -281.700732)
		(stroke
			(width 0.05715)
			(type default)
		)
		(layer "In13.Cu")
	)
	(gr_line
		(start 123.17095 -294.011858)
		(end 123.167394 -294.01389)
		(stroke
			(width 0.05715)
			(type default)
		)
		(layer "In13.Cu")
	)
	(gr_line
		(start 123.17095 -290.771834)
		(end 123.167394 -290.773866)
		(stroke
			(width 0.05715)
			(type default)
		)
		(layer "In13.Cu")
	)
	(gr_line
		(start 123.17095 -289.151822)
		(end 123.167394 -289.153854)
		(stroke
			(width 0.05715)
			(type default)
		)
		(layer "In13.Cu")
	)
	(gr_line
		(start 123.17095 -285.912052)
		(end 123.167394 -285.914084)
		(stroke
			(width 0.05715)
			(type default)
		)
		(layer "In13.Cu")
	)
	(gr_line
		(start 123.17095 -284.29204)
		(end 123.167394 -284.294072)
		(stroke
			(width 0.05715)
			(type default)
		)
		(layer "In13.Cu")
	)
	(gr_line
		(start 123.17095 -282.672028)
		(end 123.167394 -282.67406)
		(stroke
			(width 0.05715)
			(type default)
		)
		(layer "In13.Cu")
	)
	(gr_line
		(start 123.177046 -392.707622)
		(end 123.189492 -392.707622)
		(stroke
			(width 0.07112)
			(type default)
		)
		(layer "In13.Cu")
	)
	(gr_line
		(start 123.178316 -392.990832)
		(end 123.316492 -393.129008)
		(stroke
			(width 0.07112)
			(type default)
		)
		(layer "In13.Cu")
	)
	(gr_line
		(start 123.189492 -392.707622)
		(end 123.316492 -392.580622)
		(stroke
			(width 0.07112)
			(type default)
		)
		(layer "In13.Cu")
	)
	(gr_line
		(start 123.216416 -352.611944)
		(end 123.408948 -352.61169)
		(stroke
			(width 0.07112)
			(type default)
		)
		(layer "In13.Cu")
	)
	(gr_line
		(start 123.252738 -399.071846)
		(end 123.252738 -398.879314)
		(stroke
			(width 0.07112)
			(type default)
		)
		(layer "In13.Cu")
	)
	(gr_line
		(start 123.252738 -398.879314)
		(end 122.950732 -398.577308)
		(stroke
			(width 0.07112)
			(type default)
		)
		(layer "In13.Cu")
	)
	(gr_line
		(start 123.259596 -295.146222)
		(end 123.259342 -295.146222)
		(stroke
			(width 0.05715)
			(type default)
		)
		(layer "In13.Cu")
	)
	(gr_line
		(start 123.290838 -402.43379)
		(end 123.290838 -402.241512)
		(stroke
			(width 0.07112)
			(type default)
		)
		(layer "In13.Cu")
	)
	(gr_line
		(start 123.290838 -402.241512)
		(end 122.988832 -401.939506)
		(stroke
			(width 0.07112)
			(type default)
		)
		(layer "In13.Cu")
	)
	(gr_line
		(start 123.316492 -393.129008)
		(end 123.316492 -393.292838)
		(stroke
			(width 0.07112)
			(type default)
		)
		(layer "In13.Cu")
	)
	(gr_line
		(start 123.316492 -392.580622)
		(end 123.316492 -392.429238)
		(stroke
			(width 0.07112)
			(type default)
		)
		(layer "In13.Cu")
	)
	(gr_line
		(start 123.31954 -356.580948)
		(end 123.45543 -356.716838)
		(stroke
			(width 0.07112)
			(type default)
		)
		(layer "In13.Cu")
	)
	(gr_line
		(start 123.345702 -400.666458)
		(end 123.153424 -400.666458)
		(stroke
			(width 0.07112)
			(type default)
		)
		(layer "In13.Cu")
	)
	(gr_line
		(start 123.353068 -397.38808)
		(end 123.16079 -397.38808)
		(stroke
			(width 0.07112)
			(type default)
		)
		(layer "In13.Cu")
	)
	(gr_line
		(start 123.354846 -273.276314)
		(end 123.056904 -273.276314)
		(stroke
			(width 0.05715)
			(type default)
		)
		(layer "In13.Cu")
	)
	(gr_line
		(start 123.354846 -271.656302)
		(end 123.056904 -271.656302)
		(stroke
			(width 0.05715)
			(type default)
		)
		(layer "In13.Cu")
	)
	(gr_line
		(start 123.354846 -270.03629)
		(end 123.056904 -270.03629)
		(stroke
			(width 0.05715)
			(type default)
		)
		(layer "In13.Cu")
	)
	(gr_line
		(start 123.355354 -350.913954)
		(end 123.37415 -350.722438)
		(stroke
			(width 0.07112)
			(type default)
		)
		(layer "In13.Cu")
	)
	(gr_line
		(start 123.37415 -350.722438)
		(end 123.70435 -350.451674)
		(stroke
			(width 0.07112)
			(type default)
		)
		(layer "In13.Cu")
	)
	(gr_line
		(start 123.399804 -328.721466)
		(end 123.39955 -328.721466)
		(stroke
			(width 0.07112)
			(type default)
		)
		(layer "In13.Cu")
	)
	(gr_line
		(start 123.448318 -401.36191)
		(end 122.952256 -400.865848)
		(stroke
			(width 0.07112)
			(type default)
		)
		(layer "In13.Cu")
	)
	(gr_line
		(start 123.455684 -398.083532)
		(end 122.959622 -397.58747)
		(stroke
			(width 0.07112)
			(type default)
		)
		(layer "In13.Cu")
	)
	(gr_line
		(start 123.533916 -351.133664)
		(end 124.076206 -350.689164)
		(stroke
			(width 0.07112)
			(type default)
		)
		(layer "In13.Cu")
	)
	(gr_line
		(start 123.541282 -272.95348)
		(end 123.54179 -272.953734)
		(stroke
			(width 0.05715)
			(type default)
		)
		(layer "In13.Cu")
	)
	(gr_line
		(start 123.54179 -272.953734)
		(end 123.542552 -272.954242)
		(stroke
			(width 0.05715)
			(type default)
		)
		(layer "In13.Cu")
	)
	(gr_line
		(start 123.637294 -295.468548)
		(end 123.637802 -295.468802)
		(stroke
			(width 0.05715)
			(type default)
		)
		(layer "In13.Cu")
	)
	(gr_line
		(start 123.647708 -401.160742)
		(end 123.647708 -400.968464)
		(stroke
			(width 0.07112)
			(type default)
		)
		(layer "In13.Cu")
	)
	(gr_line
		(start 123.647708 -400.968464)
		(end 123.345702 -400.666458)
		(stroke
			(width 0.07112)
			(type default)
		)
		(layer "In13.Cu")
	)
	(gr_line
		(start 123.655074 -397.882364)
		(end 123.655074 -397.690086)
		(stroke
			(width 0.07112)
			(type default)
		)
		(layer "In13.Cu")
	)
	(gr_line
		(start 123.655074 -397.690086)
		(end 123.353068 -397.38808)
		(stroke
			(width 0.07112)
			(type default)
		)
		(layer "In13.Cu")
	)
	(gr_line
		(start 123.70435 -350.451674)
		(end 123.895866 -350.470724)
		(stroke
			(width 0.07112)
			(type default)
		)
		(layer "In13.Cu")
	)
	(gr_line
		(start 123.748292 -399.374868)
		(end 123.55576 -399.374868)
		(stroke
			(width 0.07112)
			(type default)
		)
		(layer "In13.Cu")
	)
	(gr_line
		(start 123.775724 -396.299944)
		(end 123.775724 -395.598904)
		(stroke
			(width 0.07112)
			(type default)
		)
		(layer "In13.Cu")
	)
	(gr_line
		(start 123.775724 -395.172184)
		(end 123.775724 -394.471144)
		(stroke
			(width 0.07112)
			(type default)
		)
		(layer "In13.Cu")
	)
	(gr_line
		(start 123.850908 -400.07032)
		(end 123.354846 -399.574258)
		(stroke
			(width 0.07112)
			(type default)
		)
		(layer "In13.Cu")
	)
	(gr_line
		(start 123.92787 -296.838116)
		(end 123.92787 -296.866564)
		(stroke
			(width 0.05715)
			(type default)
		)
		(layer "In13.Cu")
	)
	(gr_arc
		(start 123.971304 -280.912824)
		(mid 123.968887 -280.914596)
		(end 123.966478 -280.91638)
		(stroke
			(width 0.05715)
			(type default)
		)
		(layer "In13.Cu")
	)
	(gr_line
		(start 123.97359 -296.792396)
		(end 123.92787 -296.838116)
		(stroke
			(width 0.05715)
			(type default)
		)
		(layer "In13.Cu")
	)
	(gr_line
		(start 124.01169 -280.243788)
		(end 124.012198 -280.244042)
		(stroke
			(width 0.05715)
			(type default)
		)
		(layer "In13.Cu")
	)
	(gr_line
		(start 124.043186 -275.40204)
		(end 124.04344 -275.40204)
		(stroke
			(width 0.05715)
			(type default)
		)
		(layer "In13.Cu")
	)
	(gr_line
		(start 124.050298 -399.869406)
		(end 124.050298 -399.676874)
		(stroke
			(width 0.07112)
			(type default)
		)
		(layer "In13.Cu")
	)
	(gr_line
		(start 124.050298 -399.676874)
		(end 123.748292 -399.374868)
		(stroke
			(width 0.07112)
			(type default)
		)
		(layer "In13.Cu")
	)
	(gr_line
		(start 124.058934 -396.298674)
		(end 124.194824 -396.162784)
		(stroke
			(width 0.07112)
			(type default)
		)
		(layer "In13.Cu")
	)
	(gr_line
		(start 124.058934 -395.170914)
		(end 124.194824 -395.035024)
		(stroke
			(width 0.07112)
			(type default)
		)
		(layer "In13.Cu")
	)
	(gr_line
		(start 124.150628 -398.18564)
		(end 123.95835 -398.18564)
		(stroke
			(width 0.07112)
			(type default)
		)
		(layer "In13.Cu")
	)
	(gr_line
		(start 124.16409 -296.792396)
		(end 124.20981 -296.838116)
		(stroke
			(width 0.05715)
			(type default)
		)
		(layer "In13.Cu")
	)
	(gr_line
		(start 124.194824 -396.162784)
		(end 124.194824 -395.736064)
		(stroke
			(width 0.07112)
			(type default)
		)
		(layer "In13.Cu")
	)
	(gr_line
		(start 124.194824 -395.736064)
		(end 124.058934 -395.600174)
		(stroke
			(width 0.07112)
			(type default)
		)
		(layer "In13.Cu")
	)
	(gr_line
		(start 124.194824 -395.035024)
		(end 124.194824 -394.608304)
		(stroke
			(width 0.07112)
			(type default)
		)
		(layer "In13.Cu")
	)
	(gr_line
		(start 124.194824 -394.608304)
		(end 124.058934 -394.472414)
		(stroke
			(width 0.07112)
			(type default)
		)
		(layer "In13.Cu")
	)
	(gr_line
		(start 124.20981 -296.866056)
		(end 124.210318 -296.866564)
		(stroke
			(width 0.05715)
			(type default)
		)
		(layer "In13.Cu")
	)
	(gr_line
		(start 124.20981 -296.838116)
		(end 124.20981 -296.866056)
		(stroke
			(width 0.05715)
			(type default)
		)
		(layer "In13.Cu")
	)
	(gr_line
		(start 124.210318 -296.885614)
		(end 124.210318 -296.886122)
		(stroke
			(width 0.07112)
			(type default)
		)
		(layer "In13.Cu")
	)
	(gr_line
		(start 124.253244 -398.881092)
		(end 123.757436 -398.385284)
		(stroke
			(width 0.07112)
			(type default)
		)
		(layer "In13.Cu")
	)
	(gr_line
		(start 124.374656 -409.527502)
		(end 124.374656 -408.826462)
		(stroke
			(width 0.07112)
			(type default)
		)
		(layer "In13.Cu")
	)
	(gr_line
		(start 124.374656 -408.399742)
		(end 124.374656 -407.698702)
		(stroke
			(width 0.07112)
			(type default)
		)
		(layer "In13.Cu")
	)
	(gr_line
		(start 124.377196 -392.707622)
		(end 124.389642 -392.707622)
		(stroke
			(width 0.07112)
			(type default)
		)
		(layer "In13.Cu")
	)
	(gr_line
		(start 124.378466 -392.990832)
		(end 124.516642 -393.129008)
		(stroke
			(width 0.07112)
			(type default)
		)
		(layer "In13.Cu")
	)
	(gr_line
		(start 124.389642 -392.707622)
		(end 124.516642 -392.580622)
		(stroke
			(width 0.07112)
			(type default)
		)
		(layer "In13.Cu")
	)
	(gr_line
		(start 124.40539 -325.00951)
		(end 124.405644 -325.00951)
		(stroke
			(width 0.07112)
			(type default)
		)
		(layer "In13.Cu")
	)
	(gr_line
		(start 124.421646 -331.71892)
		(end 124.421646 -331.718666)
		(stroke
			(width 0.07112)
			(type default)
		)
		(layer "In13.Cu")
	)
	(gr_line
		(start 124.452634 -398.679924)
		(end 124.452634 -398.487646)
		(stroke
			(width 0.07112)
			(type default)
		)
		(layer "In13.Cu")
	)
	(gr_line
		(start 124.452634 -398.487646)
		(end 124.150628 -398.18564)
		(stroke
			(width 0.07112)
			(type default)
		)
		(layer "In13.Cu")
	)
	(gr_line
		(start 124.516642 -393.129008)
		(end 124.516642 -393.292838)
		(stroke
			(width 0.07112)
			(type default)
		)
		(layer "In13.Cu")
	)
	(gr_line
		(start 124.516642 -392.580622)
		(end 124.516642 -392.429238)
		(stroke
			(width 0.07112)
			(type default)
		)
		(layer "In13.Cu")
	)
	(gr_line
		(start 124.553218 -397.028162)
		(end 124.36094 -397.028162)
		(stroke
			(width 0.07112)
			(type default)
		)
		(layer "In13.Cu")
	)
	(gr_line
		(start 124.625862 -400.252438)
		(end 124.43333 -400.252438)
		(stroke
			(width 0.07112)
			(type default)
		)
		(layer "In13.Cu")
	)
	(gr_line
		(start 124.645674 -400.86534)
		(end 124.232416 -400.451828)
		(stroke
			(width 0.07112)
			(type default)
		)
		(layer "In13.Cu")
	)
	(gr_line
		(start 124.645928 -400.86534)
		(end 124.645674 -400.86534)
		(stroke
			(width 0.07112)
			(type default)
		)
		(layer "In13.Cu")
	)
	(gr_line
		(start 124.652532 -414.268158)
		(end 124.474986 -414.341818)
		(stroke
			(width 0.07112)
			(type default)
		)
		(layer "In13.Cu")
	)
	(gr_line
		(start 124.655834 -397.723614)
		(end 124.159772 -397.227552)
		(stroke
			(width 0.07112)
			(type default)
		)
		(layer "In13.Cu")
	)
	(gr_line
		(start 124.657866 -409.526232)
		(end 124.793756 -409.390342)
		(stroke
			(width 0.07112)
			(type default)
		)
		(layer "In13.Cu")
	)
	(gr_line
		(start 124.657866 -408.398472)
		(end 124.793756 -408.262582)
		(stroke
			(width 0.07112)
			(type default)
		)
		(layer "In13.Cu")
	)
	(gr_line
		(start 124.66955 -295.956228)
		(end 124.669296 -295.956482)
		(stroke
			(width 0.05715)
			(type default)
		)
		(layer "In13.Cu")
	)
	(gr_line
		(start 124.728478 -400.94789)
		(end 124.645928 -400.86534)
		(stroke
			(width 0.07112)
			(type default)
		)
		(layer "In13.Cu")
	)
	(gr_line
		(start 124.793756 -409.390342)
		(end 124.793756 -408.963622)
		(stroke
			(width 0.07112)
			(type default)
		)
		(layer "In13.Cu")
	)
	(gr_line
		(start 124.793756 -408.963622)
		(end 124.657866 -408.827732)
		(stroke
			(width 0.07112)
			(type default)
		)
		(layer "In13.Cu")
	)
	(gr_line
		(start 124.793756 -408.262582)
		(end 124.793756 -407.835862)
		(stroke
			(width 0.07112)
			(type default)
		)
		(layer "In13.Cu")
	)
	(gr_line
		(start 124.793756 -407.835862)
		(end 124.657866 -407.699972)
		(stroke
			(width 0.07112)
			(type default)
		)
		(layer "In13.Cu")
	)
	(gr_line
		(start 124.855224 -397.522446)
		(end 124.855224 -397.330168)
		(stroke
			(width 0.07112)
			(type default)
		)
		(layer "In13.Cu")
	)
	(gr_line
		(start 124.855224 -397.330168)
		(end 124.553218 -397.028162)
		(stroke
			(width 0.07112)
			(type default)
		)
		(layer "In13.Cu")
	)
	(gr_line
		(start 124.86005 -296.128948)
		(end 124.859796 -296.128948)
		(stroke
			(width 0.05715)
			(type default)
		)
		(layer "In13.Cu")
	)
	(gr_line
		(start 124.87275 -296.838116)
		(end 124.87275 -296.866564)
		(stroke
			(width 0.05715)
			(type default)
		)
		(layer "In13.Cu")
	)
	(gr_arc
		(start 124.904754 -294.795194)
		(mid 124.908679 -294.798005)
		(end 124.912628 -294.800782)
		(stroke
			(width 0.05715)
			(type default)
		)
		(layer "In13.Cu")
	)
	(gr_arc
		(start 124.904754 -293.175182)
		(mid 124.908679 -293.177993)
		(end 124.912628 -293.18077)
		(stroke
			(width 0.05715)
			(type default)
		)
		(layer "In13.Cu")
	)
	(gr_arc
		(start 124.904754 -289.935158)
		(mid 124.908679 -289.937969)
		(end 124.912628 -289.940746)
		(stroke
			(width 0.05715)
			(type default)
		)
		(layer "In13.Cu")
	)
	(gr_arc
		(start 124.904754 -281.835352)
		(mid 124.908679 -281.838163)
		(end 124.912628 -281.84094)
		(stroke
			(width 0.05715)
			(type default)
		)
		(layer "In13.Cu")
	)
	(gr_arc
		(start 124.904754 -278.595328)
		(mid 124.908679 -278.598139)
		(end 124.912628 -278.600916)
		(stroke
			(width 0.05715)
			(type default)
		)
		(layer "In13.Cu")
	)
	(gr_arc
		(start 124.904754 -276.975316)
		(mid 124.908679 -276.978127)
		(end 124.912628 -276.980904)
		(stroke
			(width 0.05715)
			(type default)
		)
		(layer "In13.Cu")
	)
	(gr_arc
		(start 124.904754 -275.355304)
		(mid 124.908679 -275.358115)
		(end 124.912628 -275.360892)
		(stroke
			(width 0.05715)
			(type default)
		)
		(layer "In13.Cu")
	)
	(gr_arc
		(start 124.904754 -273.735292)
		(mid 124.908679 -273.738103)
		(end 124.912628 -273.74088)
		(stroke
			(width 0.05715)
			(type default)
		)
		(layer "In13.Cu")
	)
	(gr_arc
		(start 124.904754 -272.11528)
		(mid 124.908679 -272.118091)
		(end 124.912628 -272.120868)
		(stroke
			(width 0.05715)
			(type default)
		)
		(layer "In13.Cu")
	)
	(gr_line
		(start 124.912628 -294.800782)
		(end 124.919486 -294.804846)
		(stroke
			(width 0.05715)
			(type default)
		)
		(layer "In13.Cu")
	)
	(gr_line
		(start 124.912628 -293.18077)
		(end 124.919486 -293.184834)
		(stroke
			(width 0.05715)
			(type default)
		)
		(layer "In13.Cu")
	)
	(gr_line
		(start 124.912628 -289.940746)
		(end 124.919486 -289.94481)
		(stroke
			(width 0.05715)
			(type default)
		)
		(layer "In13.Cu")
	)
	(gr_line
		(start 124.912628 -281.84094)
		(end 124.919486 -281.845004)
		(stroke
			(width 0.05715)
			(type default)
		)
		(layer "In13.Cu")
	)
	(gr_arc
		(start 124.912628 -280.911808)
		(mid 124.908679 -280.914585)
		(end 124.904754 -280.917396)
		(stroke
			(width 0.05715)
			(type default)
		)
		(layer "In13.Cu")
	)
	(gr_line
		(start 124.912628 -278.600916)
		(end 124.919486 -278.60498)
		(stroke
			(width 0.05715)
			(type default)
		)
		(layer "In13.Cu")
	)
	(gr_line
		(start 124.912628 -276.980904)
		(end 124.919486 -276.984968)
		(stroke
			(width 0.05715)
			(type default)
		)
		(layer "In13.Cu")
	)
	(gr_line
		(start 124.912628 -275.360892)
		(end 124.919486 -275.364956)
		(stroke
			(width 0.05715)
			(type default)
		)
		(layer "In13.Cu")
	)
	(gr_line
		(start 124.912628 -273.74088)
		(end 124.919486 -273.744944)
		(stroke
			(width 0.05715)
			(type default)
		)
		(layer "In13.Cu")
	)
	(gr_line
		(start 124.912628 -272.120868)
		(end 124.919486 -272.124932)
		(stroke
			(width 0.05715)
			(type default)
		)
		(layer "In13.Cu")
	)
	(gr_line
		(start 124.915422 -280.909776)
		(end 124.912628 -280.911808)
		(stroke
			(width 0.05715)
			(type default)
		)
		(layer "In13.Cu")
	)
	(gr_line
		(start 124.91847 -296.792396)
		(end 124.87275 -296.838116)
		(stroke
			(width 0.05715)
			(type default)
		)
		(layer "In13.Cu")
	)
	(gr_line
		(start 124.919486 -294.804846)
		(end 124.920248 -294.805354)
		(stroke
			(width 0.05715)
			(type default)
		)
		(layer "In13.Cu")
	)
	(gr_line
		(start 124.919486 -293.184834)
		(end 124.920248 -293.185342)
		(stroke
			(width 0.05715)
			(type default)
		)
		(layer "In13.Cu")
	)
	(gr_line
		(start 124.919486 -289.94481)
		(end 124.920248 -289.945318)
		(stroke
			(width 0.05715)
			(type default)
		)
		(layer "In13.Cu")
	)
	(gr_line
		(start 124.919486 -281.845004)
		(end 124.920248 -281.845512)
		(stroke
			(width 0.05715)
			(type default)
		)
		(layer "In13.Cu")
	)
	(gr_line
		(start 124.919486 -278.60498)
		(end 124.920248 -278.605488)
		(stroke
			(width 0.05715)
			(type default)
		)
		(layer "In13.Cu")
	)
	(gr_line
		(start 124.919486 -276.984968)
		(end 124.920248 -276.985476)
		(stroke
			(width 0.05715)
			(type default)
		)
		(layer "In13.Cu")
	)
	(gr_line
		(start 124.919486 -275.364956)
		(end 124.920248 -275.365464)
		(stroke
			(width 0.05715)
			(type default)
		)
		(layer "In13.Cu")
	)
	(gr_line
		(start 124.919486 -273.744944)
		(end 124.920248 -273.745452)
		(stroke
			(width 0.05715)
			(type default)
		)
		(layer "In13.Cu")
	)
	(gr_line
		(start 124.919486 -272.124932)
		(end 124.920248 -272.12544)
		(stroke
			(width 0.05715)
			(type default)
		)
		(layer "In13.Cu")
	)
	(gr_line
		(start 124.920248 -294.805354)
		(end 124.92101 -294.805862)
		(stroke
			(width 0.05715)
			(type default)
		)
		(layer "In13.Cu")
	)
	(gr_line
		(start 124.920248 -293.185342)
		(end 124.92101 -293.18585)
		(stroke
			(width 0.05715)
			(type default)
		)
		(layer "In13.Cu")
	)
	(gr_line
		(start 124.920248 -289.945318)
		(end 124.92101 -289.945826)
		(stroke
			(width 0.05715)
			(type default)
		)
		(layer "In13.Cu")
	)
	(gr_line
		(start 124.920248 -281.845512)
		(end 124.92101 -281.84602)
		(stroke
			(width 0.05715)
			(type default)
		)
		(layer "In13.Cu")
	)
	(gr_line
		(start 124.920248 -278.605488)
		(end 124.92101 -278.605996)
		(stroke
			(width 0.05715)
			(type default)
		)
		(layer "In13.Cu")
	)
	(gr_line
		(start 124.920248 -276.985476)
		(end 124.92101 -276.985984)
		(stroke
			(width 0.05715)
			(type default)
		)
		(layer "In13.Cu")
	)
	(gr_line
		(start 124.920248 -275.365464)
		(end 124.92101 -275.365972)
		(stroke
			(width 0.05715)
			(type default)
		)
		(layer "In13.Cu")
	)
	(gr_line
		(start 124.920248 -273.745452)
		(end 124.92101 -273.74596)
		(stroke
			(width 0.05715)
			(type default)
		)
		(layer "In13.Cu")
	)
	(gr_line
		(start 124.920248 -272.12544)
		(end 124.92101 -272.125948)
		(stroke
			(width 0.05715)
			(type default)
		)
		(layer "In13.Cu")
	)
	(gr_line
		(start 124.920756 -280.906728)
		(end 124.915422 -280.909776)
		(stroke
			(width 0.05715)
			(type default)
		)
		(layer "In13.Cu")
	)
	(gr_line
		(start 124.927868 -400.746722)
		(end 124.927868 -400.554444)
		(stroke
			(width 0.07112)
			(type default)
		)
		(layer "In13.Cu")
	)
	(gr_line
		(start 124.927868 -400.554444)
		(end 124.625862 -400.252438)
		(stroke
			(width 0.07112)
			(type default)
		)
		(layer "In13.Cu")
	)
	(gr_line
		(start 124.946156 -279.272238)
		(end 124.945394 -279.272746)
		(stroke
			(width 0.05715)
			(type default)
		)
		(layer "In13.Cu")
	)
	(gr_line
		(start 124.946156 -277.652226)
		(end 124.945394 -277.652734)
		(stroke
			(width 0.05715)
			(type default)
		)
		(layer "In13.Cu")
	)
	(gr_line
		(start 124.946156 -276.032214)
		(end 124.945394 -276.032722)
		(stroke
			(width 0.05715)
			(type default)
		)
		(layer "In13.Cu")
	)
	(gr_line
		(start 124.946156 -274.412202)
		(end 124.945394 -274.41271)
		(stroke
			(width 0.05715)
			(type default)
		)
		(layer "In13.Cu")
	)
	(gr_line
		(start 124.946156 -272.79219)
		(end 124.945394 -272.792698)
		(stroke
			(width 0.05715)
			(type default)
		)
		(layer "In13.Cu")
	)
	(gr_line
		(start 124.946156 -271.172178)
		(end 124.945394 -271.172686)
		(stroke
			(width 0.05715)
			(type default)
		)
		(layer "In13.Cu")
	)
	(gr_line
		(start 124.947426 -292.231318)
		(end 124.944886 -292.232842)
		(stroke
			(width 0.05715)
			(type default)
		)
		(layer "In13.Cu")
	)
	(gr_line
		(start 124.947426 -290.611306)
		(end 124.944886 -290.61283)
		(stroke
			(width 0.05715)
			(type default)
		)
		(layer "In13.Cu")
	)
	(gr_line
		(start 124.947426 -288.991294)
		(end 124.944886 -288.992818)
		(stroke
			(width 0.05715)
			(type default)
		)
		(layer "In13.Cu")
	)
	(gr_line
		(start 124.947426 -285.751524)
		(end 124.944886 -285.753048)
		(stroke
			(width 0.05715)
			(type default)
		)
		(layer "In13.Cu")
	)
	(gr_line
		(start 124.947426 -284.131512)
		(end 124.944886 -284.133036)
		(stroke
			(width 0.05715)
			(type default)
		)
		(layer "In13.Cu")
	)
	(gr_line
		(start 124.947426 -282.5115)
		(end 124.944886 -282.513024)
		(stroke
			(width 0.05715)
			(type default)
		)
		(layer "In13.Cu")
	)
	(gr_line
		(start 124.947426 -279.271476)
		(end 124.946156 -279.272238)
		(stroke
			(width 0.05715)
			(type default)
		)
		(layer "In13.Cu")
	)
	(gr_line
		(start 124.947426 -277.651464)
		(end 124.946156 -277.652226)
		(stroke
			(width 0.05715)
			(type default)
		)
		(layer "In13.Cu")
	)
	(gr_line
		(start 124.947426 -276.031452)
		(end 124.946156 -276.032214)
		(stroke
			(width 0.05715)
			(type default)
		)
		(layer "In13.Cu")
	)
	(gr_line
		(start 124.947426 -274.41144)
		(end 124.946156 -274.412202)
		(stroke
			(width 0.05715)
			(type default)
		)
		(layer "In13.Cu")
	)
	(gr_line
		(start 124.947426 -272.791428)
		(end 124.946156 -272.79219)
		(stroke
			(width 0.05715)
			(type default)
		)
		(layer "In13.Cu")
	)
	(gr_line
		(start 124.947426 -271.171416)
		(end 124.946156 -271.172178)
		(stroke
			(width 0.05715)
			(type default)
		)
		(layer "In13.Cu")
	)
	(gr_line
		(start 124.948188 -398.9832)
		(end 124.75591 -398.9832)
		(stroke
			(width 0.07112)
			(type default)
		)
		(layer "In13.Cu")
	)
	(gr_line
		(start 124.949204 -279.27046)
		(end 124.947426 -279.271476)
		(stroke
			(width 0.05715)
			(type default)
		)
		(layer "In13.Cu")
	)
	(gr_line
		(start 124.949204 -277.650448)
		(end 124.947426 -277.651464)
		(stroke
			(width 0.05715)
			(type default)
		)
		(layer "In13.Cu")
	)
	(gr_line
		(start 124.949204 -276.030436)
		(end 124.947426 -276.031452)
		(stroke
			(width 0.05715)
			(type default)
		)
		(layer "In13.Cu")
	)
	(gr_line
		(start 124.949204 -274.410424)
		(end 124.947426 -274.41144)
		(stroke
			(width 0.05715)
			(type default)
		)
		(layer "In13.Cu")
	)
	(gr_line
		(start 124.949204 -272.790412)
		(end 124.947426 -272.791428)
		(stroke
			(width 0.05715)
			(type default)
		)
		(layer "In13.Cu")
	)
	(gr_line
		(start 124.949204 -271.1704)
		(end 124.947426 -271.171416)
		(stroke
			(width 0.05715)
			(type default)
		)
		(layer "In13.Cu")
	)
	(gr_line
		(start 124.950728 -292.229286)
		(end 124.949204 -292.230302)
		(stroke
			(width 0.05715)
			(type default)
		)
		(layer "In13.Cu")
	)
	(gr_line
		(start 124.950728 -290.609274)
		(end 124.949204 -290.61029)
		(stroke
			(width 0.05715)
			(type default)
		)
		(layer "In13.Cu")
	)
	(gr_line
		(start 124.950728 -288.989262)
		(end 124.949204 -288.990278)
		(stroke
			(width 0.05715)
			(type default)
		)
		(layer "In13.Cu")
	)
	(gr_line
		(start 124.950728 -285.749492)
		(end 124.949204 -285.750508)
		(stroke
			(width 0.05715)
			(type default)
		)
		(layer "In13.Cu")
	)
	(gr_line
		(start 124.950728 -284.12948)
		(end 124.949204 -284.130496)
		(stroke
			(width 0.05715)
			(type default)
		)
		(layer "In13.Cu")
	)
	(gr_line
		(start 124.950728 -282.509468)
		(end 124.949204 -282.510484)
		(stroke
			(width 0.05715)
			(type default)
		)
		(layer "In13.Cu")
	)
	(gr_line
		(start 124.950728 -279.269444)
		(end 124.949204 -279.27046)
		(stroke
			(width 0.05715)
			(type default)
		)
		(layer "In13.Cu")
	)
	(gr_line
		(start 124.950728 -277.649432)
		(end 124.949204 -277.650448)
		(stroke
			(width 0.05715)
			(type default)
		)
		(layer "In13.Cu")
	)
	(gr_line
		(start 124.950728 -276.02942)
		(end 124.949204 -276.030436)
		(stroke
			(width 0.05715)
			(type default)
		)
		(layer "In13.Cu")
	)
	(gr_line
		(start 124.950728 -274.409408)
		(end 124.949204 -274.410424)
		(stroke
			(width 0.05715)
			(type default)
		)
		(layer "In13.Cu")
	)
	(gr_line
		(start 124.950728 -272.789396)
		(end 124.949204 -272.790412)
		(stroke
			(width 0.05715)
			(type default)
		)
		(layer "In13.Cu")
	)
	(gr_line
		(start 124.950728 -271.169384)
		(end 124.949204 -271.1704)
		(stroke
			(width 0.05715)
			(type default)
		)
		(layer "In13.Cu")
	)
	(gr_line
		(start 124.95149 -279.268936)
		(end 124.950728 -279.269444)
		(stroke
			(width 0.05715)
			(type default)
		)
		(layer "In13.Cu")
	)
	(gr_line
		(start 124.95149 -277.648924)
		(end 124.950728 -277.649432)
		(stroke
			(width 0.05715)
			(type default)
		)
		(layer "In13.Cu")
	)
	(gr_line
		(start 124.95149 -276.028912)
		(end 124.950728 -276.02942)
		(stroke
			(width 0.05715)
			(type default)
		)
		(layer "In13.Cu")
	)
	(gr_line
		(start 124.95149 -274.4089)
		(end 124.950728 -274.409408)
		(stroke
			(width 0.05715)
			(type default)
		)
		(layer "In13.Cu")
	)
	(gr_line
		(start 124.95149 -272.788888)
		(end 124.950728 -272.789396)
		(stroke
			(width 0.05715)
			(type default)
		)
		(layer "In13.Cu")
	)
	(gr_line
		(start 124.95149 -271.168876)
		(end 124.950728 -271.169384)
		(stroke
			(width 0.05715)
			(type default)
		)
		(layer "In13.Cu")
	)
	(gr_line
		(start 124.951744 -293.84879)
		(end 124.950728 -293.849298)
		(stroke
			(width 0.05715)
			(type default)
		)
		(layer "In13.Cu")
	)
	(gr_line
		(start 124.951744 -292.228778)
		(end 124.950728 -292.229286)
		(stroke
			(width 0.05715)
			(type default)
		)
		(layer "In13.Cu")
	)
	(gr_line
		(start 124.951744 -290.608766)
		(end 124.950728 -290.609274)
		(stroke
			(width 0.05715)
			(type default)
		)
		(layer "In13.Cu")
	)
	(gr_line
		(start 124.951744 -288.988754)
		(end 124.950728 -288.989262)
		(stroke
			(width 0.05715)
			(type default)
		)
		(layer "In13.Cu")
	)
	(gr_line
		(start 124.951744 -285.748984)
		(end 124.950728 -285.749492)
		(stroke
			(width 0.05715)
			(type default)
		)
		(layer "In13.Cu")
	)
	(gr_line
		(start 124.951744 -284.128972)
		(end 124.950728 -284.12948)
		(stroke
			(width 0.05715)
			(type default)
		)
		(layer "In13.Cu")
	)
	(gr_line
		(start 124.951744 -282.50896)
		(end 124.950728 -282.509468)
		(stroke
			(width 0.05715)
			(type default)
		)
		(layer "In13.Cu")
	)
	(gr_line
		(start 124.951744 -280.243788)
		(end 124.952252 -280.244042)
		(stroke
			(width 0.05715)
			(type default)
		)
		(layer "In13.Cu")
	)
	(gr_line
		(start 124.951998 -294.823896)
		(end 124.952506 -294.82415)
		(stroke
			(width 0.05715)
			(type default)
		)
		(layer "In13.Cu")
	)
	(gr_line
		(start 124.951998 -293.203884)
		(end 124.952506 -293.204138)
		(stroke
			(width 0.05715)
			(type default)
		)
		(layer "In13.Cu")
	)
	(gr_line
		(start 124.951998 -289.96386)
		(end 124.952506 -289.964114)
		(stroke
			(width 0.05715)
			(type default)
		)
		(layer "In13.Cu")
	)
	(gr_line
		(start 124.951998 -281.864054)
		(end 124.952506 -281.864308)
		(stroke
			(width 0.05715)
			(type default)
		)
		(layer "In13.Cu")
	)
	(gr_line
		(start 124.951998 -278.62403)
		(end 124.952506 -278.624284)
		(stroke
			(width 0.05715)
			(type default)
		)
		(layer "In13.Cu")
	)
	(gr_line
		(start 124.951998 -277.004018)
		(end 124.952506 -277.004272)
		(stroke
			(width 0.05715)
			(type default)
		)
		(layer "In13.Cu")
	)
	(gr_line
		(start 124.951998 -275.384006)
		(end 124.952506 -275.38426)
		(stroke
			(width 0.05715)
			(type default)
		)
		(layer "In13.Cu")
	)
	(gr_line
		(start 124.951998 -273.763994)
		(end 124.952506 -273.764248)
		(stroke
			(width 0.05715)
			(type default)
		)
		(layer "In13.Cu")
	)
	(gr_line
		(start 124.951998 -272.143982)
		(end 124.952506 -272.144236)
		(stroke
			(width 0.05715)
			(type default)
		)
		(layer "In13.Cu")
	)
	(gr_line
		(start 124.952252 -293.848536)
		(end 124.951744 -293.84879)
		(stroke
			(width 0.05715)
			(type default)
		)
		(layer "In13.Cu")
	)
	(gr_line
		(start 124.952506 -294.82415)
		(end 124.953776 -294.824912)
		(stroke
			(width 0.05715)
			(type default)
		)
		(layer "In13.Cu")
	)
	(gr_line
		(start 124.952506 -293.204138)
		(end 124.953776 -293.2049)
		(stroke
			(width 0.05715)
			(type default)
		)
		(layer "In13.Cu")
	)
	(gr_line
		(start 124.952506 -292.22827)
		(end 124.951744 -292.228778)
		(stroke
			(width 0.05715)
			(type default)
		)
		(layer "In13.Cu")
	)
	(gr_line
		(start 124.952506 -291.584126)
		(end 124.953776 -291.584888)
		(stroke
			(width 0.05715)
			(type default)
		)
		(layer "In13.Cu")
	)
	(gr_line
		(start 124.952506 -290.608258)
		(end 124.951744 -290.608766)
		(stroke
			(width 0.05715)
			(type default)
		)
		(layer "In13.Cu")
	)
	(gr_line
		(start 124.952506 -289.964114)
		(end 124.953776 -289.964876)
		(stroke
			(width 0.05715)
			(type default)
		)
		(layer "In13.Cu")
	)
	(gr_line
		(start 124.952506 -288.988246)
		(end 124.951744 -288.988754)
		(stroke
			(width 0.05715)
			(type default)
		)
		(layer "In13.Cu")
	)
	(gr_line
		(start 124.952506 -285.748476)
		(end 124.951744 -285.748984)
		(stroke
			(width 0.05715)
			(type default)
		)
		(layer "In13.Cu")
	)
	(gr_line
		(start 124.952506 -285.104332)
		(end 124.953776 -285.105094)
		(stroke
			(width 0.05715)
			(type default)
		)
		(layer "In13.Cu")
	)
	(gr_line
		(start 124.952506 -284.128464)
		(end 124.951744 -284.128972)
		(stroke
			(width 0.05715)
			(type default)
		)
		(layer "In13.Cu")
	)
	(gr_line
		(start 124.952506 -283.48432)
		(end 124.953776 -283.485082)
		(stroke
			(width 0.05715)
			(type default)
		)
		(layer "In13.Cu")
	)
	(gr_line
		(start 124.952506 -282.508452)
		(end 124.951744 -282.50896)
		(stroke
			(width 0.05715)
			(type default)
		)
		(layer "In13.Cu")
	)
	(gr_line
		(start 124.952506 -281.864308)
		(end 124.953776 -281.86507)
		(stroke
			(width 0.05715)
			(type default)
		)
		(layer "In13.Cu")
	)
	(gr_line
		(start 124.952506 -278.624284)
		(end 124.953776 -278.625046)
		(stroke
			(width 0.05715)
			(type default)
		)
		(layer "In13.Cu")
	)
	(gr_line
		(start 124.952506 -277.004272)
		(end 124.953776 -277.005034)
		(stroke
			(width 0.05715)
			(type default)
		)
		(layer "In13.Cu")
	)
	(gr_line
		(start 124.952506 -275.38426)
		(end 124.953776 -275.385022)
		(stroke
			(width 0.05715)
			(type default)
		)
		(layer "In13.Cu")
	)
	(gr_line
		(start 124.952506 -273.764248)
		(end 124.953776 -273.76501)
		(stroke
			(width 0.05715)
			(type default)
		)
		(layer "In13.Cu")
	)
	(gr_line
		(start 124.952506 -272.144236)
		(end 124.953776 -272.144998)
		(stroke
			(width 0.05715)
			(type default)
		)
		(layer "In13.Cu")
	)
	(gr_line
		(start 124.953776 -294.824912)
		(end 124.9553 -294.825674)
		(stroke
			(width 0.05715)
			(type default)
		)
		(layer "In13.Cu")
	)
	(gr_line
		(start 124.953776 -293.2049)
		(end 124.9553 -293.205662)
		(stroke
			(width 0.05715)
			(type default)
		)
		(layer "In13.Cu")
	)
	(gr_line
		(start 124.953776 -292.227508)
		(end 124.952506 -292.22827)
		(stroke
			(width 0.05715)
			(type default)
		)
		(layer "In13.Cu")
	)
	(gr_line
		(start 124.953776 -290.607496)
		(end 124.952506 -290.608258)
		(stroke
			(width 0.05715)
			(type default)
		)
		(layer "In13.Cu")
	)
	(gr_line
		(start 124.953776 -289.964876)
		(end 124.9553 -289.965638)
		(stroke
			(width 0.05715)
			(type default)
		)
		(layer "In13.Cu")
	)
	(gr_line
		(start 124.953776 -288.987484)
		(end 124.952506 -288.988246)
		(stroke
			(width 0.05715)
			(type default)
		)
		(layer "In13.Cu")
	)
	(gr_line
		(start 124.953776 -285.747714)
		(end 124.952506 -285.748476)
		(stroke
			(width 0.05715)
			(type default)
		)
		(layer "In13.Cu")
	)
	(gr_line
		(start 124.953776 -284.127702)
		(end 124.952506 -284.128464)
		(stroke
			(width 0.05715)
			(type default)
		)
		(layer "In13.Cu")
	)
	(gr_line
		(start 124.953776 -282.50769)
		(end 124.952506 -282.508452)
		(stroke
			(width 0.05715)
			(type default)
		)
		(layer "In13.Cu")
	)
	(gr_line
		(start 124.953776 -281.86507)
		(end 124.9553 -281.865832)
		(stroke
			(width 0.05715)
			(type default)
		)
		(layer "In13.Cu")
	)
	(gr_line
		(start 124.96038 -366.833658)
		(end 125.66142 -366.833658)
		(stroke
			(width 0.07112)
			(type default)
		)
		(layer "In13.Cu")
	)
	(gr_line
		(start 124.96165 -366.550448)
		(end 125.09754 -366.414558)
		(stroke
			(width 0.07112)
			(type default)
		)
		(layer "In13.Cu")
	)
	(gr_line
		(start 124.97562 -395.854428)
		(end 124.97562 -395.153388)
		(stroke
			(width 0.07112)
			(type default)
		)
		(layer "In13.Cu")
	)
	(gr_line
		(start 125.013212 -414.871408)
		(end 124.365512 -414.60293)
		(stroke
			(width 0.07112)
			(type default)
		)
		(layer "In13.Cu")
	)
	(gr_line
		(start 125.041914 -292.396926)
		(end 125.041152 -292.397434)
		(stroke
			(width 0.05715)
			(type default)
		)
		(layer "In13.Cu")
	)
	(gr_line
		(start 125.041914 -290.776914)
		(end 125.041152 -290.777422)
		(stroke
			(width 0.05715)
			(type default)
		)
		(layer "In13.Cu")
	)
	(gr_line
		(start 125.041914 -289.156902)
		(end 125.041152 -289.15741)
		(stroke
			(width 0.05715)
			(type default)
		)
		(layer "In13.Cu")
	)
	(gr_line
		(start 125.041914 -285.917132)
		(end 125.041152 -285.91764)
		(stroke
			(width 0.05715)
			(type default)
		)
		(layer "In13.Cu")
	)
	(gr_line
		(start 125.041914 -284.29712)
		(end 125.041152 -284.297628)
		(stroke
			(width 0.05715)
			(type default)
		)
		(layer "In13.Cu")
	)
	(gr_line
		(start 125.041914 -282.677108)
		(end 125.041152 -282.677616)
		(stroke
			(width 0.05715)
			(type default)
		)
		(layer "In13.Cu")
	)
	(gr_line
		(start 125.041914 -279.437084)
		(end 125.041406 -279.437338)
		(stroke
			(width 0.05715)
			(type default)
		)
		(layer "In13.Cu")
	)
	(gr_line
		(start 125.041914 -277.817072)
		(end 125.041406 -277.817326)
		(stroke
			(width 0.05715)
			(type default)
		)
		(layer "In13.Cu")
	)
	(gr_line
		(start 125.041914 -276.19706)
		(end 125.041406 -276.197314)
		(stroke
			(width 0.05715)
			(type default)
		)
		(layer "In13.Cu")
	)
	(gr_line
		(start 125.041914 -274.577048)
		(end 125.041406 -274.577302)
		(stroke
			(width 0.05715)
			(type default)
		)
		(layer "In13.Cu")
	)
	(gr_line
		(start 125.041914 -272.957036)
		(end 125.041406 -272.95729)
		(stroke
			(width 0.05715)
			(type default)
		)
		(layer "In13.Cu")
	)
	(gr_line
		(start 125.041914 -271.337024)
		(end 125.041406 -271.337278)
		(stroke
			(width 0.05715)
			(type default)
		)
		(layer "In13.Cu")
	)
	(gr_line
		(start 125.04293 -292.396418)
		(end 125.041914 -292.396926)
		(stroke
			(width 0.05715)
			(type default)
		)
		(layer "In13.Cu")
	)
	(gr_line
		(start 125.04293 -290.776406)
		(end 125.041914 -290.776914)
		(stroke
			(width 0.05715)
			(type default)
		)
		(layer "In13.Cu")
	)
	(gr_line
		(start 125.04293 -289.156394)
		(end 125.041914 -289.156902)
		(stroke
			(width 0.05715)
			(type default)
		)
		(layer "In13.Cu")
	)
	(gr_line
		(start 125.04293 -285.916624)
		(end 125.041914 -285.917132)
		(stroke
			(width 0.05715)
			(type default)
		)
		(layer "In13.Cu")
	)
	(gr_line
		(start 125.04293 -284.296612)
		(end 125.041914 -284.29712)
		(stroke
			(width 0.05715)
			(type default)
		)
		(layer "In13.Cu")
	)
	(gr_line
		(start 125.04293 -282.6766)
		(end 125.041914 -282.677108)
		(stroke
			(width 0.05715)
			(type default)
		)
		(layer "In13.Cu")
	)
	(gr_line
		(start 125.0442 -279.435814)
		(end 125.043438 -279.436322)
		(stroke
			(width 0.05715)
			(type default)
		)
		(layer "In13.Cu")
	)
	(gr_line
		(start 125.0442 -277.815802)
		(end 125.043438 -277.81631)
		(stroke
			(width 0.05715)
			(type default)
		)
		(layer "In13.Cu")
	)
	(gr_line
		(start 125.0442 -276.19579)
		(end 125.043438 -276.196298)
		(stroke
			(width 0.05715)
			(type default)
		)
		(layer "In13.Cu")
	)
	(gr_line
		(start 125.0442 -274.575778)
		(end 125.043438 -274.576286)
		(stroke
			(width 0.05715)
			(type default)
		)
		(layer "In13.Cu")
	)
	(gr_line
		(start 125.0442 -272.955766)
		(end 125.043438 -272.956274)
		(stroke
			(width 0.05715)
			(type default)
		)
		(layer "In13.Cu")
	)
	(gr_line
		(start 125.0442 -271.335754)
		(end 125.043438 -271.336262)
		(stroke
			(width 0.05715)
			(type default)
		)
		(layer "In13.Cu")
	)
	(gr_line
		(start 125.046232 -280.07818)
		(end 125.046994 -280.078434)
		(stroke
			(width 0.05715)
			(type default)
		)
		(layer "In13.Cu")
	)
	(gr_line
		(start 125.046994 -414.43148)
		(end 124.652532 -414.268158)
		(stroke
			(width 0.07112)
			(type default)
		)
		(layer "In13.Cu")
	)
	(gr_line
		(start 125.046994 -294.014144)
		(end 125.045724 -294.014906)
		(stroke
			(width 0.05715)
			(type default)
		)
		(layer "In13.Cu")
	)
	(gr_line
		(start 125.046994 -292.394132)
		(end 125.045724 -292.394894)
		(stroke
			(width 0.05715)
			(type default)
		)
		(layer "In13.Cu")
	)
	(gr_line
		(start 125.046994 -290.77412)
		(end 125.045724 -290.774882)
		(stroke
			(width 0.05715)
			(type default)
		)
		(layer "In13.Cu")
	)
	(gr_line
		(start 125.046994 -289.154108)
		(end 125.045724 -289.15487)
		(stroke
			(width 0.05715)
			(type default)
		)
		(layer "In13.Cu")
	)
	(gr_line
		(start 125.046994 -285.914338)
		(end 125.045724 -285.9151)
		(stroke
			(width 0.05715)
			(type default)
		)
		(layer "In13.Cu")
	)
	(gr_line
		(start 125.046994 -284.294326)
		(end 125.045724 -284.295088)
		(stroke
			(width 0.05715)
			(type default)
		)
		(layer "In13.Cu")
	)
	(gr_line
		(start 125.046994 -282.674314)
		(end 125.045724 -282.675076)
		(stroke
			(width 0.05715)
			(type default)
		)
		(layer "In13.Cu")
	)
	(gr_line
		(start 125.046994 -279.43429)
		(end 125.04547 -279.435052)
		(stroke
			(width 0.05715)
			(type default)
		)
		(layer "In13.Cu")
	)
	(gr_line
		(start 125.046994 -277.814278)
		(end 125.04547 -277.81504)
		(stroke
			(width 0.05715)
			(type default)
		)
		(layer "In13.Cu")
	)
	(gr_line
		(start 125.046994 -276.194266)
		(end 125.04547 -276.195028)
		(stroke
			(width 0.05715)
			(type default)
		)
		(layer "In13.Cu")
	)
	(gr_line
		(start 125.046994 -274.574254)
		(end 125.04547 -274.575016)
		(stroke
			(width 0.05715)
			(type default)
		)
		(layer "In13.Cu")
	)
	(gr_line
		(start 125.046994 -272.954242)
		(end 125.04547 -272.955004)
		(stroke
			(width 0.05715)
			(type default)
		)
		(layer "In13.Cu")
	)
	(gr_line
		(start 125.046994 -271.33423)
		(end 125.04547 -271.334992)
		(stroke
			(width 0.05715)
			(type default)
		)
		(layer "In13.Cu")
	)
	(gr_line
		(start 125.047248 -291.418518)
		(end 125.047756 -291.418772)
		(stroke
			(width 0.05715)
			(type default)
		)
		(layer "In13.Cu")
	)
	(gr_line
		(start 125.047248 -284.938724)
		(end 125.047756 -284.938978)
		(stroke
			(width 0.05715)
			(type default)
		)
		(layer "In13.Cu")
	)
	(gr_line
		(start 125.047248 -283.318712)
		(end 125.047756 -283.318966)
		(stroke
			(width 0.05715)
			(type default)
		)
		(layer "In13.Cu")
	)
	(gr_line
		(start 125.047502 -279.434036)
		(end 125.046994 -279.43429)
		(stroke
			(width 0.05715)
			(type default)
		)
		(layer "In13.Cu")
	)
	(gr_line
		(start 125.047502 -277.814024)
		(end 125.046994 -277.814278)
		(stroke
			(width 0.05715)
			(type default)
		)
		(layer "In13.Cu")
	)
	(gr_line
		(start 125.047502 -276.194012)
		(end 125.046994 -276.194266)
		(stroke
			(width 0.05715)
			(type default)
		)
		(layer "In13.Cu")
	)
	(gr_line
		(start 125.047502 -274.574)
		(end 125.046994 -274.574254)
		(stroke
			(width 0.05715)
			(type default)
		)
		(layer "In13.Cu")
	)
	(gr_line
		(start 125.047502 -272.953988)
		(end 125.046994 -272.954242)
		(stroke
			(width 0.05715)
			(type default)
		)
		(layer "In13.Cu")
	)
	(gr_line
		(start 125.047502 -271.333976)
		(end 125.046994 -271.33423)
		(stroke
			(width 0.05715)
			(type default)
		)
		(layer "In13.Cu")
	)
	(gr_line
		(start 125.047756 -294.658796)
		(end 125.048772 -294.659304)
		(stroke
			(width 0.05715)
			(type default)
		)
		(layer "In13.Cu")
	)
	(gr_line
		(start 125.047756 -293.038784)
		(end 125.048772 -293.039292)
		(stroke
			(width 0.05715)
			(type default)
		)
		(layer "In13.Cu")
	)
	(gr_line
		(start 125.047756 -292.393624)
		(end 125.046994 -292.394132)
		(stroke
			(width 0.05715)
			(type default)
		)
		(layer "In13.Cu")
	)
	(gr_line
		(start 125.047756 -291.418772)
		(end 125.048772 -291.41928)
		(stroke
			(width 0.05715)
			(type default)
		)
		(layer "In13.Cu")
	)
	(gr_line
		(start 125.047756 -290.773612)
		(end 125.046994 -290.77412)
		(stroke
			(width 0.05715)
			(type default)
		)
		(layer "In13.Cu")
	)
	(gr_line
		(start 125.047756 -289.79876)
		(end 125.048772 -289.799268)
		(stroke
			(width 0.05715)
			(type default)
		)
		(layer "In13.Cu")
	)
	(gr_line
		(start 125.047756 -289.1536)
		(end 125.046994 -289.154108)
		(stroke
			(width 0.05715)
			(type default)
		)
		(layer "In13.Cu")
	)
	(gr_line
		(start 125.047756 -285.91383)
		(end 125.046994 -285.914338)
		(stroke
			(width 0.05715)
			(type default)
		)
		(layer "In13.Cu")
	)
	(gr_line
		(start 125.047756 -284.938978)
		(end 125.048772 -284.939486)
		(stroke
			(width 0.05715)
			(type default)
		)
		(layer "In13.Cu")
	)
	(gr_line
		(start 125.047756 -284.293818)
		(end 125.046994 -284.294326)
		(stroke
			(width 0.05715)
			(type default)
		)
		(layer "In13.Cu")
	)
	(gr_line
		(start 125.047756 -283.318966)
		(end 125.048772 -283.319474)
		(stroke
			(width 0.05715)
			(type default)
		)
		(layer "In13.Cu")
	)
	(gr_line
		(start 125.047756 -282.673806)
		(end 125.046994 -282.674314)
		(stroke
			(width 0.05715)
			(type default)
		)
		(layer "In13.Cu")
	)
	(gr_line
		(start 125.047756 -281.698954)
		(end 125.048772 -281.699462)
		(stroke
			(width 0.05715)
			(type default)
		)
		(layer "In13.Cu")
	)
	(gr_line
		(start 125.047756 -278.45893)
		(end 125.048772 -278.459438)
		(stroke
			(width 0.05715)
			(type default)
		)
		(layer "In13.Cu")
	)
	(gr_line
		(start 125.047756 -276.838918)
		(end 125.048772 -276.839426)
		(stroke
			(width 0.05715)
			(type default)
		)
		(layer "In13.Cu")
	)
	(gr_line
		(start 125.047756 -275.218906)
		(end 125.048772 -275.219414)
		(stroke
			(width 0.05715)
			(type default)
		)
		(layer "In13.Cu")
	)
	(gr_line
		(start 125.047756 -273.598894)
		(end 125.048772 -273.599402)
		(stroke
			(width 0.05715)
			(type default)
		)
		(layer "In13.Cu")
	)
	(gr_line
		(start 125.047756 -271.978882)
		(end 125.048772 -271.97939)
		(stroke
			(width 0.05715)
			(type default)
		)
		(layer "In13.Cu")
	)
	(gr_line
		(start 125.048772 -294.659304)
		(end 125.050296 -294.66032)
		(stroke
			(width 0.05715)
			(type default)
		)
		(layer "In13.Cu")
	)
	(gr_line
		(start 125.048772 -293.039292)
		(end 125.050296 -293.040308)
		(stroke
			(width 0.05715)
			(type default)
		)
		(layer "In13.Cu")
	)
	(gr_line
		(start 125.048772 -292.393116)
		(end 125.047756 -292.393624)
		(stroke
			(width 0.05715)
			(type default)
		)
		(layer "In13.Cu")
	)
	(gr_line
		(start 125.048772 -290.773104)
		(end 125.047756 -290.773612)
		(stroke
			(width 0.05715)
			(type default)
		)
		(layer "In13.Cu")
	)
	(gr_line
		(start 125.048772 -289.799268)
		(end 125.050296 -289.800284)
		(stroke
			(width 0.05715)
			(type default)
		)
		(layer "In13.Cu")
	)
	(gr_line
		(start 125.048772 -289.153092)
		(end 125.047756 -289.1536)
		(stroke
			(width 0.05715)
			(type default)
		)
		(layer "In13.Cu")
	)
	(gr_line
		(start 125.048772 -285.913322)
		(end 125.047756 -285.91383)
		(stroke
			(width 0.05715)
			(type default)
		)
		(layer "In13.Cu")
	)
	(gr_line
		(start 125.048772 -284.29331)
		(end 125.047756 -284.293818)
		(stroke
			(width 0.05715)
			(type default)
		)
		(layer "In13.Cu")
	)
	(gr_line
		(start 125.048772 -282.673298)
		(end 125.047756 -282.673806)
		(stroke
			(width 0.05715)
			(type default)
		)
		(layer "In13.Cu")
	)
	(gr_line
		(start 125.048772 -281.699462)
		(end 125.050296 -281.700478)
		(stroke
			(width 0.05715)
			(type default)
		)
		(layer "In13.Cu")
	)
	(gr_line
		(start 125.050804 -399.678652)
		(end 124.554996 -399.182844)
		(stroke
			(width 0.07112)
			(type default)
		)
		(layer "In13.Cu")
	)
	(gr_line
		(start 125.052074 -294.661336)
		(end 125.053344 -294.662098)
		(stroke
			(width 0.05715)
			(type default)
		)
		(layer "In13.Cu")
	)
	(gr_line
		(start 125.052074 -293.041324)
		(end 125.053344 -293.042086)
		(stroke
			(width 0.05715)
			(type default)
		)
		(layer "In13.Cu")
	)
	(gr_line
		(start 125.052074 -289.8013)
		(end 125.053344 -289.802062)
		(stroke
			(width 0.05715)
			(type default)
		)
		(layer "In13.Cu")
	)
	(gr_line
		(start 125.052074 -281.701494)
		(end 125.053344 -281.702256)
		(stroke
			(width 0.05715)
			(type default)
		)
		(layer "In13.Cu")
	)
	(gr_line
		(start 125.054614 -294.66286)
		(end 125.056392 -294.663876)
		(stroke
			(width 0.05715)
			(type default)
		)
		(layer "In13.Cu")
	)
	(gr_line
		(start 125.054614 -293.042848)
		(end 125.056392 -293.043864)
		(stroke
			(width 0.05715)
			(type default)
		)
		(layer "In13.Cu")
	)
	(gr_line
		(start 125.054614 -289.802824)
		(end 125.056392 -289.80384)
		(stroke
			(width 0.05715)
			(type default)
		)
		(layer "In13.Cu")
	)
	(gr_line
		(start 125.054614 -281.703018)
		(end 125.056392 -281.704034)
		(stroke
			(width 0.05715)
			(type default)
		)
		(layer "In13.Cu")
	)
	(gr_line
		(start 125.09754 -366.414558)
		(end 125.52426 -366.414558)
		(stroke
			(width 0.07112)
			(type default)
		)
		(layer "In13.Cu")
	)
	(gr_line
		(start 125.10897 -296.792396)
		(end 125.15469 -296.838116)
		(stroke
			(width 0.05715)
			(type default)
		)
		(layer "In13.Cu")
	)
	(gr_line
		(start 125.1204 -414.60928)
		(end 125.046994 -414.43148)
		(stroke
			(width 0.07112)
			(type default)
		)
		(layer "In13.Cu")
	)
	(gr_line
		(start 125.15469 -296.866056)
		(end 125.155198 -296.866564)
		(stroke
			(width 0.05715)
			(type default)
		)
		(layer "In13.Cu")
	)
	(gr_line
		(start 125.15469 -296.838116)
		(end 125.15469 -296.866056)
		(stroke
			(width 0.05715)
			(type default)
		)
		(layer "In13.Cu")
	)
	(gr_line
		(start 125.155198 -296.875708)
		(end 125.155198 -296.876216)
		(stroke
			(width 0.07112)
			(type default)
		)
		(layer "In13.Cu")
	)
	(gr_line
		(start 125.2347 -273.276314)
		(end 125.532642 -273.276314)
		(stroke
			(width 0.05715)
			(type default)
		)
		(layer "In13.Cu")
	)
	(gr_line
		(start 125.2347 -271.656302)
		(end 125.532642 -271.656302)
		(stroke
			(width 0.05715)
			(type default)
		)
		(layer "In13.Cu")
	)
	(gr_line
		(start 125.2347 -270.03629)
		(end 125.532642 -270.03629)
		(stroke
			(width 0.05715)
			(type default)
		)
		(layer "In13.Cu")
	)
	(gr_line
		(start 125.250194 -399.477484)
		(end 125.250194 -399.285206)
		(stroke
			(width 0.07112)
			(type default)
		)
		(layer "In13.Cu")
	)
	(gr_line
		(start 125.250194 -399.285206)
		(end 124.948188 -398.9832)
		(stroke
			(width 0.07112)
			(type default)
		)
		(layer "In13.Cu")
	)
	(gr_line
		(start 125.25883 -395.853158)
		(end 125.39472 -395.717268)
		(stroke
			(width 0.07112)
			(type default)
		)
		(layer "In13.Cu")
	)
	(gr_line
		(start 125.350778 -397.825722)
		(end 125.1585 -397.825722)
		(stroke
			(width 0.07112)
			(type default)
		)
		(layer "In13.Cu")
	)
	(gr_line
		(start 125.39472 -395.717268)
		(end 125.39472 -395.290548)
		(stroke
			(width 0.07112)
			(type default)
		)
		(layer "In13.Cu")
	)
	(gr_line
		(start 125.39472 -395.290548)
		(end 125.25883 -395.154658)
		(stroke
			(width 0.07112)
			(type default)
		)
		(layer "In13.Cu")
	)
	(gr_line
		(start 125.421644 -295.633648)
		(end 125.421898 -295.633648)
		(stroke
			(width 0.05715)
			(type default)
		)
		(layer "In13.Cu")
	)
	(gr_line
		(start 125.453394 -398.521174)
		(end 124.957586 -398.025366)
		(stroke
			(width 0.07112)
			(type default)
		)
		(layer "In13.Cu")
	)
	(gr_line
		(start 125.52426 -366.414558)
		(end 125.66015 -366.550448)
		(stroke
			(width 0.07112)
			(type default)
		)
		(layer "In13.Cu")
	)
	(gr_line
		(start 125.532642 -273.276314)
		(end 125.615446 -273.359118)
		(stroke
			(width 0.05715)
			(type default)
		)
		(layer "In13.Cu")
	)
	(gr_line
		(start 125.532642 -271.656302)
		(end 125.615446 -271.739106)
		(stroke
			(width 0.05715)
			(type default)
		)
		(layer "In13.Cu")
	)
	(gr_line
		(start 125.532642 -270.03629)
		(end 125.601984 -270.105632)
		(stroke
			(width 0.05715)
			(type default)
		)
		(layer "In13.Cu")
	)
	(gr_line
		(start 125.567694 -393.011406)
		(end 125.589538 -393.011406)
		(stroke
			(width 0.07112)
			(type default)
		)
		(layer "In13.Cu")
	)
	(gr_line
		(start 125.568964 -392.728196)
		(end 125.716538 -392.580622)
		(stroke
			(width 0.07112)
			(type default)
		)
		(layer "In13.Cu")
	)
	(gr_line
		(start 125.589538 -393.011406)
		(end 125.716538 -393.138406)
		(stroke
			(width 0.07112)
			(type default)
		)
		(layer "In13.Cu")
	)
	(gr_arc
		(start 125.615446 -273.359118)
		(mid 125.617239 -273.37044)
		(end 125.619256 -273.381724)
		(stroke
			(width 0.05715)
			(type default)
		)
		(layer "In13.Cu")
	)
	(gr_arc
		(start 125.615446 -271.739106)
		(mid 125.617239 -271.750428)
		(end 125.619256 -271.761712)
		(stroke
			(width 0.05715)
			(type default)
		)
		(layer "In13.Cu")
	)
	(gr_line
		(start 125.622812 -434.038756)
		(end 125.611636 -434.038756)
		(stroke
			(width 0.07112)
			(type default)
		)
		(layer "In13.Cu")
	)
	(gr_line
		(start 125.652784 -398.320006)
		(end 125.652784 -398.127728)
		(stroke
			(width 0.07112)
			(type default)
		)
		(layer "In13.Cu")
	)
	(gr_line
		(start 125.652784 -398.127728)
		(end 125.350778 -397.825722)
		(stroke
			(width 0.07112)
			(type default)
		)
		(layer "In13.Cu")
	)
	(gr_line
		(start 125.716538 -393.138406)
		(end 125.716538 -393.292838)
		(stroke
			(width 0.07112)
			(type default)
		)
		(layer "In13.Cu")
	)
	(gr_line
		(start 125.716538 -392.580622)
		(end 125.716538 -392.429238)
		(stroke
			(width 0.07112)
			(type default)
		)
		(layer "In13.Cu")
	)
	(gr_line
		(start 125.749812 -434.48986)
		(end 125.749812 -434.165756)
		(stroke
			(width 0.07112)
			(type default)
		)
		(layer "In13.Cu")
	)
	(gr_line
		(start 125.749812 -434.165756)
		(end 125.622812 -434.038756)
		(stroke
			(width 0.07112)
			(type default)
		)
		(layer "In13.Cu")
	)
	(gr_line
		(start 125.749812 -433.61864)
		(end 125.612906 -433.755546)
		(stroke
			(width 0.07112)
			(type default)
		)
		(layer "In13.Cu")
	)
	(gr_line
		(start 125.749812 -433.289964)
		(end 125.749812 -433.61864)
		(stroke
			(width 0.07112)
			(type default)
		)
		(layer "In13.Cu")
	)
	(gr_line
		(start 125.753114 -396.582646)
		(end 125.560836 -396.582646)
		(stroke
			(width 0.07112)
			(type default)
		)
		(layer "In13.Cu")
	)
	(gr_arc
		(start 125.790198 -270.141954)
		(mid 125.79222 -270.130544)
		(end 125.794008 -270.119094)
		(stroke
			(width 0.05715)
			(type default)
		)
		(layer "In13.Cu")
	)
	(gr_line
		(start 125.838204 -296.866056)
		(end 125.838712 -296.866564)
		(stroke
			(width 0.05715)
			(type default)
		)
		(layer "In13.Cu")
	)
	(gr_line
		(start 125.838204 -296.838116)
		(end 125.838204 -296.866056)
		(stroke
			(width 0.05715)
			(type default)
		)
		(layer "In13.Cu")
	)
	(gr_arc
		(start 125.842014 -288.313368)
		(mid 125.84518 -288.315666)
		(end 125.848364 -288.31794)
		(stroke
			(width 0.05715)
			(type default)
		)
		(layer "In13.Cu")
	)
	(gr_arc
		(start 125.844554 -273.735292)
		(mid 125.848606 -273.738104)
		(end 125.852682 -273.74088)
		(stroke
			(width 0.05715)
			(type default)
		)
		(layer "In13.Cu")
	)
	(gr_arc
		(start 125.844808 -283.455364)
		(mid 125.848733 -283.458175)
		(end 125.852682 -283.460952)
		(stroke
			(width 0.05715)
			(type default)
		)
		(layer "In13.Cu")
	)
	(gr_arc
		(start 125.844808 -280.21534)
		(mid 125.848733 -280.218151)
		(end 125.852682 -280.220928)
		(stroke
			(width 0.05715)
			(type default)
		)
		(layer "In13.Cu")
	)
	(gr_arc
		(start 125.844808 -278.595328)
		(mid 125.848733 -278.598139)
		(end 125.852682 -278.600916)
		(stroke
			(width 0.05715)
			(type default)
		)
		(layer "In13.Cu")
	)
	(gr_arc
		(start 125.844808 -276.975316)
		(mid 125.848733 -276.978127)
		(end 125.852682 -276.980904)
		(stroke
			(width 0.05715)
			(type default)
		)
		(layer "In13.Cu")
	)
	(gr_arc
		(start 125.844808 -275.355304)
		(mid 125.848733 -275.358115)
		(end 125.852682 -275.360892)
		(stroke
			(width 0.05715)
			(type default)
		)
		(layer "In13.Cu")
	)
	(gr_arc
		(start 125.849126 -288.318448)
		(mid 125.850902 -288.319721)
		(end 125.852682 -288.320988)
		(stroke
			(width 0.05715)
			(type default)
		)
		(layer "In13.Cu")
	)
	(gr_line
		(start 125.852682 -288.320988)
		(end 125.858778 -288.324544)
		(stroke
			(width 0.05715)
			(type default)
		)
		(layer "In13.Cu")
	)
	(gr_line
		(start 125.852682 -283.460952)
		(end 125.85954 -283.465016)
		(stroke
			(width 0.05715)
			(type default)
		)
		(layer "In13.Cu")
	)
	(gr_arc
		(start 125.852682 -280.911808)
		(mid 125.848733 -280.914585)
		(end 125.844808 -280.917396)
		(stroke
			(width 0.05715)
			(type default)
		)
		(layer "In13.Cu")
	)
	(gr_line
		(start 125.852682 -280.220928)
		(end 125.855476 -280.22296)
		(stroke
			(width 0.05715)
			(type default)
		)
		(layer "In13.Cu")
	)
	(gr_line
		(start 125.852682 -278.600916)
		(end 125.85954 -278.60498)
		(stroke
			(width 0.05715)
			(type default)
		)
		(layer "In13.Cu")
	)
	(gr_line
		(start 125.852682 -276.980904)
		(end 125.85954 -276.984968)
		(stroke
			(width 0.05715)
			(type default)
		)
		(layer "In13.Cu")
	)
	(gr_line
		(start 125.852682 -275.360892)
		(end 125.85954 -275.364956)
		(stroke
			(width 0.05715)
			(type default)
		)
		(layer "In13.Cu")
	)
	(gr_line
		(start 125.852682 -273.74088)
		(end 125.85954 -273.744944)
		(stroke
			(width 0.05715)
			(type default)
		)
		(layer "In13.Cu")
	)
	(gr_line
		(start 125.855476 -280.909776)
		(end 125.852682 -280.911808)
		(stroke
			(width 0.05715)
			(type default)
		)
		(layer "In13.Cu")
	)
	(gr_line
		(start 125.855476 -280.22296)
		(end 125.86081 -280.226008)
		(stroke
			(width 0.05715)
			(type default)
		)
		(layer "In13.Cu")
	)
	(gr_line
		(start 125.85573 -397.278098)
		(end 125.359668 -396.782036)
		(stroke
			(width 0.07112)
			(type default)
		)
		(layer "In13.Cu")
	)
	(gr_line
		(start 125.858778 -288.324544)
		(end 125.859032 -288.324544)
		(stroke
			(width 0.05715)
			(type default)
		)
		(layer "In13.Cu")
	)
	(gr_line
		(start 125.85954 -283.465016)
		(end 125.860302 -283.465524)
		(stroke
			(width 0.05715)
			(type default)
		)
		(layer "In13.Cu")
	)
	(gr_line
		(start 125.85954 -278.60498)
		(end 125.860302 -278.605488)
		(stroke
			(width 0.05715)
			(type default)
		)
		(layer "In13.Cu")
	)
	(gr_line
		(start 125.85954 -276.984968)
		(end 125.860302 -276.985476)
		(stroke
			(width 0.05715)
			(type default)
		)
		(layer "In13.Cu")
	)
	(gr_line
		(start 125.85954 -275.364956)
		(end 125.860302 -275.365464)
		(stroke
			(width 0.05715)
			(type default)
		)
		(layer "In13.Cu")
	)
	(gr_line
		(start 125.85954 -273.744944)
		(end 125.860302 -273.745452)
		(stroke
			(width 0.05715)
			(type default)
		)
		(layer "In13.Cu")
	)
	(gr_line
		(start 125.860302 -283.465524)
		(end 125.861064 -283.466032)
		(stroke
			(width 0.05715)
			(type default)
		)
		(layer "In13.Cu")
	)
	(gr_line
		(start 125.860302 -278.605488)
		(end 125.861064 -278.605996)
		(stroke
			(width 0.05715)
			(type default)
		)
		(layer "In13.Cu")
	)
	(gr_line
		(start 125.860302 -276.985476)
		(end 125.861064 -276.985984)
		(stroke
			(width 0.05715)
			(type default)
		)
		(layer "In13.Cu")
	)
	(gr_line
		(start 125.860302 -275.365464)
		(end 125.861064 -275.365972)
		(stroke
			(width 0.05715)
			(type default)
		)
		(layer "In13.Cu")
	)
	(gr_line
		(start 125.860302 -273.745452)
		(end 125.861064 -273.74596)
		(stroke
			(width 0.05715)
			(type default)
		)
		(layer "In13.Cu")
	)
	(gr_line
		(start 125.86081 -280.906728)
		(end 125.855476 -280.909776)
		(stroke
			(width 0.05715)
			(type default)
		)
		(layer "In13.Cu")
	)
	(gr_line
		(start 125.876812 -273.276314)
		(end 125.80747 -273.345656)
		(stroke
			(width 0.05715)
			(type default)
		)
		(layer "In13.Cu")
	)
	(gr_line
		(start 125.876812 -271.656302)
		(end 125.80747 -271.725644)
		(stroke
			(width 0.05715)
			(type default)
		)
		(layer "In13.Cu")
	)
	(gr_line
		(start 125.876812 -270.03629)
		(end 125.794008 -270.119094)
		(stroke
			(width 0.05715)
			(type default)
		)
		(layer "In13.Cu")
	)
	(gr_line
		(start 125.883924 -296.792396)
		(end 125.838204 -296.838116)
		(stroke
			(width 0.05715)
			(type default)
		)
		(layer "In13.Cu")
	)
	(gr_line
		(start 125.891798 -279.268936)
		(end 125.890782 -279.269444)
		(stroke
			(width 0.05715)
			(type default)
		)
		(layer "In13.Cu")
	)
	(gr_line
		(start 125.891798 -277.648924)
		(end 125.890782 -277.649432)
		(stroke
			(width 0.05715)
			(type default)
		)
		(layer "In13.Cu")
	)
	(gr_line
		(start 125.891798 -276.028912)
		(end 125.890782 -276.02942)
		(stroke
			(width 0.05715)
			(type default)
		)
		(layer "In13.Cu")
	)
	(gr_line
		(start 125.891798 -274.4089)
		(end 125.890782 -274.409408)
		(stroke
			(width 0.05715)
			(type default)
		)
		(layer "In13.Cu")
	)
	(gr_line
		(start 125.892052 -278.62403)
		(end 125.89256 -278.624284)
		(stroke
			(width 0.05715)
			(type default)
		)
		(layer "In13.Cu")
	)
	(gr_line
		(start 125.892052 -277.004018)
		(end 125.89256 -277.004272)
		(stroke
			(width 0.05715)
			(type default)
		)
		(layer "In13.Cu")
	)
	(gr_line
		(start 125.89256 -294.82415)
		(end 125.893322 -294.824404)
		(stroke
			(width 0.05715)
			(type default)
		)
		(layer "In13.Cu")
	)
	(gr_line
		(start 125.89256 -291.584126)
		(end 125.89383 -291.584888)
		(stroke
			(width 0.05715)
			(type default)
		)
		(layer "In13.Cu")
	)
	(gr_line
		(start 125.89256 -279.268428)
		(end 125.891798 -279.268936)
		(stroke
			(width 0.05715)
			(type default)
		)
		(layer "In13.Cu")
	)
	(gr_line
		(start 125.89256 -278.624284)
		(end 125.895354 -278.625808)
		(stroke
			(width 0.05715)
			(type default)
		)
		(layer "In13.Cu")
	)
	(gr_line
		(start 125.89256 -277.648416)
		(end 125.891798 -277.648924)
		(stroke
			(width 0.05715)
			(type default)
		)
		(layer "In13.Cu")
	)
	(gr_line
		(start 125.89256 -277.004272)
		(end 125.895354 -277.005796)
		(stroke
			(width 0.05715)
			(type default)
		)
		(layer "In13.Cu")
	)
	(gr_line
		(start 125.89383 -279.267666)
		(end 125.89256 -279.268428)
		(stroke
			(width 0.05715)
			(type default)
		)
		(layer "In13.Cu")
	)
	(gr_line
		(start 125.89383 -277.647654)
		(end 125.89256 -277.648416)
		(stroke
			(width 0.05715)
			(type default)
		)
		(layer "In13.Cu")
	)
	(gr_line
		(start 125.894592 -293.205408)
		(end 125.8951 -293.205408)
		(stroke
			(width 0.05715)
			(type default)
		)
		(layer "In13.Cu")
	)
	(gr_line
		(start 125.894592 -289.965384)
		(end 125.8951 -289.965384)
		(stroke
			(width 0.05715)
			(type default)
		)
		(layer "In13.Cu")
	)
	(gr_line
		(start 125.894592 -285.105602)
		(end 125.8951 -285.105602)
		(stroke
			(width 0.05715)
			(type default)
		)
		(layer "In13.Cu")
	)
	(gr_line
		(start 125.894592 -283.48559)
		(end 125.8951 -283.48559)
		(stroke
			(width 0.05715)
			(type default)
		)
		(layer "In13.Cu")
	)
	(gr_line
		(start 125.894592 -281.865578)
		(end 125.8951 -281.865578)
		(stroke
			(width 0.05715)
			(type default)
		)
		(layer "In13.Cu")
	)
	(gr_line
		(start 125.894846 -288.345372)
		(end 125.8951 -288.345372)
		(stroke
			(width 0.05715)
			(type default)
		)
		(layer "In13.Cu")
	)
	(gr_line
		(start 125.987048 -279.43429)
		(end 125.985778 -279.435052)
		(stroke
			(width 0.05715)
			(type default)
		)
		(layer "In13.Cu")
	)
	(gr_line
		(start 125.987048 -277.814278)
		(end 125.985778 -277.81504)
		(stroke
			(width 0.05715)
			(type default)
		)
		(layer "In13.Cu")
	)
	(gr_line
		(start 125.987048 -276.194266)
		(end 125.985778 -276.195028)
		(stroke
			(width 0.05715)
			(type default)
		)
		(layer "In13.Cu")
	)
	(gr_line
		(start 125.987048 -274.574254)
		(end 125.985778 -274.575016)
		(stroke
			(width 0.05715)
			(type default)
		)
		(layer "In13.Cu")
	)
	(gr_line
		(start 125.987302 -294.658542)
		(end 125.98781 -294.658796)
		(stroke
			(width 0.05715)
			(type default)
		)
		(layer "In13.Cu")
	)
	(gr_line
		(start 125.987302 -293.03853)
		(end 125.98781 -293.038784)
		(stroke
			(width 0.05715)
			(type default)
		)
		(layer "In13.Cu")
	)
	(gr_line
		(start 125.987302 -291.418518)
		(end 125.98781 -291.418772)
		(stroke
			(width 0.05715)
			(type default)
		)
		(layer "In13.Cu")
	)
	(gr_line
		(start 125.987302 -289.798506)
		(end 125.98781 -289.79876)
		(stroke
			(width 0.05715)
			(type default)
		)
		(layer "In13.Cu")
	)
	(gr_line
		(start 125.987302 -284.938724)
		(end 125.98781 -284.938978)
		(stroke
			(width 0.05715)
			(type default)
		)
		(layer "In13.Cu")
	)
	(gr_line
		(start 125.987302 -281.6987)
		(end 125.98781 -281.698954)
		(stroke
			(width 0.05715)
			(type default)
		)
		(layer "In13.Cu")
	)
	(gr_line
		(start 125.987556 -292.393878)
		(end 125.982222 -292.396926)
		(stroke
			(width 0.05715)
			(type default)
		)
		(layer "In13.Cu")
	)
	(gr_line
		(start 125.987556 -279.434036)
		(end 125.987048 -279.43429)
		(stroke
			(width 0.05715)
			(type default)
		)
		(layer "In13.Cu")
	)
	(gr_line
		(start 125.987556 -277.814024)
		(end 125.987048 -277.814278)
		(stroke
			(width 0.05715)
			(type default)
		)
		(layer "In13.Cu")
	)
	(gr_line
		(start 125.987556 -276.194012)
		(end 125.987048 -276.194266)
		(stroke
			(width 0.05715)
			(type default)
		)
		(layer "In13.Cu")
	)
	(gr_line
		(start 125.987556 -274.574)
		(end 125.987048 -274.574254)
		(stroke
			(width 0.05715)
			(type default)
		)
		(layer "In13.Cu")
	)
	(gr_line
		(start 125.98781 -294.658796)
		(end 125.991366 -294.660828)
		(stroke
			(width 0.05715)
			(type default)
		)
		(layer "In13.Cu")
	)
	(gr_line
		(start 125.98781 -293.038784)
		(end 125.990858 -293.040562)
		(stroke
			(width 0.05715)
			(type default)
		)
		(layer "In13.Cu")
	)
	(gr_line
		(start 125.98781 -291.418772)
		(end 125.98781 -291.419026)
		(stroke
			(width 0.05715)
			(type default)
		)
		(layer "In13.Cu")
	)
	(gr_line
		(start 125.98781 -289.79876)
		(end 125.990858 -289.800538)
		(stroke
			(width 0.05715)
			(type default)
		)
		(layer "In13.Cu")
	)
	(gr_line
		(start 125.98781 -284.938978)
		(end 125.990858 -284.940756)
		(stroke
			(width 0.05715)
			(type default)
		)
		(layer "In13.Cu")
	)
	(gr_line
		(start 125.98781 -283.318966)
		(end 125.990858 -283.320744)
		(stroke
			(width 0.05715)
			(type default)
		)
		(layer "In13.Cu")
	)
	(gr_line
		(start 125.98781 -281.698954)
		(end 125.990858 -281.700732)
		(stroke
			(width 0.05715)
			(type default)
		)
		(layer "In13.Cu")
	)
	(gr_line
		(start 125.990858 -294.011858)
		(end 125.987302 -294.01389)
		(stroke
			(width 0.05715)
			(type default)
		)
		(layer "In13.Cu")
	)
	(gr_line
		(start 125.990858 -290.771834)
		(end 125.987302 -290.773866)
		(stroke
			(width 0.05715)
			(type default)
		)
		(layer "In13.Cu")
	)
	(gr_line
		(start 125.990858 -289.151822)
		(end 125.987302 -289.153854)
		(stroke
			(width 0.05715)
			(type default)
		)
		(layer "In13.Cu")
	)
	(gr_line
		(start 125.990858 -285.912052)
		(end 125.987302 -285.914084)
		(stroke
			(width 0.05715)
			(type default)
		)
		(layer "In13.Cu")
	)
	(gr_line
		(start 125.990858 -284.29204)
		(end 125.987302 -284.294072)
		(stroke
			(width 0.05715)
			(type default)
		)
		(layer "In13.Cu")
	)
	(gr_line
		(start 125.990858 -282.672028)
		(end 125.987302 -282.67406)
		(stroke
			(width 0.05715)
			(type default)
		)
		(layer "In13.Cu")
	)
	(gr_line
		(start 125.991366 -294.660828)
		(end 125.992128 -294.661336)
		(stroke
			(width 0.05715)
			(type default)
		)
		(layer "In13.Cu")
	)
	(gr_line
		(start 126.05512 -397.077184)
		(end 126.05512 -396.884652)
		(stroke
			(width 0.07112)
			(type default)
		)
		(layer "In13.Cu")
	)
	(gr_line
		(start 126.05512 -396.884652)
		(end 125.753114 -396.582646)
		(stroke
			(width 0.07112)
			(type default)
		)
		(layer "In13.Cu")
	)
	(gr_line
		(start 126.074424 -296.792396)
		(end 126.120144 -296.838116)
		(stroke
			(width 0.05715)
			(type default)
		)
		(layer "In13.Cu")
	)
	(gr_line
		(start 126.08814 -366.833658)
		(end 126.78918 -366.833658)
		(stroke
			(width 0.07112)
			(type default)
		)
		(layer "In13.Cu")
	)
	(gr_line
		(start 126.08941 -366.550448)
		(end 126.2253 -366.414558)
		(stroke
			(width 0.07112)
			(type default)
		)
		(layer "In13.Cu")
	)
	(gr_line
		(start 126.120144 -296.866056)
		(end 126.120652 -296.866564)
		(stroke
			(width 0.05715)
			(type default)
		)
		(layer "In13.Cu")
	)
	(gr_line
		(start 126.120144 -296.838116)
		(end 126.120144 -296.866056)
		(stroke
			(width 0.05715)
			(type default)
		)
		(layer "In13.Cu")
	)
	(gr_line
		(start 126.148338 -398.623282)
		(end 125.95606 -398.623282)
		(stroke
			(width 0.07112)
			(type default)
		)
		(layer "In13.Cu")
	)
	(gr_line
		(start 126.16815 -399.23593)
		(end 125.755146 -398.822926)
		(stroke
			(width 0.07112)
			(type default)
		)
		(layer "In13.Cu")
	)
	(gr_line
		(start 126.16815 -399.23593)
		(end 126.168404 -399.23593)
		(stroke
			(width 0.07112)
			(type default)
		)
		(layer "In13.Cu")
	)
	(gr_line
		(start 126.174754 -273.276314)
		(end 125.876812 -273.276314)
		(stroke
			(width 0.05715)
			(type default)
		)
		(layer "In13.Cu")
	)
	(gr_line
		(start 126.174754 -271.656302)
		(end 125.876812 -271.656302)
		(stroke
			(width 0.05715)
			(type default)
		)
		(layer "In13.Cu")
	)
	(gr_line
		(start 126.174754 -270.03629)
		(end 125.876812 -270.03629)
		(stroke
			(width 0.05715)
			(type default)
		)
		(layer "In13.Cu")
	)
	(gr_line
		(start 126.17577 -395.339062)
		(end 126.17577 -394.638022)
		(stroke
			(width 0.07112)
			(type default)
		)
		(layer "In13.Cu")
	)
	(gr_line
		(start 126.2253 -366.414558)
		(end 126.65202 -366.414558)
		(stroke
			(width 0.07112)
			(type default)
		)
		(layer "In13.Cu")
	)
	(gr_line
		(start 126.250954 -399.31848)
		(end 126.168404 -399.23593)
		(stroke
			(width 0.07112)
			(type default)
		)
		(layer "In13.Cu")
	)
	(gr_arc
		(start 126.355856 -272.950432)
		(mid 126.357379 -272.951323)
		(end 126.358904 -272.95221)
		(stroke
			(width 0.05715)
			(type default)
		)
		(layer "In13.Cu")
	)
	(gr_line
		(start 126.36373 -295.634664)
		(end 126.364746 -295.635172)
		(stroke
			(width 0.05715)
			(type default)
		)
		(layer "In13.Cu")
	)
	(gr_line
		(start 126.450344 -399.117312)
		(end 126.450344 -398.925288)
		(stroke
			(width 0.07112)
			(type default)
		)
		(layer "In13.Cu")
	)
	(gr_line
		(start 126.450344 -398.925288)
		(end 126.148338 -398.623282)
		(stroke
			(width 0.07112)
			(type default)
		)
		(layer "In13.Cu")
	)
	(gr_line
		(start 126.454916 -272.787364)
		(end 126.456948 -272.78838)
		(stroke
			(width 0.05715)
			(type default)
		)
		(layer "In13.Cu")
	)
	(gr_line
		(start 126.45898 -395.337792)
		(end 126.59487 -395.201902)
		(stroke
			(width 0.07112)
			(type default)
		)
		(layer "In13.Cu")
	)
	(gr_line
		(start 126.488444 -272.806922)
		(end 126.496064 -272.81124)
		(stroke
			(width 0.05715)
			(type default)
		)
		(layer "In13.Cu")
	)
	(gr_arc
		(start 126.496064 -272.81124)
		(mid 126.496445 -272.811494)
		(end 126.496826 -272.811748)
		(stroke
			(width 0.05715)
			(type default)
		)
		(layer "In13.Cu")
	)
	(gr_arc
		(start 126.5047 -272.817336)
		(mid 126.500775 -272.814525)
		(end 126.496826 -272.811748)
		(stroke
			(width 0.05715)
			(type default)
		)
		(layer "In13.Cu")
	)
	(gr_line
		(start 126.550674 -397.380206)
		(end 126.358142 -397.380206)
		(stroke
			(width 0.07112)
			(type default)
		)
		(layer "In13.Cu")
	)
	(gr_line
		(start 126.570486 -397.993108)
		(end 126.157228 -397.579596)
		(stroke
			(width 0.07112)
			(type default)
		)
		(layer "In13.Cu")
	)
	(gr_line
		(start 126.57074 -397.993108)
		(end 126.570486 -397.993108)
		(stroke
			(width 0.07112)
			(type default)
		)
		(layer "In13.Cu")
	)
	(gr_line
		(start 126.59487 -395.201902)
		(end 126.59487 -394.775182)
		(stroke
			(width 0.07112)
			(type default)
		)
		(layer "In13.Cu")
	)
	(gr_line
		(start 126.59487 -394.775182)
		(end 126.45898 -394.639292)
		(stroke
			(width 0.07112)
			(type default)
		)
		(layer "In13.Cu")
	)
	(gr_line
		(start 126.65202 -366.414558)
		(end 126.78791 -366.550448)
		(stroke
			(width 0.07112)
			(type default)
		)
		(layer "In13.Cu")
	)
	(gr_line
		(start 126.65329 -398.075658)
		(end 126.57074 -397.993108)
		(stroke
			(width 0.07112)
			(type default)
		)
		(layer "In13.Cu")
	)
	(gr_line
		(start 126.777242 -392.707622)
		(end 126.789688 -392.707622)
		(stroke
			(width 0.07112)
			(type default)
		)
		(layer "In13.Cu")
	)
	(gr_line
		(start 126.778512 -392.990832)
		(end 126.916688 -393.129008)
		(stroke
			(width 0.07112)
			(type default)
		)
		(layer "In13.Cu")
	)
	(gr_line
		(start 126.789688 -392.707622)
		(end 126.916688 -392.580622)
		(stroke
			(width 0.07112)
			(type default)
		)
		(layer "In13.Cu")
	)
	(gr_line
		(start 126.85268 -397.87449)
		(end 126.85268 -397.682212)
		(stroke
			(width 0.07112)
			(type default)
		)
		(layer "In13.Cu")
	)
	(gr_line
		(start 126.85268 -397.682212)
		(end 126.550674 -397.380206)
		(stroke
			(width 0.07112)
			(type default)
		)
		(layer "In13.Cu")
	)
	(gr_line
		(start 126.86284 -296.822368)
		(end 126.86284 -296.850816)
		(stroke
			(width 0.05715)
			(type default)
		)
		(layer "In13.Cu")
	)
	(gr_line
		(start 126.90856 -296.776648)
		(end 126.86284 -296.822368)
		(stroke
			(width 0.05715)
			(type default)
		)
		(layer "In13.Cu")
	)
	(gr_line
		(start 126.916688 -393.129008)
		(end 126.916688 -393.292838)
		(stroke
			(width 0.07112)
			(type default)
		)
		(layer "In13.Cu")
	)
	(gr_line
		(start 126.916688 -392.580622)
		(end 126.916688 -392.429238)
		(stroke
			(width 0.07112)
			(type default)
		)
		(layer "In13.Cu")
	)
	(gr_line
		(start 127.0762 -396.378176)
		(end 126.883922 -396.378176)
		(stroke
			(width 0.07112)
			(type default)
		)
		(layer "In13.Cu")
	)
	(gr_line
		(start 127.09906 -296.776648)
		(end 127.14478 -296.822368)
		(stroke
			(width 0.05715)
			(type default)
		)
		(layer "In13.Cu")
	)
	(gr_line
		(start 127.14478 -296.850308)
		(end 127.145288 -296.850816)
		(stroke
			(width 0.05715)
			(type default)
		)
		(layer "In13.Cu")
	)
	(gr_line
		(start 127.14478 -296.822368)
		(end 127.14478 -296.850308)
		(stroke
			(width 0.05715)
			(type default)
		)
		(layer "In13.Cu")
	)
	(gr_line
		(start 127.145288 -296.85996)
		(end 127.145288 -296.860468)
		(stroke
			(width 0.07112)
			(type default)
		)
		(layer "In13.Cu")
	)
	(gr_line
		(start 127.178816 -397.073628)
		(end 126.682754 -396.577566)
		(stroke
			(width 0.07112)
			(type default)
		)
		(layer "In13.Cu")
	)
	(gr_arc
		(start 127.254762 -295.6052)
		(mid 127.258687 -295.608011)
		(end 127.262636 -295.610788)
		(stroke
			(width 0.05715)
			(type default)
		)
		(layer "In13.Cu")
	)
	(gr_line
		(start 127.262636 -295.610788)
		(end 127.26543 -295.61282)
		(stroke
			(width 0.05715)
			(type default)
		)
		(layer "In13.Cu")
	)
	(gr_line
		(start 127.26543 -295.61282)
		(end 127.270764 -295.615868)
		(stroke
			(width 0.05715)
			(type default)
		)
		(layer "In13.Cu")
	)
	(gr_line
		(start 127.375666 -395.200124)
		(end 127.375666 -394.499084)
		(stroke
			(width 0.07112)
			(type default)
		)
		(layer "In13.Cu")
	)
	(gr_line
		(start 127.378206 -396.87246)
		(end 127.378206 -396.680182)
		(stroke
			(width 0.07112)
			(type default)
		)
		(layer "In13.Cu")
	)
	(gr_line
		(start 127.378206 -396.680182)
		(end 127.0762 -396.378176)
		(stroke
			(width 0.07112)
			(type default)
		)
		(layer "In13.Cu")
	)
	(gr_line
		(start 127.437896 -408.914854)
		(end 127.437896 -408.213814)
		(stroke
			(width 0.07112)
			(type default)
		)
		(layer "In13.Cu")
	)
	(gr_line
		(start 127.622808 -435.038754)
		(end 127.611632 -435.038754)
		(stroke
			(width 0.07112)
			(type default)
		)
		(layer "In13.Cu")
	)
	(gr_line
		(start 127.658876 -395.198854)
		(end 127.794766 -395.062964)
		(stroke
			(width 0.07112)
			(type default)
		)
		(layer "In13.Cu")
	)
	(gr_line
		(start 127.721106 -408.913584)
		(end 127.856996 -408.777694)
		(stroke
			(width 0.07112)
			(type default)
		)
		(layer "In13.Cu")
	)
	(gr_line
		(start 127.749808 -435.489858)
		(end 127.749808 -435.165754)
		(stroke
			(width 0.07112)
			(type default)
		)
		(layer "In13.Cu")
	)
	(gr_line
		(start 127.749808 -435.165754)
		(end 127.622808 -435.038754)
		(stroke
			(width 0.07112)
			(type default)
		)
		(layer "In13.Cu")
	)
	(gr_line
		(start 127.749808 -434.618638)
		(end 127.612902 -434.755544)
		(stroke
			(width 0.07112)
			(type default)
		)
		(layer "In13.Cu")
	)
	(gr_line
		(start 127.749808 -434.289962)
		(end 127.749808 -434.618638)
		(stroke
			(width 0.07112)
			(type default)
		)
		(layer "In13.Cu")
	)
	(gr_line
		(start 127.794766 -395.062964)
		(end 127.794766 -394.636244)
		(stroke
			(width 0.07112)
			(type default)
		)
		(layer "In13.Cu")
	)
	(gr_line
		(start 127.794766 -394.636244)
		(end 127.658876 -394.500354)
		(stroke
			(width 0.07112)
			(type default)
		)
		(layer "In13.Cu")
	)
	(gr_line
		(start 127.856996 -408.777694)
		(end 127.856996 -408.350974)
		(stroke
			(width 0.07112)
			(type default)
		)
		(layer "In13.Cu")
	)
	(gr_line
		(start 127.856996 -408.350974)
		(end 127.721106 -408.215084)
		(stroke
			(width 0.07112)
			(type default)
		)
		(layer "In13.Cu")
	)
	(gr_line
		(start 127.87376 -397.175736)
		(end 127.681482 -397.175736)
		(stroke
			(width 0.07112)
			(type default)
		)
		(layer "In13.Cu")
	)
	(gr_line
		(start 127.976376 -397.871188)
		(end 127.480314 -397.375126)
		(stroke
			(width 0.07112)
			(type default)
		)
		(layer "In13.Cu")
	)
	(gr_line
		(start 127.977138 -392.707622)
		(end 127.989584 -392.707622)
		(stroke
			(width 0.07112)
			(type default)
		)
		(layer "In13.Cu")
	)
	(gr_line
		(start 127.977392 -296.696638)
		(end 127.997458 -296.716704)
		(stroke
			(width 0.05715)
			(type default)
		)
		(layer "In13.Cu")
	)
	(gr_line
		(start 127.977392 -296.632376)
		(end 127.977392 -296.696638)
		(stroke
			(width 0.05715)
			(type default)
		)
		(layer "In13.Cu")
	)
	(gr_line
		(start 127.978408 -392.990832)
		(end 128.116584 -393.129008)
		(stroke
			(width 0.07112)
			(type default)
		)
		(layer "In13.Cu")
	)
	(gr_line
		(start 127.989584 -392.707622)
		(end 128.116584 -392.580622)
		(stroke
			(width 0.07112)
			(type default)
		)
		(layer "In13.Cu")
	)
	(gr_line
		(start 127.997458 -296.716704)
		(end 128.17221 -296.891456)
		(stroke
			(width 0.07112)
			(type default)
		)
		(layer "In13.Cu")
	)
	(gr_line
		(start 128.105408 -330.117958)
		(end 128.105154 -330.117958)
		(stroke
			(width 0.07112)
			(type default)
		)
		(layer "In13.Cu")
	)
	(gr_line
		(start 128.112012 -296.49674)
		(end 128.11252 -296.497248)
		(stroke
			(width 0.05715)
			(type default)
		)
		(layer "In13.Cu")
	)
	(gr_line
		(start 128.11252 -296.497248)
		(end 128.176528 -296.497248)
		(stroke
			(width 0.05715)
			(type default)
		)
		(layer "In13.Cu")
	)
	(gr_line
		(start 128.116584 -393.129008)
		(end 128.116584 -393.292838)
		(stroke
			(width 0.07112)
			(type default)
		)
		(layer "In13.Cu")
	)
	(gr_line
		(start 128.116584 -392.580622)
		(end 128.116584 -392.429238)
		(stroke
			(width 0.07112)
			(type default)
		)
		(layer "In13.Cu")
	)
	(gr_line
		(start 128.175766 -397.67002)
		(end 128.175766 -397.477742)
		(stroke
			(width 0.07112)
			(type default)
		)
		(layer "In13.Cu")
	)
	(gr_line
		(start 128.175766 -397.477742)
		(end 127.87376 -397.175736)
		(stroke
			(width 0.07112)
			(type default)
		)
		(layer "In13.Cu")
	)
	(gr_line
		(start 128.176528 -296.497248)
		(end 128.196594 -296.517314)
		(stroke
			(width 0.05715)
			(type default)
		)
		(layer "In13.Cu")
	)
	(gr_line
		(start 128.196848 -296.517314)
		(end 128.371346 -296.692066)
		(stroke
			(width 0.07112)
			(type default)
		)
		(layer "In13.Cu")
	)
	(gr_line
		(start 128.495298 -416.913822)
		(end 128.495298 -416.913568)
		(stroke
			(width 0.07112)
			(type default)
		)
		(layer "In13.Cu")
	)
	(gr_line
		(start 129.177034 -392.707622)
		(end 129.18948 -392.707622)
		(stroke
			(width 0.07112)
			(type default)
		)
		(layer "In13.Cu")
	)
	(gr_line
		(start 129.178304 -392.990832)
		(end 129.31648 -393.129008)
		(stroke
			(width 0.07112)
			(type default)
		)
		(layer "In13.Cu")
	)
	(gr_line
		(start 129.18948 -392.707622)
		(end 129.31648 -392.580622)
		(stroke
			(width 0.07112)
			(type default)
		)
		(layer "In13.Cu")
	)
	(gr_line
		(start 129.210816 -433.991512)
		(end 129.151634 -433.93233)
		(stroke
			(width 0.07112)
			(type default)
		)
		(layer "In13.Cu")
	)
	(gr_arc
		(start 129.210816 -433.991512)
		(mid 129.263137 -434.026494)
		(end 129.324862 -434.038756)
		(stroke
			(width 0.07112)
			(type default)
		)
		(layer "In13.Cu")
	)
	(gr_line
		(start 129.31648 -393.129008)
		(end 129.31648 -393.292838)
		(stroke
			(width 0.07112)
			(type default)
		)
		(layer "In13.Cu")
	)
	(gr_line
		(start 129.31648 -392.580622)
		(end 129.31648 -392.429238)
		(stroke
			(width 0.07112)
			(type default)
		)
		(layer "In13.Cu")
	)
	(gr_arc
		(start 129.342642 -433.72278)
		(mid 129.379804 -433.744474)
		(end 129.421382 -433.755546)
		(stroke
			(width 0.07112)
			(type default)
		)
		(layer "In13.Cu")
	)
	(gr_line
		(start 129.376932 -367.801144)
		(end 130.077972 -367.801144)
		(stroke
			(width 0.07112)
			(type default)
		)
		(layer "In13.Cu")
	)
	(gr_line
		(start 129.378202 -367.517934)
		(end 129.514092 -367.382044)
		(stroke
			(width 0.07112)
			(type default)
		)
		(layer "In13.Cu")
	)
	(gr_line
		(start 129.408174 -434.038756)
		(end 129.324862 -434.038756)
		(stroke
			(width 0.07112)
			(type default)
		)
		(layer "In13.Cu")
	)
	(gr_line
		(start 129.450338 -395.751558)
		(end 129.25806 -395.760956)
		(stroke
			(width 0.07112)
			(type default)
		)
		(layer "In13.Cu")
	)
	(gr_line
		(start 129.514092 -367.382044)
		(end 129.940812 -367.382044)
		(stroke
			(width 0.07112)
			(type default)
		)
		(layer "In13.Cu")
	)
	(gr_line
		(start 129.586736 -396.441168)
		(end 129.067306 -395.969998)
		(stroke
			(width 0.07112)
			(type default)
		)
		(layer "In13.Cu")
	)
	(gr_line
		(start 129.622804 -434.038756)
		(end 129.611628 -434.038756)
		(stroke
			(width 0.07112)
			(type default)
		)
		(layer "In13.Cu")
	)
	(gr_line
		(start 129.749804 -434.48986)
		(end 129.749804 -434.165756)
		(stroke
			(width 0.07112)
			(type default)
		)
		(layer "In13.Cu")
	)
	(gr_line
		(start 129.749804 -434.165756)
		(end 129.622804 -434.038756)
		(stroke
			(width 0.07112)
			(type default)
		)
		(layer "In13.Cu")
	)
	(gr_line
		(start 129.749804 -433.61864)
		(end 129.612898 -433.755546)
		(stroke
			(width 0.07112)
			(type default)
		)
		(layer "In13.Cu")
	)
	(gr_line
		(start 129.749804 -433.289964)
		(end 129.749804 -433.61864)
		(stroke
			(width 0.07112)
			(type default)
		)
		(layer "In13.Cu")
	)
	(gr_line
		(start 129.766822 -396.038578)
		(end 129.450338 -395.751558)
		(stroke
			(width 0.07112)
			(type default)
		)
		(layer "In13.Cu")
	)
	(gr_line
		(start 129.77622 -396.230856)
		(end 129.766822 -396.038578)
		(stroke
			(width 0.07112)
			(type default)
		)
		(layer "In13.Cu")
	)
	(gr_line
		(start 129.940812 -367.382044)
		(end 130.076702 -367.517934)
		(stroke
			(width 0.07112)
			(type default)
		)
		(layer "In13.Cu")
	)
	(gr_line
		(start 130.389376 -392.989562)
		(end 130.516376 -393.116562)
		(stroke
			(width 0.07112)
			(type default)
		)
		(layer "In13.Cu")
	)
	(gr_line
		(start 130.389376 -392.707622)
		(end 130.516376 -392.580622)
		(stroke
			(width 0.07112)
			(type default)
		)
		(layer "In13.Cu")
	)
	(gr_line
		(start 130.395218 -415.125408)
		(end 130.259582 -415.01949)
		(stroke
			(width 0.07112)
			(type default)
		)
		(layer "In13.Cu")
	)
	(gr_line
		(start 130.501136 -409.793186)
		(end 130.501136 -409.092146)
		(stroke
			(width 0.07112)
			(type default)
		)
		(layer "In13.Cu")
	)
	(gr_line
		(start 130.501136 -408.665426)
		(end 130.501136 -407.964386)
		(stroke
			(width 0.07112)
			(type default)
		)
		(layer "In13.Cu")
	)
	(gr_line
		(start 130.504692 -367.801144)
		(end 131.205732 -367.801144)
		(stroke
			(width 0.07112)
			(type default)
		)
		(layer "In13.Cu")
	)
	(gr_line
		(start 130.505962 -367.517934)
		(end 130.641852 -367.382044)
		(stroke
			(width 0.07112)
			(type default)
		)
		(layer "In13.Cu")
	)
	(gr_line
		(start 130.516376 -393.116562)
		(end 130.516376 -393.292838)
		(stroke
			(width 0.07112)
			(type default)
		)
		(layer "In13.Cu")
	)
	(gr_line
		(start 130.516376 -392.580622)
		(end 130.516376 -392.429238)
		(stroke
			(width 0.07112)
			(type default)
		)
		(layer "In13.Cu")
	)
	(gr_line
		(start 130.625596 -414.773364)
		(end 130.434842 -414.796986)
		(stroke
			(width 0.07112)
			(type default)
		)
		(layer "In13.Cu")
	)
	(gr_line
		(start 130.641852 -367.382044)
		(end 131.068572 -367.382044)
		(stroke
			(width 0.07112)
			(type default)
		)
		(layer "In13.Cu")
	)
	(gr_line
		(start 130.784346 -409.791916)
		(end 130.920236 -409.656026)
		(stroke
			(width 0.07112)
			(type default)
		)
		(layer "In13.Cu")
	)
	(gr_line
		(start 130.784346 -408.664156)
		(end 130.920236 -408.528266)
		(stroke
			(width 0.07112)
			(type default)
		)
		(layer "In13.Cu")
	)
	(gr_line
		(start 130.81254 -415.451036)
		(end 130.395218 -415.125408)
		(stroke
			(width 0.07112)
			(type default)
		)
		(layer "In13.Cu")
	)
	(gr_line
		(start 130.920236 -409.656026)
		(end 130.920236 -409.229306)
		(stroke
			(width 0.07112)
			(type default)
		)
		(layer "In13.Cu")
	)
	(gr_line
		(start 130.920236 -409.229306)
		(end 130.784346 -409.093416)
		(stroke
			(width 0.07112)
			(type default)
		)
		(layer "In13.Cu")
	)
	(gr_line
		(start 130.920236 -408.528266)
		(end 130.920236 -408.101546)
		(stroke
			(width 0.07112)
			(type default)
		)
		(layer "In13.Cu")
	)
	(gr_line
		(start 130.920236 -408.101546)
		(end 130.784346 -407.965656)
		(stroke
			(width 0.07112)
			(type default)
		)
		(layer "In13.Cu")
	)
	(gr_line
		(start 130.962146 -415.036254)
		(end 130.625596 -414.773364)
		(stroke
			(width 0.07112)
			(type default)
		)
		(layer "In13.Cu")
	)
	(gr_line
		(start 130.985768 -415.227008)
		(end 130.962146 -415.036254)
		(stroke
			(width 0.07112)
			(type default)
		)
		(layer "In13.Cu")
	)
	(gr_line
		(start 131.068572 -367.382044)
		(end 131.204462 -367.517934)
		(stroke
			(width 0.07112)
			(type default)
		)
		(layer "In13.Cu")
	)
	(gr_line
		(start 131.57708 -392.707622)
		(end 131.589526 -392.707622)
		(stroke
			(width 0.07112)
			(type default)
		)
		(layer "In13.Cu")
	)
	(gr_line
		(start 131.57835 -392.990832)
		(end 131.716526 -393.129008)
		(stroke
			(width 0.07112)
			(type default)
		)
		(layer "In13.Cu")
	)
	(gr_line
		(start 131.589526 -392.707622)
		(end 131.716526 -392.580622)
		(stroke
			(width 0.07112)
			(type default)
		)
		(layer "In13.Cu")
	)
	(gr_line
		(start 131.6228 -435.038754)
		(end 131.611624 -435.038754)
		(stroke
			(width 0.07112)
			(type default)
		)
		(layer "In13.Cu")
	)
	(gr_line
		(start 131.716526 -393.129008)
		(end 131.716526 -393.292838)
		(stroke
			(width 0.07112)
			(type default)
		)
		(layer "In13.Cu")
	)
	(gr_line
		(start 131.716526 -392.580622)
		(end 131.716526 -392.429238)
		(stroke
			(width 0.07112)
			(type default)
		)
		(layer "In13.Cu")
	)
	(gr_line
		(start 131.7498 -435.489858)
		(end 131.7498 -435.165754)
		(stroke
			(width 0.07112)
			(type default)
		)
		(layer "In13.Cu")
	)
	(gr_line
		(start 131.7498 -435.165754)
		(end 131.6228 -435.038754)
		(stroke
			(width 0.07112)
			(type default)
		)
		(layer "In13.Cu")
	)
	(gr_line
		(start 131.7498 -434.618638)
		(end 131.612894 -434.755544)
		(stroke
			(width 0.07112)
			(type default)
		)
		(layer "In13.Cu")
	)
	(gr_line
		(start 131.7498 -434.289962)
		(end 131.7498 -434.618638)
		(stroke
			(width 0.07112)
			(type default)
		)
		(layer "In13.Cu")
	)
	(gr_line
		(start 131.876292 -366.69726)
		(end 131.876292 -366.27054)
		(stroke
			(width 0.07112)
			(type default)
		)
		(layer "In13.Cu")
	)
	(gr_line
		(start 131.876292 -366.27054)
		(end 132.012182 -366.13465)
		(stroke
			(width 0.07112)
			(type default)
		)
		(layer "In13.Cu")
	)
	(gr_line
		(start 131.953 -372.565422)
		(end 131.954016 -372.565422)
		(stroke
			(width 0.07112)
			(type default)
		)
		(layer "In13.Cu")
	)
	(gr_line
		(start 131.954778 -372.565422)
		(end 131.954016 -372.565422)
		(stroke
			(width 0.07112)
			(type default)
		)
		(layer "In13.Cu")
	)
	(gr_line
		(start 132.012182 -366.83315)
		(end 131.876292 -366.69726)
		(stroke
			(width 0.07112)
			(type default)
		)
		(layer "In13.Cu")
	)
	(gr_line
		(start 132.295392 -366.83442)
		(end 132.295392 -366.13338)
		(stroke
			(width 0.07112)
			(type default)
		)
		(layer "In13.Cu")
	)
	(gr_line
		(start 132.776976 -392.707622)
		(end 132.789422 -392.707622)
		(stroke
			(width 0.07112)
			(type default)
		)
		(layer "In13.Cu")
	)
	(gr_line
		(start 132.778246 -392.990832)
		(end 132.916422 -393.129008)
		(stroke
			(width 0.07112)
			(type default)
		)
		(layer "In13.Cu")
	)
	(gr_line
		(start 132.789422 -392.707622)
		(end 132.916422 -392.580622)
		(stroke
			(width 0.07112)
			(type default)
		)
		(layer "In13.Cu")
	)
	(gr_line
		(start 132.847842 -402.83765)
		(end 132.848096 -402.83765)
		(stroke
			(width 0.07112)
			(type default)
		)
		(layer "In13.Cu")
	)
	(gr_line
		(start 132.89788 -413.852868)
		(end 132.706364 -413.834072)
		(stroke
			(width 0.07112)
			(type default)
		)
		(layer "In13.Cu")
	)
	(gr_line
		(start 132.907532 -357.17607)
		(end 133.006592 -357.01097)
		(stroke
			(width 0.07112)
			(type default)
		)
		(layer "In13.Cu")
	)
	(gr_line
		(start 132.916422 -393.129008)
		(end 132.916422 -393.292838)
		(stroke
			(width 0.07112)
			(type default)
		)
		(layer "In13.Cu")
	)
	(gr_line
		(start 132.916422 -392.580622)
		(end 132.916422 -392.429238)
		(stroke
			(width 0.07112)
			(type default)
		)
		(layer "In13.Cu")
	)
	(gr_line
		(start 132.931662 -414.554924)
		(end 132.486908 -414.012888)
		(stroke
			(width 0.07112)
			(type default)
		)
		(layer "In13.Cu")
	)
	(gr_line
		(start 133.011418 -357.59009)
		(end 132.907532 -357.17607)
		(stroke
			(width 0.07112)
			(type default)
		)
		(layer "In13.Cu")
	)
	(gr_line
		(start 133.134862 -402.502624)
		(end 132.957316 -402.576538)
		(stroke
			(width 0.07112)
			(type default)
		)
		(layer "In13.Cu")
	)
	(gr_line
		(start 133.149848 -414.37433)
		(end 133.168644 -414.183068)
		(stroke
			(width 0.07112)
			(type default)
		)
		(layer "In13.Cu")
	)
	(gr_line
		(start 133.168644 -414.183068)
		(end 132.89788 -413.852868)
		(stroke
			(width 0.07112)
			(type default)
		)
		(layer "In13.Cu")
	)
	(gr_line
		(start 133.176518 -357.688896)
		(end 133.011418 -357.59009)
		(stroke
			(width 0.07112)
			(type default)
		)
		(layer "In13.Cu")
	)
	(gr_line
		(start 133.270244 -358.057704)
		(end 133.178042 -357.689912)
		(stroke
			(width 0.07112)
			(type default)
		)
		(layer "In13.Cu")
	)
	(gr_line
		(start 133.451346 -357.621586)
		(end 133.280912 -356.940866)
		(stroke
			(width 0.07112)
			(type default)
		)
		(layer "In13.Cu")
	)
	(gr_line
		(start 133.49605 -403.105874)
		(end 132.847842 -402.83765)
		(stroke
			(width 0.07112)
			(type default)
		)
		(layer "In13.Cu")
	)
	(gr_line
		(start 133.529578 -402.665946)
		(end 133.134862 -402.502624)
		(stroke
			(width 0.07112)
			(type default)
		)
		(layer "In13.Cu")
	)
	(gr_line
		(start 133.543548 -357.989124)
		(end 133.451346 -357.621586)
		(stroke
			(width 0.07112)
			(type default)
		)
		(layer "In13.Cu")
	)
	(gr_line
		(start 133.564376 -409.3718)
		(end 133.564376 -408.67076)
		(stroke
			(width 0.07112)
			(type default)
		)
		(layer "In13.Cu")
	)
	(gr_line
		(start 133.564376 -408.24404)
		(end 133.564376 -407.543)
		(stroke
			(width 0.07112)
			(type default)
		)
		(layer "In13.Cu")
	)
	(gr_line
		(start 133.602984 -402.843746)
		(end 133.529578 -402.665946)
		(stroke
			(width 0.07112)
			(type default)
		)
		(layer "In13.Cu")
	)
	(gr_line
		(start 133.622796 -434.038756)
		(end 133.61162 -434.038756)
		(stroke
			(width 0.07112)
			(type default)
		)
		(layer "In13.Cu")
	)
	(gr_line
		(start 133.749796 -434.48986)
		(end 133.749796 -434.165756)
		(stroke
			(width 0.07112)
			(type default)
		)
		(layer "In13.Cu")
	)
	(gr_line
		(start 133.749796 -434.165756)
		(end 133.622796 -434.038756)
		(stroke
			(width 0.07112)
			(type default)
		)
		(layer "In13.Cu")
	)
	(gr_line
		(start 133.749796 -433.61864)
		(end 133.61289 -433.755546)
		(stroke
			(width 0.07112)
			(type default)
		)
		(layer "In13.Cu")
	)
	(gr_line
		(start 133.749796 -433.289964)
		(end 133.749796 -433.61864)
		(stroke
			(width 0.07112)
			(type default)
		)
		(layer "In13.Cu")
	)
	(gr_line
		(start 133.847586 -409.37053)
		(end 133.983476 -409.23464)
		(stroke
			(width 0.07112)
			(type default)
		)
		(layer "In13.Cu")
	)
	(gr_line
		(start 133.847586 -408.24277)
		(end 133.983476 -408.10688)
		(stroke
			(width 0.07112)
			(type default)
		)
		(layer "In13.Cu")
	)
	(gr_line
		(start 133.983476 -409.23464)
		(end 133.983476 -408.80792)
		(stroke
			(width 0.07112)
			(type default)
		)
		(layer "In13.Cu")
	)
	(gr_line
		(start 133.983476 -408.80792)
		(end 133.847586 -408.67203)
		(stroke
			(width 0.07112)
			(type default)
		)
		(layer "In13.Cu")
	)
	(gr_line
		(start 133.983476 -408.10688)
		(end 133.983476 -407.68016)
		(stroke
			(width 0.07112)
			(type default)
		)
		(layer "In13.Cu")
	)
	(gr_line
		(start 133.983476 -407.68016)
		(end 133.847586 -407.54427)
		(stroke
			(width 0.07112)
			(type default)
		)
		(layer "In13.Cu")
	)
	(gr_line
		(start 134.182866 -416.507676)
		(end 133.837172 -415.897314)
		(stroke
			(width 0.07112)
			(type default)
		)
		(layer "In13.Cu")
	)
	(gr_line
		(start 134.269734 -415.810192)
		(end 134.08406 -415.758884)
		(stroke
			(width 0.07112)
			(type default)
		)
		(layer "In13.Cu")
	)
	(gr_arc
		(start 134.422388 -403.290278)
		(mid 134.422642 -403.290278)
		(end 134.422896 -403.290278)
		(stroke
			(width 0.07112)
			(type default)
		)
		(layer "In13.Cu")
	)
	(gr_line
		(start 134.428738 -416.36696)
		(end 134.480046 -416.181794)
		(stroke
			(width 0.07112)
			(type default)
		)
		(layer "In13.Cu")
	)
	(gr_line
		(start 134.480046 -416.181794)
		(end 134.269734 -415.810192)
		(stroke
			(width 0.07112)
			(type default)
		)
		(layer "In13.Cu")
	)
	(gr_line
		(start 135.41375 -394.852906)
		(end 135.26516 -394.97508)
		(stroke
			(width 0.07112)
			(type default)
		)
		(layer "In13.Cu")
	)
	(gr_arc
		(start 135.434324 -405.742902)
		(mid 135.435085 -405.743665)
		(end 135.435848 -405.744426)
		(stroke
			(width 0.07112)
			(type default)
		)
		(layer "In13.Cu")
	)
	(gr_arc
		(start 135.435848 -405.744426)
		(mid 135.560769 -405.826114)
		(end 135.706866 -405.856694)
		(stroke
			(width 0.07112)
			(type default)
		)
		(layer "In13.Cu")
	)
	(gr_line
		(start 135.622792 -435.038754)
		(end 135.611616 -435.038754)
		(stroke
			(width 0.07112)
			(type default)
		)
		(layer "In13.Cu")
	)
	(gr_line
		(start 135.635238 -405.545036)
		(end 135.631936 -405.541734)
		(stroke
			(width 0.07112)
			(type default)
		)
		(layer "In13.Cu")
	)
	(gr_line
		(start 135.635746 -405.54529)
		(end 135.635238 -405.545036)
		(stroke
			(width 0.07112)
			(type default)
		)
		(layer "In13.Cu")
	)
	(gr_line
		(start 135.702294 -405.572722)
		(end 135.63981 -405.546814)
		(stroke
			(width 0.07112)
			(type default)
		)
		(layer "In13.Cu")
	)
	(gr_line
		(start 135.706866 -405.574754)
		(end 135.706104 -405.5745)
		(stroke
			(width 0.07112)
			(type default)
		)
		(layer "In13.Cu")
	)
	(gr_line
		(start 135.71474 -405.856694)
		(end 135.706866 -405.856694)
		(stroke
			(width 0.07112)
			(type default)
		)
		(layer "In13.Cu")
	)
	(gr_line
		(start 135.71474 -405.574754)
		(end 135.706866 -405.574754)
		(stroke
			(width 0.07112)
			(type default)
		)
		(layer "In13.Cu")
	)
	(gr_line
		(start 135.749792 -435.489858)
		(end 135.749792 -435.165754)
		(stroke
			(width 0.07112)
			(type default)
		)
		(layer "In13.Cu")
	)
	(gr_line
		(start 135.749792 -435.165754)
		(end 135.622792 -435.038754)
		(stroke
			(width 0.07112)
			(type default)
		)
		(layer "In13.Cu")
	)
	(gr_line
		(start 135.749792 -434.618638)
		(end 135.612886 -434.755544)
		(stroke
			(width 0.07112)
			(type default)
		)
		(layer "In13.Cu")
	)
	(gr_line
		(start 135.749792 -434.289962)
		(end 135.749792 -434.618638)
		(stroke
			(width 0.07112)
			(type default)
		)
		(layer "In13.Cu")
	)
	(gr_line
		(start 135.838692 -394.894816)
		(end 135.41375 -394.852906)
		(stroke
			(width 0.07112)
			(type default)
		)
		(layer "In13.Cu")
	)
	(gr_line
		(start 135.850884 -415.294826)
		(end 135.716772 -414.970976)
		(stroke
			(width 0.07112)
			(type default)
		)
		(layer "In13.Cu")
	)
	(gr_line
		(start 135.934196 -395.3256)
		(end 135.236204 -395.256766)
		(stroke
			(width 0.07112)
			(type default)
		)
		(layer "In13.Cu")
	)
	(gr_line
		(start 135.960866 -395.04366)
		(end 135.838692 -394.894816)
		(stroke
			(width 0.07112)
			(type default)
		)
		(layer "In13.Cu")
	)
	(gr_line
		(start 135.984996 -415.61893)
		(end 135.850884 -415.294826)
		(stroke
			(width 0.07112)
			(type default)
		)
		(layer "In13.Cu")
	)
	(gr_line
		(start 136.1567 -414.937194)
		(end 135.9789 -414.863534)
		(stroke
			(width 0.07112)
			(type default)
		)
		(layer "In13.Cu")
	)
	(gr_line
		(start 136.246362 -415.50971)
		(end 136.320022 -415.331656)
		(stroke
			(width 0.07112)
			(type default)
		)
		(layer "In13.Cu")
	)
	(gr_line
		(start 136.320022 -415.331656)
		(end 136.1567 -414.937194)
		(stroke
			(width 0.07112)
			(type default)
		)
		(layer "In13.Cu")
	)
	(gr_line
		(start 136.416796 -416.661092)
		(end 136.148318 -416.012884)
		(stroke
			(width 0.07112)
			(type default)
		)
		(layer "In13.Cu")
	)
	(gr_line
		(start 136.5885 -415.979356)
		(end 136.410446 -415.90595)
		(stroke
			(width 0.07112)
			(type default)
		)
		(layer "In13.Cu")
	)
	(gr_line
		(start 136.627616 -409.476702)
		(end 136.627616 -408.775662)
		(stroke
			(width 0.07112)
			(type default)
		)
		(layer "In13.Cu")
	)
	(gr_line
		(start 136.627616 -408.348942)
		(end 136.627616 -407.647902)
		(stroke
			(width 0.07112)
			(type default)
		)
		(layer "In13.Cu")
	)
	(gr_line
		(start 136.677908 -416.551618)
		(end 136.751568 -416.373818)
		(stroke
			(width 0.07112)
			(type default)
		)
		(layer "In13.Cu")
	)
	(gr_line
		(start 136.751568 -416.373818)
		(end 136.5885 -415.979356)
		(stroke
			(width 0.07112)
			(type default)
		)
		(layer "In13.Cu")
	)
	(gr_line
		(start 136.910826 -409.475432)
		(end 137.046716 -409.339542)
		(stroke
			(width 0.07112)
			(type default)
		)
		(layer "In13.Cu")
	)
	(gr_line
		(start 136.910826 -408.347672)
		(end 137.046716 -408.211782)
		(stroke
			(width 0.07112)
			(type default)
		)
		(layer "In13.Cu")
	)
	(gr_line
		(start 137.046716 -409.339542)
		(end 137.046716 -408.912822)
		(stroke
			(width 0.07112)
			(type default)
		)
		(layer "In13.Cu")
	)
	(gr_line
		(start 137.046716 -408.912822)
		(end 136.910826 -408.776932)
		(stroke
			(width 0.07112)
			(type default)
		)
		(layer "In13.Cu")
	)
	(gr_line
		(start 137.046716 -408.211782)
		(end 137.046716 -407.785062)
		(stroke
			(width 0.07112)
			(type default)
		)
		(layer "In13.Cu")
	)
	(gr_line
		(start 137.046716 -407.785062)
		(end 136.910826 -407.649172)
		(stroke
			(width 0.07112)
			(type default)
		)
		(layer "In13.Cu")
	)
	(gr_line
		(start 137.43813 -395.052296)
		(end 137.28954 -395.17447)
		(stroke
			(width 0.07112)
			(type default)
		)
		(layer "In13.Cu")
	)
	(gr_line
		(start 137.622788 -434.038756)
		(end 137.611612 -434.038756)
		(stroke
			(width 0.07112)
			(type default)
		)
		(layer "In13.Cu")
	)
	(gr_line
		(start 137.749788 -434.48986)
		(end 137.749788 -434.165756)
		(stroke
			(width 0.07112)
			(type default)
		)
		(layer "In13.Cu")
	)
	(gr_line
		(start 137.749788 -434.165756)
		(end 137.622788 -434.038756)
		(stroke
			(width 0.07112)
			(type default)
		)
		(layer "In13.Cu")
	)
	(gr_line
		(start 137.749788 -433.61864)
		(end 137.612882 -433.755546)
		(stroke
			(width 0.07112)
			(type default)
		)
		(layer "In13.Cu")
	)
	(gr_line
		(start 137.749788 -433.289964)
		(end 137.749788 -433.61864)
		(stroke
			(width 0.07112)
			(type default)
		)
		(layer "In13.Cu")
	)
	(gr_line
		(start 137.863072 -395.094206)
		(end 137.43813 -395.052296)
		(stroke
			(width 0.07112)
			(type default)
		)
		(layer "In13.Cu")
	)
	(gr_line
		(start 137.914634 -398.619472)
		(end 137.75436 -398.726152)
		(stroke
			(width 0.07112)
			(type default)
		)
		(layer "In13.Cu")
	)
	(gr_line
		(start 137.958576 -395.52499)
		(end 137.260584 -395.456156)
		(stroke
			(width 0.07112)
			(type default)
		)
		(layer "In13.Cu")
	)
	(gr_line
		(start 137.981182 -397.532098)
		(end 137.826496 -397.646906)
		(stroke
			(width 0.07112)
			(type default)
		)
		(layer "In13.Cu")
	)
	(gr_line
		(start 137.985246 -395.24305)
		(end 137.863072 -395.094206)
		(stroke
			(width 0.07112)
			(type default)
		)
		(layer "In13.Cu")
	)
	(gr_line
		(start 138.333226 -398.703292)
		(end 137.914634 -398.619472)
		(stroke
			(width 0.07112)
			(type default)
		)
		(layer "In13.Cu")
	)
	(gr_line
		(start 138.385296 -399.141442)
		(end 137.697718 -399.00352)
		(stroke
			(width 0.07112)
			(type default)
		)
		(layer "In13.Cu")
	)
	(gr_line
		(start 138.403584 -397.594836)
		(end 137.981182 -397.532098)
		(stroke
			(width 0.07112)
			(type default)
		)
		(layer "In13.Cu")
	)
	(gr_line
		(start 138.41349 -415.003234)
		(end 138.317732 -414.308798)
		(stroke
			(width 0.07112)
			(type default)
		)
		(layer "In13.Cu")
	)
	(gr_line
		(start 138.431524 -399.882868)
		(end 138.268964 -399.985738)
		(stroke
			(width 0.07112)
			(type default)
		)
		(layer "In13.Cu")
	)
	(gr_line
		(start 138.439652 -398.863312)
		(end 138.333226 -398.703292)
		(stroke
			(width 0.07112)
			(type default)
		)
		(layer "In13.Cu")
	)
	(gr_line
		(start 138.477752 -398.029684)
		(end 137.784078 -397.926814)
		(stroke
			(width 0.07112)
			(type default)
		)
		(layer "In13.Cu")
	)
	(gr_line
		(start 138.518138 -397.749522)
		(end 138.403584 -397.594836)
		(stroke
			(width 0.07112)
			(type default)
		)
		(layer "In13.Cu")
	)
	(gr_line
		(start 138.567414 -416.120834)
		(end 138.471656 -415.42589)
		(stroke
			(width 0.07112)
			(type default)
		)
		(layer "In13.Cu")
	)
	(gr_line
		(start 138.663426 -395.172946)
		(end 138.514836 -395.29512)
		(stroke
			(width 0.07112)
			(type default)
		)
		(layer "In13.Cu")
	)
	(gr_line
		(start 138.693906 -414.96361)
		(end 138.809984 -414.810448)
		(stroke
			(width 0.07112)
			(type default)
		)
		(layer "In13.Cu")
	)
	(gr_line
		(start 138.698986 -396.416276)
		(end 138.544554 -396.53083)
		(stroke
			(width 0.07112)
			(type default)
		)
		(layer "In13.Cu")
	)
	(gr_line
		(start 138.751818 -414.387284)
		(end 138.598402 -414.271206)
		(stroke
			(width 0.07112)
			(type default)
		)
		(layer "In13.Cu")
	)
	(gr_line
		(start 138.809984 -414.810448)
		(end 138.751818 -414.387284)
		(stroke
			(width 0.07112)
			(type default)
		)
		(layer "In13.Cu")
	)
	(gr_line
		(start 138.848084 -416.080956)
		(end 138.964162 -415.92754)
		(stroke
			(width 0.07112)
			(type default)
		)
		(layer "In13.Cu")
	)
	(gr_line
		(start 138.848084 -399.976594)
		(end 138.431524 -399.882868)
		(stroke
			(width 0.07112)
			(type default)
		)
		(layer "In13.Cu")
	)
	(gr_line
		(start 138.889994 -400.416014)
		(end 138.205718 -400.261836)
		(stroke
			(width 0.07112)
			(type default)
		)
		(layer "In13.Cu")
	)
	(gr_line
		(start 138.905742 -415.50463)
		(end 138.75258 -415.388552)
		(stroke
			(width 0.07112)
			(type default)
		)
		(layer "In13.Cu")
	)
	(gr_line
		(start 138.951208 -400.139408)
		(end 138.848084 -399.976594)
		(stroke
			(width 0.07112)
			(type default)
		)
		(layer "In13.Cu")
	)
	(gr_line
		(start 138.964162 -415.92754)
		(end 138.905742 -415.50463)
		(stroke
			(width 0.07112)
			(type default)
		)
		(layer "In13.Cu")
	)
	(gr_line
		(start 138.980926 -401.170902)
		(end 138.811254 -401.26158)
		(stroke
			(width 0.07112)
			(type default)
		)
		(layer "In13.Cu")
	)
	(gr_arc
		(start 139.048236 -350.92005)
		(mid 139.050442 -350.929594)
		(end 139.052808 -350.9391)
		(stroke
			(width 0.07112)
			(type default)
		)
		(layer "In13.Cu")
	)
	(gr_line
		(start 139.048744 -398.846802)
		(end 138.88847 -398.953228)
		(stroke
			(width 0.07112)
			(type default)
		)
		(layer "In13.Cu")
	)
	(gr_arc
		(start 139.052808 -350.9391)
		(mid 139.0614 -350.968947)
		(end 139.071604 -350.998282)
		(stroke
			(width 0.07112)
			(type default)
		)
		(layer "In13.Cu")
	)
	(gr_arc
		(start 139.071604 -350.998282)
		(mid 139.074962 -351.006946)
		(end 139.078462 -351.015554)
		(stroke
			(width 0.07112)
			(type default)
		)
		(layer "In13.Cu")
	)
	(gr_line
		(start 139.088368 -395.214856)
		(end 138.663426 -395.172946)
		(stroke
			(width 0.07112)
			(type default)
		)
		(layer "In13.Cu")
	)
	(gr_line
		(start 139.121388 -396.47876)
		(end 138.698986 -396.416276)
		(stroke
			(width 0.07112)
			(type default)
		)
		(layer "In13.Cu")
	)
	(gr_line
		(start 139.183618 -395.64564)
		(end 138.48588 -395.576806)
		(stroke
			(width 0.07112)
			(type default)
		)
		(layer "In13.Cu")
	)
	(gr_line
		(start 139.195556 -396.913862)
		(end 138.501882 -396.810992)
		(stroke
			(width 0.07112)
			(type default)
		)
		(layer "In13.Cu")
	)
	(gr_line
		(start 139.210288 -395.3637)
		(end 139.088368 -395.214856)
		(stroke
			(width 0.07112)
			(type default)
		)
		(layer "In13.Cu")
	)
	(gr_line
		(start 139.235942 -396.633446)
		(end 139.121388 -396.47876)
		(stroke
			(width 0.07112)
			(type default)
		)
		(layer "In13.Cu")
	)
	(gr_line
		(start 139.32408 -350.861376)
		(end 139.328652 -350.884236)
		(stroke
			(width 0.07112)
			(type default)
		)
		(layer "In13.Cu")
	)
	(gr_line
		(start 139.328652 -350.884236)
		(end 139.337796 -350.90481)
		(stroke
			(width 0.07112)
			(type default)
		)
		(layer "In13.Cu")
	)
	(gr_line
		(start 139.389612 -401.294854)
		(end 138.980926 -401.170902)
		(stroke
			(width 0.07112)
			(type default)
		)
		(layer "In13.Cu")
	)
	(gr_line
		(start 139.399264 -401.735798)
		(end 138.728196 -401.532344)
		(stroke
			(width 0.07112)
			(type default)
		)
		(layer "In13.Cu")
	)
	(gr_line
		(start 139.413742 -397.744696)
		(end 139.25931 -397.859504)
		(stroke
			(width 0.07112)
			(type default)
		)
		(layer "In13.Cu")
	)
	(gr_line
		(start 139.467336 -398.930622)
		(end 139.048744 -398.846802)
		(stroke
			(width 0.07112)
			(type default)
		)
		(layer "In13.Cu")
	)
	(gr_line
		(start 139.48029 -401.464526)
		(end 139.389612 -401.294854)
		(stroke
			(width 0.07112)
			(type default)
		)
		(layer "In13.Cu")
	)
	(gr_line
		(start 139.51966 -399.368772)
		(end 138.831828 -399.23085)
		(stroke
			(width 0.07112)
			(type default)
		)
		(layer "In13.Cu")
	)
	(gr_line
		(start 139.532106 -400.130772)
		(end 139.369292 -400.233642)
		(stroke
			(width 0.07112)
			(type default)
		)
		(layer "In13.Cu")
	)
	(gr_line
		(start 139.574016 -399.090642)
		(end 139.467336 -398.930622)
		(stroke
			(width 0.07112)
			(type default)
		)
		(layer "In13.Cu")
	)
	(gr_line
		(start 139.616942 -371.543072)
		(end 139.616942 -372.244112)
		(stroke
			(width 0.07112)
			(type default)
		)
		(layer "In13.Cu")
	)
	(gr_line
		(start 139.616942 -370.415312)
		(end 139.616942 -371.116352)
		(stroke
			(width 0.07112)
			(type default)
		)
		(layer "In13.Cu")
	)
	(gr_line
		(start 139.616942 -369.27409)
		(end 139.616942 -369.97513)
		(stroke
			(width 0.07112)
			(type default)
		)
		(layer "In13.Cu")
	)
	(gr_line
		(start 139.616942 -367.859564)
		(end 139.616942 -368.560604)
		(stroke
			(width 0.07112)
			(type default)
		)
		(layer "In13.Cu")
	)
	(gr_line
		(start 139.622784 -435.038754)
		(end 139.611608 -435.038754)
		(stroke
			(width 0.07112)
			(type default)
		)
		(layer "In13.Cu")
	)
	(gr_line
		(start 139.690856 -409.601416)
		(end 139.690856 -408.900376)
		(stroke
			(width 0.07112)
			(type default)
		)
		(layer "In13.Cu")
	)
	(gr_line
		(start 139.690856 -408.473656)
		(end 139.690856 -407.772616)
		(stroke
			(width 0.07112)
			(type default)
		)
		(layer "In13.Cu")
	)
	(gr_line
		(start 139.749784 -435.489858)
		(end 139.749784 -435.165754)
		(stroke
			(width 0.07112)
			(type default)
		)
		(layer "In13.Cu")
	)
	(gr_line
		(start 139.749784 -435.165754)
		(end 139.622784 -435.038754)
		(stroke
			(width 0.07112)
			(type default)
		)
		(layer "In13.Cu")
	)
	(gr_line
		(start 139.749784 -434.618638)
		(end 139.612878 -434.755544)
		(stroke
			(width 0.07112)
			(type default)
		)
		(layer "In13.Cu")
	)
	(gr_line
		(start 139.749784 -434.289962)
		(end 139.749784 -434.618638)
		(stroke
			(width 0.07112)
			(type default)
		)
		(layer "In13.Cu")
	)
	(gr_line
		(start 139.836144 -397.807434)
		(end 139.413742 -397.744696)
		(stroke
			(width 0.07112)
			(type default)
		)
		(layer "In13.Cu")
	)
	(gr_line
		(start 139.898882 -366.136682)
		(end 139.898882 -366.137952)
		(stroke
			(width 0.07112)
			(type default)
		)
		(layer "In13.Cu")
	)
	(gr_line
		(start 139.900152 -371.544342)
		(end 140.036042 -371.680232)
		(stroke
			(width 0.07112)
			(type default)
		)
		(layer "In13.Cu")
	)
	(gr_line
		(start 139.900152 -370.416582)
		(end 140.036042 -370.552472)
		(stroke
			(width 0.07112)
			(type default)
		)
		(layer "In13.Cu")
	)
	(gr_line
		(start 139.900152 -369.27536)
		(end 140.036042 -369.41125)
		(stroke
			(width 0.07112)
			(type default)
		)
		(layer "In13.Cu")
	)
	(gr_line
		(start 139.900152 -367.860834)
		(end 140.036042 -367.996724)
		(stroke
			(width 0.07112)
			(type default)
		)
		(layer "In13.Cu")
	)
	(gr_line
		(start 139.910312 -398.242282)
		(end 139.216638 -398.139412)
		(stroke
			(width 0.07112)
			(type default)
		)
		(layer "In13.Cu")
	)
	(gr_line
		(start 139.948666 -400.224752)
		(end 139.532106 -400.130772)
		(stroke
			(width 0.07112)
			(type default)
		)
		(layer "In13.Cu")
	)
	(gr_line
		(start 139.950698 -397.961866)
		(end 139.836144 -397.807434)
		(stroke
			(width 0.07112)
			(type default)
		)
		(layer "In13.Cu")
	)
	(gr_line
		(start 139.974066 -409.600146)
		(end 140.109956 -409.464256)
		(stroke
			(width 0.07112)
			(type default)
		)
		(layer "In13.Cu")
	)
	(gr_line
		(start 139.974066 -408.472386)
		(end 140.109956 -408.336496)
		(stroke
			(width 0.07112)
			(type default)
		)
		(layer "In13.Cu")
	)
	(gr_line
		(start 139.990322 -400.663918)
		(end 139.306046 -400.50974)
		(stroke
			(width 0.07112)
			(type default)
		)
		(layer "In13.Cu")
	)
	(gr_line
		(start 140.0175 -395.306296)
		(end 139.86891 -395.42847)
		(stroke
			(width 0.07112)
			(type default)
		)
		(layer "In13.Cu")
	)
	(gr_line
		(start 140.036042 -372.106952)
		(end 139.900152 -372.242842)
		(stroke
			(width 0.07112)
			(type default)
		)
		(layer "In13.Cu")
	)
	(gr_line
		(start 140.036042 -371.680232)
		(end 140.036042 -372.106952)
		(stroke
			(width 0.07112)
			(type default)
		)
		(layer "In13.Cu")
	)
	(gr_line
		(start 140.036042 -370.979192)
		(end 139.900152 -371.115082)
		(stroke
			(width 0.07112)
			(type default)
		)
		(layer "In13.Cu")
	)
	(gr_line
		(start 140.036042 -370.552472)
		(end 140.036042 -370.979192)
		(stroke
			(width 0.07112)
			(type default)
		)
		(layer "In13.Cu")
	)
	(gr_line
		(start 140.036042 -369.83797)
		(end 139.900152 -369.97386)
		(stroke
			(width 0.07112)
			(type default)
		)
		(layer "In13.Cu")
	)
	(gr_line
		(start 140.036042 -369.41125)
		(end 140.036042 -369.83797)
		(stroke
			(width 0.07112)
			(type default)
		)
		(layer "In13.Cu")
	)
	(gr_line
		(start 140.036042 -368.423444)
		(end 139.900152 -368.559334)
		(stroke
			(width 0.07112)
			(type default)
		)
		(layer "In13.Cu")
	)
	(gr_line
		(start 140.036042 -367.996724)
		(end 140.036042 -368.423444)
		(stroke
			(width 0.07112)
			(type default)
		)
		(layer "In13.Cu")
	)
	(gr_line
		(start 140.051282 -400.387312)
		(end 139.948666 -400.224752)
		(stroke
			(width 0.07112)
			(type default)
		)
		(layer "In13.Cu")
	)
	(gr_line
		(start 140.109956 -409.464256)
		(end 140.109956 -409.037536)
		(stroke
			(width 0.07112)
			(type default)
		)
		(layer "In13.Cu")
	)
	(gr_line
		(start 140.109956 -409.037536)
		(end 139.974066 -408.901646)
		(stroke
			(width 0.07112)
			(type default)
		)
		(layer "In13.Cu")
	)
	(gr_line
		(start 140.109956 -408.336496)
		(end 140.109956 -407.909776)
		(stroke
			(width 0.07112)
			(type default)
		)
		(layer "In13.Cu")
	)
	(gr_line
		(start 140.109956 -407.909776)
		(end 139.974066 -407.773886)
		(stroke
			(width 0.07112)
			(type default)
		)
		(layer "In13.Cu")
	)
	(gr_line
		(start 140.302742 -396.654274)
		(end 140.14831 -396.769082)
		(stroke
			(width 0.07112)
			(type default)
		)
		(layer "In13.Cu")
	)
	(gr_line
		(start 140.406374 -400.757898)
		(end 140.406374 -400.757644)
		(stroke
			(width 0.07112)
			(type default)
		)
		(layer "In13.Cu")
	)
	(gr_line
		(start 140.442442 -395.348206)
		(end 140.0175 -395.306296)
		(stroke
			(width 0.07112)
			(type default)
		)
		(layer "In13.Cu")
	)
	(gr_line
		(start 140.521944 -316.15634)
		(end 140.521944 -316.156594)
		(stroke
			(width 0.07112)
			(type default)
		)
		(layer "In13.Cu")
	)
	(gr_line
		(start 140.537946 -395.77899)
		(end 139.839954 -395.710156)
		(stroke
			(width 0.07112)
			(type default)
		)
		(layer "In13.Cu")
	)
	(gr_line
		(start 140.564616 -395.49705)
		(end 140.442442 -395.348206)
		(stroke
			(width 0.07112)
			(type default)
		)
		(layer "In13.Cu")
	)
	(gr_line
		(start 140.632434 -400.378676)
		(end 140.46962 -400.4818)
		(stroke
			(width 0.07112)
			(type default)
		)
		(layer "In13.Cu")
	)
	(gr_line
		(start 140.725144 -396.717012)
		(end 140.302742 -396.654274)
		(stroke
			(width 0.07112)
			(type default)
		)
		(layer "In13.Cu")
	)
	(gr_line
		(start 140.767562 -382.07823)
		(end 141.058392 -382.36906)
		(stroke
			(width 0.07112)
			(type default)
		)
		(layer "In13.Cu")
	)
	(gr_line
		(start 140.767562 -381.79629)
		(end 141.058392 -381.50546)
		(stroke
			(width 0.07112)
			(type default)
		)
		(layer "In13.Cu")
	)
	(gr_line
		(start 140.799312 -397.15186)
		(end 140.105638 -397.04899)
		(stroke
			(width 0.07112)
			(type default)
		)
		(layer "In13.Cu")
	)
	(gr_line
		(start 140.839698 -396.871698)
		(end 140.725144 -396.717012)
		(stroke
			(width 0.07112)
			(type default)
		)
		(layer "In13.Cu")
	)
	(gr_line
		(start 140.88999 -370.70284)
		(end 141.02588 -370.83873)
		(stroke
			(width 0.07112)
			(type default)
		)
		(layer "In13.Cu")
	)
	(gr_line
		(start 140.88999 -370.27612)
		(end 140.88999 -370.70284)
		(stroke
			(width 0.07112)
			(type default)
		)
		(layer "In13.Cu")
	)
	(gr_line
		(start 140.88999 -369.57508)
		(end 141.02588 -369.71097)
		(stroke
			(width 0.07112)
			(type default)
		)
		(layer "In13.Cu")
	)
	(gr_line
		(start 140.88999 -369.14836)
		(end 140.88999 -369.57508)
		(stroke
			(width 0.07112)
			(type default)
		)
		(layer "In13.Cu")
	)
	(gr_line
		(start 140.88999 -368.44732)
		(end 141.02588 -368.58321)
		(stroke
			(width 0.07112)
			(type default)
		)
		(layer "In13.Cu")
	)
	(gr_line
		(start 140.88999 -368.0206)
		(end 140.88999 -368.44732)
		(stroke
			(width 0.07112)
			(type default)
		)
		(layer "In13.Cu")
	)
	(gr_line
		(start 141.02588 -370.14023)
		(end 140.88999 -370.27612)
		(stroke
			(width 0.07112)
			(type default)
		)
		(layer "In13.Cu")
	)
	(gr_line
		(start 141.02588 -369.01247)
		(end 140.88999 -369.14836)
		(stroke
			(width 0.07112)
			(type default)
		)
		(layer "In13.Cu")
	)
	(gr_line
		(start 141.02588 -367.88471)
		(end 140.88999 -368.0206)
		(stroke
			(width 0.07112)
			(type default)
		)
		(layer "In13.Cu")
	)
	(gr_line
		(start 141.04874 -400.472656)
		(end 140.632434 -400.378676)
		(stroke
			(width 0.07112)
			(type default)
		)
		(layer "In13.Cu")
	)
	(gr_line
		(start 141.07795 -411.654498)
		(end 141.077696 -411.654498)
		(stroke
			(width 0.07112)
			(type default)
		)
		(layer "In13.Cu")
	)
	(gr_line
		(start 141.09065 -400.912076)
		(end 140.406374 -400.757898)
		(stroke
			(width 0.07112)
			(type default)
		)
		(layer "In13.Cu")
	)
	(gr_line
		(start 141.151864 -400.63547)
		(end 141.04874 -400.472656)
		(stroke
			(width 0.07112)
			(type default)
		)
		(layer "In13.Cu")
	)
	(gr_line
		(start 141.30909 -370.13896)
		(end 141.30909 -370.84)
		(stroke
			(width 0.07112)
			(type default)
		)
		(layer "In13.Cu")
	)
	(gr_line
		(start 141.30909 -369.0112)
		(end 141.30909 -369.71224)
		(stroke
			(width 0.07112)
			(type default)
		)
		(layer "In13.Cu")
	)
	(gr_line
		(start 141.30909 -367.88344)
		(end 141.30909 -368.58448)
		(stroke
			(width 0.07112)
			(type default)
		)
		(layer "In13.Cu")
	)
	(gr_line
		(start 141.343126 -315.712094)
		(end 141.343126 -315.712348)
		(stroke
			(width 0.07112)
			(type default)
		)
		(layer "In13.Cu")
	)
	(gr_line
		(start 141.349222 -376.54103)
		(end 141.058392 -376.83186)
		(stroke
			(width 0.07112)
			(type default)
		)
		(layer "In13.Cu")
	)
	(gr_line
		(start 141.349222 -376.25909)
		(end 141.058392 -375.96826)
		(stroke
			(width 0.07112)
			(type default)
		)
		(layer "In13.Cu")
	)
	(gr_line
		(start 141.367764 -414.720532)
		(end 141.29893 -414.02254)
		(stroke
			(width 0.07112)
			(type default)
		)
		(layer "In13.Cu")
	)
	(gr_line
		(start 141.504162 -416.105086)
		(end 141.435328 -415.407348)
		(stroke
			(width 0.07112)
			(type default)
		)
		(layer "In13.Cu")
	)
	(gr_line
		(start 141.607032 -398.07007)
		(end 141.4526 -398.184878)
		(stroke
			(width 0.07112)
			(type default)
		)
		(layer "In13.Cu")
	)
	(gr_line
		(start 141.616176 -373.62765)
		(end 141.779498 -374.022112)
		(stroke
			(width 0.07112)
			(type default)
		)
		(layer "In13.Cu")
	)
	(gr_line
		(start 141.64183 -418.063934)
		(end 141.607286 -417.363402)
		(stroke
			(width 0.07112)
			(type default)
		)
		(layer "In13.Cu")
	)
	(gr_line
		(start 141.64945 -414.691576)
		(end 141.771624 -414.542986)
		(stroke
			(width 0.07112)
			(type default)
		)
		(layer "In13.Cu")
	)
	(gr_line
		(start 141.689836 -373.44985)
		(end 141.616176 -373.62765)
		(stroke
			(width 0.07112)
			(type default)
		)
		(layer "In13.Cu")
	)
	(gr_line
		(start 141.729714 -414.118044)
		(end 141.58087 -413.99587)
		(stroke
			(width 0.07112)
			(type default)
		)
		(layer "In13.Cu")
	)
	(gr_line
		(start 141.732762 -400.62658)
		(end 141.569694 -400.729704)
		(stroke
			(width 0.07112)
			(type default)
		)
		(layer "In13.Cu")
	)
	(gr_line
		(start 141.771624 -414.542986)
		(end 141.729714 -414.118044)
		(stroke
			(width 0.07112)
			(type default)
		)
		(layer "In13.Cu")
	)
	(gr_line
		(start 141.779498 -374.022112)
		(end 141.957298 -374.095518)
		(stroke
			(width 0.07112)
			(type default)
		)
		(layer "In13.Cu")
	)
	(gr_line
		(start 141.785848 -416.07613)
		(end 141.908022 -415.92754)
		(stroke
			(width 0.07112)
			(type default)
		)
		(layer "In13.Cu")
	)
	(gr_line
		(start 141.866112 -415.502598)
		(end 141.717268 -415.380678)
		(stroke
			(width 0.07112)
			(type default)
		)
		(layer "In13.Cu")
	)
	(gr_line
		(start 141.908022 -415.92754)
		(end 141.866112 -415.502598)
		(stroke
			(width 0.07112)
			(type default)
		)
		(layer "In13.Cu")
	)
	(gr_line
		(start 141.924532 -418.049202)
		(end 142.053818 -417.906454)
		(stroke
			(width 0.07112)
			(type default)
		)
		(layer "In13.Cu")
	)
	(gr_line
		(start 141.950948 -373.340376)
		(end 142.219426 -373.98833)
		(stroke
			(width 0.07112)
			(type default)
		)
		(layer "In13.Cu")
	)
	(gr_line
		(start 141.984476 -376.25909)
		(end 141.983968 -376.25909)
		(stroke
			(width 0.07112)
			(type default)
		)
		(layer "In13.Cu")
	)
	(gr_line
		(start 142.029434 -398.132554)
		(end 141.607032 -398.07007)
		(stroke
			(width 0.07112)
			(type default)
		)
		(layer "In13.Cu")
	)
	(gr_line
		(start 142.03299 -417.479988)
		(end 141.890242 -417.350702)
		(stroke
			(width 0.07112)
			(type default)
		)
		(layer "In13.Cu")
	)
	(gr_line
		(start 142.053818 -417.906454)
		(end 142.03299 -417.479988)
		(stroke
			(width 0.07112)
			(type default)
		)
		(layer "In13.Cu")
	)
	(gr_line
		(start 142.103856 -398.567656)
		(end 141.409928 -398.464786)
		(stroke
			(width 0.07112)
			(type default)
		)
		(layer "In13.Cu")
	)
	(gr_line
		(start 142.143988 -398.28724)
		(end 142.029434 -398.132554)
		(stroke
			(width 0.07112)
			(type default)
		)
		(layer "In13.Cu")
	)
	(gr_line
		(start 142.149068 -400.72056)
		(end 141.732762 -400.62658)
		(stroke
			(width 0.07112)
			(type default)
		)
		(layer "In13.Cu")
	)
	(gr_line
		(start 142.190978 -401.15998)
		(end 141.506702 -401.005802)
		(stroke
			(width 0.07112)
			(type default)
		)
		(layer "In13.Cu")
	)
	(gr_line
		(start 142.252192 -400.883628)
		(end 142.149068 -400.72056)
		(stroke
			(width 0.07112)
			(type default)
		)
		(layer "In13.Cu")
	)
	(gr_line
		(start 142.340076 -396.956788)
		(end 142.18539 -397.071342)
		(stroke
			(width 0.07112)
			(type default)
		)
		(layer "In13.Cu")
	)
	(gr_line
		(start 142.456916 -317.796164)
		(end 142.456916 -317.796418)
		(stroke
			(width 0.07112)
			(type default)
		)
		(layer "In13.Cu")
	)
	(gr_line
		(start 142.623032 -434.038756)
		(end 142.611856 -434.038756)
		(stroke
			(width 0.07112)
			(type default)
		)
		(layer "In13.Cu")
	)
	(gr_line
		(start 142.750032 -434.48986)
		(end 142.750032 -434.165756)
		(stroke
			(width 0.07112)
			(type default)
		)
		(layer "In13.Cu")
	)
	(gr_line
		(start 142.750032 -434.165756)
		(end 142.623032 -434.038756)
		(stroke
			(width 0.07112)
			(type default)
		)
		(layer "In13.Cu")
	)
	(gr_line
		(start 142.750032 -433.61864)
		(end 142.613126 -433.755546)
		(stroke
			(width 0.07112)
			(type default)
		)
		(layer "In13.Cu")
	)
	(gr_line
		(start 142.750032 -433.289964)
		(end 142.750032 -433.61864)
		(stroke
			(width 0.07112)
			(type default)
		)
		(layer "In13.Cu")
	)
	(gr_line
		(start 142.754096 -409.22702)
		(end 142.754096 -408.52598)
		(stroke
			(width 0.07112)
			(type default)
		)
		(layer "In13.Cu")
	)
	(gr_line
		(start 142.754096 -408.09926)
		(end 142.754096 -407.39822)
		(stroke
			(width 0.07112)
			(type default)
		)
		(layer "In13.Cu")
	)
	(gr_line
		(start 142.756128 -398.240504)
		(end 142.601696 -398.355312)
		(stroke
			(width 0.07112)
			(type default)
		)
		(layer "In13.Cu")
	)
	(gr_line
		(start 142.762224 -397.019526)
		(end 142.340076 -396.956788)
		(stroke
			(width 0.07112)
			(type default)
		)
		(layer "In13.Cu")
	)
	(gr_line
		(start 142.832836 -400.874738)
		(end 142.670022 -400.977608)
		(stroke
			(width 0.07112)
			(type default)
		)
		(layer "In13.Cu")
	)
	(gr_line
		(start 142.836392 -397.454374)
		(end 142.142718 -397.351504)
		(stroke
			(width 0.07112)
			(type default)
		)
		(layer "In13.Cu")
	)
	(gr_line
		(start 142.876778 -397.174212)
		(end 142.762224 -397.019526)
		(stroke
			(width 0.07112)
			(type default)
		)
		(layer "In13.Cu")
	)
	(gr_line
		(start 142.933674 -371.2083)
		(end 142.642844 -371.49913)
		(stroke
			(width 0.07112)
			(type default)
		)
		(layer "In13.Cu")
	)
	(gr_line
		(start 143.037306 -409.22575)
		(end 143.173196 -409.08986)
		(stroke
			(width 0.07112)
			(type default)
		)
		(layer "In13.Cu")
	)
	(gr_line
		(start 143.037306 -408.09799)
		(end 143.173196 -407.9621)
		(stroke
			(width 0.07112)
			(type default)
		)
		(layer "In13.Cu")
	)
	(gr_line
		(start 143.067024 -395.606524)
		(end 142.91818 -395.728698)
		(stroke
			(width 0.07112)
			(type default)
		)
		(layer "In13.Cu")
	)
	(gr_line
		(start 143.173196 -409.08986)
		(end 143.173196 -408.66314)
		(stroke
			(width 0.07112)
			(type default)
		)
		(layer "In13.Cu")
	)
	(gr_line
		(start 143.173196 -408.66314)
		(end 143.037306 -408.52725)
		(stroke
			(width 0.07112)
			(type default)
		)
		(layer "In13.Cu")
	)
	(gr_line
		(start 143.173196 -407.9621)
		(end 143.173196 -407.53538)
		(stroke
			(width 0.07112)
			(type default)
		)
		(layer "In13.Cu")
	)
	(gr_line
		(start 143.173196 -407.53538)
		(end 143.037306 -407.39949)
		(stroke
			(width 0.07112)
			(type default)
		)
		(layer "In13.Cu")
	)
	(gr_line
		(start 143.17853 -398.302988)
		(end 142.756128 -398.240504)
		(stroke
			(width 0.07112)
			(type default)
		)
		(layer "In13.Cu")
	)
	(gr_line
		(start 143.215614 -371.2083)
		(end 143.506444 -371.49913)
		(stroke
			(width 0.07112)
			(type default)
		)
		(layer "In13.Cu")
	)
	(gr_line
		(start 143.249396 -400.968718)
		(end 142.832836 -400.874738)
		(stroke
			(width 0.07112)
			(type default)
		)
		(layer "In13.Cu")
	)
	(gr_line
		(start 143.252698 -398.73809)
		(end 142.559278 -398.63522)
		(stroke
			(width 0.07112)
			(type default)
		)
		(layer "In13.Cu")
	)
	(gr_line
		(start 143.291052 -401.407884)
		(end 142.60703 -401.253706)
		(stroke
			(width 0.07112)
			(type default)
		)
		(layer "In13.Cu")
	)
	(gr_line
		(start 143.293084 -398.457674)
		(end 143.17853 -398.302988)
		(stroke
			(width 0.07112)
			(type default)
		)
		(layer "In13.Cu")
	)
	(gr_line
		(start 143.352266 -401.131532)
		(end 143.249396 -400.968718)
		(stroke
			(width 0.07112)
			(type default)
		)
		(layer "In13.Cu")
	)
	(gr_line
		(start 143.491966 -395.648434)
		(end 143.067024 -395.606524)
		(stroke
			(width 0.07112)
			(type default)
		)
		(layer "In13.Cu")
	)
	(gr_line
		(start 143.527018 -399.744184)
		(end 143.366744 -399.850864)
		(stroke
			(width 0.07112)
			(type default)
		)
		(layer "In13.Cu")
	)
	(gr_line
		(start 143.587216 -396.079218)
		(end 142.889224 -396.010384)
		(stroke
			(width 0.07112)
			(type default)
		)
		(layer "In13.Cu")
	)
	(gr_line
		(start 143.613886 -395.797278)
		(end 143.491966 -395.648434)
		(stroke
			(width 0.07112)
			(type default)
		)
		(layer "In13.Cu")
	)
	(gr_line
		(start 143.94561 -399.828004)
		(end 143.527018 -399.744184)
		(stroke
			(width 0.07112)
			(type default)
		)
		(layer "In13.Cu")
	)
	(gr_line
		(start 143.979138 -419.632638)
		(end 143.979392 -419.632638)
		(stroke
			(width 0.07112)
			(type default)
		)
		(layer "In13.Cu")
	)
	(gr_line
		(start 143.979392 -419.632638)
		(end 143.979392 -419.631114)
		(stroke
			(width 0.07112)
			(type default)
		)
		(layer "In13.Cu")
	)
	(gr_line
		(start 143.979392 -419.631114)
		(end 144.01292 -418.930582)
		(stroke
			(width 0.07112)
			(type default)
		)
		(layer "In13.Cu")
	)
	(gr_line
		(start 143.99768 -400.2659)
		(end 143.310102 -400.128232)
		(stroke
			(width 0.07112)
			(type default)
		)
		(layer "In13.Cu")
	)
	(gr_line
		(start 144.03324 -418.50437)
		(end 144.066768 -417.804092)
		(stroke
			(width 0.07112)
			(type default)
		)
		(layer "In13.Cu")
	)
	(gr_line
		(start 144.052036 -399.988024)
		(end 143.94561 -399.828004)
		(stroke
			(width 0.07112)
			(type default)
		)
		(layer "In13.Cu")
	)
	(gr_line
		(start 144.087088 -417.37788)
		(end 144.120362 -416.677856)
		(stroke
			(width 0.07112)
			(type default)
		)
		(layer "In13.Cu")
	)
	(gr_line
		(start 144.140682 -416.251644)
		(end 144.17421 -415.551112)
		(stroke
			(width 0.07112)
			(type default)
		)
		(layer "In13.Cu")
	)
	(gr_line
		(start 144.218406 -414.622742)
		(end 144.251934 -413.921956)
		(stroke
			(width 0.07112)
			(type default)
		)
		(layer "In13.Cu")
	)
	(gr_line
		(start 144.261078 -419.6461)
		(end 144.261078 -419.644576)
		(stroke
			(width 0.07112)
			(type default)
		)
		(layer "In13.Cu")
	)
	(gr_line
		(start 144.262348 -419.643306)
		(end 144.404842 -419.51402)
		(stroke
			(width 0.07112)
			(type default)
		)
		(layer "In13.Cu")
	)
	(gr_line
		(start 144.316196 -418.516816)
		(end 144.458944 -418.38753)
		(stroke
			(width 0.07112)
			(type default)
		)
		(layer "In13.Cu")
	)
	(gr_line
		(start 144.36979 -417.39058)
		(end 144.512792 -417.26104)
		(stroke
			(width 0.07112)
			(type default)
		)
		(layer "In13.Cu")
	)
	(gr_line
		(start 144.404842 -419.51402)
		(end 144.425416 -419.087554)
		(stroke
			(width 0.07112)
			(type default)
		)
		(layer "In13.Cu")
	)
	(gr_line
		(start 144.423638 -416.263836)
		(end 144.56664 -416.13455)
		(stroke
			(width 0.07112)
			(type default)
		)
		(layer "In13.Cu")
	)
	(gr_line
		(start 144.425416 -419.087554)
		(end 144.295622 -418.94506)
		(stroke
			(width 0.07112)
			(type default)
		)
		(layer "In13.Cu")
	)
	(gr_line
		(start 144.436338 -366.070896)
		(end 144.436592 -366.070896)
		(stroke
			(width 0.07112)
			(type default)
		)
		(layer "In13.Cu")
	)
	(gr_line
		(start 144.436592 -366.070896)
		(end 144.440402 -366.082326)
		(stroke
			(width 0.07112)
			(type default)
		)
		(layer "In13.Cu")
	)
	(gr_line
		(start 144.440402 -366.082326)
		(end 144.44345 -366.09401)
		(stroke
			(width 0.07112)
			(type default)
		)
		(layer "In13.Cu")
	)
	(gr_line
		(start 144.458944 -418.38753)
		(end 144.479264 -417.961064)
		(stroke
			(width 0.07112)
			(type default)
		)
		(layer "In13.Cu")
	)
	(gr_line
		(start 144.479264 -417.961064)
		(end 144.34947 -417.818316)
		(stroke
			(width 0.07112)
			(type default)
		)
		(layer "In13.Cu")
	)
	(gr_line
		(start 144.501362 -414.635188)
		(end 144.64411 -414.505648)
		(stroke
			(width 0.07112)
			(type default)
		)
		(layer "In13.Cu")
	)
	(gr_line
		(start 144.512792 -417.26104)
		(end 144.533112 -416.834574)
		(stroke
			(width 0.07112)
			(type default)
		)
		(layer "In13.Cu")
	)
	(gr_line
		(start 144.533112 -416.834574)
		(end 144.403318 -416.691826)
		(stroke
			(width 0.07112)
			(type default)
		)
		(layer "In13.Cu")
	)
	(gr_line
		(start 144.533874 -413.935672)
		(end 144.53362 -413.935418)
		(stroke
			(width 0.07112)
			(type default)
		)
		(layer "In13.Cu")
	)
	(gr_line
		(start 144.56664 -416.13455)
		(end 144.586706 -415.708084)
		(stroke
			(width 0.07112)
			(type default)
		)
		(layer "In13.Cu")
	)
	(gr_line
		(start 144.586706 -415.708084)
		(end 144.456912 -415.565336)
		(stroke
			(width 0.07112)
			(type default)
		)
		(layer "In13.Cu")
	)
	(gr_line
		(start 144.623028 -435.038754)
		(end 144.611852 -435.038754)
		(stroke
			(width 0.07112)
			(type default)
		)
		(layer "In13.Cu")
	)
	(gr_line
		(start 144.635474 -368.7445)
		(end 144.344644 -369.03533)
		(stroke
			(width 0.07112)
			(type default)
		)
		(layer "In13.Cu")
	)
	(gr_line
		(start 144.64411 -414.505648)
		(end 144.66443 -414.079182)
		(stroke
			(width 0.07112)
			(type default)
		)
		(layer "In13.Cu")
	)
	(gr_line
		(start 144.66443 -414.079182)
		(end 144.534636 -413.936688)
		(stroke
			(width 0.07112)
			(type default)
		)
		(layer "In13.Cu")
	)
	(gr_line
		(start 144.750028 -435.489858)
		(end 144.750028 -435.165754)
		(stroke
			(width 0.07112)
			(type default)
		)
		(layer "In13.Cu")
	)
	(gr_line
		(start 144.750028 -435.165754)
		(end 144.623028 -435.038754)
		(stroke
			(width 0.07112)
			(type default)
		)
		(layer "In13.Cu")
	)
	(gr_line
		(start 144.750028 -434.618638)
		(end 144.613122 -434.755544)
		(stroke
			(width 0.07112)
			(type default)
		)
		(layer "In13.Cu")
	)
	(gr_line
		(start 144.750028 -434.289962)
		(end 144.750028 -434.618638)
		(stroke
			(width 0.07112)
			(type default)
		)
		(layer "In13.Cu")
	)
	(gr_line
		(start 144.772126 -397.317976)
		(end 144.617694 -397.43253)
		(stroke
			(width 0.07112)
			(type default)
		)
		(layer "In13.Cu")
	)
	(gr_line
		(start 144.917414 -368.7445)
		(end 145.208244 -369.03533)
		(stroke
			(width 0.07112)
			(type default)
		)
		(layer "In13.Cu")
	)
	(gr_line
		(start 145.176494 -395.814296)
		(end 145.027904 -395.93647)
		(stroke
			(width 0.07112)
			(type default)
		)
		(layer "In13.Cu")
	)
	(gr_line
		(start 145.194528 -397.38046)
		(end 144.772126 -397.317976)
		(stroke
			(width 0.07112)
			(type default)
		)
		(layer "In13.Cu")
	)
	(gr_line
		(start 145.268696 -397.815562)
		(end 144.575022 -397.712438)
		(stroke
			(width 0.07112)
			(type default)
		)
		(layer "In13.Cu")
	)
	(gr_line
		(start 145.29689 -397.819626)
		(end 145.268696 -397.815562)
		(stroke
			(width 0.07112)
			(type default)
		)
		(layer "In13.Cu")
	)
	(gr_line
		(start 145.309082 -397.535146)
		(end 145.194528 -397.38046)
		(stroke
			(width 0.07112)
			(type default)
		)
		(layer "In13.Cu")
	)
	(gr_line
		(start 145.338292 -397.540734)
		(end 145.310098 -397.53667)
		(stroke
			(width 0.07112)
			(type default)
		)
		(layer "In13.Cu")
	)
	(gr_line
		(start 145.601436 -395.856206)
		(end 145.176494 -395.814296)
		(stroke
			(width 0.07112)
			(type default)
		)
		(layer "In13.Cu")
	)
	(gr_line
		(start 145.69694 -396.28699)
		(end 144.998948 -396.218156)
		(stroke
			(width 0.07112)
			(type default)
		)
		(layer "In13.Cu")
	)
	(gr_line
		(start 145.72361 -396.00505)
		(end 145.601436 -395.856206)
		(stroke
			(width 0.07112)
			(type default)
		)
		(layer "In13.Cu")
	)
	(gr_line
		(start 145.817336 -409.401264)
		(end 145.817336 -408.700224)
		(stroke
			(width 0.07112)
			(type default)
		)
		(layer "In13.Cu")
	)
	(gr_line
		(start 145.817336 -408.273504)
		(end 145.817336 -407.572464)
		(stroke
			(width 0.07112)
			(type default)
		)
		(layer "In13.Cu")
	)
	(gr_arc
		(start 145.826734 -365.568484)
		(mid 145.825852 -365.565307)
		(end 145.824956 -365.562134)
		(stroke
			(width 0.07112)
			(type default)
		)
		(layer "In13.Cu")
	)
	(gr_line
		(start 146.099022 -422.092374)
		(end 146.201892 -421.398446)
		(stroke
			(width 0.07112)
			(type default)
		)
		(layer "In13.Cu")
	)
	(gr_line
		(start 146.100546 -409.399994)
		(end 146.236436 -409.264104)
		(stroke
			(width 0.07112)
			(type default)
		)
		(layer "In13.Cu")
	)
	(gr_line
		(start 146.100546 -408.272234)
		(end 146.236436 -408.136344)
		(stroke
			(width 0.07112)
			(type default)
		)
		(layer "In13.Cu")
	)
	(gr_line
		(start 146.236436 -409.264104)
		(end 146.236436 -408.837384)
		(stroke
			(width 0.07112)
			(type default)
		)
		(layer "In13.Cu")
	)
	(gr_line
		(start 146.236436 -408.837384)
		(end 146.100546 -408.701494)
		(stroke
			(width 0.07112)
			(type default)
		)
		(layer "In13.Cu")
	)
	(gr_line
		(start 146.236436 -408.136344)
		(end 146.236436 -407.709624)
		(stroke
			(width 0.07112)
			(type default)
		)
		(layer "In13.Cu")
	)
	(gr_line
		(start 146.236436 -407.709624)
		(end 146.100546 -407.573734)
		(stroke
			(width 0.07112)
			(type default)
		)
		(layer "In13.Cu")
	)
	(gr_line
		(start 146.264376 -420.976552)
		(end 146.367246 -420.282878)
		(stroke
			(width 0.07112)
			(type default)
		)
		(layer "In13.Cu")
	)
	(gr_line
		(start 146.379438 -422.13276)
		(end 146.534124 -422.018206)
		(stroke
			(width 0.07112)
			(type default)
		)
		(layer "In13.Cu")
	)
	(gr_line
		(start 146.508216 -397.575532)
		(end 146.353276 -397.69034)
		(stroke
			(width 0.07112)
			(type default)
		)
		(layer "In13.Cu")
	)
	(gr_line
		(start 146.534124 -422.018206)
		(end 146.596608 -421.595804)
		(stroke
			(width 0.07112)
			(type default)
		)
		(layer "In13.Cu")
	)
	(gr_line
		(start 146.544792 -421.016938)
		(end 146.699478 -420.902638)
		(stroke
			(width 0.07112)
			(type default)
		)
		(layer "In13.Cu")
	)
	(gr_line
		(start 146.550126 -419.049454)
		(end 146.652996 -418.35578)
		(stroke
			(width 0.07112)
			(type default)
		)
		(layer "In13.Cu")
	)
	(gr_line
		(start 146.596608 -421.595804)
		(end 146.4818 -421.441118)
		(stroke
			(width 0.07112)
			(type default)
		)
		(layer "In13.Cu")
	)
	(gr_line
		(start 146.635724 -433.73294)
		(end 146.599148 -433.73294)
		(stroke
			(width 0.07112)
			(type default)
		)
		(layer "In13.Cu")
	)
	(gr_arc
		(start 146.689318 -402.633942)
		(mid 146.689699 -402.634196)
		(end 146.69008 -402.63445)
		(stroke
			(width 0.07112)
			(type default)
		)
		(layer "In13.Cu")
	)
	(gr_line
		(start 146.699478 -420.902638)
		(end 146.761962 -420.480236)
		(stroke
			(width 0.07112)
			(type default)
		)
		(layer "In13.Cu")
	)
	(gr_line
		(start 146.750024 -434.48986)
		(end 146.750024 -434.165756)
		(stroke
			(width 0.07112)
			(type default)
		)
		(layer "In13.Cu")
	)
	(gr_line
		(start 146.750024 -434.165756)
		(end 146.600418 -434.01615)
		(stroke
			(width 0.07112)
			(type default)
		)
		(layer "In13.Cu")
	)
	(gr_line
		(start 146.750024 -433.61864)
		(end 146.635724 -433.73294)
		(stroke
			(width 0.07112)
			(type default)
		)
		(layer "In13.Cu")
	)
	(gr_line
		(start 146.750024 -433.289964)
		(end 146.750024 -433.61864)
		(stroke
			(width 0.07112)
			(type default)
		)
		(layer "In13.Cu")
	)
	(gr_line
		(start 146.752818 -417.68268)
		(end 146.855688 -416.989006)
		(stroke
			(width 0.07112)
			(type default)
		)
		(layer "In13.Cu")
	)
	(gr_line
		(start 146.761962 -420.480236)
		(end 146.647408 -420.32555)
		(stroke
			(width 0.07112)
			(type default)
		)
		(layer "In13.Cu")
	)
	(gr_line
		(start 146.830542 -419.08984)
		(end 146.985228 -418.975286)
		(stroke
			(width 0.07112)
			(type default)
		)
		(layer "In13.Cu")
	)
	(gr_line
		(start 146.871182 -360.347006)
		(end 146.88566 -360.376724)
		(stroke
			(width 0.07112)
			(type default)
		)
		(layer "In13.Cu")
	)
	(gr_line
		(start 146.88566 -360.376724)
		(end 146.903186 -360.403394)
		(stroke
			(width 0.07112)
			(type default)
		)
		(layer "In13.Cu")
	)
	(gr_line
		(start 146.927824 -416.503358)
		(end 147.030694 -415.809684)
		(stroke
			(width 0.07112)
			(type default)
		)
		(layer "In13.Cu")
	)
	(gr_line
		(start 146.930364 -397.63827)
		(end 146.508216 -397.575532)
		(stroke
			(width 0.07112)
			(type default)
		)
		(layer "In13.Cu")
	)
	(gr_line
		(start 146.985228 -418.975286)
		(end 147.047966 -418.552884)
		(stroke
			(width 0.07112)
			(type default)
		)
		(layer "In13.Cu")
	)
	(gr_line
		(start 147.004532 -398.073372)
		(end 146.310858 -397.970248)
		(stroke
			(width 0.07112)
			(type default)
		)
		(layer "In13.Cu")
	)
	(gr_line
		(start 147.033234 -417.723066)
		(end 147.18792 -417.608512)
		(stroke
			(width 0.07112)
			(type default)
		)
		(layer "In13.Cu")
	)
	(gr_line
		(start 147.044918 -397.792956)
		(end 146.930364 -397.63827)
		(stroke
			(width 0.07112)
			(type default)
		)
		(layer "In13.Cu")
	)
	(gr_line
		(start 147.047966 -418.552884)
		(end 146.933158 -418.398198)
		(stroke
			(width 0.07112)
			(type default)
		)
		(layer "In13.Cu")
	)
	(gr_arc
		(start 147.12315 -360.21772)
		(mid 147.13288 -360.235219)
		(end 147.142962 -360.252518)
		(stroke
			(width 0.07112)
			(type default)
		)
		(layer "In13.Cu")
	)
	(gr_line
		(start 147.18792 -417.608512)
		(end 147.250658 -417.18611)
		(stroke
			(width 0.07112)
			(type default)
		)
		(layer "In13.Cu")
	)
	(gr_line
		(start 147.20824 -416.543998)
		(end 147.362926 -416.42919)
		(stroke
			(width 0.07112)
			(type default)
		)
		(layer "In13.Cu")
	)
	(gr_line
		(start 147.244816 -411.771338)
		(end 147.245324 -411.771846)
		(stroke
			(width 0.07112)
			(type default)
		)
		(layer "In13.Cu")
	)
	(gr_line
		(start 147.250658 -417.18611)
		(end 147.13585 -417.031424)
		(stroke
			(width 0.07112)
			(type default)
		)
		(layer "In13.Cu")
	)
	(gr_line
		(start 147.27428 -370.408708)
		(end 147.274534 -370.408962)
		(stroke
			(width 0.07112)
			(type default)
		)
		(layer "In13.Cu")
	)
	(gr_line
		(start 147.362926 -416.42919)
		(end 147.425664 -416.006788)
		(stroke
			(width 0.07112)
			(type default)
		)
		(layer "In13.Cu")
	)
	(gr_line
		(start 147.425664 -416.006788)
		(end 147.310856 -415.851848)
		(stroke
			(width 0.07112)
			(type default)
		)
		(layer "In13.Cu")
	)
	(gr_line
		(start 147.53209 -400.89963)
		(end 147.343368 -400.937222)
		(stroke
			(width 0.07112)
			(type default)
		)
		(layer "In13.Cu")
	)
	(gr_line
		(start 147.768056 -401.561554)
		(end 147.185126 -401.172172)
		(stroke
			(width 0.07112)
			(type default)
		)
		(layer "In13.Cu")
	)
	(gr_line
		(start 147.886928 -401.136866)
		(end 147.53209 -400.89963)
		(stroke
			(width 0.07112)
			(type default)
		)
		(layer "In13.Cu")
	)
	(gr_line
		(start 147.92452 -401.325334)
		(end 147.886928 -401.136866)
		(stroke
			(width 0.07112)
			(type default)
		)
		(layer "In13.Cu")
	)
	(gr_line
		(start 148.039074 -373.6721)
		(end 147.748244 -373.96293)
		(stroke
			(width 0.07112)
			(type default)
		)
		(layer "In13.Cu")
	)
	(gr_line
		(start 148.102574 -396.251938)
		(end 147.942554 -396.358872)
		(stroke
			(width 0.07112)
			(type default)
		)
		(layer "In13.Cu")
	)
	(gr_line
		(start 148.321014 -373.6721)
		(end 148.611844 -373.96293)
		(stroke
			(width 0.07112)
			(type default)
		)
		(layer "In13.Cu")
	)
	(gr_line
		(start 148.469604 -401.526248)
		(end 148.281136 -401.56384)
		(stroke
			(width 0.07112)
			(type default)
		)
		(layer "In13.Cu")
	)
	(gr_line
		(start 148.521166 -396.334996)
		(end 148.102574 -396.251938)
		(stroke
			(width 0.07112)
			(type default)
		)
		(layer "In13.Cu")
	)
	(gr_line
		(start 148.573998 -396.773146)
		(end 147.886166 -396.636494)
		(stroke
			(width 0.07112)
			(type default)
		)
		(layer "In13.Cu")
	)
	(gr_line
		(start 148.621242 -434.747416)
		(end 148.613622 -434.747416)
		(stroke
			(width 0.07112)
			(type default)
		)
		(layer "In13.Cu")
	)
	(gr_line
		(start 148.628354 -396.49527)
		(end 148.521166 -396.334996)
		(stroke
			(width 0.07112)
			(type default)
		)
		(layer "In13.Cu")
	)
	(gr_line
		(start 148.705824 -402.188172)
		(end 148.12264 -401.798536)
		(stroke
			(width 0.07112)
			(type default)
		)
		(layer "In13.Cu")
	)
	(gr_line
		(start 148.75002 -435.489858)
		(end 148.75002 -435.165754)
		(stroke
			(width 0.07112)
			(type default)
		)
		(layer "In13.Cu")
	)
	(gr_line
		(start 148.75002 -435.165754)
		(end 148.614892 -435.030626)
		(stroke
			(width 0.07112)
			(type default)
		)
		(layer "In13.Cu")
	)
	(gr_line
		(start 148.75002 -434.618638)
		(end 148.621242 -434.747416)
		(stroke
			(width 0.07112)
			(type default)
		)
		(layer "In13.Cu")
	)
	(gr_line
		(start 148.75002 -434.289962)
		(end 148.75002 -434.618638)
		(stroke
			(width 0.07112)
			(type default)
		)
		(layer "In13.Cu")
	)
	(gr_line
		(start 148.824696 -401.763484)
		(end 148.469604 -401.526248)
		(stroke
			(width 0.07112)
			(type default)
		)
		(layer "In13.Cu")
	)
	(gr_line
		(start 148.862288 -401.952206)
		(end 148.824696 -401.763484)
		(stroke
			(width 0.07112)
			(type default)
		)
		(layer "In13.Cu")
	)
	(gr_line
		(start 148.880576 -409.382976)
		(end 148.880576 -408.681936)
		(stroke
			(width 0.07112)
			(type default)
		)
		(layer "In13.Cu")
	)
	(gr_line
		(start 148.880576 -408.255216)
		(end 148.880576 -407.554176)
		(stroke
			(width 0.07112)
			(type default)
		)
		(layer "In13.Cu")
	)
	(gr_line
		(start 149.163786 -409.381706)
		(end 149.299676 -409.245816)
		(stroke
			(width 0.07112)
			(type default)
		)
		(layer "In13.Cu")
	)
	(gr_line
		(start 149.163786 -408.253946)
		(end 149.299676 -408.118056)
		(stroke
			(width 0.07112)
			(type default)
		)
		(layer "In13.Cu")
	)
	(gr_line
		(start 149.299676 -409.245816)
		(end 149.299676 -408.819096)
		(stroke
			(width 0.07112)
			(type default)
		)
		(layer "In13.Cu")
	)
	(gr_line
		(start 149.299676 -408.819096)
		(end 149.163786 -408.683206)
		(stroke
			(width 0.07112)
			(type default)
		)
		(layer "In13.Cu")
	)
	(gr_line
		(start 149.299676 -408.118056)
		(end 149.299676 -407.691336)
		(stroke
			(width 0.07112)
			(type default)
		)
		(layer "In13.Cu")
	)
	(gr_line
		(start 149.299676 -407.691336)
		(end 149.163786 -407.555446)
		(stroke
			(width 0.07112)
			(type default)
		)
		(layer "In13.Cu")
	)
	(gr_line
		(start 149.396958 -415.632392)
		(end 149.665436 -414.984438)
		(stroke
			(width 0.07112)
			(type default)
		)
		(layer "In13.Cu")
	)
	(gr_line
		(start 149.659086 -415.739834)
		(end 149.836886 -415.66592)
		(stroke
			(width 0.07112)
			(type default)
		)
		(layer "In13.Cu")
	)
	(gr_line
		(start 149.74062 -368.910616)
		(end 149.740874 -368.91087)
		(stroke
			(width 0.07112)
			(type default)
		)
		(layer "In13.Cu")
	)
	(gr_line
		(start 149.740874 -371.2083)
		(end 149.450044 -371.49913)
		(stroke
			(width 0.07112)
			(type default)
		)
		(layer "In13.Cu")
	)
	(gr_line
		(start 149.836886 -415.66592)
		(end 150.000208 -415.271458)
		(stroke
			(width 0.07112)
			(type default)
		)
		(layer "In13.Cu")
	)
	(gr_line
		(start 149.888956 -414.444688)
		(end 150.157434 -413.796734)
		(stroke
			(width 0.07112)
			(type default)
		)
		(layer "In13.Cu")
	)
	(gr_line
		(start 150.000208 -415.271458)
		(end 149.926548 -415.093912)
		(stroke
			(width 0.07112)
			(type default)
		)
		(layer "In13.Cu")
	)
	(gr_line
		(start 150.005034 -368.812318)
		(end 150.022814 -368.859816)
		(stroke
			(width 0.07112)
			(type default)
		)
		(layer "In13.Cu")
	)
	(gr_line
		(start 150.022814 -371.2083)
		(end 150.313644 -371.49913)
		(stroke
			(width 0.07112)
			(type default)
		)
		(layer "In13.Cu")
	)
	(gr_line
		(start 150.022814 -368.859816)
		(end 150.022814 -368.91087)
		(stroke
			(width 0.07112)
			(type default)
		)
		(layer "In13.Cu")
	)
	(gr_line
		(start 150.151084 -414.55213)
		(end 150.328884 -414.47847)
		(stroke
			(width 0.07112)
			(type default)
		)
		(layer "In13.Cu")
	)
	(gr_line
		(start 150.328884 -414.47847)
		(end 150.492206 -414.084008)
		(stroke
			(width 0.07112)
			(type default)
		)
		(layer "In13.Cu")
	)
	(gr_line
		(start 150.492206 -414.084008)
		(end 150.418546 -413.906208)
		(stroke
			(width 0.07112)
			(type default)
		)
		(layer "In13.Cu")
	)
	(gr_line
		(start 150.631652 -434.047392)
		(end 150.603204 -434.047392)
		(stroke
			(width 0.07112)
			(type default)
		)
		(layer "In13.Cu")
	)
	(gr_line
		(start 150.750016 -434.48986)
		(end 150.750016 -434.165756)
		(stroke
			(width 0.07112)
			(type default)
		)
		(layer "In13.Cu")
	)
	(gr_line
		(start 150.750016 -434.165756)
		(end 150.631652 -434.047392)
		(stroke
			(width 0.07112)
			(type default)
		)
		(layer "In13.Cu")
	)
	(gr_line
		(start 150.750016 -433.61864)
		(end 150.604474 -433.764182)
		(stroke
			(width 0.07112)
			(type default)
		)
		(layer "In13.Cu")
	)
	(gr_line
		(start 150.750016 -433.289964)
		(end 150.750016 -433.61864)
		(stroke
			(width 0.07112)
			(type default)
		)
		(layer "In13.Cu")
	)
	(gr_line
		(start 151.442674 -368.7445)
		(end 151.151844 -369.03533)
		(stroke
			(width 0.07112)
			(type default)
		)
		(layer "In13.Cu")
	)
	(gr_line
		(start 151.724614 -368.7445)
		(end 152.015444 -369.03533)
		(stroke
			(width 0.07112)
			(type default)
		)
		(layer "In13.Cu")
	)
	(gr_line
		(start 151.802084 -417.391596)
		(end 152.070562 -416.743642)
		(stroke
			(width 0.07112)
			(type default)
		)
		(layer "In13.Cu")
	)
	(gr_line
		(start 151.831802 -401.710652)
		(end 151.64308 -401.748244)
		(stroke
			(width 0.07112)
			(type default)
		)
		(layer "In13.Cu")
	)
	(gr_line
		(start 151.943816 -409.476702)
		(end 151.943816 -408.775662)
		(stroke
			(width 0.07112)
			(type default)
		)
		(layer "In13.Cu")
	)
	(gr_line
		(start 151.943816 -408.348942)
		(end 151.943816 -407.647902)
		(stroke
			(width 0.07112)
			(type default)
		)
		(layer "In13.Cu")
	)
	(gr_line
		(start 152.064212 -417.498784)
		(end 152.242012 -417.425378)
		(stroke
			(width 0.07112)
			(type default)
		)
		(layer "In13.Cu")
	)
	(gr_line
		(start 152.068022 -402.37283)
		(end 151.484838 -401.98294)
		(stroke
			(width 0.07112)
			(type default)
		)
		(layer "In13.Cu")
	)
	(gr_line
		(start 152.186894 -401.948142)
		(end 151.831802 -401.710652)
		(stroke
			(width 0.07112)
			(type default)
		)
		(layer "In13.Cu")
	)
	(gr_line
		(start 152.224486 -402.13661)
		(end 152.186894 -401.948142)
		(stroke
			(width 0.07112)
			(type default)
		)
		(layer "In13.Cu")
	)
	(gr_line
		(start 152.227026 -409.475432)
		(end 152.362916 -409.339542)
		(stroke
			(width 0.07112)
			(type default)
		)
		(layer "In13.Cu")
	)
	(gr_line
		(start 152.227026 -408.347672)
		(end 152.362916 -408.211782)
		(stroke
			(width 0.07112)
			(type default)
		)
		(layer "In13.Cu")
	)
	(gr_line
		(start 152.242012 -417.425378)
		(end 152.405334 -417.030916)
		(stroke
			(width 0.07112)
			(type default)
		)
		(layer "In13.Cu")
	)
	(gr_line
		(start 152.362916 -409.339542)
		(end 152.362916 -408.912822)
		(stroke
			(width 0.07112)
			(type default)
		)
		(layer "In13.Cu")
	)
	(gr_line
		(start 152.362916 -408.912822)
		(end 152.227026 -408.776932)
		(stroke
			(width 0.07112)
			(type default)
		)
		(layer "In13.Cu")
	)
	(gr_line
		(start 152.362916 -408.211782)
		(end 152.362916 -407.785062)
		(stroke
			(width 0.07112)
			(type default)
		)
		(layer "In13.Cu")
	)
	(gr_line
		(start 152.362916 -407.785062)
		(end 152.227026 -407.649172)
		(stroke
			(width 0.07112)
			(type default)
		)
		(layer "In13.Cu")
	)
	(gr_line
		(start 152.405334 -417.030916)
		(end 152.331674 -416.853116)
		(stroke
			(width 0.07112)
			(type default)
		)
		(layer "In13.Cu")
	)
	(gr_line
		(start 152.44445 -410.927296)
		(end 152.44445 -410.92755)
		(stroke
			(width 0.07112)
			(type default)
		)
		(layer "In13.Cu")
	)
	(gr_line
		(start 152.505664 -421.260524)
		(end 152.505918 -421.26027)
		(stroke
			(width 0.07112)
			(type default)
		)
		(layer "In13.Cu")
	)
	(gr_line
		(start 152.628854 -434.739796)
		(end 152.605994 -434.739796)
		(stroke
			(width 0.07112)
			(type default)
		)
		(layer "In13.Cu")
	)
	(gr_line
		(start 152.750012 -435.489858)
		(end 152.750012 -435.165754)
		(stroke
			(width 0.07112)
			(type default)
		)
		(layer "In13.Cu")
	)
	(gr_line
		(start 152.750012 -435.165754)
		(end 152.607264 -435.023006)
		(stroke
			(width 0.07112)
			(type default)
		)
		(layer "In13.Cu")
	)
	(gr_line
		(start 152.750012 -434.618638)
		(end 152.628854 -434.739796)
		(stroke
			(width 0.07112)
			(type default)
		)
		(layer "In13.Cu")
	)
	(gr_line
		(start 152.750012 -434.289962)
		(end 152.750012 -434.618638)
		(stroke
			(width 0.07112)
			(type default)
		)
		(layer "In13.Cu")
	)
	(gr_line
		(start 152.810464 -414.95726)
		(end 153.078942 -414.309306)
		(stroke
			(width 0.07112)
			(type default)
		)
		(layer "In13.Cu")
	)
	(gr_line
		(start 153.072592 -415.064448)
		(end 153.250392 -414.991042)
		(stroke
			(width 0.07112)
			(type default)
		)
		(layer "In13.Cu")
	)
	(gr_line
		(start 153.250392 -414.991042)
		(end 153.413714 -414.59658)
		(stroke
			(width 0.07112)
			(type default)
		)
		(layer "In13.Cu")
	)
	(gr_line
		(start 153.413714 -414.59658)
		(end 153.340054 -414.41878)
		(stroke
			(width 0.07112)
			(type default)
		)
		(layer "In13.Cu")
	)
	(gr_line
		(start 153.419048 -398.540224)
		(end 153.230326 -398.577816)
		(stroke
			(width 0.07112)
			(type default)
		)
		(layer "In13.Cu")
	)
	(gr_line
		(start 153.627328 -418.7063)
		(end 153.682446 -418.602922)
		(stroke
			(width 0.07112)
			(type default)
		)
		(layer "In13.Cu")
	)
	(gr_line
		(start 153.655268 -399.202148)
		(end 153.072084 -398.812512)
		(stroke
			(width 0.07112)
			(type default)
		)
		(layer "In13.Cu")
	)
	(gr_line
		(start 153.682446 -418.602922)
		(end 153.682954 -418.602668)
		(stroke
			(width 0.07112)
			(type default)
		)
		(layer "In13.Cu")
	)
	(gr_line
		(start 153.682954 -418.602668)
		(end 153.95829 -418.087556)
		(stroke
			(width 0.07112)
			(type default)
		)
		(layer "In13.Cu")
	)
	(gr_line
		(start 153.77414 -398.77746)
		(end 153.419048 -398.540224)
		(stroke
			(width 0.07112)
			(type default)
		)
		(layer "In13.Cu")
	)
	(gr_line
		(start 153.811732 -398.966182)
		(end 153.77414 -398.77746)
		(stroke
			(width 0.07112)
			(type default)
		)
		(layer "In13.Cu")
	)
	(gr_line
		(start 153.859738 -356.373938)
		(end 153.872946 -356.4001)
		(stroke
			(width 0.07112)
			(type default)
		)
		(layer "In13.Cu")
	)
	(gr_line
		(start 153.872946 -356.4001)
		(end 153.889456 -356.42423)
		(stroke
			(width 0.07112)
			(type default)
		)
		(layer "In13.Cu")
	)
	(gr_line
		(start 153.877518 -418.838634)
		(end 154.062176 -418.783008)
		(stroke
			(width 0.07112)
			(type default)
		)
		(layer "In13.Cu")
	)
	(gr_line
		(start 154.044904 -370.116354)
		(end 154.045158 -370.116354)
		(stroke
			(width 0.07112)
			(type default)
		)
		(layer "In13.Cu")
	)
	(gr_line
		(start 154.062176 -418.783008)
		(end 154.263344 -418.406326)
		(stroke
			(width 0.07112)
			(type default)
		)
		(layer "In13.Cu")
	)
	(gr_arc
		(start 154.109928 -356.240842)
		(mid 154.118186 -356.255139)
		(end 154.126692 -356.26929)
		(stroke
			(width 0.07112)
			(type default)
		)
		(layer "In13.Cu")
	)
	(gr_line
		(start 154.159204 -417.711636)
		(end 154.489912 -417.092892)
		(stroke
			(width 0.07112)
			(type default)
		)
		(layer "In13.Cu")
	)
	(gr_line
		(start 154.263344 -418.406326)
		(end 154.207718 -418.221922)
		(stroke
			(width 0.07112)
			(type default)
		)
		(layer "In13.Cu")
	)
	(gr_arc
		(start 154.281632 -356.99573)
		(mid 154.281378 -356.995349)
		(end 154.281124 -356.994968)
		(stroke
			(width 0.07112)
			(type default)
		)
		(layer "In13.Cu")
	)
	(gr_line
		(start 154.409648 -417.84397)
		(end 154.593798 -417.788344)
		(stroke
			(width 0.07112)
			(type default)
		)
		(layer "In13.Cu")
	)
	(gr_line
		(start 154.593798 -417.788344)
		(end 154.794966 -417.411662)
		(stroke
			(width 0.07112)
			(type default)
		)
		(layer "In13.Cu")
	)
	(gr_line
		(start 154.619706 -433.748942)
		(end 154.615134 -433.748942)
		(stroke
			(width 0.07112)
			(type default)
		)
		(layer "In13.Cu")
	)
	(gr_line
		(start 154.750008 -434.48986)
		(end 154.750008 -434.165756)
		(stroke
			(width 0.07112)
			(type default)
		)
		(layer "In13.Cu")
	)
	(gr_line
		(start 154.750008 -434.165756)
		(end 154.616404 -434.032152)
		(stroke
			(width 0.07112)
			(type default)
		)
		(layer "In13.Cu")
	)
	(gr_line
		(start 154.750008 -433.61864)
		(end 154.619706 -433.748942)
		(stroke
			(width 0.07112)
			(type default)
		)
		(layer "In13.Cu")
	)
	(gr_line
		(start 154.750008 -433.289964)
		(end 154.750008 -433.61864)
		(stroke
			(width 0.07112)
			(type default)
		)
		(layer "In13.Cu")
	)
	(gr_line
		(start 154.75712 -416.593528)
		(end 155.087574 -415.975038)
		(stroke
			(width 0.07112)
			(type default)
		)
		(layer "In13.Cu")
	)
	(gr_line
		(start 154.794966 -417.411662)
		(end 154.73934 -417.227512)
		(stroke
			(width 0.07112)
			(type default)
		)
		(layer "In13.Cu")
	)
	(gr_line
		(start 154.846274 -373.6721)
		(end 154.555444 -373.96293)
		(stroke
			(width 0.07112)
			(type default)
		)
		(layer "In13.Cu")
	)
	(gr_line
		(start 155.00731 -416.725862)
		(end 155.191714 -416.670236)
		(stroke
			(width 0.07112)
			(type default)
		)
		(layer "In13.Cu")
	)
	(gr_line
		(start 155.128214 -373.6721)
		(end 155.419044 -373.96293)
		(stroke
			(width 0.07112)
			(type default)
		)
		(layer "In13.Cu")
	)
	(gr_line
		(start 155.191714 -416.670236)
		(end 155.392882 -416.293554)
		(stroke
			(width 0.07112)
			(type default)
		)
		(layer "In13.Cu")
	)
	(gr_line
		(start 155.288742 -415.598864)
		(end 155.61945 -414.98012)
		(stroke
			(width 0.07112)
			(type default)
		)
		(layer "In13.Cu")
	)
	(gr_line
		(start 155.392882 -416.293554)
		(end 155.337002 -416.109404)
		(stroke
			(width 0.07112)
			(type default)
		)
		(layer "In13.Cu")
	)
	(gr_line
		(start 155.539186 -415.731198)
		(end 155.723336 -415.675318)
		(stroke
			(width 0.07112)
			(type default)
		)
		(layer "In13.Cu")
	)
	(gr_line
		(start 155.723336 -415.675318)
		(end 155.924504 -415.29889)
		(stroke
			(width 0.07112)
			(type default)
		)
		(layer "In13.Cu")
	)
	(gr_line
		(start 155.851352 -414.546288)
		(end 156.18206 -413.927544)
		(stroke
			(width 0.07112)
			(type default)
		)
		(layer "In13.Cu")
	)
	(gr_line
		(start 155.924504 -415.29889)
		(end 155.868878 -415.114486)
		(stroke
			(width 0.07112)
			(type default)
		)
		(layer "In13.Cu")
	)
	(gr_line
		(start 156.101796 -414.678622)
		(end 156.2862 -414.622742)
		(stroke
			(width 0.07112)
			(type default)
		)
		(layer "In13.Cu")
	)
	(gr_line
		(start 156.2862 -414.622742)
		(end 156.487368 -414.246314)
		(stroke
			(width 0.07112)
			(type default)
		)
		(layer "In13.Cu")
	)
	(gr_line
		(start 156.487368 -414.246314)
		(end 156.431488 -414.06191)
		(stroke
			(width 0.07112)
			(type default)
		)
		(layer "In13.Cu")
	)
	(gr_line
		(start 156.548074 -371.2083)
		(end 156.257244 -371.49913)
		(stroke
			(width 0.07112)
			(type default)
		)
		(layer "In13.Cu")
	)
	(gr_line
		(start 156.6291 -434.739542)
		(end 156.605732 -434.739542)
		(stroke
			(width 0.07112)
			(type default)
		)
		(layer "In13.Cu")
	)
	(gr_line
		(start 156.750004 -435.489858)
		(end 156.750004 -435.165754)
		(stroke
			(width 0.07112)
			(type default)
		)
		(layer "In13.Cu")
	)
	(gr_line
		(start 156.750004 -435.165754)
		(end 156.607002 -435.022752)
		(stroke
			(width 0.07112)
			(type default)
		)
		(layer "In13.Cu")
	)
	(gr_line
		(start 156.750004 -434.618638)
		(end 156.6291 -434.739542)
		(stroke
			(width 0.07112)
			(type default)
		)
		(layer "In13.Cu")
	)
	(gr_line
		(start 156.750004 -434.289962)
		(end 156.750004 -434.618638)
		(stroke
			(width 0.07112)
			(type default)
		)
		(layer "In13.Cu")
	)
	(gr_line
		(start 156.830014 -371.2083)
		(end 157.120844 -371.49913)
		(stroke
			(width 0.07112)
			(type default)
		)
		(layer "In13.Cu")
	)
	(gr_line
		(start 157.609286 -416.938206)
		(end 157.95498 -416.328098)
		(stroke
			(width 0.07112)
			(type default)
		)
		(layer "In13.Cu")
	)
	(gr_line
		(start 157.856174 -417.076636)
		(end 158.041848 -417.025328)
		(stroke
			(width 0.07112)
			(type default)
		)
		(layer "In13.Cu")
	)
	(gr_line
		(start 158.041848 -417.025328)
		(end 158.25216 -416.65398)
		(stroke
			(width 0.07112)
			(type default)
		)
		(layer "In13.Cu")
	)
	(gr_line
		(start 158.070296 -409.382976)
		(end 158.070296 -408.681936)
		(stroke
			(width 0.07112)
			(type default)
		)
		(layer "In13.Cu")
	)
	(gr_line
		(start 158.070296 -408.255216)
		(end 158.070296 -407.554176)
		(stroke
			(width 0.07112)
			(type default)
		)
		(layer "In13.Cu")
	)
	(gr_line
		(start 158.165038 -415.957004)
		(end 158.510986 -415.346642)
		(stroke
			(width 0.07112)
			(type default)
		)
		(layer "In13.Cu")
	)
	(gr_line
		(start 158.249874 -368.7445)
		(end 157.959044 -369.03533)
		(stroke
			(width 0.07112)
			(type default)
		)
		(layer "In13.Cu")
	)
	(gr_line
		(start 158.25216 -416.65398)
		(end 158.200852 -416.46856)
		(stroke
			(width 0.07112)
			(type default)
		)
		(layer "In13.Cu")
	)
	(gr_arc
		(start 158.266892 -366.625378)
		(mid 158.246146 -366.613688)
		(end 158.224982 -366.602772)
		(stroke
			(width 0.07112)
			(type default)
		)
		(layer "In13.Cu")
	)
	(gr_line
		(start 158.340806 -366.3442)
		(end 158.380938 -366.360964)
		(stroke
			(width 0.07112)
			(type default)
		)
		(layer "In13.Cu")
	)
	(gr_line
		(start 158.353506 -409.381706)
		(end 158.489396 -409.245816)
		(stroke
			(width 0.07112)
			(type default)
		)
		(layer "In13.Cu")
	)
	(gr_line
		(start 158.353506 -408.253946)
		(end 158.489396 -408.118056)
		(stroke
			(width 0.07112)
			(type default)
		)
		(layer "In13.Cu")
	)
	(gr_line
		(start 158.380938 -366.360964)
		(end 158.417768 -366.385602)
		(stroke
			(width 0.07112)
			(type default)
		)
		(layer "In13.Cu")
	)
	(gr_line
		(start 158.41218 -416.095434)
		(end 158.5976 -416.044126)
		(stroke
			(width 0.07112)
			(type default)
		)
		(layer "In13.Cu")
	)
	(gr_line
		(start 158.489396 -409.245816)
		(end 158.489396 -408.819096)
		(stroke
			(width 0.07112)
			(type default)
		)
		(layer "In13.Cu")
	)
	(gr_line
		(start 158.489396 -408.819096)
		(end 158.353506 -408.683206)
		(stroke
			(width 0.07112)
			(type default)
		)
		(layer "In13.Cu")
	)
	(gr_line
		(start 158.489396 -408.118056)
		(end 158.489396 -407.691336)
		(stroke
			(width 0.07112)
			(type default)
		)
		(layer "In13.Cu")
	)
	(gr_line
		(start 158.489396 -407.691336)
		(end 158.353506 -407.555446)
		(stroke
			(width 0.07112)
			(type default)
		)
		(layer "In13.Cu")
	)
	(gr_line
		(start 158.531814 -368.7445)
		(end 158.822644 -369.03533)
		(stroke
			(width 0.07112)
			(type default)
		)
		(layer "In13.Cu")
	)
	(gr_line
		(start 158.5976 -416.044126)
		(end 158.807912 -415.672524)
		(stroke
			(width 0.07112)
			(type default)
		)
		(layer "In13.Cu")
	)
	(gr_line
		(start 158.807912 -415.672524)
		(end 158.756858 -415.487104)
		(stroke
			(width 0.07112)
			(type default)
		)
		(layer "In13.Cu")
	)
	(gr_line
		(start 159.019748 -414.448244)
		(end 159.365442 -413.838136)
		(stroke
			(width 0.07112)
			(type default)
		)
		(layer "In13.Cu")
	)
	(gr_line
		(start 159.26689 -414.586674)
		(end 159.45231 -414.53562)
		(stroke
			(width 0.07112)
			(type default)
		)
		(layer "In13.Cu")
	)
	(gr_line
		(start 159.45231 -414.53562)
		(end 159.662622 -414.164018)
		(stroke
			(width 0.07112)
			(type default)
		)
		(layer "In13.Cu")
	)
	(gr_line
		(start 159.662622 -414.164018)
		(end 159.611314 -413.978598)
		(stroke
			(width 0.07112)
			(type default)
		)
		(layer "In13.Cu")
	)
	(gr_line
		(start 160.065466 -362.960412)
		(end 160.138872 -363.138212)
		(stroke
			(width 0.07112)
			(type default)
		)
		(layer "In13.Cu")
	)
	(gr_line
		(start 160.138872 -363.138212)
		(end 160.533334 -363.301534)
		(stroke
			(width 0.07112)
			(type default)
		)
		(layer "In13.Cu")
	)
	(gr_line
		(start 160.166812 -369.902486)
		(end 160.17113 -369.906804)
		(stroke
			(width 0.07112)
			(type default)
		)
		(layer "In13.Cu")
	)
	(gr_line
		(start 160.172654 -362.698284)
		(end 160.820608 -362.966762)
		(stroke
			(width 0.07112)
			(type default)
		)
		(layer "In13.Cu")
	)
	(gr_line
		(start 160.533334 -363.301534)
		(end 160.711134 -363.227874)
		(stroke
			(width 0.07112)
			(type default)
		)
		(layer "In13.Cu")
	)
	(gr_line
		(start 161.133536 -409.289504)
		(end 161.133536 -408.588464)
		(stroke
			(width 0.07112)
			(type default)
		)
		(layer "In13.Cu")
	)
	(gr_line
		(start 161.133536 -408.161744)
		(end 161.133536 -407.460704)
		(stroke
			(width 0.07112)
			(type default)
		)
		(layer "In13.Cu")
	)
	(gr_line
		(start 161.416746 -409.288234)
		(end 161.552636 -409.152344)
		(stroke
			(width 0.07112)
			(type default)
		)
		(layer "In13.Cu")
	)
	(gr_line
		(start 161.416746 -408.160474)
		(end 161.552636 -408.024584)
		(stroke
			(width 0.07112)
			(type default)
		)
		(layer "In13.Cu")
	)
	(gr_line
		(start 161.552636 -409.152344)
		(end 161.552636 -408.725624)
		(stroke
			(width 0.07112)
			(type default)
		)
		(layer "In13.Cu")
	)
	(gr_line
		(start 161.552636 -408.725624)
		(end 161.416746 -408.589734)
		(stroke
			(width 0.07112)
			(type default)
		)
		(layer "In13.Cu")
	)
	(gr_line
		(start 161.552636 -408.024584)
		(end 161.552636 -407.597864)
		(stroke
			(width 0.07112)
			(type default)
		)
		(layer "In13.Cu")
	)
	(gr_line
		(start 161.552636 -407.597864)
		(end 161.416746 -407.461974)
		(stroke
			(width 0.07112)
			(type default)
		)
		(layer "In13.Cu")
	)
	(gr_line
		(start 161.60623 -373.719344)
		(end 161.362644 -373.96293)
		(stroke
			(width 0.07112)
			(type default)
		)
		(layer "In13.Cu")
	)
	(gr_arc
		(start 161.60623 -373.719344)
		(mid 161.637672 -373.674934)
		(end 161.652458 -373.62257)
		(stroke
			(width 0.07112)
			(type default)
		)
		(layer "In13.Cu")
	)
	(gr_arc
		(start 161.93643 -373.62257)
		(mid 161.951287 -373.674901)
		(end 161.982658 -373.719344)
		(stroke
			(width 0.07112)
			(type default)
		)
		(layer "In13.Cu")
	)
	(gr_line
		(start 161.982658 -373.719344)
		(end 162.226244 -373.96293)
		(stroke
			(width 0.07112)
			(type default)
		)
		(layer "In13.Cu")
	)
	(gr_line
		(start 162.231578 -362.54817)
		(end 162.304984 -362.72597)
		(stroke
			(width 0.07112)
			(type default)
		)
		(layer "In13.Cu")
	)
	(gr_line
		(start 162.304984 -362.72597)
		(end 162.699446 -362.889292)
		(stroke
			(width 0.07112)
			(type default)
		)
		(layer "In13.Cu")
	)
	(gr_line
		(start 162.338766 -362.286042)
		(end 162.98672 -362.55452)
		(stroke
			(width 0.07112)
			(type default)
		)
		(layer "In13.Cu")
	)
	(gr_line
		(start 162.377374 -363.917992)
		(end 162.451034 -364.096046)
		(stroke
			(width 0.07112)
			(type default)
		)
		(layer "In13.Cu")
	)
	(gr_line
		(start 162.451034 -364.096046)
		(end 162.845496 -364.259368)
		(stroke
			(width 0.07112)
			(type default)
		)
		(layer "In13.Cu")
	)
	(gr_line
		(start 162.484562 -363.655864)
		(end 163.132516 -363.924342)
		(stroke
			(width 0.07112)
			(type default)
		)
		(layer "In13.Cu")
	)
	(gr_line
		(start 162.699446 -362.889292)
		(end 162.877246 -362.815632)
		(stroke
			(width 0.07112)
			(type default)
		)
		(layer "In13.Cu")
	)
	(gr_line
		(start 162.845496 -364.259368)
		(end 163.023296 -364.185708)
		(stroke
			(width 0.07112)
			(type default)
		)
		(layer "In13.Cu")
	)
	(gr_line
		(start 163.355274 -371.2083)
		(end 163.064444 -371.49913)
		(stroke
			(width 0.07112)
			(type default)
		)
		(layer "In13.Cu")
	)
	(gr_line
		(start 163.366704 -363.018324)
		(end 163.44011 -363.196124)
		(stroke
			(width 0.07112)
			(type default)
		)
		(layer "In13.Cu")
	)
	(gr_line
		(start 163.419282 -364.349792)
		(end 163.492942 -364.527592)
		(stroke
			(width 0.07112)
			(type default)
		)
		(layer "In13.Cu")
	)
	(gr_line
		(start 163.44011 -363.196124)
		(end 163.834572 -363.359446)
		(stroke
			(width 0.07112)
			(type default)
		)
		(layer "In13.Cu")
	)
	(gr_line
		(start 163.473892 -362.756196)
		(end 164.121846 -363.024674)
		(stroke
			(width 0.07112)
			(type default)
		)
		(layer "In13.Cu")
	)
	(gr_line
		(start 163.492942 -364.527592)
		(end 163.887404 -364.690914)
		(stroke
			(width 0.07112)
			(type default)
		)
		(layer "In13.Cu")
	)
	(gr_line
		(start 163.526724 -364.087664)
		(end 164.174678 -364.356142)
		(stroke
			(width 0.07112)
			(type default)
		)
		(layer "In13.Cu")
	)
	(gr_line
		(start 163.637214 -371.2083)
		(end 163.928044 -371.49913)
		(stroke
			(width 0.07112)
			(type default)
		)
		(layer "In13.Cu")
	)
	(gr_line
		(start 163.834572 -363.359446)
		(end 164.012372 -363.285786)
		(stroke
			(width 0.07112)
			(type default)
		)
		(layer "In13.Cu")
	)
	(gr_line
		(start 163.887404 -364.690914)
		(end 164.065458 -364.617254)
		(stroke
			(width 0.07112)
			(type default)
		)
		(layer "In13.Cu")
	)
	(gr_line
		(start 164.566092 -363.515148)
		(end 164.639498 -363.692948)
		(stroke
			(width 0.07112)
			(type default)
		)
		(layer "In13.Cu")
	)
	(gr_line
		(start 164.639498 -363.692948)
		(end 165.03396 -363.85627)
		(stroke
			(width 0.07112)
			(type default)
		)
		(layer "In13.Cu")
	)
	(gr_line
		(start 164.673026 -363.25302)
		(end 165.321234 -363.521498)
		(stroke
			(width 0.07112)
			(type default)
		)
		(layer "In13.Cu")
	)
	(gr_line
		(start 165.03396 -363.85627)
		(end 165.21176 -363.78261)
		(stroke
			(width 0.07112)
			(type default)
		)
		(layer "In13.Cu")
	)
	(gr_line
		(start 165.057074 -368.7445)
		(end 164.766244 -369.03533)
		(stroke
			(width 0.07112)
			(type default)
		)
		(layer "In13.Cu")
	)
	(gr_line
		(start 165.060884 -365.02975)
		(end 165.134798 -365.207804)
		(stroke
			(width 0.07112)
			(type default)
		)
		(layer "In13.Cu")
	)
	(gr_line
		(start 165.134798 -365.207804)
		(end 165.52926 -365.370872)
		(stroke
			(width 0.07112)
			(type default)
		)
		(layer "In13.Cu")
	)
	(gr_line
		(start 165.168326 -364.767622)
		(end 165.81628 -365.0361)
		(stroke
			(width 0.07112)
			(type default)
		)
		(layer "In13.Cu")
	)
	(gr_line
		(start 165.339014 -368.7445)
		(end 165.629844 -369.03533)
		(stroke
			(width 0.07112)
			(type default)
		)
		(layer "In13.Cu")
	)
	(gr_line
		(start 165.52926 -365.370872)
		(end 165.706806 -365.297212)
		(stroke
			(width 0.07112)
			(type default)
		)
		(layer "In13.Cu")
	)
	(gr_line
		(start 165.880796 -364.059724)
		(end 165.954456 -364.237778)
		(stroke
			(width 0.07112)
			(type default)
		)
		(layer "In13.Cu")
	)
	(gr_line
		(start 165.954456 -364.237778)
		(end 166.348918 -364.4011)
		(stroke
			(width 0.07112)
			(type default)
		)
		(layer "In13.Cu")
	)
	(gr_line
		(start 165.987984 -363.797596)
		(end 166.635938 -364.066074)
		(stroke
			(width 0.07112)
			(type default)
		)
		(layer "In13.Cu")
	)
	(gr_line
		(start 166.348918 -364.4011)
		(end 166.526718 -364.32744)
		(stroke
			(width 0.07112)
			(type default)
		)
		(layer "In13.Cu")
	)
	(gr_line
		(start 168.460674 -368.7445)
		(end 168.169844 -369.03533)
		(stroke
			(width 0.07112)
			(type default)
		)
		(layer "In13.Cu")
	)
	(gr_line
		(start 168.742614 -368.7445)
		(end 169.033444 -369.03533)
		(stroke
			(width 0.07112)
			(type default)
		)
		(layer "In13.Cu")
	)
	(gr_line
		(start 171.196254 -380.069598)
		(end 170.905424 -380.360428)
		(stroke
			(width 0.07112)
			(type default)
		)
		(layer "In13.Cu")
	)
	(gr_line
		(start 171.196254 -379.787658)
		(end 170.905424 -379.496828)
		(stroke
			(width 0.07112)
			(type default)
		)
		(layer "In13.Cu")
	)
	(gr_line
		(start 171.196254 -376.665998)
		(end 170.905424 -376.956828)
		(stroke
			(width 0.07112)
			(type default)
		)
		(layer "In13.Cu")
	)
	(gr_line
		(start 171.196254 -376.384058)
		(end 170.905424 -376.093228)
		(stroke
			(width 0.07112)
			(type default)
		)
		(layer "In13.Cu")
	)
	(gr_line
		(start 172.735748 -378.075698)
		(end 172.871638 -378.211588)
		(stroke
			(width 0.07112)
			(type default)
		)
		(layer "In13.Cu")
	)
	(gr_line
		(start 172.735748 -377.648978)
		(end 172.735748 -378.075698)
		(stroke
			(width 0.07112)
			(type default)
		)
		(layer "In13.Cu")
	)
	(gr_line
		(start 172.871638 -377.513088)
		(end 172.735748 -377.648978)
		(stroke
			(width 0.07112)
			(type default)
		)
		(layer "In13.Cu")
	)
	(gr_line
		(start 172.960792 -372.7831)
		(end 172.960538 -372.784116)
		(stroke
			(width 0.07112)
			(type default)
		)
		(layer "In13.Cu")
	)
	(gr_line
		(start 173.154848 -377.511818)
		(end 173.154848 -378.212858)
		(stroke
			(width 0.07112)
			(type default)
		)
		(layer "In13.Cu")
	)
	(gr_line
		(start 173.232826 -372.857268)
		(end 173.232572 -372.857776)
		(stroke
			(width 0.07112)
			(type default)
		)
		(layer "In13.Cu")
	)
	(gr_line
		(start 184.38495 3.091434)
		(end 184.09412 3.382264)
		(stroke
			(width 0.07112)
			(type default)
		)
		(layer "In13.Cu")
	)
	(gr_line
		(start 184.38495 3.955034)
		(end 184.09412 3.664204)
		(stroke
			(width 0.07112)
			(type default)
		)
		(layer "In13.Cu")
	)
	(gr_line
		(start 283.714952 -403.924262)
		(end 284.005782 -404.215092)
		(stroke
			(width 0.07112)
			(type default)
		)
		(layer "In13.Cu")
	)
	(gr_line
		(start 283.714952 -403.642322)
		(end 284.005782 -403.351492)
		(stroke
			(width 0.07112)
			(type default)
		)
		(layer "In13.Cu")
	)
	(gr_line
		(start 284.482794 -414.598104)
		(end 284.482794 -413.897064)
		(stroke
			(width 0.07112)
			(type default)
		)
		(layer "In13.Cu")
	)
	(gr_line
		(start 284.482794 -413.470344)
		(end 284.482794 -412.769304)
		(stroke
			(width 0.07112)
			(type default)
		)
		(layer "In13.Cu")
	)
	(gr_line
		(start 284.482794 -412.342584)
		(end 284.482794 -411.641544)
		(stroke
			(width 0.07112)
			(type default)
		)
		(layer "In13.Cu")
	)
	(gr_line
		(start 284.482794 -411.214824)
		(end 284.482794 -410.513784)
		(stroke
			(width 0.07112)
			(type default)
		)
		(layer "In13.Cu")
	)
	(gr_line
		(start 284.766004 -414.596834)
		(end 284.901894 -414.460944)
		(stroke
			(width 0.07112)
			(type default)
		)
		(layer "In13.Cu")
	)
	(gr_line
		(start 284.766004 -413.469074)
		(end 284.901894 -413.333184)
		(stroke
			(width 0.07112)
			(type default)
		)
		(layer "In13.Cu")
	)
	(gr_line
		(start 284.766004 -412.341314)
		(end 284.901894 -412.205424)
		(stroke
			(width 0.07112)
			(type default)
		)
		(layer "In13.Cu")
	)
	(gr_line
		(start 284.766004 -411.213554)
		(end 284.901894 -411.077664)
		(stroke
			(width 0.07112)
			(type default)
		)
		(layer "In13.Cu")
	)
	(gr_line
		(start 284.901894 -414.460944)
		(end 284.901894 -414.034224)
		(stroke
			(width 0.07112)
			(type default)
		)
		(layer "In13.Cu")
	)
	(gr_line
		(start 284.901894 -414.034224)
		(end 284.766004 -413.898334)
		(stroke
			(width 0.07112)
			(type default)
		)
		(layer "In13.Cu")
	)
	(gr_line
		(start 284.901894 -413.333184)
		(end 284.901894 -412.906464)
		(stroke
			(width 0.07112)
			(type default)
		)
		(layer "In13.Cu")
	)
	(gr_line
		(start 284.901894 -412.906464)
		(end 284.766004 -412.770574)
		(stroke
			(width 0.07112)
			(type default)
		)
		(layer "In13.Cu")
	)
	(gr_line
		(start 284.901894 -412.205424)
		(end 284.901894 -411.778704)
		(stroke
			(width 0.07112)
			(type default)
		)
		(layer "In13.Cu")
	)
	(gr_line
		(start 284.901894 -411.778704)
		(end 284.766004 -411.642814)
		(stroke
			(width 0.07112)
			(type default)
		)
		(layer "In13.Cu")
	)
	(gr_line
		(start 284.901894 -411.077664)
		(end 284.901894 -410.650944)
		(stroke
			(width 0.07112)
			(type default)
		)
		(layer "In13.Cu")
	)
	(gr_line
		(start 284.901894 -410.650944)
		(end 284.766004 -410.515054)
		(stroke
			(width 0.07112)
			(type default)
		)
		(layer "In13.Cu")
	)
	(gr_line
		(start 285.949136 -422.32707)
		(end 286.239966 -422.03624)
		(stroke
			(width 0.07112)
			(type default)
		)
		(layer "In13.Cu")
	)
	(gr_line
		(start 286.423608 -414.869376)
		(end 286.423608 -414.168336)
		(stroke
			(width 0.07112)
			(type default)
		)
		(layer "In13.Cu")
	)
	(gr_line
		(start 286.423608 -413.741616)
		(end 286.423608 -413.040576)
		(stroke
			(width 0.07112)
			(type default)
		)
		(layer "In13.Cu")
	)
	(gr_line
		(start 286.423608 -412.613856)
		(end 286.423608 -411.912816)
		(stroke
			(width 0.07112)
			(type default)
		)
		(layer "In13.Cu")
	)
	(gr_line
		(start 286.423608 -411.486096)
		(end 286.423608 -410.785056)
		(stroke
			(width 0.07112)
			(type default)
		)
		(layer "In13.Cu")
	)
	(gr_line
		(start 286.423608 -410.358336)
		(end 286.423608 -409.657296)
		(stroke
			(width 0.07112)
			(type default)
		)
		(layer "In13.Cu")
	)
	(gr_line
		(start 286.423608 -409.230576)
		(end 286.423608 -408.529536)
		(stroke
			(width 0.07112)
			(type default)
		)
		(layer "In13.Cu")
	)
	(gr_line
		(start 286.706818 -414.868106)
		(end 286.842708 -414.732216)
		(stroke
			(width 0.07112)
			(type default)
		)
		(layer "In13.Cu")
	)
	(gr_line
		(start 286.706818 -413.740346)
		(end 286.842708 -413.604456)
		(stroke
			(width 0.07112)
			(type default)
		)
		(layer "In13.Cu")
	)
	(gr_line
		(start 286.706818 -412.612586)
		(end 286.842708 -412.476696)
		(stroke
			(width 0.07112)
			(type default)
		)
		(layer "In13.Cu")
	)
	(gr_line
		(start 286.706818 -411.484826)
		(end 286.842708 -411.348936)
		(stroke
			(width 0.07112)
			(type default)
		)
		(layer "In13.Cu")
	)
	(gr_line
		(start 286.706818 -410.357066)
		(end 286.842708 -410.221176)
		(stroke
			(width 0.07112)
			(type default)
		)
		(layer "In13.Cu")
	)
	(gr_line
		(start 286.706818 -409.229306)
		(end 286.842708 -409.093416)
		(stroke
			(width 0.07112)
			(type default)
		)
		(layer "In13.Cu")
	)
	(gr_line
		(start 286.812736 -422.32707)
		(end 286.521906 -422.03624)
		(stroke
			(width 0.07112)
			(type default)
		)
		(layer "In13.Cu")
	)
	(gr_line
		(start 286.842708 -414.732216)
		(end 286.842708 -414.305496)
		(stroke
			(width 0.07112)
			(type default)
		)
		(layer "In13.Cu")
	)
	(gr_line
		(start 286.842708 -414.305496)
		(end 286.706818 -414.169606)
		(stroke
			(width 0.07112)
			(type default)
		)
		(layer "In13.Cu")
	)
	(gr_line
		(start 286.842708 -413.604456)
		(end 286.842708 -413.177736)
		(stroke
			(width 0.07112)
			(type default)
		)
		(layer "In13.Cu")
	)
	(gr_line
		(start 286.842708 -413.177736)
		(end 286.706818 -413.041846)
		(stroke
			(width 0.07112)
			(type default)
		)
		(layer "In13.Cu")
	)
	(gr_line
		(start 286.842708 -412.476696)
		(end 286.842708 -412.049976)
		(stroke
			(width 0.07112)
			(type default)
		)
		(layer "In13.Cu")
	)
	(gr_line
		(start 286.842708 -412.049976)
		(end 286.706818 -411.914086)
		(stroke
			(width 0.07112)
			(type default)
		)
		(layer "In13.Cu")
	)
	(gr_line
		(start 286.842708 -411.348936)
		(end 286.842708 -410.922216)
		(stroke
			(width 0.07112)
			(type default)
		)
		(layer "In13.Cu")
	)
	(gr_line
		(start 286.842708 -410.922216)
		(end 286.706818 -410.786326)
		(stroke
			(width 0.07112)
			(type default)
		)
		(layer "In13.Cu")
	)
	(gr_line
		(start 286.842708 -410.221176)
		(end 286.842708 -409.794456)
		(stroke
			(width 0.07112)
			(type default)
		)
		(layer "In13.Cu")
	)
	(gr_line
		(start 286.842708 -409.794456)
		(end 286.706818 -409.658566)
		(stroke
			(width 0.07112)
			(type default)
		)
		(layer "In13.Cu")
	)
	(gr_line
		(start 286.842708 -409.093416)
		(end 286.842708 -408.666696)
		(stroke
			(width 0.07112)
			(type default)
		)
		(layer "In13.Cu")
	)
	(gr_line
		(start 286.842708 -408.666696)
		(end 286.706818 -408.530806)
		(stroke
			(width 0.07112)
			(type default)
		)
		(layer "In13.Cu")
	)
	(gr_line
		(start 287.192466 -407.123392)
		(end 287.483296 -407.414222)
		(stroke
			(width 0.07112)
			(type default)
		)
		(layer "In13.Cu")
	)
	(gr_line
		(start 287.192466 -406.841452)
		(end 287.483296 -406.550622)
		(stroke
			(width 0.07112)
			(type default)
		)
		(layer "In13.Cu")
	)
	(gr_line
		(start 287.837626 -419.31336)
		(end 287.837626 -418.61232)
		(stroke
			(width 0.07112)
			(type default)
		)
		(layer "In13.Cu")
	)
	(gr_line
		(start 288.120836 -419.31209)
		(end 288.256726 -419.1762)
		(stroke
			(width 0.07112)
			(type default)
		)
		(layer "In13.Cu")
	)
	(gr_line
		(start 288.166302 -412.549594)
		(end 288.166302 -411.848554)
		(stroke
			(width 0.07112)
			(type default)
		)
		(layer "In13.Cu")
	)
	(gr_line
		(start 288.166302 -411.421834)
		(end 288.166302 -410.720794)
		(stroke
			(width 0.07112)
			(type default)
		)
		(layer "In13.Cu")
	)
	(gr_line
		(start 288.166302 -410.294074)
		(end 288.166302 -409.593034)
		(stroke
			(width 0.07112)
			(type default)
		)
		(layer "In13.Cu")
	)
	(gr_line
		(start 288.166302 -409.166314)
		(end 288.166302 -408.465274)
		(stroke
			(width 0.07112)
			(type default)
		)
		(layer "In13.Cu")
	)
	(gr_line
		(start 288.166302 -408.038554)
		(end 288.166302 -407.337514)
		(stroke
			(width 0.07112)
			(type default)
		)
		(layer "In13.Cu")
	)
	(gr_line
		(start 288.256726 -419.1762)
		(end 288.256726 -418.74948)
		(stroke
			(width 0.07112)
			(type default)
		)
		(layer "In13.Cu")
	)
	(gr_line
		(start 288.256726 -418.74948)
		(end 288.120836 -418.61359)
		(stroke
			(width 0.07112)
			(type default)
		)
		(layer "In13.Cu")
	)
	(gr_line
		(start 288.449512 -412.548324)
		(end 288.585402 -412.412434)
		(stroke
			(width 0.07112)
			(type default)
		)
		(layer "In13.Cu")
	)
	(gr_line
		(start 288.449512 -411.420564)
		(end 288.585402 -411.284674)
		(stroke
			(width 0.07112)
			(type default)
		)
		(layer "In13.Cu")
	)
	(gr_line
		(start 288.449512 -410.292804)
		(end 288.585402 -410.156914)
		(stroke
			(width 0.07112)
			(type default)
		)
		(layer "In13.Cu")
	)
	(gr_line
		(start 288.449512 -409.165044)
		(end 288.585402 -409.029154)
		(stroke
			(width 0.07112)
			(type default)
		)
		(layer "In13.Cu")
	)
	(gr_line
		(start 288.449512 -408.037284)
		(end 288.585402 -407.901394)
		(stroke
			(width 0.07112)
			(type default)
		)
		(layer "In13.Cu")
	)
	(gr_line
		(start 288.585402 -412.412434)
		(end 288.585402 -411.985714)
		(stroke
			(width 0.07112)
			(type default)
		)
		(layer "In13.Cu")
	)
	(gr_line
		(start 288.585402 -411.985714)
		(end 288.449512 -411.849824)
		(stroke
			(width 0.07112)
			(type default)
		)
		(layer "In13.Cu")
	)
	(gr_line
		(start 288.585402 -411.284674)
		(end 288.585402 -410.857954)
		(stroke
			(width 0.07112)
			(type default)
		)
		(layer "In13.Cu")
	)
	(gr_line
		(start 288.585402 -410.857954)
		(end 288.449512 -410.722064)
		(stroke
			(width 0.07112)
			(type default)
		)
		(layer "In13.Cu")
	)
	(gr_line
		(start 288.585402 -410.156914)
		(end 288.585402 -409.730194)
		(stroke
			(width 0.07112)
			(type default)
		)
		(layer "In13.Cu")
	)
	(gr_line
		(start 288.585402 -409.730194)
		(end 288.449512 -409.594304)
		(stroke
			(width 0.07112)
			(type default)
		)
		(layer "In13.Cu")
	)
	(gr_line
		(start 288.585402 -409.029154)
		(end 288.585402 -408.602434)
		(stroke
			(width 0.07112)
			(type default)
		)
		(layer "In13.Cu")
	)
	(gr_line
		(start 288.585402 -408.602434)
		(end 288.449512 -408.466544)
		(stroke
			(width 0.07112)
			(type default)
		)
		(layer "In13.Cu")
	)
	(gr_line
		(start 288.585402 -407.901394)
		(end 288.585402 -407.474674)
		(stroke
			(width 0.07112)
			(type default)
		)
		(layer "In13.Cu")
	)
	(gr_line
		(start 288.585402 -407.474674)
		(end 288.449512 -407.338784)
		(stroke
			(width 0.07112)
			(type default)
		)
		(layer "In13.Cu")
	)
	(gr_line
		(start 288.78657 -416.998658)
		(end 288.78657 -416.297618)
		(stroke
			(width 0.07112)
			(type default)
		)
		(layer "In13.Cu")
	)
	(gr_line
		(start 288.78657 -415.870898)
		(end 288.78657 -415.169858)
		(stroke
			(width 0.07112)
			(type default)
		)
		(layer "In13.Cu")
	)
	(gr_line
		(start 288.78657 -414.743138)
		(end 288.78657 -414.042098)
		(stroke
			(width 0.07112)
			(type default)
		)
		(layer "In13.Cu")
	)
	(gr_line
		(start 289.06978 -416.997388)
		(end 289.20567 -416.861498)
		(stroke
			(width 0.07112)
			(type default)
		)
		(layer "In13.Cu")
	)
	(gr_line
		(start 289.06978 -415.869628)
		(end 289.20567 -415.733738)
		(stroke
			(width 0.07112)
			(type default)
		)
		(layer "In13.Cu")
	)
	(gr_line
		(start 289.06978 -414.741868)
		(end 289.20567 -414.605978)
		(stroke
			(width 0.07112)
			(type default)
		)
		(layer "In13.Cu")
	)
	(gr_line
		(start 289.20567 -416.861498)
		(end 289.20567 -416.434778)
		(stroke
			(width 0.07112)
			(type default)
		)
		(layer "In13.Cu")
	)
	(gr_line
		(start 289.20567 -416.434778)
		(end 289.06978 -416.298888)
		(stroke
			(width 0.07112)
			(type default)
		)
		(layer "In13.Cu")
	)
	(gr_line
		(start 289.20567 -415.733738)
		(end 289.20567 -415.307018)
		(stroke
			(width 0.07112)
			(type default)
		)
		(layer "In13.Cu")
	)
	(gr_line
		(start 289.20567 -415.307018)
		(end 289.06978 -415.171128)
		(stroke
			(width 0.07112)
			(type default)
		)
		(layer "In13.Cu")
	)
	(gr_line
		(start 289.20567 -414.605978)
		(end 289.20567 -414.179258)
		(stroke
			(width 0.07112)
			(type default)
		)
		(layer "In13.Cu")
	)
	(gr_line
		(start 289.20567 -414.179258)
		(end 289.06978 -414.043368)
		(stroke
			(width 0.07112)
			(type default)
		)
		(layer "In13.Cu")
	)
	(gr_line
		(start 289.835336 -418.254688)
		(end 289.544506 -417.963858)
		(stroke
			(width 0.07112)
			(type default)
		)
		(layer "In13.Cu")
	)
	(gr_line
		(start 289.835336 -417.391088)
		(end 289.544506 -417.681918)
		(stroke
			(width 0.07112)
			(type default)
		)
		(layer "In13.Cu")
	)
	(gr_line
		(start 289.929824 -419.814502)
		(end 289.793934 -419.950392)
		(stroke
			(width 0.07112)
			(type default)
		)
		(layer "In13.Cu")
	)
	(gr_line
		(start 290.010088 -402.734526)
		(end 290.300918 -403.025356)
		(stroke
			(width 0.07112)
			(type default)
		)
		(layer "In13.Cu")
	)
	(gr_line
		(start 290.010088 -402.452586)
		(end 290.300918 -402.161756)
		(stroke
			(width 0.07112)
			(type default)
		)
		(layer "In13.Cu")
	)
	(gr_line
		(start 290.356544 -419.814502)
		(end 289.929824 -419.814502)
		(stroke
			(width 0.07112)
			(type default)
		)
		(layer "In13.Cu")
	)
	(gr_line
		(start 290.492434 -419.950392)
		(end 290.356544 -419.814502)
		(stroke
			(width 0.07112)
			(type default)
		)
		(layer "In13.Cu")
	)
	(gr_line
		(start 290.493704 -420.233602)
		(end 289.792664 -420.233602)
		(stroke
			(width 0.07112)
			(type default)
		)
		(layer "In13.Cu")
	)
	(gr_line
		(start 291.211254 -420.524432)
		(end 290.920424 -420.233602)
		(stroke
			(width 0.07112)
			(type default)
		)
		(layer "In13.Cu")
	)
	(gr_line
		(start 291.211254 -419.660832)
		(end 290.920424 -419.951662)
		(stroke
			(width 0.07112)
			(type default)
		)
		(layer "In13.Cu")
	)
	(gr_line
		(start 297.495214 -379.368304)
		(end 297.495214 -378.667264)
		(stroke
			(width 0.07112)
			(type default)
		)
		(layer "In13.Cu")
	)
	(gr_line
		(start 297.495214 -378.240544)
		(end 297.495214 -377.539504)
		(stroke
			(width 0.07112)
			(type default)
		)
		(layer "In13.Cu")
	)
	(gr_line
		(start 297.778424 -379.367034)
		(end 297.914314 -379.231144)
		(stroke
			(width 0.07112)
			(type default)
		)
		(layer "In13.Cu")
	)
	(gr_line
		(start 297.778424 -378.239274)
		(end 297.914314 -378.103384)
		(stroke
			(width 0.07112)
			(type default)
		)
		(layer "In13.Cu")
	)
	(gr_line
		(start 297.914314 -379.231144)
		(end 297.914314 -378.804424)
		(stroke
			(width 0.07112)
			(type default)
		)
		(layer "In13.Cu")
	)
	(gr_line
		(start 297.914314 -378.804424)
		(end 297.778424 -378.668534)
		(stroke
			(width 0.07112)
			(type default)
		)
		(layer "In13.Cu")
	)
	(gr_line
		(start 297.914314 -378.103384)
		(end 297.914314 -377.676664)
		(stroke
			(width 0.07112)
			(type default)
		)
		(layer "In13.Cu")
	)
	(gr_line
		(start 297.914314 -377.676664)
		(end 297.778424 -377.540774)
		(stroke
			(width 0.07112)
			(type default)
		)
		(layer "In13.Cu")
	)
	(gr_line
		(start 298.2595 -375.886472)
		(end 298.259754 -375.886472)
		(stroke
			(width 0.07112)
			(type default)
		)
		(layer "In13.Cu")
	)
	(gr_line
		(start 298.37634 -376.168412)
		(end 298.376594 -376.168412)
		(stroke
			(width 0.07112)
			(type default)
		)
		(layer "In13.Cu")
	)
	(gr_line
		(start 299.172884 -374.973088)
		(end 299.6692 -374.476772)
		(stroke
			(width 0.07112)
			(type default)
		)
		(layer "In13.Cu")
	)
	(gr_line
		(start 299.173138 -374.973088)
		(end 299.172884 -374.973088)
		(stroke
			(width 0.07112)
			(type default)
		)
		(layer "In13.Cu")
	)
	(gr_line
		(start 299.374052 -375.172478)
		(end 299.566584 -375.172478)
		(stroke
			(width 0.07112)
			(type default)
		)
		(layer "In13.Cu")
	)
	(gr_line
		(start 299.566584 -375.172478)
		(end 299.86859 -374.870472)
		(stroke
			(width 0.07112)
			(type default)
		)
		(layer "In13.Cu")
	)
	(gr_line
		(start 299.86859 -374.870472)
		(end 299.86859 -374.67794)
		(stroke
			(width 0.07112)
			(type default)
		)
		(layer "In13.Cu")
	)
	(gr_line
		(start 300.325536 -373.820436)
		(end 300.821598 -373.324374)
		(stroke
			(width 0.07112)
			(type default)
		)
		(layer "In13.Cu")
	)
	(gr_line
		(start 300.526704 -374.019826)
		(end 300.718982 -374.019826)
		(stroke
			(width 0.07112)
			(type default)
		)
		(layer "In13.Cu")
	)
	(gr_line
		(start 300.718982 -374.019826)
		(end 301.020988 -373.71782)
		(stroke
			(width 0.07112)
			(type default)
		)
		(layer "In13.Cu")
	)
	(gr_line
		(start 301.020988 -373.71782)
		(end 301.020988 -373.525542)
		(stroke
			(width 0.07112)
			(type default)
		)
		(layer "In13.Cu")
	)
	(gr_line
		(start 301.447962 -386.475732)
		(end 301.447962 -386.283454)
		(stroke
			(width 0.07112)
			(type default)
		)
		(layer "In13.Cu")
	)
	(gr_line
		(start 301.749968 -386.777738)
		(end 301.447962 -386.475732)
		(stroke
			(width 0.07112)
			(type default)
		)
		(layer "In13.Cu")
	)
	(gr_line
		(start 301.942246 -386.777738)
		(end 301.749968 -386.777738)
		(stroke
			(width 0.07112)
			(type default)
		)
		(layer "In13.Cu")
	)
	(gr_line
		(start 302.143414 -386.578348)
		(end 301.647352 -386.082286)
		(stroke
			(width 0.07112)
			(type default)
		)
		(layer "In13.Cu")
	)
	(gr_line
		(start 302.245522 -387.273292)
		(end 302.245522 -387.081014)
		(stroke
			(width 0.07112)
			(type default)
		)
		(layer "In13.Cu")
	)
	(gr_line
		(start 302.547528 -387.575298)
		(end 302.245522 -387.273292)
		(stroke
			(width 0.07112)
			(type default)
		)
		(layer "In13.Cu")
	)
	(gr_line
		(start 302.739806 -387.575298)
		(end 302.547528 -387.575298)
		(stroke
			(width 0.07112)
			(type default)
		)
		(layer "In13.Cu")
	)
	(gr_line
		(start 302.940974 -387.375908)
		(end 302.444912 -386.879846)
		(stroke
			(width 0.07112)
			(type default)
		)
		(layer "In13.Cu")
	)
	(gr_line
		(start 303.043082 -388.070852)
		(end 303.043082 -387.878574)
		(stroke
			(width 0.07112)
			(type default)
		)
		(layer "In13.Cu")
	)
	(gr_line
		(start 303.345088 -388.372858)
		(end 303.043082 -388.070852)
		(stroke
			(width 0.07112)
			(type default)
		)
		(layer "In13.Cu")
	)
	(gr_line
		(start 303.537366 -388.372858)
		(end 303.345088 -388.372858)
		(stroke
			(width 0.07112)
			(type default)
		)
		(layer "In13.Cu")
	)
	(gr_line
		(start 303.738534 -388.173468)
		(end 303.242472 -387.677406)
		(stroke
			(width 0.07112)
			(type default)
		)
		(layer "In13.Cu")
	)
	(gr_line
		(start 303.791112 -393.69238)
		(end 304.144426 -393.787376)
		(stroke
			(width 0.07112)
			(type default)
		)
		(layer "In13.Cu")
	)
	(gr_line
		(start 303.840642 -388.868412)
		(end 303.840642 -388.676134)
		(stroke
			(width 0.07112)
			(type default)
		)
		(layer "In13.Cu")
	)
	(gr_line
		(start 303.90338 -379.603508)
		(end 303.90338 -379.176788)
		(stroke
			(width 0.07112)
			(type default)
		)
		(layer "In13.Cu")
	)
	(gr_line
		(start 303.90338 -379.176788)
		(end 304.03927 -379.040898)
		(stroke
			(width 0.07112)
			(type default)
		)
		(layer "In13.Cu")
	)
	(gr_line
		(start 303.90338 -378.46)
		(end 303.90338 -378.03328)
		(stroke
			(width 0.07112)
			(type default)
		)
		(layer "In13.Cu")
	)
	(gr_line
		(start 303.90338 -378.03328)
		(end 304.03927 -377.89739)
		(stroke
			(width 0.07112)
			(type default)
		)
		(layer "In13.Cu")
	)
	(gr_line
		(start 303.90338 -377.33224)
		(end 303.90338 -376.90552)
		(stroke
			(width 0.07112)
			(type default)
		)
		(layer "In13.Cu")
	)
	(gr_line
		(start 303.90338 -376.90552)
		(end 304.03927 -376.76963)
		(stroke
			(width 0.07112)
			(type default)
		)
		(layer "In13.Cu")
	)
	(gr_line
		(start 304.015648 -386.354574)
		(end 304.05324 -386.165852)
		(stroke
			(width 0.07112)
			(type default)
		)
		(layer "In13.Cu")
	)
	(gr_line
		(start 304.03927 -379.739398)
		(end 303.90338 -379.603508)
		(stroke
			(width 0.07112)
			(type default)
		)
		(layer "In13.Cu")
	)
	(gr_line
		(start 304.03927 -378.59589)
		(end 303.90338 -378.46)
		(stroke
			(width 0.07112)
			(type default)
		)
		(layer "In13.Cu")
	)
	(gr_line
		(start 304.03927 -377.46813)
		(end 303.90338 -377.33224)
		(stroke
			(width 0.07112)
			(type default)
		)
		(layer "In13.Cu")
	)
	(gr_line
		(start 304.142648 -389.170418)
		(end 303.840642 -388.868412)
		(stroke
			(width 0.07112)
			(type default)
		)
		(layer "In13.Cu")
	)
	(gr_line
		(start 304.144426 -393.787376)
		(end 304.144934 -393.786868)
		(stroke
			(width 0.07112)
			(type default)
		)
		(layer "In13.Cu")
	)
	(gr_line
		(start 304.191162 -394.385292)
		(end 304.285904 -394.031724)
		(stroke
			(width 0.07112)
			(type default)
		)
		(layer "In13.Cu")
	)
	(gr_line
		(start 304.252884 -386.709666)
		(end 304.015648 -386.354574)
		(stroke
			(width 0.07112)
			(type default)
		)
		(layer "In13.Cu")
	)
	(gr_line
		(start 304.287936 -390.353804)
		(end 304.287682 -390.353804)
		(stroke
			(width 0.07112)
			(type default)
		)
		(layer "In13.Cu")
	)
	(gr_line
		(start 304.32248 -379.740668)
		(end 304.32248 -379.039628)
		(stroke
			(width 0.07112)
			(type default)
		)
		(layer "In13.Cu")
	)
	(gr_line
		(start 304.32248 -378.59716)
		(end 304.32248 -377.89612)
		(stroke
			(width 0.07112)
			(type default)
		)
		(layer "In13.Cu")
	)
	(gr_line
		(start 304.32248 -377.4694)
		(end 304.32248 -376.76836)
		(stroke
			(width 0.07112)
			(type default)
		)
		(layer "In13.Cu")
	)
	(gr_line
		(start 304.334926 -389.170418)
		(end 304.142648 -389.170418)
		(stroke
			(width 0.07112)
			(type default)
		)
		(layer "In13.Cu")
	)
	(gr_line
		(start 304.40757 -393.961112)
		(end 304.460402 -393.930632)
		(stroke
			(width 0.07112)
			(type default)
		)
		(layer "In13.Cu")
	)
	(gr_line
		(start 304.441606 -386.747258)
		(end 304.252884 -386.709666)
		(stroke
			(width 0.07112)
			(type default)
		)
		(layer "In13.Cu")
	)
	(gr_line
		(start 304.460402 -393.930632)
		(end 304.54854 -393.842494)
		(stroke
			(width 0.07112)
			(type default)
		)
		(layer "In13.Cu")
	)
	(gr_line
		(start 304.536094 -388.971028)
		(end 304.040032 -388.474966)
		(stroke
			(width 0.07112)
			(type default)
		)
		(layer "In13.Cu")
	)
	(gr_line
		(start 304.54854 -393.842494)
		(end 304.54854 -393.716764)
		(stroke
			(width 0.07112)
			(type default)
		)
		(layer "In13.Cu")
	)
	(gr_line
		(start 304.642266 -387.292342)
		(end 304.679858 -387.10362)
		(stroke
			(width 0.07112)
			(type default)
		)
		(layer "In13.Cu")
	)
	(gr_line
		(start 304.677826 -386.590794)
		(end 304.287936 -386.00761)
		(stroke
			(width 0.07112)
			(type default)
		)
		(layer "In13.Cu")
	)
	(gr_line
		(start 304.879502 -387.647434)
		(end 304.642266 -387.292342)
		(stroke
			(width 0.07112)
			(type default)
		)
		(layer "In13.Cu")
	)
	(gr_line
		(start 304.991008 -393.69238)
		(end 305.344322 -393.787376)
		(stroke
			(width 0.07112)
			(type default)
		)
		(layer "In13.Cu")
	)
	(gr_line
		(start 305.068478 -387.685026)
		(end 304.879502 -387.647434)
		(stroke
			(width 0.07112)
			(type default)
		)
		(layer "In13.Cu")
	)
	(gr_line
		(start 305.268884 -388.23011)
		(end 305.306476 -388.041388)
		(stroke
			(width 0.07112)
			(type default)
		)
		(layer "In13.Cu")
	)
	(gr_line
		(start 305.304444 -387.528562)
		(end 304.914808 -386.945378)
		(stroke
			(width 0.07112)
			(type default)
		)
		(layer "In13.Cu")
	)
	(gr_line
		(start 305.344322 -393.787376)
		(end 305.34483 -393.786868)
		(stroke
			(width 0.07112)
			(type default)
		)
		(layer "In13.Cu")
	)
	(gr_line
		(start 305.391058 -394.385292)
		(end 305.4858 -394.031724)
		(stroke
			(width 0.07112)
			(type default)
		)
		(layer "In13.Cu")
	)
	(gr_line
		(start 305.506374 -388.585202)
		(end 305.268884 -388.23011)
		(stroke
			(width 0.07112)
			(type default)
		)
		(layer "In13.Cu")
	)
	(gr_line
		(start 305.607466 -393.961112)
		(end 305.660298 -393.930632)
		(stroke
			(width 0.07112)
			(type default)
		)
		(layer "In13.Cu")
	)
	(gr_line
		(start 305.660298 -393.930632)
		(end 305.748436 -393.842494)
		(stroke
			(width 0.07112)
			(type default)
		)
		(layer "In13.Cu")
	)
	(gr_line
		(start 305.695096 -388.622794)
		(end 305.506374 -388.585202)
		(stroke
			(width 0.07112)
			(type default)
		)
		(layer "In13.Cu")
	)
	(gr_line
		(start 305.748436 -393.842494)
		(end 305.748436 -393.716764)
		(stroke
			(width 0.07112)
			(type default)
		)
		(layer "In13.Cu")
	)
	(gr_line
		(start 305.931062 -388.46633)
		(end 305.541426 -387.883146)
		(stroke
			(width 0.07112)
			(type default)
		)
		(layer "In13.Cu")
	)
	(gr_line
		(start 306.191158 -393.69238)
		(end 306.544218 -393.787376)
		(stroke
			(width 0.07112)
			(type default)
		)
		(layer "In13.Cu")
	)
	(gr_line
		(start 306.415694 -419.607238)
		(end 306.41544 -419.607238)
		(stroke
			(width 0.07112)
			(type default)
		)
		(layer "In13.Cu")
	)
	(gr_line
		(start 306.544218 -393.787376)
		(end 306.544726 -393.786868)
		(stroke
			(width 0.07112)
			(type default)
		)
		(layer "In13.Cu")
	)
	(gr_line
		(start 306.590954 -394.385292)
		(end 306.685696 -394.031724)
		(stroke
			(width 0.07112)
			(type default)
		)
		(layer "In13.Cu")
	)
	(gr_line
		(start 306.807362 -393.961112)
		(end 306.860194 -393.930632)
		(stroke
			(width 0.07112)
			(type default)
		)
		(layer "In13.Cu")
	)
	(gr_line
		(start 306.860194 -393.930632)
		(end 306.948332 -393.842494)
		(stroke
			(width 0.07112)
			(type default)
		)
		(layer "In13.Cu")
	)
	(gr_line
		(start 306.948332 -393.842494)
		(end 306.948332 -393.716764)
		(stroke
			(width 0.07112)
			(type default)
		)
		(layer "In13.Cu")
	)
	(gr_line
		(start 307.060346 -424.735498)
		(end 306.642516 -424.172126)
		(stroke
			(width 0.07112)
			(type default)
		)
		(layer "In13.Cu")
	)
	(gr_line
		(start 307.061108 -424.03268)
		(end 306.870608 -424.004486)
		(stroke
			(width 0.07112)
			(type default)
		)
		(layer "In13.Cu")
	)
	(gr_line
		(start 307.147976 -417.590224)
		(end 307.147976 -416.889184)
		(stroke
			(width 0.07112)
			(type default)
		)
		(layer "In13.Cu")
	)
	(gr_line
		(start 307.147976 -416.462464)
		(end 307.147976 -415.761424)
		(stroke
			(width 0.07112)
			(type default)
		)
		(layer "In13.Cu")
	)
	(gr_line
		(start 307.287168 -424.56608)
		(end 307.315362 -424.375834)
		(stroke
			(width 0.07112)
			(type default)
		)
		(layer "In13.Cu")
	)
	(gr_line
		(start 307.315362 -424.375834)
		(end 307.061108 -424.03268)
		(stroke
			(width 0.07112)
			(type default)
		)
		(layer "In13.Cu")
	)
	(gr_line
		(start 307.391054 -393.69238)
		(end 307.744368 -393.787376)
		(stroke
			(width 0.07112)
			(type default)
		)
		(layer "In13.Cu")
	)
	(gr_line
		(start 307.431186 -417.588954)
		(end 307.567076 -417.453064)
		(stroke
			(width 0.07112)
			(type default)
		)
		(layer "In13.Cu")
	)
	(gr_line
		(start 307.431186 -416.461194)
		(end 307.567076 -416.325304)
		(stroke
			(width 0.07112)
			(type default)
		)
		(layer "In13.Cu")
	)
	(gr_line
		(start 307.567076 -417.453064)
		(end 307.567076 -417.026344)
		(stroke
			(width 0.07112)
			(type default)
		)
		(layer "In13.Cu")
	)
	(gr_line
		(start 307.567076 -417.026344)
		(end 307.431186 -416.890454)
		(stroke
			(width 0.07112)
			(type default)
		)
		(layer "In13.Cu")
	)
	(gr_line
		(start 307.567076 -416.325304)
		(end 307.567076 -415.898584)
		(stroke
			(width 0.07112)
			(type default)
		)
		(layer "In13.Cu")
	)
	(gr_line
		(start 307.567076 -415.898584)
		(end 307.431186 -415.762694)
		(stroke
			(width 0.07112)
			(type default)
		)
		(layer "In13.Cu")
	)
	(gr_line
		(start 307.744368 -393.787376)
		(end 307.744876 -393.786868)
		(stroke
			(width 0.07112)
			(type default)
		)
		(layer "In13.Cu")
	)
	(gr_line
		(start 307.791104 -394.385292)
		(end 307.885846 -394.031724)
		(stroke
			(width 0.07112)
			(type default)
		)
		(layer "In13.Cu")
	)
	(gr_line
		(start 307.848508 -388.506208)
		(end 307.848508 -388.505954)
		(stroke
			(width 0.07112)
			(type default)
		)
		(layer "In13.Cu")
	)
	(gr_line
		(start 307.91404 -379.420628)
		(end 307.913786 -379.420628)
		(stroke
			(width 0.07112)
			(type default)
		)
		(layer "In13.Cu")
	)
	(gr_line
		(start 307.992526 -425.992544)
		(end 307.574696 -425.429172)
		(stroke
			(width 0.07112)
			(type default)
		)
		(layer "In13.Cu")
	)
	(gr_line
		(start 307.993034 -425.289726)
		(end 307.803042 -425.261532)
		(stroke
			(width 0.07112)
			(type default)
		)
		(layer "In13.Cu")
	)
	(gr_line
		(start 308.007512 -393.961112)
		(end 308.060344 -393.930632)
		(stroke
			(width 0.07112)
			(type default)
		)
		(layer "In13.Cu")
	)
	(gr_line
		(start 308.060344 -393.930632)
		(end 308.148482 -393.842494)
		(stroke
			(width 0.07112)
			(type default)
		)
		(layer "In13.Cu")
	)
	(gr_line
		(start 308.140354 -388.55396)
		(end 308.140354 -388.554722)
		(stroke
			(width 0.07112)
			(type default)
		)
		(layer "In13.Cu")
	)
	(gr_line
		(start 308.148482 -393.842494)
		(end 308.148482 -393.716764)
		(stroke
			(width 0.07112)
			(type default)
		)
		(layer "In13.Cu")
	)
	(gr_line
		(start 308.219348 -425.822872)
		(end 308.247542 -425.632626)
		(stroke
			(width 0.07112)
			(type default)
		)
		(layer "In13.Cu")
	)
	(gr_line
		(start 308.247542 -425.632626)
		(end 307.993034 -425.289726)
		(stroke
			(width 0.07112)
			(type default)
		)
		(layer "In13.Cu")
	)
	(gr_line
		(start 308.59095 -393.69238)
		(end 308.944264 -393.787376)
		(stroke
			(width 0.07112)
			(type default)
		)
		(layer "In13.Cu")
	)
	(gr_line
		(start 308.771544 -427.043088)
		(end 308.353714 -426.479716)
		(stroke
			(width 0.07112)
			(type default)
		)
		(layer "In13.Cu")
	)
	(gr_line
		(start 308.772052 -426.340016)
		(end 308.581806 -426.311822)
		(stroke
			(width 0.07112)
			(type default)
		)
		(layer "In13.Cu")
	)
	(gr_line
		(start 308.944264 -393.787376)
		(end 308.944772 -393.786868)
		(stroke
			(width 0.07112)
			(type default)
		)
		(layer "In13.Cu")
	)
	(gr_line
		(start 308.991 -394.385292)
		(end 309.085742 -394.031724)
		(stroke
			(width 0.07112)
			(type default)
		)
		(layer "In13.Cu")
	)
	(gr_line
		(start 308.998366 -426.873416)
		(end 309.02656 -426.682916)
		(stroke
			(width 0.07112)
			(type default)
		)
		(layer "In13.Cu")
	)
	(gr_line
		(start 309.02656 -426.682916)
		(end 308.772052 -426.340016)
		(stroke
			(width 0.07112)
			(type default)
		)
		(layer "In13.Cu")
	)
	(gr_line
		(start 309.048404 -387.920484)
		(end 309.048404 -387.92023)
		(stroke
			(width 0.07112)
			(type default)
		)
		(layer "In13.Cu")
	)
	(gr_line
		(start 309.207408 -393.961112)
		(end 309.26024 -393.930632)
		(stroke
			(width 0.07112)
			(type default)
		)
		(layer "In13.Cu")
	)
	(gr_line
		(start 309.26024 -393.930632)
		(end 309.348378 -393.842494)
		(stroke
			(width 0.07112)
			(type default)
		)
		(layer "In13.Cu")
	)
	(gr_line
		(start 309.34025 -387.967982)
		(end 309.34025 -387.968998)
		(stroke
			(width 0.07112)
			(type default)
		)
		(layer "In13.Cu")
	)
	(gr_line
		(start 309.348378 -393.842494)
		(end 309.348378 -393.716764)
		(stroke
			(width 0.07112)
			(type default)
		)
		(layer "In13.Cu")
	)
	(gr_line
		(start 309.450486 -427.958504)
		(end 309.032656 -427.395132)
		(stroke
			(width 0.07112)
			(type default)
		)
		(layer "In13.Cu")
	)
	(gr_line
		(start 309.450994 -427.255432)
		(end 309.260748 -427.227238)
		(stroke
			(width 0.07112)
			(type default)
		)
		(layer "In13.Cu")
	)
	(gr_line
		(start 309.677308 -427.788832)
		(end 309.705502 -427.598586)
		(stroke
			(width 0.07112)
			(type default)
		)
		(layer "In13.Cu")
	)
	(gr_line
		(start 309.705502 -427.598586)
		(end 309.450994 -427.255432)
		(stroke
			(width 0.07112)
			(type default)
		)
		(layer "In13.Cu")
	)
	(gr_line
		(start 309.7911 -393.69238)
		(end 310.144414 -393.787376)
		(stroke
			(width 0.07112)
			(type default)
		)
		(layer "In13.Cu")
	)
	(gr_line
		(start 310.144414 -393.787376)
		(end 310.144922 -393.786868)
		(stroke
			(width 0.07112)
			(type default)
		)
		(layer "In13.Cu")
	)
	(gr_line
		(start 310.146446 -422.273476)
		(end 309.973472 -422.357296)
		(stroke
			(width 0.07112)
			(type default)
		)
		(layer "In13.Cu")
	)
	(gr_line
		(start 310.19115 -394.385292)
		(end 310.285892 -394.031724)
		(stroke
			(width 0.07112)
			(type default)
		)
		(layer "In13.Cu")
	)
	(gr_line
		(start 310.196738 -428.964852)
		(end 309.778908 -428.401226)
		(stroke
			(width 0.07112)
			(type default)
		)
		(layer "In13.Cu")
	)
	(gr_line
		(start 310.1975 -428.26178)
		(end 310.007 -428.233586)
		(stroke
			(width 0.07112)
			(type default)
		)
		(layer "In13.Cu")
	)
	(gr_line
		(start 310.211216 -417.684458)
		(end 310.211216 -416.983418)
		(stroke
			(width 0.07112)
			(type default)
		)
		(layer "In13.Cu")
	)
	(gr_line
		(start 310.211216 -416.487102)
		(end 310.211216 -415.786062)
		(stroke
			(width 0.07112)
			(type default)
		)
		(layer "In13.Cu")
	)
	(gr_line
		(start 310.248554 -387.106414)
		(end 310.248554 -387.10616)
		(stroke
			(width 0.07112)
			(type default)
		)
		(layer "In13.Cu")
	)
	(gr_line
		(start 310.407558 -393.961112)
		(end 310.46039 -393.930632)
		(stroke
			(width 0.07112)
			(type default)
		)
		(layer "In13.Cu")
	)
	(gr_line
		(start 310.423814 -428.795434)
		(end 310.452008 -428.604934)
		(stroke
			(width 0.07112)
			(type default)
		)
		(layer "In13.Cu")
	)
	(gr_line
		(start 310.452008 -428.604934)
		(end 310.1975 -428.26178)
		(stroke
			(width 0.07112)
			(type default)
		)
		(layer "In13.Cu")
	)
	(gr_line
		(start 310.46039 -393.930632)
		(end 310.548528 -393.842494)
		(stroke
			(width 0.07112)
			(type default)
		)
		(layer "In13.Cu")
	)
	(gr_line
		(start 310.494426 -417.683188)
		(end 310.630316 -417.547298)
		(stroke
			(width 0.07112)
			(type default)
		)
		(layer "In13.Cu")
	)
	(gr_line
		(start 310.494426 -416.485832)
		(end 310.630316 -416.349942)
		(stroke
			(width 0.07112)
			(type default)
		)
		(layer "In13.Cu")
	)
	(gr_line
		(start 310.5404 -387.153912)
		(end 310.5404 -387.154928)
		(stroke
			(width 0.07112)
			(type default)
		)
		(layer "In13.Cu")
	)
	(gr_line
		(start 310.541924 -422.854882)
		(end 309.879238 -422.624504)
		(stroke
			(width 0.07112)
			(type default)
		)
		(layer "In13.Cu")
	)
	(gr_line
		(start 310.548528 -393.842494)
		(end 310.548528 -393.716764)
		(stroke
			(width 0.07112)
			(type default)
		)
		(layer "In13.Cu")
	)
	(gr_line
		(start 310.549798 -422.413684)
		(end 310.146446 -422.273476)
		(stroke
			(width 0.07112)
			(type default)
		)
		(layer "In13.Cu")
	)
	(gr_line
		(start 310.630316 -417.547298)
		(end 310.630316 -417.120578)
		(stroke
			(width 0.07112)
			(type default)
		)
		(layer "In13.Cu")
	)
	(gr_line
		(start 310.630316 -417.120578)
		(end 310.494426 -416.984688)
		(stroke
			(width 0.07112)
			(type default)
		)
		(layer "In13.Cu")
	)
	(gr_line
		(start 310.630316 -416.349942)
		(end 310.630316 -415.923222)
		(stroke
			(width 0.07112)
			(type default)
		)
		(layer "In13.Cu")
	)
	(gr_line
		(start 310.630316 -415.923222)
		(end 310.494426 -415.787332)
		(stroke
			(width 0.07112)
			(type default)
		)
		(layer "In13.Cu")
	)
	(gr_line
		(start 310.633618 -422.587166)
		(end 310.549798 -422.413684)
		(stroke
			(width 0.07112)
			(type default)
		)
		(layer "In13.Cu")
	)
	(gr_line
		(start 310.743854 -410.727652)
		(end 311.383172 -410.4386)
		(stroke
			(width 0.07112)
			(type default)
		)
		(layer "In13.Cu")
	)
	(gr_line
		(start 310.861456 -410.985208)
		(end 311.041542 -411.05328)
		(stroke
			(width 0.07112)
			(type default)
		)
		(layer "In13.Cu")
	)
	(gr_line
		(start 310.990996 -393.69238)
		(end 311.34431 -393.787376)
		(stroke
			(width 0.07112)
			(type default)
		)
		(layer "In13.Cu")
	)
	(gr_line
		(start 311.041542 -411.05328)
		(end 311.43067 -410.877512)
		(stroke
			(width 0.07112)
			(type default)
		)
		(layer "In13.Cu")
	)
	(gr_line
		(start 311.21985 -422.646856)
		(end 311.046622 -422.730676)
		(stroke
			(width 0.07112)
			(type default)
		)
		(layer "In13.Cu")
	)
	(gr_line
		(start 311.34431 -393.787376)
		(end 311.344818 -393.786868)
		(stroke
			(width 0.07112)
			(type default)
		)
		(layer "In13.Cu")
	)
	(gr_line
		(start 311.391046 -394.385292)
		(end 311.485788 -394.031724)
		(stroke
			(width 0.07112)
			(type default)
		)
		(layer "In13.Cu")
	)
	(gr_line
		(start 311.43067 -410.877512)
		(end 311.498742 -410.697172)
		(stroke
			(width 0.07112)
			(type default)
		)
		(layer "In13.Cu")
	)
	(gr_line
		(start 311.607454 -393.961112)
		(end 311.660286 -393.930632)
		(stroke
			(width 0.07112)
			(type default)
		)
		(layer "In13.Cu")
	)
	(gr_line
		(start 311.61482 -423.228262)
		(end 310.952388 -422.997884)
		(stroke
			(width 0.07112)
			(type default)
		)
		(layer "In13.Cu")
	)
	(gr_line
		(start 311.622948 -422.787064)
		(end 311.21985 -422.646856)
		(stroke
			(width 0.07112)
			(type default)
		)
		(layer "In13.Cu")
	)
	(gr_line
		(start 311.660286 -393.930632)
		(end 311.748424 -393.842494)
		(stroke
			(width 0.07112)
			(type default)
		)
		(layer "In13.Cu")
	)
	(gr_line
		(start 311.707022 -422.960546)
		(end 311.622948 -422.787064)
		(stroke
			(width 0.07112)
			(type default)
		)
		(layer "In13.Cu")
	)
	(gr_line
		(start 311.748424 -393.842494)
		(end 311.748424 -393.716764)
		(stroke
			(width 0.07112)
			(type default)
		)
		(layer "In13.Cu")
	)
	(gr_line
		(start 312.191146 -393.69238)
		(end 312.544206 -393.787376)
		(stroke
			(width 0.07112)
			(type default)
		)
		(layer "In13.Cu")
	)
	(gr_line
		(start 312.544206 -393.787376)
		(end 312.544714 -393.786868)
		(stroke
			(width 0.07112)
			(type default)
		)
		(layer "In13.Cu")
	)
	(gr_line
		(start 312.590942 -394.385292)
		(end 312.685684 -394.031724)
		(stroke
			(width 0.07112)
			(type default)
		)
		(layer "In13.Cu")
	)
	(gr_line
		(start 312.80735 -393.961112)
		(end 312.860182 -393.930632)
		(stroke
			(width 0.07112)
			(type default)
		)
		(layer "In13.Cu")
	)
	(gr_line
		(start 312.860182 -393.930632)
		(end 312.94832 -393.842494)
		(stroke
			(width 0.07112)
			(type default)
		)
		(layer "In13.Cu")
	)
	(gr_line
		(start 312.94832 -393.842494)
		(end 312.94832 -393.716764)
		(stroke
			(width 0.07112)
			(type default)
		)
		(layer "In13.Cu")
	)
	(gr_line
		(start 313.274456 -418.07638)
		(end 313.274456 -417.37534)
		(stroke
			(width 0.07112)
			(type default)
		)
		(layer "In13.Cu")
	)
	(gr_line
		(start 313.274456 -416.94862)
		(end 313.274456 -416.24758)
		(stroke
			(width 0.07112)
			(type default)
		)
		(layer "In13.Cu")
	)
	(gr_line
		(start 313.42203 -423.323258)
		(end 313.254898 -423.418508)
		(stroke
			(width 0.07112)
			(type default)
		)
		(layer "In13.Cu")
	)
	(gr_line
		(start 313.511438 -409.476702)
		(end 314.150502 -409.18765)
		(stroke
			(width 0.07112)
			(type default)
		)
		(layer "In13.Cu")
	)
	(gr_line
		(start 313.557666 -418.07511)
		(end 313.693556 -417.93922)
		(stroke
			(width 0.07112)
			(type default)
		)
		(layer "In13.Cu")
	)
	(gr_line
		(start 313.557666 -416.94735)
		(end 313.693556 -416.81146)
		(stroke
			(width 0.07112)
			(type default)
		)
		(layer "In13.Cu")
	)
	(gr_line
		(start 313.62904 -409.734258)
		(end 313.809126 -409.80233)
		(stroke
			(width 0.07112)
			(type default)
		)
		(layer "In13.Cu")
	)
	(gr_line
		(start 313.693556 -417.93922)
		(end 313.693556 -417.5125)
		(stroke
			(width 0.07112)
			(type default)
		)
		(layer "In13.Cu")
	)
	(gr_line
		(start 313.693556 -417.5125)
		(end 313.557666 -417.37661)
		(stroke
			(width 0.07112)
			(type default)
		)
		(layer "In13.Cu")
	)
	(gr_line
		(start 313.693556 -416.81146)
		(end 313.693556 -416.38474)
		(stroke
			(width 0.07112)
			(type default)
		)
		(layer "In13.Cu")
	)
	(gr_line
		(start 313.693556 -416.38474)
		(end 313.557666 -416.24885)
		(stroke
			(width 0.07112)
			(type default)
		)
		(layer "In13.Cu")
	)
	(gr_line
		(start 313.725814 -410.958284)
		(end 314.374022 -410.690314)
		(stroke
			(width 0.07112)
			(type default)
		)
		(layer "In13.Cu")
	)
	(gr_line
		(start 313.809126 -409.80233)
		(end 314.198 -409.626562)
		(stroke
			(width 0.07112)
			(type default)
		)
		(layer "In13.Cu")
	)
	(gr_line
		(start 313.833764 -423.436288)
		(end 313.42203 -423.323258)
		(stroke
			(width 0.07112)
			(type default)
		)
		(layer "In13.Cu")
	)
	(gr_line
		(start 313.835034 -411.21965)
		(end 314.012834 -411.29331)
		(stroke
			(width 0.07112)
			(type default)
		)
		(layer "In13.Cu")
	)
	(gr_line
		(start 313.855354 -423.876978)
		(end 313.178952 -423.691558)
		(stroke
			(width 0.07112)
			(type default)
		)
		(layer "In13.Cu")
	)
	(gr_line
		(start 313.929014 -423.60342)
		(end 313.833764 -423.436288)
		(stroke
			(width 0.07112)
			(type default)
		)
		(layer "In13.Cu")
	)
	(gr_line
		(start 314.012834 -411.29331)
		(end 314.407296 -411.130242)
		(stroke
			(width 0.07112)
			(type default)
		)
		(layer "In13.Cu")
	)
	(gr_line
		(start 314.198 -409.626562)
		(end 314.266072 -409.446476)
		(stroke
			(width 0.07112)
			(type default)
		)
		(layer "In13.Cu")
	)
	(gr_line
		(start 314.407296 -411.130242)
		(end 314.48121 -410.952442)
		(stroke
			(width 0.07112)
			(type default)
		)
		(layer "In13.Cu")
	)
	(gr_line
		(start 314.539122 -409.012136)
		(end 315.178186 -408.723084)
		(stroke
			(width 0.07112)
			(type default)
		)
		(layer "In13.Cu")
	)
	(gr_line
		(start 314.649612 -434.48986)
		(end 314.649612 -434.157882)
		(stroke
			(width 0.07112)
			(type default)
		)
		(layer "In13.Cu")
	)
	(gr_line
		(start 314.649612 -434.157882)
		(end 314.522612 -434.030882)
		(stroke
			(width 0.07112)
			(type default)
		)
		(layer "In13.Cu")
	)
	(gr_line
		(start 314.649612 -433.621942)
		(end 314.522612 -433.748942)
		(stroke
			(width 0.07112)
			(type default)
		)
		(layer "In13.Cu")
	)
	(gr_line
		(start 314.649612 -433.289964)
		(end 314.649612 -433.621942)
		(stroke
			(width 0.07112)
			(type default)
		)
		(layer "In13.Cu")
	)
	(gr_line
		(start 314.656724 -409.269692)
		(end 314.83681 -409.33751)
		(stroke
			(width 0.07112)
			(type default)
		)
		(layer "In13.Cu")
	)
	(gr_line
		(start 314.703206 -422.635172)
		(end 314.525152 -422.708832)
		(stroke
			(width 0.07112)
			(type default)
		)
		(layer "In13.Cu")
	)
	(gr_line
		(start 314.83681 -409.33751)
		(end 315.225938 -409.161742)
		(stroke
			(width 0.07112)
			(type default)
		)
		(layer "In13.Cu")
	)
	(gr_line
		(start 315.06414 -423.238676)
		(end 314.415932 -422.970198)
		(stroke
			(width 0.07112)
			(type default)
		)
		(layer "In13.Cu")
	)
	(gr_line
		(start 315.097668 -422.798494)
		(end 314.703206 -422.635172)
		(stroke
			(width 0.07112)
			(type default)
		)
		(layer "In13.Cu")
	)
	(gr_line
		(start 315.171074 -422.976548)
		(end 315.097668 -422.798494)
		(stroke
			(width 0.07112)
			(type default)
		)
		(layer "In13.Cu")
	)
	(gr_line
		(start 315.178186 -408.723084)
		(end 315.189362 -408.718258)
		(stroke
			(width 0.07112)
			(type default)
		)
		(layer "In13.Cu")
	)
	(gr_line
		(start 315.225938 -409.161742)
		(end 315.293756 -408.98191)
		(stroke
			(width 0.07112)
			(type default)
		)
		(layer "In13.Cu")
	)
	(gr_line
		(start 315.294264 -408.980132)
		(end 315.30544 -408.975052)
		(stroke
			(width 0.07112)
			(type default)
		)
		(layer "In13.Cu")
	)
	(gr_line
		(start 315.745368 -423.066972)
		(end 315.567314 -423.140632)
		(stroke
			(width 0.07112)
			(type default)
		)
		(layer "In13.Cu")
	)
	(gr_line
		(start 315.953648 -425.172632)
		(end 315.93663 -425.131738)
		(stroke
			(width 0.07112)
			(type default)
		)
		(layer "In13.Cu")
	)
	(gr_line
		(start 315.95822 -425.239942)
		(end 315.95822 -425.196)
		(stroke
			(width 0.07112)
			(type default)
		)
		(layer "In13.Cu")
	)
	(gr_line
		(start 315.95822 -425.196)
		(end 315.953648 -425.172632)
		(stroke
			(width 0.07112)
			(type default)
		)
		(layer "In13.Cu")
	)
	(gr_line
		(start 316.106048 -423.670222)
		(end 315.458094 -423.401744)
		(stroke
			(width 0.07112)
			(type default)
		)
		(layer "In13.Cu")
	)
	(gr_line
		(start 316.13983 -423.230294)
		(end 315.745368 -423.066972)
		(stroke
			(width 0.07112)
			(type default)
		)
		(layer "In13.Cu")
	)
	(gr_line
		(start 316.172596 -411.02788)
		(end 316.82309 -410.766006)
		(stroke
			(width 0.07112)
			(type default)
		)
		(layer "In13.Cu")
	)
	(gr_line
		(start 316.21349 -423.408094)
		(end 316.13983 -423.230294)
		(stroke
			(width 0.07112)
			(type default)
		)
		(layer "In13.Cu")
	)
	(gr_line
		(start 316.279276 -411.290262)
		(end 316.456314 -411.3657)
		(stroke
			(width 0.07112)
			(type default)
		)
		(layer "In13.Cu")
	)
	(gr_line
		(start 316.337696 -417.961318)
		(end 316.337696 -417.260278)
		(stroke
			(width 0.07112)
			(type default)
		)
		(layer "In13.Cu")
	)
	(gr_line
		(start 316.337696 -416.833558)
		(end 316.337696 -416.132518)
		(stroke
			(width 0.07112)
			(type default)
		)
		(layer "In13.Cu")
	)
	(gr_line
		(start 316.456314 -411.3657)
		(end 316.852554 -411.206442)
		(stroke
			(width 0.07112)
			(type default)
		)
		(layer "In13.Cu")
	)
	(gr_line
		(start 316.494922 -434.74894)
		(end 316.484254 -434.74894)
		(stroke
			(width 0.07112)
			(type default)
		)
		(layer "In13.Cu")
	)
	(gr_line
		(start 316.54877 -422.220644)
		(end 316.37097 -422.294304)
		(stroke
			(width 0.07112)
			(type default)
		)
		(layer "In13.Cu")
	)
	(gr_line
		(start 316.620906 -417.960048)
		(end 316.756796 -417.824158)
		(stroke
			(width 0.07112)
			(type default)
		)
		(layer "In13.Cu")
	)
	(gr_line
		(start 316.620906 -416.832288)
		(end 316.756796 -416.696398)
		(stroke
			(width 0.07112)
			(type default)
		)
		(layer "In13.Cu")
	)
	(gr_line
		(start 316.649608 -435.489858)
		(end 316.649608 -435.196234)
		(stroke
			(width 0.07112)
			(type default)
		)
		(layer "In13.Cu")
	)
	(gr_line
		(start 316.649608 -435.196234)
		(end 316.485524 -435.03215)
		(stroke
			(width 0.07112)
			(type default)
		)
		(layer "In13.Cu")
	)
	(gr_line
		(start 316.649608 -434.594254)
		(end 316.494922 -434.74894)
		(stroke
			(width 0.07112)
			(type default)
		)
		(layer "In13.Cu")
	)
	(gr_line
		(start 316.649608 -434.289962)
		(end 316.649608 -434.594254)
		(stroke
			(width 0.07112)
			(type default)
		)
		(layer "In13.Cu")
	)
	(gr_line
		(start 316.73419 7.481824)
		(end 316.44336 7.190994)
		(stroke
			(width 0.07112)
			(type default)
		)
		(layer "In13.Cu")
	)
	(gr_line
		(start 316.73419 7.763764)
		(end 316.44336 8.054594)
		(stroke
			(width 0.07112)
			(type default)
		)
		(layer "In13.Cu")
	)
	(gr_line
		(start 316.756796 -417.824158)
		(end 316.756796 -417.397438)
		(stroke
			(width 0.07112)
			(type default)
		)
		(layer "In13.Cu")
	)
	(gr_line
		(start 316.756796 -417.397438)
		(end 316.620906 -417.261548)
		(stroke
			(width 0.07112)
			(type default)
		)
		(layer "In13.Cu")
	)
	(gr_line
		(start 316.756796 -416.696398)
		(end 316.756796 -416.269678)
		(stroke
			(width 0.07112)
			(type default)
		)
		(layer "In13.Cu")
	)
	(gr_line
		(start 316.756796 -416.269678)
		(end 316.620906 -416.133788)
		(stroke
			(width 0.07112)
			(type default)
		)
		(layer "In13.Cu")
	)
	(gr_line
		(start 316.852554 -411.206442)
		(end 316.927738 -411.029404)
		(stroke
			(width 0.07112)
			(type default)
		)
		(layer "In13.Cu")
	)
	(gr_line
		(start 316.909704 -422.823894)
		(end 316.26175 -422.55567)
		(stroke
			(width 0.07112)
			(type default)
		)
		(layer "In13.Cu")
	)
	(gr_line
		(start 316.943232 -422.383966)
		(end 316.54877 -422.220644)
		(stroke
			(width 0.07112)
			(type default)
		)
		(layer "In13.Cu")
	)
	(gr_line
		(start 317.016638 -422.561766)
		(end 316.943232 -422.383966)
		(stroke
			(width 0.07112)
			(type default)
		)
		(layer "In13.Cu")
	)
	(gr_line
		(start 317.127636 -422.914318)
		(end 316.909704 -422.823894)
		(stroke
			(width 0.07112)
			(type default)
		)
		(layer "In13.Cu")
	)
	(gr_line
		(start 318.103758 -423.024046)
		(end 317.915036 -423.061638)
		(stroke
			(width 0.07112)
			(type default)
		)
		(layer "In13.Cu")
	)
	(gr_line
		(start 318.339978 -423.68597)
		(end 317.756794 -423.296334)
		(stroke
			(width 0.07112)
			(type default)
		)
		(layer "In13.Cu")
	)
	(gr_line
		(start 318.45885 -423.261282)
		(end 318.103758 -423.024046)
		(stroke
			(width 0.07112)
			(type default)
		)
		(layer "In13.Cu")
	)
	(gr_line
		(start 318.496442 -423.450004)
		(end 318.45885 -423.261282)
		(stroke
			(width 0.07112)
			(type default)
		)
		(layer "In13.Cu")
	)
	(gr_line
		(start 318.649604 -434.48986)
		(end 318.649604 -434.157882)
		(stroke
			(width 0.07112)
			(type default)
		)
		(layer "In13.Cu")
	)
	(gr_line
		(start 318.649604 -434.157882)
		(end 318.522604 -434.030882)
		(stroke
			(width 0.07112)
			(type default)
		)
		(layer "In13.Cu")
	)
	(gr_line
		(start 318.649604 -433.621942)
		(end 318.522604 -433.748942)
		(stroke
			(width 0.07112)
			(type default)
		)
		(layer "In13.Cu")
	)
	(gr_line
		(start 318.649604 -433.289964)
		(end 318.649604 -433.621942)
		(stroke
			(width 0.07112)
			(type default)
		)
		(layer "In13.Cu")
	)
	(gr_line
		(start 318.941196 -410.995368)
		(end 319.595246 -410.741368)
		(stroke
			(width 0.07112)
			(type default)
		)
		(layer "In13.Cu")
	)
	(gr_line
		(start 319.04432 -411.25902)
		(end 319.220596 -411.336744)
		(stroke
			(width 0.07112)
			(type default)
		)
		(layer "In13.Cu")
	)
	(gr_line
		(start 319.220596 -411.336744)
		(end 319.618868 -411.182312)
		(stroke
			(width 0.07112)
			(type default)
		)
		(layer "In13.Cu")
	)
	(gr_line
		(start 319.400936 -417.879784)
		(end 319.400936 -417.178744)
		(stroke
			(width 0.07112)
			(type default)
		)
		(layer "In13.Cu")
	)
	(gr_line
		(start 319.400936 -416.70859)
		(end 319.400936 -416.00755)
		(stroke
			(width 0.07112)
			(type default)
		)
		(layer "In13.Cu")
	)
	(gr_line
		(start 319.618868 -411.182312)
		(end 319.696592 -411.006036)
		(stroke
			(width 0.07112)
			(type default)
		)
		(layer "In13.Cu")
	)
	(gr_line
		(start 319.684146 -417.878514)
		(end 319.820036 -417.742624)
		(stroke
			(width 0.07112)
			(type default)
		)
		(layer "In13.Cu")
	)
	(gr_line
		(start 319.684146 -416.70732)
		(end 319.820036 -416.57143)
		(stroke
			(width 0.07112)
			(type default)
		)
		(layer "In13.Cu")
	)
	(gr_line
		(start 319.820036 -417.742624)
		(end 319.820036 -417.315904)
		(stroke
			(width 0.07112)
			(type default)
		)
		(layer "In13.Cu")
	)
	(gr_line
		(start 319.820036 -417.315904)
		(end 319.684146 -417.180014)
		(stroke
			(width 0.07112)
			(type default)
		)
		(layer "In13.Cu")
	)
	(gr_line
		(start 319.820036 -416.57143)
		(end 319.820036 -416.14471)
		(stroke
			(width 0.07112)
			(type default)
		)
		(layer "In13.Cu")
	)
	(gr_line
		(start 319.820036 -416.14471)
		(end 319.684146 -416.00882)
		(stroke
			(width 0.07112)
			(type default)
		)
		(layer "In13.Cu")
	)
	(gr_line
		(start 319.992756 -410.58719)
		(end 320.646806 -410.333444)
		(stroke
			(width 0.07112)
			(type default)
		)
		(layer "In13.Cu")
	)
	(gr_line
		(start 320.096134 -410.850842)
		(end 320.272156 -410.928566)
		(stroke
			(width 0.07112)
			(type default)
		)
		(layer "In13.Cu")
	)
	(gr_line
		(start 320.255392 -422.921938)
		(end 320.06667 -422.95953)
		(stroke
			(width 0.07112)
			(type default)
		)
		(layer "In13.Cu")
	)
	(gr_line
		(start 320.272156 -410.928566)
		(end 320.670428 -410.774134)
		(stroke
			(width 0.07112)
			(type default)
		)
		(layer "In13.Cu")
	)
	(gr_line
		(start 320.491104 -423.584116)
		(end 319.908428 -423.194226)
		(stroke
			(width 0.07112)
			(type default)
		)
		(layer "In13.Cu")
	)
	(gr_line
		(start 320.61023 -423.159428)
		(end 320.255392 -422.921938)
		(stroke
			(width 0.07112)
			(type default)
		)
		(layer "In13.Cu")
	)
	(gr_line
		(start 320.647822 -423.34815)
		(end 320.61023 -423.159428)
		(stroke
			(width 0.07112)
			(type default)
		)
		(layer "In13.Cu")
	)
	(gr_line
		(start 320.6496 -435.489858)
		(end 320.6496 -435.15788)
		(stroke
			(width 0.07112)
			(type default)
		)
		(layer "In13.Cu")
	)
	(gr_line
		(start 320.6496 -435.15788)
		(end 320.5226 -435.03088)
		(stroke
			(width 0.07112)
			(type default)
		)
		(layer "In13.Cu")
	)
	(gr_line
		(start 320.6496 -434.62194)
		(end 320.5226 -434.74894)
		(stroke
			(width 0.07112)
			(type default)
		)
		(layer "In13.Cu")
	)
	(gr_line
		(start 320.6496 -434.289962)
		(end 320.6496 -434.62194)
		(stroke
			(width 0.07112)
			(type default)
		)
		(layer "In13.Cu")
	)
	(gr_line
		(start 320.670428 -410.774134)
		(end 320.747898 -410.597858)
		(stroke
			(width 0.07112)
			(type default)
		)
		(layer "In13.Cu")
	)
	(gr_line
		(start 320.797428 -406.381712)
		(end 320.797428 -406.381966)
		(stroke
			(width 0.07112)
			(type default)
		)
		(layer "In13.Cu")
	)
	(gr_line
		(start 321.044316 -410.179012)
		(end 321.698366 -409.925266)
		(stroke
			(width 0.07112)
			(type default)
		)
		(layer "In13.Cu")
	)
	(gr_line
		(start 321.147694 -410.442664)
		(end 321.323716 -410.520388)
		(stroke
			(width 0.07112)
			(type default)
		)
		(layer "In13.Cu")
	)
	(gr_line
		(start 321.323716 -410.520388)
		(end 321.721988 -410.365956)
		(stroke
			(width 0.07112)
			(type default)
		)
		(layer "In13.Cu")
	)
	(gr_line
		(start 321.721988 -410.365956)
		(end 321.799458 -410.18968)
		(stroke
			(width 0.07112)
			(type default)
		)
		(layer "In13.Cu")
	)
	(gr_line
		(start 322.095876 -409.770834)
		(end 322.749926 -409.517088)
		(stroke
			(width 0.07112)
			(type default)
		)
		(layer "In13.Cu")
	)
	(gr_line
		(start 322.199254 -410.034486)
		(end 322.375276 -410.11221)
		(stroke
			(width 0.07112)
			(type default)
		)
		(layer "In13.Cu")
	)
	(gr_line
		(start 322.375276 -410.11221)
		(end 322.773548 -409.957778)
		(stroke
			(width 0.07112)
			(type default)
		)
		(layer "In13.Cu")
	)
	(gr_line
		(start 322.464176 -417.698174)
		(end 322.464176 -416.997134)
		(stroke
			(width 0.07112)
			(type default)
		)
		(layer "In13.Cu")
	)
	(gr_line
		(start 322.464176 -416.570414)
		(end 322.464176 -415.869374)
		(stroke
			(width 0.07112)
			(type default)
		)
		(layer "In13.Cu")
	)
	(gr_line
		(start 322.649596 -434.48986)
		(end 322.649596 -434.157882)
		(stroke
			(width 0.07112)
			(type default)
		)
		(layer "In13.Cu")
	)
	(gr_line
		(start 322.649596 -434.157882)
		(end 322.522596 -434.030882)
		(stroke
			(width 0.07112)
			(type default)
		)
		(layer "In13.Cu")
	)
	(gr_line
		(start 322.649596 -433.621942)
		(end 322.522596 -433.748942)
		(stroke
			(width 0.07112)
			(type default)
		)
		(layer "In13.Cu")
	)
	(gr_line
		(start 322.649596 -433.289964)
		(end 322.649596 -433.621942)
		(stroke
			(width 0.07112)
			(type default)
		)
		(layer "In13.Cu")
	)
	(gr_line
		(start 322.747386 -417.696904)
		(end 322.883276 -417.561014)
		(stroke
			(width 0.07112)
			(type default)
		)
		(layer "In13.Cu")
	)
	(gr_line
		(start 322.747386 -416.569144)
		(end 322.883276 -416.433254)
		(stroke
			(width 0.07112)
			(type default)
		)
		(layer "In13.Cu")
	)
	(gr_line
		(start 322.773548 -409.957778)
		(end 322.851018 -409.781502)
		(stroke
			(width 0.07112)
			(type default)
		)
		(layer "In13.Cu")
	)
	(gr_line
		(start 322.876164 -410.745432)
		(end 323.520816 -410.469334)
		(stroke
			(width 0.07112)
			(type default)
		)
		(layer "In13.Cu")
	)
	(gr_line
		(start 322.883276 -417.561014)
		(end 322.883276 -417.134294)
		(stroke
			(width 0.07112)
			(type default)
		)
		(layer "In13.Cu")
	)
	(gr_line
		(start 322.883276 -417.134294)
		(end 322.747386 -416.998404)
		(stroke
			(width 0.07112)
			(type default)
		)
		(layer "In13.Cu")
	)
	(gr_line
		(start 322.883276 -416.433254)
		(end 322.883276 -416.006534)
		(stroke
			(width 0.07112)
			(type default)
		)
		(layer "In13.Cu")
	)
	(gr_line
		(start 322.883276 -416.006534)
		(end 322.747386 -415.870644)
		(stroke
			(width 0.07112)
			(type default)
		)
		(layer "In13.Cu")
	)
	(gr_line
		(start 322.988432 -411.005528)
		(end 323.167248 -411.076902)
		(stroke
			(width 0.07112)
			(type default)
		)
		(layer "In13.Cu")
	)
	(gr_line
		(start 323.101716 -423.546524)
		(end 322.9102 -423.527728)
		(stroke
			(width 0.07112)
			(type default)
		)
		(layer "In13.Cu")
	)
	(gr_line
		(start 323.134736 -407.066242)
		(end 323.782944 -406.798018)
		(stroke
			(width 0.07112)
			(type default)
		)
		(layer "In13.Cu")
	)
	(gr_line
		(start 323.135498 -424.24858)
		(end 322.69049 -423.706544)
		(stroke
			(width 0.07112)
			(type default)
		)
		(layer "In13.Cu")
	)
	(gr_line
		(start 323.147436 -409.362656)
		(end 323.801486 -409.10891)
		(stroke
			(width 0.07112)
			(type default)
		)
		(layer "In13.Cu")
	)
	(gr_line
		(start 323.167248 -411.076902)
		(end 323.559678 -410.909008)
		(stroke
			(width 0.07112)
			(type default)
		)
		(layer "In13.Cu")
	)
	(gr_line
		(start 323.243702 -407.327608)
		(end 323.421756 -407.401522)
		(stroke
			(width 0.07112)
			(type default)
		)
		(layer "In13.Cu")
	)
	(gr_line
		(start 323.250814 -409.626308)
		(end 323.426836 -409.704032)
		(stroke
			(width 0.07112)
			(type default)
		)
		(layer "In13.Cu")
	)
	(gr_line
		(start 323.353938 -424.06824)
		(end 323.372734 -423.87647)
		(stroke
			(width 0.07112)
			(type default)
		)
		(layer "In13.Cu")
	)
	(gr_line
		(start 323.372734 -423.87647)
		(end 323.101716 -423.546524)
		(stroke
			(width 0.07112)
			(type default)
		)
		(layer "In13.Cu")
	)
	(gr_line
		(start 323.380354 -408.126184)
		(end 324.031102 -407.864056)
		(stroke
			(width 0.07112)
			(type default)
		)
		(layer "In13.Cu")
	)
	(gr_line
		(start 323.421756 -407.401522)
		(end 323.816472 -407.238454)
		(stroke
			(width 0.07112)
			(type default)
		)
		(layer "In13.Cu")
	)
	(gr_line
		(start 323.426836 -409.704032)
		(end 323.825108 -409.5496)
		(stroke
			(width 0.07112)
			(type default)
		)
		(layer "In13.Cu")
	)
	(gr_line
		(start 323.487034 -408.388312)
		(end 323.664072 -408.46375)
		(stroke
			(width 0.07112)
			(type default)
		)
		(layer "In13.Cu")
	)
	(gr_line
		(start 323.559678 -410.909008)
		(end 323.631306 -410.729938)
		(stroke
			(width 0.07112)
			(type default)
		)
		(layer "In13.Cu")
	)
	(gr_line
		(start 323.664072 -408.46375)
		(end 324.060312 -408.304492)
		(stroke
			(width 0.07112)
			(type default)
		)
		(layer "In13.Cu")
	)
	(gr_line
		(start 323.816472 -407.238454)
		(end 323.890386 -407.060146)
		(stroke
			(width 0.07112)
			(type default)
		)
		(layer "In13.Cu")
	)
	(gr_line
		(start 323.825108 -409.5496)
		(end 323.902578 -409.373324)
		(stroke
			(width 0.07112)
			(type default)
		)
		(layer "In13.Cu")
	)
	(gr_line
		(start 323.912992 -410.301186)
		(end 324.557644 -410.025088)
		(stroke
			(width 0.07112)
			(type default)
		)
		(layer "In13.Cu")
	)
	(gr_line
		(start 324.02526 -410.561282)
		(end 324.204076 -410.632656)
		(stroke
			(width 0.07112)
			(type default)
		)
		(layer "In13.Cu")
	)
	(gr_line
		(start 324.031102 -407.864056)
		(end 324.06844 -407.84907)
		(stroke
			(width 0.07112)
			(type default)
		)
		(layer "In13.Cu")
	)
	(gr_line
		(start 324.060312 -408.304492)
		(end 324.135496 -408.127454)
		(stroke
			(width 0.07112)
			(type default)
		)
		(layer "In13.Cu")
	)
	(gr_line
		(start 324.136258 -408.125676)
		(end 324.17385 -408.11069)
		(stroke
			(width 0.07112)
			(type default)
		)
		(layer "In13.Cu")
	)
	(gr_line
		(start 324.19925 -408.954478)
		(end 324.852792 -408.700732)
		(stroke
			(width 0.07112)
			(type default)
		)
		(layer "In13.Cu")
	)
	(gr_line
		(start 324.204076 -410.632656)
		(end 324.596506 -410.464762)
		(stroke
			(width 0.07112)
			(type default)
		)
		(layer "In13.Cu")
	)
	(gr_line
		(start 324.302374 -409.21813)
		(end 324.478396 -409.295854)
		(stroke
			(width 0.07112)
			(type default)
		)
		(layer "In13.Cu")
	)
	(gr_line
		(start 324.426834 -407.704798)
		(end 325.077074 -407.442924)
		(stroke
			(width 0.07112)
			(type default)
		)
		(layer "In13.Cu")
	)
	(gr_line
		(start 324.450964 -406.52192)
		(end 325.099172 -406.253696)
		(stroke
			(width 0.07112)
			(type default)
		)
		(layer "In13.Cu")
	)
	(gr_line
		(start 324.478396 -409.295854)
		(end 324.876668 -409.141422)
		(stroke
			(width 0.07112)
			(type default)
		)
		(layer "In13.Cu")
	)
	(gr_line
		(start 324.533514 -407.96718)
		(end 324.710298 -408.042618)
		(stroke
			(width 0.07112)
			(type default)
		)
		(layer "In13.Cu")
	)
	(gr_line
		(start 324.55993 -406.783286)
		(end 324.737984 -406.8572)
		(stroke
			(width 0.07112)
			(type default)
		)
		(layer "In13.Cu")
	)
	(gr_line
		(start 324.596506 -410.464762)
		(end 324.668134 -410.285692)
		(stroke
			(width 0.07112)
			(type default)
		)
		(layer "In13.Cu")
	)
	(gr_line
		(start 324.649592 -435.489858)
		(end 324.649592 -435.15788)
		(stroke
			(width 0.07112)
			(type default)
		)
		(layer "In13.Cu")
	)
	(gr_line
		(start 324.649592 -435.15788)
		(end 324.522592 -435.03088)
		(stroke
			(width 0.07112)
			(type default)
		)
		(layer "In13.Cu")
	)
	(gr_line
		(start 324.649592 -434.62194)
		(end 324.522592 -434.74894)
		(stroke
			(width 0.07112)
			(type default)
		)
		(layer "In13.Cu")
	)
	(gr_line
		(start 324.649592 -434.289962)
		(end 324.649592 -434.62194)
		(stroke
			(width 0.07112)
			(type default)
		)
		(layer "In13.Cu")
	)
	(gr_line
		(start 324.710298 -408.042618)
		(end 325.106538 -407.883106)
		(stroke
			(width 0.07112)
			(type default)
		)
		(layer "In13.Cu")
	)
	(gr_line
		(start 324.737984 -406.8572)
		(end 325.1327 -406.693878)
		(stroke
			(width 0.07112)
			(type default)
		)
		(layer "In13.Cu")
	)
	(gr_line
		(start 324.803262 -423.238422)
		(end 324.472808 -422.619678)
		(stroke
			(width 0.07112)
			(type default)
		)
		(layer "In13.Cu")
	)
	(gr_line
		(start 324.876668 -409.141422)
		(end 324.954138 -408.965146)
		(stroke
			(width 0.07112)
			(type default)
		)
		(layer "In13.Cu")
	)
	(gr_line
		(start 324.907148 -422.543224)
		(end 324.722998 -422.487344)
		(stroke
			(width 0.07112)
			(type default)
		)
		(layer "In13.Cu")
	)
	(gr_line
		(start 324.94982 -409.85694)
		(end 325.594472 -409.580842)
		(stroke
			(width 0.07112)
			(type default)
		)
		(layer "In13.Cu")
	)
	(gr_line
		(start 325.052436 -423.104056)
		(end 325.108316 -422.919906)
		(stroke
			(width 0.07112)
			(type default)
		)
		(layer "In13.Cu")
	)
	(gr_line
		(start 325.062088 -410.117036)
		(end 325.240904 -410.18841)
		(stroke
			(width 0.07112)
			(type default)
		)
		(layer "In13.Cu")
	)
	(gr_line
		(start 325.106538 -407.883106)
		(end 325.181722 -407.706068)
		(stroke
			(width 0.07112)
			(type default)
		)
		(layer "In13.Cu")
	)
	(gr_line
		(start 325.108316 -422.919906)
		(end 324.907148 -422.543224)
		(stroke
			(width 0.07112)
			(type default)
		)
		(layer "In13.Cu")
	)
	(gr_line
		(start 325.1327 -406.693878)
		(end 325.206614 -406.51557)
		(stroke
			(width 0.07112)
			(type default)
		)
		(layer "In13.Cu")
	)
	(gr_line
		(start 325.240904 -410.18841)
		(end 325.633334 -410.020516)
		(stroke
			(width 0.07112)
			(type default)
		)
		(layer "In13.Cu")
	)
	(gr_line
		(start 325.479918 -424.622214)
		(end 325.180198 -423.987976)
		(stroke
			(width 0.07112)
			(type default)
		)
		(layer "In13.Cu")
	)
	(gr_line
		(start 325.525384 -406.07742)
		(end 326.173338 -405.809196)
		(stroke
			(width 0.07112)
			(type default)
		)
		(layer "In13.Cu")
	)
	(gr_line
		(start 325.527416 -417.826698)
		(end 325.527416 -417.125658)
		(stroke
			(width 0.07112)
			(type default)
		)
		(layer "In13.Cu")
	)
	(gr_line
		(start 325.527416 -416.698938)
		(end 325.527416 -415.997898)
		(stroke
			(width 0.07112)
			(type default)
		)
		(layer "In13.Cu")
	)
	(gr_line
		(start 325.618094 -423.932858)
		(end 325.436738 -423.867834)
		(stroke
			(width 0.07112)
			(type default)
		)
		(layer "In13.Cu")
	)
	(gr_line
		(start 325.633334 -410.020516)
		(end 325.704962 -409.841446)
		(stroke
			(width 0.07112)
			(type default)
		)
		(layer "In13.Cu")
	)
	(gr_line
		(start 325.63435 -406.338786)
		(end 325.812404 -406.412446)
		(stroke
			(width 0.07112)
			(type default)
		)
		(layer "In13.Cu")
	)
	(gr_line
		(start 325.735442 -424.50004)
		(end 325.800466 -424.318938)
		(stroke
			(width 0.07112)
			(type default)
		)
		(layer "In13.Cu")
	)
	(gr_line
		(start 325.800466 -424.318938)
		(end 325.618094 -423.932858)
		(stroke
			(width 0.07112)
			(type default)
		)
		(layer "In13.Cu")
	)
	(gr_line
		(start 325.810626 -417.825428)
		(end 325.946516 -417.689538)
		(stroke
			(width 0.07112)
			(type default)
		)
		(layer "In13.Cu")
	)
	(gr_line
		(start 325.810626 -416.697668)
		(end 325.946516 -416.561778)
		(stroke
			(width 0.07112)
			(type default)
		)
		(layer "In13.Cu")
	)
	(gr_line
		(start 325.812404 -406.412446)
		(end 326.206866 -406.249378)
		(stroke
			(width 0.07112)
			(type default)
		)
		(layer "In13.Cu")
	)
	(gr_line
		(start 325.946516 -417.689538)
		(end 325.946516 -417.262818)
		(stroke
			(width 0.07112)
			(type default)
		)
		(layer "In13.Cu")
	)
	(gr_line
		(start 325.946516 -417.262818)
		(end 325.810626 -417.126928)
		(stroke
			(width 0.07112)
			(type default)
		)
		(layer "In13.Cu")
	)
	(gr_line
		(start 325.946516 -416.561778)
		(end 325.946516 -416.135058)
		(stroke
			(width 0.07112)
			(type default)
		)
		(layer "In13.Cu")
	)
	(gr_line
		(start 325.946516 -416.135058)
		(end 325.810626 -415.999168)
		(stroke
			(width 0.07112)
			(type default)
		)
		(layer "In13.Cu")
	)
	(gr_line
		(start 325.986648 -409.412694)
		(end 326.631046 -409.136596)
		(stroke
			(width 0.07112)
			(type default)
		)
		(layer "In13.Cu")
	)
	(gr_line
		(start 325.989442 -407.07564)
		(end 326.640444 -406.813512)
		(stroke
			(width 0.07112)
			(type default)
		)
		(layer "In13.Cu")
	)
	(gr_line
		(start 326.096376 -407.337768)
		(end 326.273414 -407.413206)
		(stroke
			(width 0.07112)
			(type default)
		)
		(layer "In13.Cu")
	)
	(gr_line
		(start 326.098916 -409.67279)
		(end 326.277732 -409.744164)
		(stroke
			(width 0.07112)
			(type default)
		)
		(layer "In13.Cu")
	)
	(gr_line
		(start 326.206866 -406.249378)
		(end 326.28078 -406.071324)
		(stroke
			(width 0.07112)
			(type default)
		)
		(layer "In13.Cu")
	)
	(gr_line
		(start 326.273414 -407.413206)
		(end 326.669654 -407.253948)
		(stroke
			(width 0.07112)
			(type default)
		)
		(layer "In13.Cu")
	)
	(gr_line
		(start 326.277732 -409.744164)
		(end 326.670162 -409.57627)
		(stroke
			(width 0.07112)
			(type default)
		)
		(layer "In13.Cu")
	)
	(gr_line
		(start 326.567546 -405.646128)
		(end 327.215754 -405.378158)
		(stroke
			(width 0.07112)
			(type default)
		)
		(layer "In13.Cu")
	)
	(gr_line
		(start 326.623172 -410.459174)
		(end 327.278746 -410.209238)
		(stroke
			(width 0.07112)
			(type default)
		)
		(layer "In13.Cu")
	)
	(gr_line
		(start 326.649588 -434.48986)
		(end 326.649588 -434.157882)
		(stroke
			(width 0.07112)
			(type default)
		)
		(layer "In13.Cu")
	)
	(gr_line
		(start 326.649588 -434.157882)
		(end 326.522588 -434.030882)
		(stroke
			(width 0.07112)
			(type default)
		)
		(layer "In13.Cu")
	)
	(gr_line
		(start 326.649588 -433.621942)
		(end 326.522588 -433.748942)
		(stroke
			(width 0.07112)
			(type default)
		)
		(layer "In13.Cu")
	)
	(gr_line
		(start 326.649588 -433.289964)
		(end 326.649588 -433.621942)
		(stroke
			(width 0.07112)
			(type default)
		)
		(layer "In13.Cu")
	)
	(gr_line
		(start 326.669654 -407.253948)
		(end 326.744838 -407.076656)
		(stroke
			(width 0.07112)
			(type default)
		)
		(layer "In13.Cu")
	)
	(gr_line
		(start 326.670162 -409.57627)
		(end 326.74179 -409.3972)
		(stroke
			(width 0.07112)
			(type default)
		)
		(layer "In13.Cu")
	)
	(gr_line
		(start 326.676766 -405.907494)
		(end 326.854566 -405.981408)
		(stroke
			(width 0.07112)
			(type default)
		)
		(layer "In13.Cu")
	)
	(gr_line
		(start 326.725026 -410.723334)
		(end 326.90054 -410.802074)
		(stroke
			(width 0.07112)
			(type default)
		)
		(layer "In13.Cu")
	)
	(gr_line
		(start 326.854566 -405.981408)
		(end 327.249282 -405.81834)
		(stroke
			(width 0.07112)
			(type default)
		)
		(layer "In13.Cu")
	)
	(gr_line
		(start 326.90054 -410.802074)
		(end 327.299574 -410.650182)
		(stroke
			(width 0.07112)
			(type default)
		)
		(layer "In13.Cu")
	)
	(gr_line
		(start 327.051924 -368.36604)
		(end 327.052178 -368.36604)
		(stroke
			(width 0.07112)
			(type default)
		)
		(layer "In13.Cu")
	)
	(gr_line
		(start 327.192386 -422.171368)
		(end 327.18375 -422.127934)
		(stroke
			(width 0.07112)
			(type default)
		)
		(layer "In13.Cu")
	)
	(gr_line
		(start 327.249282 -405.81834)
		(end 327.322942 -405.640286)
		(stroke
			(width 0.07112)
			(type default)
		)
		(layer "In13.Cu")
	)
	(gr_line
		(start 327.299574 -410.650182)
		(end 327.378314 -410.474414)
		(stroke
			(width 0.07112)
			(type default)
		)
		(layer "In13.Cu")
	)
	(gr_line
		(start 327.328784 -422.859454)
		(end 327.192386 -422.171368)
		(stroke
			(width 0.07112)
			(type default)
		)
		(layer "In13.Cu")
	)
	(gr_line
		(start 327.468992 -422.116504)
		(end 327.460356 -422.07307)
		(stroke
			(width 0.07112)
			(type default)
		)
		(layer "In13.Cu")
	)
	(gr_line
		(start 327.556876 -424.009312)
		(end 327.420478 -423.32148)
		(stroke
			(width 0.07112)
			(type default)
		)
		(layer "In13.Cu")
	)
	(gr_line
		(start 327.606406 -422.80332)
		(end 327.71334 -422.6433)
		(stroke
			(width 0.07112)
			(type default)
		)
		(layer "In13.Cu")
	)
	(gr_line
		(start 327.630536 -422.224454)
		(end 327.470516 -422.11752)
		(stroke
			(width 0.07112)
			(type default)
		)
		(layer "In13.Cu")
	)
	(gr_line
		(start 327.677272 -410.0576)
		(end 328.332846 -409.807918)
		(stroke
			(width 0.07112)
			(type default)
		)
		(layer "In13.Cu")
	)
	(gr_line
		(start 327.688956 -424.749214)
		(end 327.688702 -424.749468)
		(stroke
			(width 0.07112)
			(type default)
		)
		(layer "In13.Cu")
	)
	(gr_line
		(start 327.71334 -422.6433)
		(end 327.630536 -422.224454)
		(stroke
			(width 0.07112)
			(type default)
		)
		(layer "In13.Cu")
	)
	(gr_line
		(start 327.730358 -406.3746)
		(end 328.380852 -406.112726)
		(stroke
			(width 0.07112)
			(type default)
		)
		(layer "In13.Cu")
	)
	(gr_line
		(start 327.779126 -410.32176)
		(end 327.95464 -410.4005)
		(stroke
			(width 0.07112)
			(type default)
		)
		(layer "In13.Cu")
	)
	(gr_line
		(start 327.834244 -423.953178)
		(end 327.941432 -423.793412)
		(stroke
			(width 0.07112)
			(type default)
		)
		(layer "In13.Cu")
	)
	(gr_line
		(start 327.837038 -406.636982)
		(end 328.014076 -406.71242)
		(stroke
			(width 0.07112)
			(type default)
		)
		(layer "In13.Cu")
	)
	(gr_line
		(start 327.858374 -423.374566)
		(end 327.698354 -423.267632)
		(stroke
			(width 0.07112)
			(type default)
		)
		(layer "In13.Cu")
	)
	(gr_line
		(start 327.941432 -423.793412)
		(end 327.858374 -423.374566)
		(stroke
			(width 0.07112)
			(type default)
		)
		(layer "In13.Cu")
	)
	(gr_line
		(start 327.951338 -424.54957)
		(end 327.951338 -424.550078)
		(stroke
			(width 0.07112)
			(type default)
		)
		(layer "In13.Cu")
	)
	(gr_line
		(start 327.95464 -410.4005)
		(end 328.353674 -410.248608)
		(stroke
			(width 0.07112)
			(type default)
		)
		(layer "In13.Cu")
	)
	(gr_line
		(start 328.014076 -406.71242)
		(end 328.410316 -406.552908)
		(stroke
			(width 0.07112)
			(type default)
		)
		(layer "In13.Cu")
	)
	(gr_line
		(start 328.353674 -410.248608)
		(end 328.432414 -410.07284)
		(stroke
			(width 0.07112)
			(type default)
		)
		(layer "In13.Cu")
	)
	(gr_line
		(start 328.36231 -408.435302)
		(end 329.028044 -408.21483)
		(stroke
			(width 0.07112)
			(type default)
		)
		(layer "In13.Cu")
	)
	(gr_line
		(start 328.387456 -419.378384)
		(end 328.38771 -419.378384)
		(stroke
			(width 0.07112)
			(type default)
		)
		(layer "In13.Cu")
	)
	(gr_line
		(start 328.410316 -406.552908)
		(end 328.4855 -406.37587)
		(stroke
			(width 0.07112)
			(type default)
		)
		(layer "In13.Cu")
	)
	(gr_line
		(start 328.45248 -408.70378)
		(end 328.624438 -408.79014)
		(stroke
			(width 0.07112)
			(type default)
		)
		(layer "In13.Cu")
	)
	(gr_line
		(start 328.49566 -419.638988)
		(end 328.541634 -419.619938)
		(stroke
			(width 0.07112)
			(type default)
		)
		(layer "In13.Cu")
	)
	(gr_arc
		(start 328.541634 -419.619938)
		(mid 328.563529 -419.600458)
		(end 328.584814 -419.580314)
		(stroke
			(width 0.07112)
			(type default)
		)
		(layer "In13.Cu")
	)
	(gr_line
		(start 328.590656 -417.92144)
		(end 328.590656 -417.2204)
		(stroke
			(width 0.07112)
			(type default)
		)
		(layer "In13.Cu")
	)
	(gr_line
		(start 328.590656 -416.79368)
		(end 328.590656 -416.09264)
		(stroke
			(width 0.07112)
			(type default)
		)
		(layer "In13.Cu")
	)
	(gr_line
		(start 328.59472 -411.1371)
		(end 329.239118 -410.861002)
		(stroke
			(width 0.07112)
			(type default)
		)
		(layer "In13.Cu")
	)
	(gr_line
		(start 328.624438 -408.79014)
		(end 329.029822 -408.656028)
		(stroke
			(width 0.07112)
			(type default)
		)
		(layer "In13.Cu")
	)
	(gr_line
		(start 328.649584 -435.489858)
		(end 328.649584 -435.15788)
		(stroke
			(width 0.07112)
			(type default)
		)
		(layer "In13.Cu")
	)
	(gr_line
		(start 328.649584 -435.15788)
		(end 328.522584 -435.03088)
		(stroke
			(width 0.07112)
			(type default)
		)
		(layer "In13.Cu")
	)
	(gr_line
		(start 328.649584 -434.62194)
		(end 328.522584 -434.74894)
		(stroke
			(width 0.07112)
			(type default)
		)
		(layer "In13.Cu")
	)
	(gr_line
		(start 328.649584 -434.289962)
		(end 328.649584 -434.62194)
		(stroke
			(width 0.07112)
			(type default)
		)
		(layer "In13.Cu")
	)
	(gr_line
		(start 328.706734 -411.397196)
		(end 328.885804 -411.46857)
		(stroke
			(width 0.07112)
			(type default)
		)
		(layer "In13.Cu")
	)
	(gr_line
		(start 328.731372 -409.656026)
		(end 329.386946 -409.406344)
		(stroke
			(width 0.07112)
			(type default)
		)
		(layer "In13.Cu")
	)
	(gr_line
		(start 328.833226 -409.920186)
		(end 329.00874 -409.998926)
		(stroke
			(width 0.07112)
			(type default)
		)
		(layer "In13.Cu")
	)
	(gr_line
		(start 328.873866 -417.92017)
		(end 329.009756 -417.78428)
		(stroke
			(width 0.07112)
			(type default)
		)
		(layer "In13.Cu")
	)
	(gr_line
		(start 328.873866 -416.79241)
		(end 329.009756 -416.65652)
		(stroke
			(width 0.07112)
			(type default)
		)
		(layer "In13.Cu")
	)
	(gr_line
		(start 328.885804 -411.46857)
		(end 329.278234 -411.300676)
		(stroke
			(width 0.07112)
			(type default)
		)
		(layer "In13.Cu")
	)
	(gr_line
		(start 329.00874 -409.998926)
		(end 329.407774 -409.847034)
		(stroke
			(width 0.07112)
			(type default)
		)
		(layer "In13.Cu")
	)
	(gr_line
		(start 329.009756 -417.78428)
		(end 329.009756 -417.35756)
		(stroke
			(width 0.07112)
			(type default)
		)
		(layer "In13.Cu")
	)
	(gr_line
		(start 329.009756 -417.35756)
		(end 328.873866 -417.22167)
		(stroke
			(width 0.07112)
			(type default)
		)
		(layer "In13.Cu")
	)
	(gr_line
		(start 329.009756 -416.65652)
		(end 329.009756 -416.2298)
		(stroke
			(width 0.07112)
			(type default)
		)
		(layer "In13.Cu")
	)
	(gr_line
		(start 329.009756 -416.2298)
		(end 328.873866 -416.09391)
		(stroke
			(width 0.07112)
			(type default)
		)
		(layer "In13.Cu")
	)
	(gr_line
		(start 329.029822 -408.656028)
		(end 329.115928 -408.48407)
		(stroke
			(width 0.07112)
			(type default)
		)
		(layer "In13.Cu")
	)
	(gr_line
		(start 329.278234 -411.300676)
		(end 329.349354 -411.12186)
		(stroke
			(width 0.07112)
			(type default)
		)
		(layer "In13.Cu")
	)
	(gr_line
		(start 329.407774 -409.847034)
		(end 329.486514 -409.671266)
		(stroke
			(width 0.07112)
			(type default)
		)
		(layer "In13.Cu")
	)
	(gr_line
		(start 329.43292 -408.080718)
		(end 330.098654 -407.860246)
		(stroke
			(width 0.07112)
			(type default)
		)
		(layer "In13.Cu")
	)
	(gr_line
		(start 329.52309 -408.349196)
		(end 329.695048 -408.435556)
		(stroke
			(width 0.07112)
			(type default)
		)
		(layer "In13.Cu")
	)
	(gr_line
		(start 329.631294 -410.692854)
		(end 330.275946 -410.416502)
		(stroke
			(width 0.07112)
			(type default)
		)
		(layer "In13.Cu")
	)
	(gr_line
		(start 329.695048 -408.435556)
		(end 330.100432 -408.301444)
		(stroke
			(width 0.07112)
			(type default)
		)
		(layer "In13.Cu")
	)
	(gr_line
		(start 329.743816 -410.952696)
		(end 329.922378 -411.02407)
		(stroke
			(width 0.07112)
			(type default)
		)
		(layer "In13.Cu")
	)
	(gr_line
		(start 329.785472 -409.254452)
		(end 330.441046 -409.00477)
		(stroke
			(width 0.07112)
			(type default)
		)
		(layer "In13.Cu")
	)
	(gr_line
		(start 329.887326 -409.518612)
		(end 330.06284 -409.597352)
		(stroke
			(width 0.07112)
			(type default)
		)
		(layer "In13.Cu")
	)
	(gr_line
		(start 329.922378 -411.02407)
		(end 330.314808 -410.856176)
		(stroke
			(width 0.07112)
			(type default)
		)
		(layer "In13.Cu")
	)
	(gr_line
		(start 330.06284 -409.597352)
		(end 330.461874 -409.44546)
		(stroke
			(width 0.07112)
			(type default)
		)
		(layer "In13.Cu")
	)
	(gr_line
		(start 330.100432 -408.301444)
		(end 330.186538 -408.129486)
		(stroke
			(width 0.07112)
			(type default)
		)
		(layer "In13.Cu")
	)
	(gr_line
		(start 330.122276 -424.292522)
		(end 330.122276 -423.591482)
		(stroke
			(width 0.07112)
			(type default)
		)
		(layer "In13.Cu")
	)
	(gr_line
		(start 330.122276 -423.164762)
		(end 330.122276 -422.463722)
		(stroke
			(width 0.07112)
			(type default)
		)
		(layer "In13.Cu")
	)
	(gr_line
		(start 330.122276 -422.037002)
		(end 330.122276 -421.335962)
		(stroke
			(width 0.07112)
			(type default)
		)
		(layer "In13.Cu")
	)
	(gr_line
		(start 330.314808 -410.856176)
		(end 330.386436 -410.67736)
		(stroke
			(width 0.07112)
			(type default)
		)
		(layer "In13.Cu")
	)
	(gr_line
		(start 330.405486 -424.291252)
		(end 330.541376 -424.155362)
		(stroke
			(width 0.07112)
			(type default)
		)
		(layer "In13.Cu")
	)
	(gr_line
		(start 330.405486 -423.163492)
		(end 330.541376 -423.027602)
		(stroke
			(width 0.07112)
			(type default)
		)
		(layer "In13.Cu")
	)
	(gr_line
		(start 330.405486 -422.035732)
		(end 330.541376 -421.899842)
		(stroke
			(width 0.07112)
			(type default)
		)
		(layer "In13.Cu")
	)
	(gr_line
		(start 330.461874 -409.44546)
		(end 330.540614 -409.269692)
		(stroke
			(width 0.07112)
			(type default)
		)
		(layer "In13.Cu")
	)
	(gr_line
		(start 330.50353 -407.726134)
		(end 331.169264 -407.505662)
		(stroke
			(width 0.07112)
			(type default)
		)
		(layer "In13.Cu")
	)
	(gr_line
		(start 330.541376 -424.155362)
		(end 330.541376 -423.728642)
		(stroke
			(width 0.07112)
			(type default)
		)
		(layer "In13.Cu")
	)
	(gr_line
		(start 330.541376 -423.728642)
		(end 330.405486 -423.592752)
		(stroke
			(width 0.07112)
			(type default)
		)
		(layer "In13.Cu")
	)
	(gr_line
		(start 330.541376 -423.027602)
		(end 330.541376 -422.600882)
		(stroke
			(width 0.07112)
			(type default)
		)
		(layer "In13.Cu")
	)
	(gr_line
		(start 330.541376 -422.600882)
		(end 330.405486 -422.464992)
		(stroke
			(width 0.07112)
			(type default)
		)
		(layer "In13.Cu")
	)
	(gr_line
		(start 330.541376 -421.899842)
		(end 330.541376 -421.473122)
		(stroke
			(width 0.07112)
			(type default)
		)
		(layer "In13.Cu")
	)
	(gr_line
		(start 330.541376 -421.473122)
		(end 330.405486 -421.337232)
		(stroke
			(width 0.07112)
			(type default)
		)
		(layer "In13.Cu")
	)
	(gr_line
		(start 330.5937 -407.994612)
		(end 330.765658 -408.080972)
		(stroke
			(width 0.07112)
			(type default)
		)
		(layer "In13.Cu")
	)
	(gr_line
		(start 330.668122 -410.248608)
		(end 331.31252 -409.972256)
		(stroke
			(width 0.07112)
			(type default)
		)
		(layer "In13.Cu")
	)
	(gr_line
		(start 330.762356 -405.322278)
		(end 331.439266 -405.14016)
		(stroke
			(width 0.07112)
			(type default)
		)
		(layer "In13.Cu")
	)
	(gr_line
		(start 330.765658 -408.080972)
		(end 331.171042 -407.94686)
		(stroke
			(width 0.07112)
			(type default)
		)
		(layer "In13.Cu")
	)
	(gr_line
		(start 330.78039 -410.50845)
		(end 330.959206 -410.579824)
		(stroke
			(width 0.07112)
			(type default)
		)
		(layer "In13.Cu")
	)
	(gr_line
		(start 330.836524 -405.595582)
		(end 331.003402 -405.691594)
		(stroke
			(width 0.07112)
			(type default)
		)
		(layer "In13.Cu")
	)
	(gr_line
		(start 330.839572 -408.852878)
		(end 331.495146 -408.602942)
		(stroke
			(width 0.07112)
			(type default)
		)
		(layer "In13.Cu")
	)
	(gr_line
		(start 330.941426 -409.117038)
		(end 331.11694 -409.195778)
		(stroke
			(width 0.07112)
			(type default)
		)
		(layer "In13.Cu")
	)
	(gr_line
		(start 330.959206 -410.579824)
		(end 331.351636 -410.41193)
		(stroke
			(width 0.07112)
			(type default)
		)
		(layer "In13.Cu")
	)
	(gr_line
		(start 331.003402 -405.691594)
		(end 331.415898 -405.58085)
		(stroke
			(width 0.07112)
			(type default)
		)
		(layer "In13.Cu")
	)
	(gr_line
		(start 331.11694 -409.195778)
		(end 331.515974 -409.043886)
		(stroke
			(width 0.07112)
			(type default)
		)
		(layer "In13.Cu")
	)
	(gr_line
		(start 331.171042 -407.94686)
		(end 331.257148 -407.774902)
		(stroke
			(width 0.07112)
			(type default)
		)
		(layer "In13.Cu")
	)
	(gr_line
		(start 331.351636 -410.41193)
		(end 331.423264 -410.233114)
		(stroke
			(width 0.07112)
			(type default)
		)
		(layer "In13.Cu")
	)
	(gr_line
		(start 331.415898 -405.58085)
		(end 331.51191 -405.413718)
		(stroke
			(width 0.07112)
			(type default)
		)
		(layer "In13.Cu")
	)
	(gr_line
		(start 331.515974 -409.043886)
		(end 331.594714 -408.868118)
		(stroke
			(width 0.07112)
			(type default)
		)
		(layer "In13.Cu")
	)
	(gr_line
		(start 331.649832 -434.48986)
		(end 331.649832 -434.157882)
		(stroke
			(width 0.07112)
			(type default)
		)
		(layer "In13.Cu")
	)
	(gr_line
		(start 331.649832 -434.157882)
		(end 331.522832 -434.030882)
		(stroke
			(width 0.07112)
			(type default)
		)
		(layer "In13.Cu")
	)
	(gr_line
		(start 331.649832 -433.621942)
		(end 331.522832 -433.748942)
		(stroke
			(width 0.07112)
			(type default)
		)
		(layer "In13.Cu")
	)
	(gr_line
		(start 331.649832 -433.289964)
		(end 331.649832 -433.621942)
		(stroke
			(width 0.07112)
			(type default)
		)
		(layer "In13.Cu")
	)
	(gr_line
		(start 331.653896 -417.951158)
		(end 331.653896 -417.250118)
		(stroke
			(width 0.07112)
			(type default)
		)
		(layer "In13.Cu")
	)
	(gr_line
		(start 331.653896 -416.823398)
		(end 331.653896 -416.122358)
		(stroke
			(width 0.07112)
			(type default)
		)
		(layer "In13.Cu")
	)
	(gr_line
		(start 331.691742 -410.99867)
		(end 332.334616 -410.718254)
		(stroke
			(width 0.07112)
			(type default)
		)
		(layer "In13.Cu")
	)
	(gr_line
		(start 331.755242 -409.782518)
		(end 332.400148 -409.506166)
		(stroke
			(width 0.07112)
			(type default)
		)
		(layer "In13.Cu")
	)
	(gr_line
		(start 331.806042 -411.25775)
		(end 331.985112 -411.328108)
		(stroke
			(width 0.07112)
			(type default)
		)
		(layer "In13.Cu")
	)
	(gr_line
		(start 331.868018 -410.04236)
		(end 332.04658 -410.113988)
		(stroke
			(width 0.07112)
			(type default)
		)
		(layer "In13.Cu")
	)
	(gr_line
		(start 331.893672 -408.451304)
		(end 332.549246 -408.201368)
		(stroke
			(width 0.07112)
			(type default)
		)
		(layer "In13.Cu")
	)
	(gr_line
		(start 331.937106 -417.949888)
		(end 332.072996 -417.813998)
		(stroke
			(width 0.07112)
			(type default)
		)
		(layer "In13.Cu")
	)
	(gr_line
		(start 331.937106 -416.822128)
		(end 332.072996 -416.686238)
		(stroke
			(width 0.07112)
			(type default)
		)
		(layer "In13.Cu")
	)
	(gr_line
		(start 331.985112 -411.328108)
		(end 332.376526 -411.157674)
		(stroke
			(width 0.07112)
			(type default)
		)
		(layer "In13.Cu")
	)
	(gr_line
		(start 331.995272 -408.715464)
		(end 332.17104 -408.794204)
		(stroke
			(width 0.07112)
			(type default)
		)
		(layer "In13.Cu")
	)
	(gr_line
		(start 332.04658 -410.113988)
		(end 332.43901 -409.94584)
		(stroke
			(width 0.07112)
			(type default)
		)
		(layer "In13.Cu")
	)
	(gr_line
		(start 332.072996 -417.813998)
		(end 332.072996 -417.387278)
		(stroke
			(width 0.07112)
			(type default)
		)
		(layer "In13.Cu")
	)
	(gr_line
		(start 332.072996 -417.387278)
		(end 331.937106 -417.251388)
		(stroke
			(width 0.07112)
			(type default)
		)
		(layer "In13.Cu")
	)
	(gr_line
		(start 332.072996 -416.686238)
		(end 332.072996 -416.259518)
		(stroke
			(width 0.07112)
			(type default)
		)
		(layer "In13.Cu")
	)
	(gr_line
		(start 332.072996 -416.259518)
		(end 331.937106 -416.123628)
		(stroke
			(width 0.07112)
			(type default)
		)
		(layer "In13.Cu")
	)
	(gr_line
		(start 332.17104 -408.794204)
		(end 332.570074 -408.642312)
		(stroke
			(width 0.07112)
			(type default)
		)
		(layer "In13.Cu")
	)
	(gr_line
		(start 332.334616 -410.718254)
		(end 332.33487 -410.718254)
		(stroke
			(width 0.07112)
			(type default)
		)
		(layer "In13.Cu")
	)
	(gr_line
		(start 332.376526 -411.157674)
		(end 332.446884 -410.97835)
		(stroke
			(width 0.07112)
			(type default)
		)
		(layer "In13.Cu")
	)
	(gr_line
		(start 332.40472 -404.880318)
		(end 333.082138 -404.6982)
		(stroke
			(width 0.07112)
			(type default)
		)
		(layer "In13.Cu")
	)
	(gr_line
		(start 332.43901 -409.94584)
		(end 332.510638 -409.767024)
		(stroke
			(width 0.07112)
			(type default)
		)
		(layer "In13.Cu")
	)
	(gr_line
		(start 332.479142 -405.153622)
		(end 332.64602 -405.249888)
		(stroke
			(width 0.07112)
			(type default)
		)
		(layer "In13.Cu")
	)
	(gr_line
		(start 332.570074 -408.642312)
		(end 332.648814 -408.466544)
		(stroke
			(width 0.07112)
			(type default)
		)
		(layer "In13.Cu")
	)
	(gr_line
		(start 332.64602 -405.249888)
		(end 333.058516 -405.13889)
		(stroke
			(width 0.07112)
			(type default)
		)
		(layer "In13.Cu")
	)
	(gr_line
		(start 332.667102 -368.073686)
		(end 332.66761 -368.073686)
		(stroke
			(width 0.07112)
			(type default)
		)
		(layer "In13.Cu")
	)
	(gr_line
		(start 332.725522 -410.54782)
		(end 333.368396 -410.267404)
		(stroke
			(width 0.07112)
			(type default)
		)
		(layer "In13.Cu")
	)
	(gr_line
		(start 332.78445 -424.034966)
		(end 332.790038 -424.007026)
		(stroke
			(width 0.07112)
			(type default)
		)
		(layer "In13.Cu")
	)
	(gr_line
		(start 332.790038 -424.007026)
		(end 332.92669 -423.319194)
		(stroke
			(width 0.07112)
			(type default)
		)
		(layer "In13.Cu")
	)
	(gr_line
		(start 332.792324 -409.338272)
		(end 333.436722 -409.06192)
		(stroke
			(width 0.07112)
			(type default)
		)
		(layer "In13.Cu")
	)
	(gr_line
		(start 332.839822 -410.8069)
		(end 333.018892 -410.877258)
		(stroke
			(width 0.07112)
			(type default)
		)
		(layer "In13.Cu")
	)
	(gr_line
		(start 332.904592 -409.598114)
		(end 333.083408 -409.669488)
		(stroke
			(width 0.07112)
			(type default)
		)
		(layer "In13.Cu")
	)
	(gr_line
		(start 332.958694 -406.91308)
		(end 333.624428 -406.692608)
		(stroke
			(width 0.07112)
			(type default)
		)
		(layer "In13.Cu")
	)
	(gr_line
		(start 333.018892 -410.877258)
		(end 333.410306 -410.706824)
		(stroke
			(width 0.07112)
			(type default)
		)
		(layer "In13.Cu")
	)
	(gr_line
		(start 333.048864 -407.181558)
		(end 333.220568 -407.267918)
		(stroke
			(width 0.07112)
			(type default)
		)
		(layer "In13.Cu")
	)
	(gr_line
		(start 333.058516 -405.13889)
		(end 333.154528 -404.972012)
		(stroke
			(width 0.07112)
			(type default)
		)
		(layer "In13.Cu")
	)
	(gr_line
		(start 333.061056 -424.090084)
		(end 333.066644 -424.06189)
		(stroke
			(width 0.07112)
			(type default)
		)
		(layer "In13.Cu")
	)
	(gr_line
		(start 333.068168 -424.060874)
		(end 333.228188 -423.95394)
		(stroke
			(width 0.07112)
			(type default)
		)
		(layer "In13.Cu")
	)
	(gr_line
		(start 333.083408 -409.669488)
		(end 333.475838 -409.501594)
		(stroke
			(width 0.07112)
			(type default)
		)
		(layer "In13.Cu")
	)
	(gr_line
		(start 333.220568 -407.267918)
		(end 333.625952 -407.133806)
		(stroke
			(width 0.07112)
			(type default)
		)
		(layer "In13.Cu")
	)
	(gr_line
		(start 333.228188 -423.95394)
		(end 333.311246 -423.535348)
		(stroke
			(width 0.07112)
			(type default)
		)
		(layer "In13.Cu")
	)
	(gr_line
		(start 333.311246 -423.535348)
		(end 333.204312 -423.375328)
		(stroke
			(width 0.07112)
			(type default)
		)
		(layer "In13.Cu")
	)
	(gr_line
		(start 333.410306 -410.706824)
		(end 333.480664 -410.5275)
		(stroke
			(width 0.07112)
			(type default)
		)
		(layer "In13.Cu")
	)
	(gr_arc
		(start 333.467456 -422.00449)
		(mid 333.467456 -422.004744)
		(end 333.467456 -422.004998)
		(stroke
			(width 0.07112)
			(type default)
		)
		(layer "In13.Cu")
	)
	(gr_line
		(start 333.475838 -409.501594)
		(end 333.547466 -409.322524)
		(stroke
			(width 0.07112)
			(type default)
		)
		(layer "In13.Cu")
	)
	(gr_line
		(start 333.495142 -434.74894)
		(end 333.484474 -434.74894)
		(stroke
			(width 0.07112)
			(type default)
		)
		(layer "In13.Cu")
	)
	(gr_line
		(start 333.625952 -407.133806)
		(end 333.712312 -406.961848)
		(stroke
			(width 0.07112)
			(type default)
		)
		(layer "In13.Cu")
	)
	(gr_line
		(start 333.649828 -435.489858)
		(end 333.649828 -435.196234)
		(stroke
			(width 0.07112)
			(type default)
		)
		(layer "In13.Cu")
	)
	(gr_line
		(start 333.649828 -435.196234)
		(end 333.485744 -435.03215)
		(stroke
			(width 0.07112)
			(type default)
		)
		(layer "In13.Cu")
	)
	(gr_line
		(start 333.649828 -434.594254)
		(end 333.495142 -434.74894)
		(stroke
			(width 0.07112)
			(type default)
		)
		(layer "In13.Cu")
	)
	(gr_line
		(start 333.649828 -434.289962)
		(end 333.649828 -434.594254)
		(stroke
			(width 0.07112)
			(type default)
		)
		(layer "In13.Cu")
	)
	(gr_line
		(start 333.759302 -410.09697)
		(end 334.402176 -409.816554)
		(stroke
			(width 0.07112)
			(type default)
		)
		(layer "In13.Cu")
	)
	(gr_line
		(start 333.873602 -410.35605)
		(end 334.052672 -410.426408)
		(stroke
			(width 0.07112)
			(type default)
		)
		(layer "In13.Cu")
	)
	(gr_line
		(start 334.052672 -410.426408)
		(end 334.444086 -410.255974)
		(stroke
			(width 0.07112)
			(type default)
		)
		(layer "In13.Cu")
	)
	(gr_line
		(start 334.402176 -409.816554)
		(end 334.40243 -409.816554)
		(stroke
			(width 0.07112)
			(type default)
		)
		(layer "In13.Cu")
	)
	(gr_line
		(start 334.43037 -411.157928)
		(end 335.076292 -410.88437)
		(stroke
			(width 0.07112)
			(type default)
		)
		(layer "In13.Cu")
	)
	(gr_line
		(start 334.444086 -410.255974)
		(end 334.514444 -410.07665)
		(stroke
			(width 0.07112)
			(type default)
		)
		(layer "In13.Cu")
	)
	(gr_line
		(start 334.541622 -411.418278)
		(end 334.71993 -411.490668)
		(stroke
			(width 0.07112)
			(type default)
		)
		(layer "In13.Cu")
	)
	(gr_line
		(start 334.717136 -417.742878)
		(end 334.717136 -417.041838)
		(stroke
			(width 0.07112)
			(type default)
		)
		(layer "In13.Cu")
	)
	(gr_line
		(start 334.717136 -416.615118)
		(end 334.717136 -415.914078)
		(stroke
			(width 0.07112)
			(type default)
		)
		(layer "In13.Cu")
	)
	(gr_line
		(start 334.71993 -411.490668)
		(end 335.113122 -411.324298)
		(stroke
			(width 0.07112)
			(type default)
		)
		(layer "In13.Cu")
	)
	(gr_line
		(start 334.793336 -409.64612)
		(end 335.43621 -409.365958)
		(stroke
			(width 0.07112)
			(type default)
		)
		(layer "In13.Cu")
	)
	(gr_line
		(start 334.907636 -409.9052)
		(end 335.086452 -409.975558)
		(stroke
			(width 0.07112)
			(type default)
		)
		(layer "In13.Cu")
	)
	(gr_line
		(start 335.000346 -417.741608)
		(end 335.136236 -417.605718)
		(stroke
			(width 0.07112)
			(type default)
		)
		(layer "In13.Cu")
	)
	(gr_line
		(start 335.000346 -416.613848)
		(end 335.136236 -416.477958)
		(stroke
			(width 0.07112)
			(type default)
		)
		(layer "In13.Cu")
	)
	(gr_line
		(start 335.056734 -423.984674)
		(end 335.371186 -423.357802)
		(stroke
			(width 0.07112)
			(type default)
		)
		(layer "In13.Cu")
	)
	(gr_line
		(start 335.086452 -409.975558)
		(end 335.477866 -409.805124)
		(stroke
			(width 0.07112)
			(type default)
		)
		(layer "In13.Cu")
	)
	(gr_line
		(start 335.113122 -411.324298)
		(end 335.185258 -411.145736)
		(stroke
			(width 0.07112)
			(type default)
		)
		(layer "In13.Cu")
	)
	(gr_line
		(start 335.136236 -417.605718)
		(end 335.136236 -417.178998)
		(stroke
			(width 0.07112)
			(type default)
		)
		(layer "In13.Cu")
	)
	(gr_line
		(start 335.136236 -417.178998)
		(end 335.000346 -417.043108)
		(stroke
			(width 0.07112)
			(type default)
		)
		(layer "In13.Cu")
	)
	(gr_line
		(start 335.136236 -416.477958)
		(end 335.136236 -416.051238)
		(stroke
			(width 0.07112)
			(type default)
		)
		(layer "In13.Cu")
	)
	(gr_line
		(start 335.136236 -416.051238)
		(end 335.000346 -415.915348)
		(stroke
			(width 0.07112)
			(type default)
		)
		(layer "In13.Cu")
	)
	(gr_line
		(start 335.31048 -424.110658)
		(end 335.49336 -424.050206)
		(stroke
			(width 0.07112)
			(type default)
		)
		(layer "In13.Cu")
	)
	(gr_line
		(start 335.43621 -409.365958)
		(end 335.436464 -409.365704)
		(stroke
			(width 0.07112)
			(type default)
		)
		(layer "In13.Cu")
	)
	(gr_line
		(start 335.468976 -410.718254)
		(end 336.114898 -410.444696)
		(stroke
			(width 0.07112)
			(type default)
		)
		(layer "In13.Cu")
	)
	(gr_line
		(start 335.477866 -409.805124)
		(end 335.548224 -409.626054)
		(stroke
			(width 0.07112)
			(type default)
		)
		(layer "In13.Cu")
	)
	(gr_line
		(start 335.49336 -424.050206)
		(end 335.684622 -423.668444)
		(stroke
			(width 0.07112)
			(type default)
		)
		(layer "In13.Cu")
	)
	(gr_line
		(start 335.562194 -422.976802)
		(end 335.8769 -422.349422)
		(stroke
			(width 0.07112)
			(type default)
		)
		(layer "In13.Cu")
	)
	(gr_line
		(start 335.580228 -410.978604)
		(end 335.758536 -411.05074)
		(stroke
			(width 0.07112)
			(type default)
		)
		(layer "In13.Cu")
	)
	(gr_line
		(start 335.649824 -434.48986)
		(end 335.649824 -434.157882)
		(stroke
			(width 0.07112)
			(type default)
		)
		(layer "In13.Cu")
	)
	(gr_line
		(start 335.649824 -434.157882)
		(end 335.522824 -434.030882)
		(stroke
			(width 0.07112)
			(type default)
		)
		(layer "In13.Cu")
	)
	(gr_line
		(start 335.649824 -433.621942)
		(end 335.522824 -433.748942)
		(stroke
			(width 0.07112)
			(type default)
		)
		(layer "In13.Cu")
	)
	(gr_line
		(start 335.649824 -433.289964)
		(end 335.649824 -433.621942)
		(stroke
			(width 0.07112)
			(type default)
		)
		(layer "In13.Cu")
	)
	(gr_line
		(start 335.684622 -423.668444)
		(end 335.623916 -423.485818)
		(stroke
			(width 0.07112)
			(type default)
		)
		(layer "In13.Cu")
	)
	(gr_line
		(start 335.758536 -411.05074)
		(end 336.151728 -410.88437)
		(stroke
			(width 0.07112)
			(type default)
		)
		(layer "In13.Cu")
	)
	(gr_line
		(start 335.81594 -423.102532)
		(end 335.99882 -423.041826)
		(stroke
			(width 0.07112)
			(type default)
		)
		(layer "In13.Cu")
	)
	(gr_line
		(start 335.99882 -423.041826)
		(end 336.190082 -422.660064)
		(stroke
			(width 0.07112)
			(type default)
		)
		(layer "In13.Cu")
	)
	(gr_line
		(start 336.053176 -401.384008)
		(end 336.344006 -401.674838)
		(stroke
			(width 0.07112)
			(type default)
		)
		(layer "In13.Cu")
	)
	(gr_line
		(start 336.053176 -401.102068)
		(end 336.344006 -400.811238)
		(stroke
			(width 0.07112)
			(type default)
		)
		(layer "In13.Cu")
	)
	(gr_line
		(start 336.151728 -410.88437)
		(end 336.224118 -410.706062)
		(stroke
			(width 0.07112)
			(type default)
		)
		(layer "In13.Cu")
	)
	(gr_line
		(start 336.190082 -422.660064)
		(end 336.129376 -422.477438)
		(stroke
			(width 0.07112)
			(type default)
		)
		(layer "In13.Cu")
	)
	(gr_line
		(start 336.191098 -409.099004)
		(end 336.864706 -408.903932)
		(stroke
			(width 0.07112)
			(type default)
		)
		(layer "In13.Cu")
	)
	(gr_line
		(start 336.270854 -409.370784)
		(end 336.43951 -409.463494)
		(stroke
			(width 0.07112)
			(type default)
		)
		(layer "In13.Cu")
	)
	(gr_line
		(start 336.43951 -409.463494)
		(end 336.84972 -409.344876)
		(stroke
			(width 0.07112)
			(type default)
		)
		(layer "In13.Cu")
	)
	(gr_line
		(start 336.507582 -410.278326)
		(end 337.15325 -410.005022)
		(stroke
			(width 0.07112)
			(type default)
		)
		(layer "In13.Cu")
	)
	(gr_line
		(start 336.530696 -420.22776)
		(end 336.53095 -420.228014)
		(stroke
			(width 0.07112)
			(type default)
		)
		(layer "In13.Cu")
	)
	(gr_line
		(start 336.618834 -410.53893)
		(end 336.797142 -410.611066)
		(stroke
			(width 0.07112)
			(type default)
		)
		(layer "In13.Cu")
	)
	(gr_line
		(start 336.797142 -410.611066)
		(end 337.190334 -410.444696)
		(stroke
			(width 0.07112)
			(type default)
		)
		(layer "In13.Cu")
	)
	(gr_line
		(start 336.84972 -409.344876)
		(end 336.94243 -409.17622)
		(stroke
			(width 0.07112)
			(type default)
		)
		(layer "In13.Cu")
	)
	(gr_line
		(start 337.011264 -423.983404)
		(end 337.025996 -423.96156)
		(stroke
			(width 0.07112)
			(type default)
		)
		(layer "In13.Cu")
	)
	(gr_line
		(start 337.011518 -423.983404)
		(end 337.011264 -423.983404)
		(stroke
			(width 0.07112)
			(type default)
		)
		(layer "In13.Cu")
	)
	(gr_line
		(start 337.025996 -423.96156)
		(end 337.044284 -423.943018)
		(stroke
			(width 0.07112)
			(type default)
		)
		(layer "In13.Cu")
	)
	(gr_line
		(start 337.190334 -410.444696)
		(end 337.262724 -410.266388)
		(stroke
			(width 0.07112)
			(type default)
		)
		(layer "In13.Cu")
	)
	(gr_line
		(start 337.34248 -423.637964)
		(end 337.832954 -423.136314)
		(stroke
			(width 0.07112)
			(type default)
		)
		(layer "In13.Cu")
	)
	(gr_line
		(start 337.405472 -401.399756)
		(end 337.416902 -401.399756)
		(stroke
			(width 0.07112)
			(type default)
		)
		(layer "In13.Cu")
	)
	(gr_line
		(start 337.406742 -401.116546)
		(end 337.543902 -400.979386)
		(stroke
			(width 0.07112)
			(type default)
		)
		(layer "In13.Cu")
	)
	(gr_line
		(start 337.416902 -401.399756)
		(end 337.543902 -401.526756)
		(stroke
			(width 0.07112)
			(type default)
		)
		(layer "In13.Cu")
	)
	(gr_line
		(start 337.543902 -401.526756)
		(end 337.543902 -401.674838)
		(stroke
			(width 0.07112)
			(type default)
		)
		(layer "In13.Cu")
	)
	(gr_line
		(start 337.543902 -400.979386)
		(end 337.543902 -400.811238)
		(stroke
			(width 0.07112)
			(type default)
		)
		(layer "In13.Cu")
	)
	(gr_line
		(start 337.54568 -423.835068)
		(end 337.738212 -423.833036)
		(stroke
			(width 0.07112)
			(type default)
		)
		(layer "In13.Cu")
	)
	(gr_line
		(start 337.64982 -435.489858)
		(end 337.64982 -435.15788)
		(stroke
			(width 0.07112)
			(type default)
		)
		(layer "In13.Cu")
	)
	(gr_line
		(start 337.64982 -435.15788)
		(end 337.52282 -435.03088)
		(stroke
			(width 0.07112)
			(type default)
		)
		(layer "In13.Cu")
	)
	(gr_line
		(start 337.64982 -434.62194)
		(end 337.52282 -434.74894)
		(stroke
			(width 0.07112)
			(type default)
		)
		(layer "In13.Cu")
	)
	(gr_line
		(start 337.64982 -434.289962)
		(end 337.64982 -434.62194)
		(stroke
			(width 0.07112)
			(type default)
		)
		(layer "In13.Cu")
	)
	(gr_line
		(start 337.738212 -423.833036)
		(end 338.036662 -423.527474)
		(stroke
			(width 0.07112)
			(type default)
		)
		(layer "In13.Cu")
	)
	(gr_line
		(start 337.780376 -417.797234)
		(end 337.780376 -417.096194)
		(stroke
			(width 0.07112)
			(type default)
		)
		(layer "In13.Cu")
	)
	(gr_line
		(start 337.780376 -416.669474)
		(end 337.780376 -415.968434)
		(stroke
			(width 0.07112)
			(type default)
		)
		(layer "In13.Cu")
	)
	(gr_line
		(start 338.01177 -410.792676)
		(end 338.65947 -410.524198)
		(stroke
			(width 0.07112)
			(type default)
		)
		(layer "In13.Cu")
	)
	(gr_line
		(start 338.036662 -423.527474)
		(end 338.03463 -423.335196)
		(stroke
			(width 0.07112)
			(type default)
		)
		(layer "In13.Cu")
	)
	(gr_line
		(start 338.063586 -417.795964)
		(end 338.199476 -417.660074)
		(stroke
			(width 0.07112)
			(type default)
		)
		(layer "In13.Cu")
	)
	(gr_line
		(start 338.063586 -416.668204)
		(end 338.199476 -416.532314)
		(stroke
			(width 0.07112)
			(type default)
		)
		(layer "In13.Cu")
	)
	(gr_line
		(start 338.12099 -411.053788)
		(end 338.29879 -411.127702)
		(stroke
			(width 0.07112)
			(type default)
		)
		(layer "In13.Cu")
	)
	(gr_line
		(start 338.13115 -422.831514)
		(end 338.62137 -422.330118)
		(stroke
			(width 0.07112)
			(type default)
		)
		(layer "In13.Cu")
	)
	(gr_line
		(start 338.199476 -417.660074)
		(end 338.199476 -417.233354)
		(stroke
			(width 0.07112)
			(type default)
		)
		(layer "In13.Cu")
	)
	(gr_line
		(start 338.199476 -417.233354)
		(end 338.063586 -417.097464)
		(stroke
			(width 0.07112)
			(type default)
		)
		(layer "In13.Cu")
	)
	(gr_line
		(start 338.199476 -416.532314)
		(end 338.199476 -416.105594)
		(stroke
			(width 0.07112)
			(type default)
		)
		(layer "In13.Cu")
	)
	(gr_line
		(start 338.199476 -416.105594)
		(end 338.063586 -415.969704)
		(stroke
			(width 0.07112)
			(type default)
		)
		(layer "In13.Cu")
	)
	(gr_line
		(start 338.29879 -411.127702)
		(end 338.693252 -410.96438)
		(stroke
			(width 0.07112)
			(type default)
		)
		(layer "In13.Cu")
	)
	(gr_line
		(start 338.33435 -423.028618)
		(end 338.526882 -423.026586)
		(stroke
			(width 0.07112)
			(type default)
		)
		(layer "In13.Cu")
	)
	(gr_line
		(start 338.526882 -423.026586)
		(end 338.825332 -422.721024)
		(stroke
			(width 0.07112)
			(type default)
		)
		(layer "In13.Cu")
	)
	(gr_line
		(start 338.605622 -401.399756)
		(end 338.617052 -401.399756)
		(stroke
			(width 0.07112)
			(type default)
		)
		(layer "In13.Cu")
	)
	(gr_line
		(start 338.606892 -401.116546)
		(end 338.744052 -400.979386)
		(stroke
			(width 0.07112)
			(type default)
		)
		(layer "In13.Cu")
	)
	(gr_line
		(start 338.617052 -401.399756)
		(end 338.744052 -401.526756)
		(stroke
			(width 0.07112)
			(type default)
		)
		(layer "In13.Cu")
	)
	(gr_line
		(start 338.688934 -433.55641)
		(end 338.68868 -433.55641)
		(stroke
			(width 0.07112)
			(type default)
		)
		(layer "In13.Cu")
	)
	(gr_line
		(start 338.693252 -410.96438)
		(end 338.766658 -410.786326)
		(stroke
			(width 0.07112)
			(type default)
		)
		(layer "In13.Cu")
	)
	(gr_line
		(start 338.744052 -401.526756)
		(end 338.744052 -401.674838)
		(stroke
			(width 0.07112)
			(type default)
		)
		(layer "In13.Cu")
	)
	(gr_line
		(start 338.744052 -400.979386)
		(end 338.744052 -400.811238)
		(stroke
			(width 0.07112)
			(type default)
		)
		(layer "In13.Cu")
	)
	(gr_line
		(start 338.825332 -422.721024)
		(end 338.823046 -422.528746)
		(stroke
			(width 0.07112)
			(type default)
		)
		(layer "In13.Cu")
	)
	(gr_line
		(start 339.083396 -410.348684)
		(end 339.731096 -410.08046)
		(stroke
			(width 0.07112)
			(type default)
		)
		(layer "In13.Cu")
	)
	(gr_line
		(start 339.19287 -410.609796)
		(end 339.370416 -410.683456)
		(stroke
			(width 0.07112)
			(type default)
		)
		(layer "In13.Cu")
	)
	(gr_line
		(start 339.360764 -423.705782)
		(end 339.944964 -423.317162)
		(stroke
			(width 0.07112)
			(type default)
		)
		(layer "In13.Cu")
	)
	(gr_line
		(start 339.370416 -410.683456)
		(end 339.764878 -410.520134)
		(stroke
			(width 0.07112)
			(type default)
		)
		(layer "In13.Cu")
	)
	(gr_line
		(start 339.518752 -423.940986)
		(end 339.707474 -423.978832)
		(stroke
			(width 0.07112)
			(type default)
		)
		(layer "In13.Cu")
	)
	(gr_line
		(start 339.649816 -434.48986)
		(end 339.649816 -434.157882)
		(stroke
			(width 0.07112)
			(type default)
		)
		(layer "In13.Cu")
	)
	(gr_line
		(start 339.649816 -434.157882)
		(end 339.522816 -434.030882)
		(stroke
			(width 0.07112)
			(type default)
		)
		(layer "In13.Cu")
	)
	(gr_line
		(start 339.649816 -433.621942)
		(end 339.522816 -433.748942)
		(stroke
			(width 0.07112)
			(type default)
		)
		(layer "In13.Cu")
	)
	(gr_line
		(start 339.649816 -433.289964)
		(end 339.649816 -433.621942)
		(stroke
			(width 0.07112)
			(type default)
		)
		(layer "In13.Cu")
	)
	(gr_line
		(start 339.707474 -423.978832)
		(end 340.063074 -423.742358)
		(stroke
			(width 0.07112)
			(type default)
		)
		(layer "In13.Cu")
	)
	(gr_line
		(start 339.764878 -410.520134)
		(end 339.838538 -410.342334)
		(stroke
			(width 0.07112)
			(type default)
		)
		(layer "In13.Cu")
	)
	(gr_line
		(start 339.805518 -401.399756)
		(end 339.816948 -401.399756)
		(stroke
			(width 0.07112)
			(type default)
		)
		(layer "In13.Cu")
	)
	(gr_line
		(start 339.806788 -401.116546)
		(end 339.943948 -400.979386)
		(stroke
			(width 0.07112)
			(type default)
		)
		(layer "In13.Cu")
	)
	(gr_line
		(start 339.816948 -401.399756)
		(end 339.943948 -401.526756)
		(stroke
			(width 0.07112)
			(type default)
		)
		(layer "In13.Cu")
	)
	(gr_line
		(start 339.943948 -401.526756)
		(end 339.943948 -401.674838)
		(stroke
			(width 0.07112)
			(type default)
		)
		(layer "In13.Cu")
	)
	(gr_line
		(start 339.943948 -400.979386)
		(end 339.943948 -400.811238)
		(stroke
			(width 0.07112)
			(type default)
		)
		(layer "In13.Cu")
	)
	(gr_line
		(start 339.945218 -423.317162)
		(end 339.944964 -423.317162)
		(stroke
			(width 0.07112)
			(type default)
		)
		(layer "In13.Cu")
	)
	(gr_line
		(start 340.063074 -423.742358)
		(end 340.10092 -423.553636)
		(stroke
			(width 0.07112)
			(type default)
		)
		(layer "In13.Cu")
	)
	(gr_line
		(start 340.300056 -423.080942)
		(end 340.884002 -422.692322)
		(stroke
			(width 0.07112)
			(type default)
		)
		(layer "In13.Cu")
	)
	(gr_line
		(start 340.45779 -423.316146)
		(end 340.646512 -423.353992)
		(stroke
			(width 0.07112)
			(type default)
		)
		(layer "In13.Cu")
	)
	(gr_line
		(start 340.646512 -423.353992)
		(end 341.002112 -423.117518)
		(stroke
			(width 0.07112)
			(type default)
		)
		(layer "In13.Cu")
	)
	(gr_line
		(start 340.843616 -417.769294)
		(end 340.843616 -417.068254)
		(stroke
			(width 0.07112)
			(type default)
		)
		(layer "In13.Cu")
	)
	(gr_line
		(start 340.843616 -416.641534)
		(end 340.843616 -415.940494)
		(stroke
			(width 0.07112)
			(type default)
		)
		(layer "In13.Cu")
	)
	(gr_line
		(start 340.884256 -422.692322)
		(end 340.884002 -422.692322)
		(stroke
			(width 0.07112)
			(type default)
		)
		(layer "In13.Cu")
	)
	(gr_line
		(start 341.002112 -423.117518)
		(end 341.039958 -422.928796)
		(stroke
			(width 0.07112)
			(type default)
		)
		(layer "In13.Cu")
	)
	(gr_line
		(start 341.005668 -401.399756)
		(end 341.017098 -401.399756)
		(stroke
			(width 0.07112)
			(type default)
		)
		(layer "In13.Cu")
	)
	(gr_line
		(start 341.006938 -401.116546)
		(end 341.144098 -400.979386)
		(stroke
			(width 0.07112)
			(type default)
		)
		(layer "In13.Cu")
	)
	(gr_line
		(start 341.017098 -401.399756)
		(end 341.144098 -401.526756)
		(stroke
			(width 0.07112)
			(type default)
		)
		(layer "In13.Cu")
	)
	(gr_line
		(start 341.040212 -422.927272)
		(end 341.04072 -422.927018)
		(stroke
			(width 0.07112)
			(type default)
		)
		(layer "In13.Cu")
	)
	(gr_line
		(start 341.109554 -410.656532)
		(end 341.688674 -410.2608)
		(stroke
			(width 0.07112)
			(type default)
		)
		(layer "In13.Cu")
	)
	(gr_line
		(start 341.126826 -417.768024)
		(end 341.262716 -417.632134)
		(stroke
			(width 0.07112)
			(type default)
		)
		(layer "In13.Cu")
	)
	(gr_line
		(start 341.126826 -416.640264)
		(end 341.262716 -416.504374)
		(stroke
			(width 0.07112)
			(type default)
		)
		(layer "In13.Cu")
	)
	(gr_line
		(start 341.144098 -401.526756)
		(end 341.144098 -401.674838)
		(stroke
			(width 0.07112)
			(type default)
		)
		(layer "In13.Cu")
	)
	(gr_line
		(start 341.144098 -400.979386)
		(end 341.144098 -400.811238)
		(stroke
			(width 0.07112)
			(type default)
		)
		(layer "In13.Cu")
	)
	(gr_line
		(start 341.239602 -422.456102)
		(end 341.823548 -422.067736)
		(stroke
			(width 0.07112)
			(type default)
		)
		(layer "In13.Cu")
	)
	(gr_line
		(start 341.262716 -417.632134)
		(end 341.262716 -417.205414)
		(stroke
			(width 0.07112)
			(type default)
		)
		(layer "In13.Cu")
	)
	(gr_line
		(start 341.262716 -417.205414)
		(end 341.126826 -417.069524)
		(stroke
			(width 0.07112)
			(type default)
		)
		(layer "In13.Cu")
	)
	(gr_line
		(start 341.262716 -416.504374)
		(end 341.262716 -416.077654)
		(stroke
			(width 0.07112)
			(type default)
		)
		(layer "In13.Cu")
	)
	(gr_line
		(start 341.262716 -416.077654)
		(end 341.126826 -415.941764)
		(stroke
			(width 0.07112)
			(type default)
		)
		(layer "In13.Cu")
	)
	(gr_line
		(start 341.270336 -410.889704)
		(end 341.459566 -410.925264)
		(stroke
			(width 0.07112)
			(type default)
		)
		(layer "In13.Cu")
	)
	(gr_line
		(start 341.327486 -409.251658)
		(end 341.890858 -408.834082)
		(stroke
			(width 0.07112)
			(type default)
		)
		(layer "In13.Cu")
	)
	(gr_line
		(start 341.397336 -422.691052)
		(end 341.586058 -422.729152)
		(stroke
			(width 0.07112)
			(type default)
		)
		(layer "In13.Cu")
	)
	(gr_line
		(start 341.459566 -410.925264)
		(end 341.812118 -410.684218)
		(stroke
			(width 0.07112)
			(type default)
		)
		(layer "In13.Cu")
	)
	(gr_line
		(start 341.495888 -405.04364)
		(end 341.991696 -404.547832)
		(stroke
			(width 0.07112)
			(type default)
		)
		(layer "In13.Cu")
	)
	(gr_line
		(start 341.497158 -409.47848)
		(end 341.645494 -409.500578)
		(stroke
			(width 0.07112)
			(type default)
		)
		(layer "In13.Cu")
	)
	(gr_line
		(start 341.573358 -423.585894)
		(end 342.191848 -423.254932)
		(stroke
			(width 0.07112)
			(type default)
		)
		(layer "In13.Cu")
	)
	(gr_line
		(start 341.586058 -422.729152)
		(end 341.941658 -422.492424)
		(stroke
			(width 0.07112)
			(type default)
		)
		(layer "In13.Cu")
	)
	(gr_line
		(start 341.603076 -403.410674)
		(end 341.603076 -402.709634)
		(stroke
			(width 0.07112)
			(type default)
		)
		(layer "In13.Cu")
	)
	(gr_line
		(start 341.645494 -409.500578)
		(end 342.0364 -409.210764)
		(stroke
			(width 0.07112)
			(type default)
		)
		(layer "In13.Cu")
	)
	(gr_line
		(start 341.649812 -435.489858)
		(end 341.649812 -435.15788)
		(stroke
			(width 0.07112)
			(type default)
		)
		(layer "In13.Cu")
	)
	(gr_line
		(start 341.649812 -435.15788)
		(end 341.522812 -435.03088)
		(stroke
			(width 0.07112)
			(type default)
		)
		(layer "In13.Cu")
	)
	(gr_line
		(start 341.649812 -434.62194)
		(end 341.522812 -434.74894)
		(stroke
			(width 0.07112)
			(type default)
		)
		(layer "In13.Cu")
	)
	(gr_line
		(start 341.649812 -434.289962)
		(end 341.649812 -434.62194)
		(stroke
			(width 0.07112)
			(type default)
		)
		(layer "In13.Cu")
	)
	(gr_line
		(start 341.697056 -405.24303)
		(end 341.84082 -405.24303)
		(stroke
			(width 0.07112)
			(type default)
		)
		(layer "In13.Cu")
	)
	(gr_line
		(start 341.707978 -423.835068)
		(end 341.892128 -423.890948)
		(stroke
			(width 0.07112)
			(type default)
		)
		(layer "In13.Cu")
	)
	(gr_line
		(start 341.812118 -410.684218)
		(end 341.847678 -410.495242)
		(stroke
			(width 0.07112)
			(type default)
		)
		(layer "In13.Cu")
	)
	(gr_line
		(start 341.84082 -405.24303)
		(end 342.191086 -404.892764)
		(stroke
			(width 0.07112)
			(type default)
		)
		(layer "In13.Cu")
	)
	(gr_line
		(start 341.886286 -403.409404)
		(end 342.022176 -403.273514)
		(stroke
			(width 0.07112)
			(type default)
		)
		(layer "In13.Cu")
	)
	(gr_line
		(start 341.892128 -423.890948)
		(end 342.268556 -423.68978)
		(stroke
			(width 0.07112)
			(type default)
		)
		(layer "In13.Cu")
	)
	(gr_line
		(start 341.941658 -422.492424)
		(end 341.979504 -422.303956)
		(stroke
			(width 0.07112)
			(type default)
		)
		(layer "In13.Cu")
	)
	(gr_line
		(start 342.022176 -403.273514)
		(end 342.022176 -402.846794)
		(stroke
			(width 0.07112)
			(type default)
		)
		(layer "In13.Cu")
	)
	(gr_line
		(start 342.022176 -402.846794)
		(end 341.886286 -402.710904)
		(stroke
			(width 0.07112)
			(type default)
		)
		(layer "In13.Cu")
	)
	(gr_line
		(start 342.0364 -409.210764)
		(end 342.058498 -409.062428)
		(stroke
			(width 0.07112)
			(type default)
		)
		(layer "In13.Cu")
	)
	(gr_line
		(start 342.040718 -410.020008)
		(end 342.620092 -409.624276)
		(stroke
			(width 0.07112)
			(type default)
		)
		(layer "In13.Cu")
	)
	(gr_line
		(start 342.191086 -404.892764)
		(end 342.191086 -404.749)
		(stroke
			(width 0.07112)
			(type default)
		)
		(layer "In13.Cu")
	)
	(gr_line
		(start 342.2015 -410.25318)
		(end 342.39073 -410.28874)
		(stroke
			(width 0.07112)
			(type default)
		)
		(layer "In13.Cu")
	)
	(gr_line
		(start 342.205564 -401.399756)
		(end 342.216994 -401.399756)
		(stroke
			(width 0.07112)
			(type default)
		)
		(layer "In13.Cu")
	)
	(gr_line
		(start 342.206834 -401.116546)
		(end 342.343994 -400.979386)
		(stroke
			(width 0.07112)
			(type default)
		)
		(layer "In13.Cu")
	)
	(gr_line
		(start 342.216994 -401.399756)
		(end 342.343994 -401.526756)
		(stroke
			(width 0.07112)
			(type default)
		)
		(layer "In13.Cu")
	)
	(gr_line
		(start 342.268556 -423.68978)
		(end 342.324436 -423.505376)
		(stroke
			(width 0.07112)
			(type default)
		)
		(layer "In13.Cu")
	)
	(gr_line
		(start 342.343994 -401.526756)
		(end 342.343994 -401.674838)
		(stroke
			(width 0.07112)
			(type default)
		)
		(layer "In13.Cu")
	)
	(gr_line
		(start 342.343994 -400.979386)
		(end 342.343994 -400.811238)
		(stroke
			(width 0.07112)
			(type default)
		)
		(layer "In13.Cu")
	)
	(gr_line
		(start 342.39073 -410.28874)
		(end 342.743282 -410.047694)
		(stroke
			(width 0.07112)
			(type default)
		)
		(layer "In13.Cu")
	)
	(gr_line
		(start 342.514174 -408.295094)
		(end 343.010236 -407.799286)
		(stroke
			(width 0.07112)
			(type default)
		)
		(layer "In13.Cu")
	)
	(gr_line
		(start 342.715088 -408.494738)
		(end 342.907366 -408.494738)
		(stroke
			(width 0.07112)
			(type default)
		)
		(layer "In13.Cu")
	)
	(gr_line
		(start 342.743282 -410.047694)
		(end 342.778842 -409.858718)
		(stroke
			(width 0.07112)
			(type default)
		)
		(layer "In13.Cu")
	)
	(gr_line
		(start 342.803226 -403.521418)
		(end 342.803226 -402.820378)
		(stroke
			(width 0.07112)
			(type default)
		)
		(layer "In13.Cu")
	)
	(gr_line
		(start 342.907366 -408.494738)
		(end 343.209626 -408.192732)
		(stroke
			(width 0.07112)
			(type default)
		)
		(layer "In13.Cu")
	)
	(gr_line
		(start 342.948514 -411.333696)
		(end 343.419684 -410.814012)
		(stroke
			(width 0.07112)
			(type default)
		)
		(layer "In13.Cu")
	)
	(gr_line
		(start 343.086436 -403.520148)
		(end 343.222326 -403.384258)
		(stroke
			(width 0.07112)
			(type default)
		)
		(layer "In13.Cu")
	)
	(gr_line
		(start 343.09812 -406.256744)
		(end 343.568782 -405.73706)
		(stroke
			(width 0.07112)
			(type default)
		)
		(layer "In13.Cu")
	)
	(gr_line
		(start 343.159334 -411.52318)
		(end 343.351358 -411.513528)
		(stroke
			(width 0.07112)
			(type default)
		)
		(layer "In13.Cu")
	)
	(gr_line
		(start 343.209626 -408.192732)
		(end 343.209626 -408.000454)
		(stroke
			(width 0.07112)
			(type default)
		)
		(layer "In13.Cu")
	)
	(gr_line
		(start 343.222326 -403.384258)
		(end 343.222326 -402.957538)
		(stroke
			(width 0.07112)
			(type default)
		)
		(layer "In13.Cu")
	)
	(gr_line
		(start 343.222326 -402.957538)
		(end 343.086436 -402.821648)
		(stroke
			(width 0.07112)
			(type default)
		)
		(layer "In13.Cu")
	)
	(gr_line
		(start 343.308686 -406.446228)
		(end 343.449148 -406.43937)
		(stroke
			(width 0.07112)
			(type default)
		)
		(layer "In13.Cu")
	)
	(gr_line
		(start 343.311734 -409.061666)
		(end 343.807542 -408.565858)
		(stroke
			(width 0.07112)
			(type default)
		)
		(layer "In13.Cu")
	)
	(gr_line
		(start 343.311734 -407.497788)
		(end 343.807796 -407.00198)
		(stroke
			(width 0.07112)
			(type default)
		)
		(layer "In13.Cu")
	)
	(gr_line
		(start 343.351358 -411.513528)
		(end 343.638124 -411.197044)
		(stroke
			(width 0.07112)
			(type default)
		)
		(layer "In13.Cu")
	)
	(gr_line
		(start 343.405714 -401.399756)
		(end 343.417144 -401.399756)
		(stroke
			(width 0.07112)
			(type default)
		)
		(layer "In13.Cu")
	)
	(gr_line
		(start 343.406984 -401.116546)
		(end 343.544144 -400.979386)
		(stroke
			(width 0.07112)
			(type default)
		)
		(layer "In13.Cu")
	)
	(gr_line
		(start 343.417144 -401.399756)
		(end 343.544144 -401.526756)
		(stroke
			(width 0.07112)
			(type default)
		)
		(layer "In13.Cu")
	)
	(gr_line
		(start 343.449148 -406.43937)
		(end 343.784936 -406.068784)
		(stroke
			(width 0.07112)
			(type default)
		)
		(layer "In13.Cu")
	)
	(gr_line
		(start 343.512648 -409.26131)
		(end 343.704926 -409.26131)
		(stroke
			(width 0.07112)
			(type default)
		)
		(layer "In13.Cu")
	)
	(gr_line
		(start 343.512648 -407.697432)
		(end 343.70518 -407.697432)
		(stroke
			(width 0.07112)
			(type default)
		)
		(layer "In13.Cu")
	)
	(gr_line
		(start 343.544144 -401.526756)
		(end 343.544144 -401.674838)
		(stroke
			(width 0.07112)
			(type default)
		)
		(layer "In13.Cu")
	)
	(gr_line
		(start 343.544144 -400.979386)
		(end 343.544144 -400.811238)
		(stroke
			(width 0.07112)
			(type default)
		)
		(layer "In13.Cu")
	)
	(gr_line
		(start 343.638124 -411.197044)
		(end 343.628472 -411.005274)
		(stroke
			(width 0.07112)
			(type default)
		)
		(layer "In13.Cu")
	)
	(gr_line
		(start 343.649808 -434.48986)
		(end 343.649808 -434.157882)
		(stroke
			(width 0.07112)
			(type default)
		)
		(layer "In13.Cu")
	)
	(gr_line
		(start 343.649808 -434.157882)
		(end 343.522808 -434.030882)
		(stroke
			(width 0.07112)
			(type default)
		)
		(layer "In13.Cu")
	)
	(gr_line
		(start 343.649808 -433.621942)
		(end 343.522808 -433.748942)
		(stroke
			(width 0.07112)
			(type default)
		)
		(layer "In13.Cu")
	)
	(gr_line
		(start 343.649808 -433.289964)
		(end 343.649808 -433.621942)
		(stroke
			(width 0.07112)
			(type default)
		)
		(layer "In13.Cu")
	)
	(gr_line
		(start 343.704926 -409.26131)
		(end 344.006932 -408.959304)
		(stroke
			(width 0.07112)
			(type default)
		)
		(layer "In13.Cu")
	)
	(gr_line
		(start 343.70518 -407.697432)
		(end 344.007186 -407.395426)
		(stroke
			(width 0.07112)
			(type default)
		)
		(layer "In13.Cu")
	)
	(gr_line
		(start 343.705942 -410.498036)
		(end 344.177112 -409.978352)
		(stroke
			(width 0.07112)
			(type default)
		)
		(layer "In13.Cu")
	)
	(gr_line
		(start 343.784936 -406.068784)
		(end 343.778078 -405.927814)
		(stroke
			(width 0.07112)
			(type default)
		)
		(layer "In13.Cu")
	)
	(gr_line
		(start 343.906856 -418.022024)
		(end 343.906856 -417.320984)
		(stroke
			(width 0.07112)
			(type default)
		)
		(layer "In13.Cu")
	)
	(gr_line
		(start 343.906856 -416.894264)
		(end 343.906856 -416.193224)
		(stroke
			(width 0.07112)
			(type default)
		)
		(layer "In13.Cu")
	)
	(gr_line
		(start 343.916508 -410.68752)
		(end 344.108532 -410.677868)
		(stroke
			(width 0.07112)
			(type default)
		)
		(layer "In13.Cu")
	)
	(gr_line
		(start 343.971626 -403.587458)
		(end 343.97188 -403.587712)
		(stroke
			(width 0.07112)
			(type default)
		)
		(layer "In13.Cu")
	)
	(gr_line
		(start 343.97188 -403.160738)
		(end 343.97188 -402.459698)
		(stroke
			(width 0.07112)
			(type default)
		)
		(layer "In13.Cu")
	)
	(gr_line
		(start 344.006932 -408.959304)
		(end 344.006932 -408.767026)
		(stroke
			(width 0.07112)
			(type default)
		)
		(layer "In13.Cu")
	)
	(gr_line
		(start 344.007186 -407.395426)
		(end 344.007186 -407.202894)
		(stroke
			(width 0.07112)
			(type default)
		)
		(layer "In13.Cu")
	)
	(gr_line
		(start 344.108532 -410.677868)
		(end 344.395552 -410.361384)
		(stroke
			(width 0.07112)
			(type default)
		)
		(layer "In13.Cu")
	)
	(gr_line
		(start 344.109294 -408.264106)
		(end 344.605102 -407.768298)
		(stroke
			(width 0.07112)
			(type default)
		)
		(layer "In13.Cu")
	)
	(gr_line
		(start 344.190066 -418.020754)
		(end 344.325956 -417.884864)
		(stroke
			(width 0.07112)
			(type default)
		)
		(layer "In13.Cu")
	)
	(gr_line
		(start 344.190066 -416.892994)
		(end 344.325956 -416.757104)
		(stroke
			(width 0.07112)
			(type default)
		)
		(layer "In13.Cu")
	)
	(gr_line
		(start 344.25509 -403.159468)
		(end 344.39098 -403.023578)
		(stroke
			(width 0.07112)
			(type default)
		)
		(layer "In13.Cu")
	)
	(gr_line
		(start 344.310208 -408.46375)
		(end 344.502486 -408.46375)
		(stroke
			(width 0.07112)
			(type default)
		)
		(layer "In13.Cu")
	)
	(gr_line
		(start 344.325956 -417.884864)
		(end 344.325956 -417.458144)
		(stroke
			(width 0.07112)
			(type default)
		)
		(layer "In13.Cu")
	)
	(gr_line
		(start 344.325956 -417.458144)
		(end 344.190066 -417.322254)
		(stroke
			(width 0.07112)
			(type default)
		)
		(layer "In13.Cu")
	)
	(gr_line
		(start 344.325956 -416.757104)
		(end 344.325956 -416.330384)
		(stroke
			(width 0.07112)
			(type default)
		)
		(layer "In13.Cu")
	)
	(gr_line
		(start 344.325956 -416.330384)
		(end 344.190066 -416.194494)
		(stroke
			(width 0.07112)
			(type default)
		)
		(layer "In13.Cu")
	)
	(gr_line
		(start 344.39098 -403.023578)
		(end 344.39098 -402.596858)
		(stroke
			(width 0.07112)
			(type default)
		)
		(layer "In13.Cu")
	)
	(gr_line
		(start 344.39098 -402.596858)
		(end 344.25509 -402.460968)
		(stroke
			(width 0.07112)
			(type default)
		)
		(layer "In13.Cu")
	)
	(gr_line
		(start 344.395552 -410.361384)
		(end 344.3859 -410.169614)
		(stroke
			(width 0.07112)
			(type default)
		)
		(layer "In13.Cu")
	)
	(gr_line
		(start 344.46337 -409.662376)
		(end 344.93454 -409.142692)
		(stroke
			(width 0.07112)
			(type default)
		)
		(layer "In13.Cu")
	)
	(gr_line
		(start 344.478102 -406.274778)
		(end 344.92311 -405.732488)
		(stroke
			(width 0.07112)
			(type default)
		)
		(layer "In13.Cu")
	)
	(gr_line
		(start 344.502486 -408.46375)
		(end 344.804492 -408.161744)
		(stroke
			(width 0.07112)
			(type default)
		)
		(layer "In13.Cu")
	)
	(gr_line
		(start 344.605102 -404.450042)
		(end 345.008962 -403.876764)
		(stroke
			(width 0.07112)
			(type default)
		)
		(layer "In13.Cu")
	)
	(gr_line
		(start 344.60561 -401.399756)
		(end 344.61704 -401.399756)
		(stroke
			(width 0.07112)
			(type default)
		)
		(layer "In13.Cu")
	)
	(gr_line
		(start 344.60688 -401.116546)
		(end 344.74404 -400.979386)
		(stroke
			(width 0.07112)
			(type default)
		)
		(layer "In13.Cu")
	)
	(gr_line
		(start 344.61704 -401.399756)
		(end 344.74404 -401.526756)
		(stroke
			(width 0.07112)
			(type default)
		)
		(layer "In13.Cu")
	)
	(gr_line
		(start 344.673936 -409.85186)
		(end 344.86596 -409.842208)
		(stroke
			(width 0.07112)
			(type default)
		)
		(layer "In13.Cu")
	)
	(gr_line
		(start 344.697558 -406.45334)
		(end 344.889074 -406.434544)
		(stroke
			(width 0.07112)
			(type default)
		)
		(layer "In13.Cu")
	)
	(gr_line
		(start 344.74404 -401.526756)
		(end 344.74404 -401.674838)
		(stroke
			(width 0.07112)
			(type default)
		)
		(layer "In13.Cu")
	)
	(gr_line
		(start 344.74404 -400.979386)
		(end 344.74404 -400.811238)
		(stroke
			(width 0.07112)
			(type default)
		)
		(layer "In13.Cu")
	)
	(gr_line
		(start 344.804492 -408.161744)
		(end 344.804492 -407.969466)
		(stroke
			(width 0.07112)
			(type default)
		)
		(layer "In13.Cu")
	)
	(gr_line
		(start 344.837258 -404.612348)
		(end 345.026742 -404.579328)
		(stroke
			(width 0.07112)
			(type default)
		)
		(layer "In13.Cu")
	)
	(gr_line
		(start 344.847164 -296.079164)
		(end 344.847164 -296.050716)
		(stroke
			(width 0.05715)
			(type default)
		)
		(layer "In13.Cu")
	)
	(gr_line
		(start 344.847164 -296.050716)
		(end 344.891614 -296.006266)
		(stroke
			(width 0.05715)
			(type default)
		)
		(layer "In13.Cu")
	)
	(gr_line
		(start 344.86596 -409.842208)
		(end 345.15298 -409.525724)
		(stroke
			(width 0.07112)
			(type default)
		)
		(layer "In13.Cu")
	)
	(gr_line
		(start 344.889074 -406.434544)
		(end 345.160092 -406.104598)
		(stroke
			(width 0.07112)
			(type default)
		)
		(layer "In13.Cu")
	)
	(gr_line
		(start 344.92311 -405.732488)
		(end 344.923364 -405.732488)
		(stroke
			(width 0.07112)
			(type default)
		)
		(layer "In13.Cu")
	)
	(gr_line
		(start 345.026742 -404.579328)
		(end 345.272868 -404.230078)
		(stroke
			(width 0.07112)
			(type default)
		)
		(layer "In13.Cu")
	)
	(gr_line
		(start 345.083384 -296.018966)
		(end 345.083384 -296.004996)
		(stroke
			(width 0.05715)
			(type default)
		)
		(layer "In13.Cu")
	)
	(gr_line
		(start 345.129104 -296.079164)
		(end 345.129104 -296.064686)
		(stroke
			(width 0.05715)
			(type default)
		)
		(layer "In13.Cu")
	)
	(gr_line
		(start 345.129104 -296.064686)
		(end 345.083384 -296.018966)
		(stroke
			(width 0.05715)
			(type default)
		)
		(layer "In13.Cu")
	)
	(gr_arc
		(start 345.129104 -286.581342)
		(mid 345.124388 -286.58462)
		(end 345.119706 -286.587946)
		(stroke
			(width 0.05715)
			(type default)
		)
		(layer "In13.Cu")
	)
	(gr_line
		(start 345.129104 -286.581342)
		(end 345.131136 -286.579818)
		(stroke
			(width 0.05715)
			(type default)
		)
		(layer "In13.Cu")
	)
	(gr_line
		(start 345.129358 -299.310806)
		(end 345.129104 -299.31106)
		(stroke
			(width 0.07112)
			(type default)
		)
		(layer "In13.Cu")
	)
	(gr_line
		(start 345.131136 -286.579818)
		(end 345.135962 -286.577024)
		(stroke
			(width 0.05715)
			(type default)
		)
		(layer "In13.Cu")
	)
	(gr_line
		(start 345.15298 -409.525724)
		(end 345.143328 -409.333954)
		(stroke
			(width 0.07112)
			(type default)
		)
		(layer "In13.Cu")
	)
	(gr_line
		(start 345.160092 -406.104598)
		(end 345.14155 -405.912828)
		(stroke
			(width 0.07112)
			(type default)
		)
		(layer "In13.Cu")
	)
	(gr_line
		(start 345.19489 -405.401526)
		(end 345.41206 -405.136858)
		(stroke
			(width 0.07112)
			(type default)
		)
		(layer "In13.Cu")
	)
	(gr_line
		(start 345.203272 -403.407626)
		(end 345.203272 -402.706586)
		(stroke
			(width 0.07112)
			(type default)
		)
		(layer "In13.Cu")
	)
	(gr_line
		(start 345.220798 -408.826716)
		(end 345.691714 -408.307032)
		(stroke
			(width 0.07112)
			(type default)
		)
		(layer "In13.Cu")
	)
	(gr_line
		(start 345.26347 -286.723836)
		(end 345.263978 -286.723582)
		(stroke
			(width 0.05715)
			(type default)
		)
		(layer "In13.Cu")
	)
	(gr_line
		(start 345.272868 -404.230078)
		(end 345.239848 -404.040594)
		(stroke
			(width 0.07112)
			(type default)
		)
		(layer "In13.Cu")
	)
	(gr_line
		(start 345.41206 -405.136858)
		(end 345.638628 -404.860506)
		(stroke
			(width 0.07112)
			(type default)
		)
		(layer "In13.Cu")
	)
	(gr_line
		(start 345.4146 -405.580088)
		(end 345.556332 -405.566372)
		(stroke
			(width 0.07112)
			(type default)
		)
		(layer "In13.Cu")
	)
	(gr_line
		(start 345.431364 -409.0162)
		(end 345.623388 -409.006548)
		(stroke
			(width 0.07112)
			(type default)
		)
		(layer "In13.Cu")
	)
	(gr_arc
		(start 345.485212 -403.560534)
		(mid 345.485212 -403.560788)
		(end 345.485212 -403.561042)
		(stroke
			(width 0.07112)
			(type default)
		)
		(layer "In13.Cu")
	)
	(gr_line
		(start 345.486482 -403.406356)
		(end 345.622372 -403.270466)
		(stroke
			(width 0.07112)
			(type default)
		)
		(layer "In13.Cu")
	)
	(gr_line
		(start 345.556332 -405.566372)
		(end 345.870784 -405.182832)
		(stroke
			(width 0.07112)
			(type default)
		)
		(layer "In13.Cu")
	)
	(gr_line
		(start 345.622372 -403.270466)
		(end 345.622372 -402.843746)
		(stroke
			(width 0.07112)
			(type default)
		)
		(layer "In13.Cu")
	)
	(gr_line
		(start 345.622372 -402.843746)
		(end 345.486482 -402.707856)
		(stroke
			(width 0.07112)
			(type default)
		)
		(layer "In13.Cu")
	)
	(gr_line
		(start 345.623388 -409.006548)
		(end 345.910408 -408.690064)
		(stroke
			(width 0.07112)
			(type default)
		)
		(layer "In13.Cu")
	)
	(gr_line
		(start 345.632024 -272.791936)
		(end 345.63304 -272.791428)
		(stroke
			(width 0.05715)
			(type default)
		)
		(layer "In13.Cu")
	)
	(gr_line
		(start 345.649804 -435.489858)
		(end 345.649804 -435.15788)
		(stroke
			(width 0.07112)
			(type default)
		)
		(layer "In13.Cu")
	)
	(gr_line
		(start 345.649804 -435.15788)
		(end 345.522804 -435.03088)
		(stroke
			(width 0.07112)
			(type default)
		)
		(layer "In13.Cu")
	)
	(gr_line
		(start 345.649804 -434.62194)
		(end 345.522804 -434.74894)
		(stroke
			(width 0.07112)
			(type default)
		)
		(layer "In13.Cu")
	)
	(gr_line
		(start 345.649804 -434.289962)
		(end 345.649804 -434.62194)
		(stroke
			(width 0.07112)
			(type default)
		)
		(layer "In13.Cu")
	)
	(gr_line
		(start 345.700096 -406.575006)
		(end 346.10421 -406.00122)
		(stroke
			(width 0.07112)
			(type default)
		)
		(layer "In13.Cu")
	)
	(gr_line
		(start 345.726512 -272.957798)
		(end 345.727782 -272.957036)
		(stroke
			(width 0.05715)
			(type default)
		)
		(layer "In13.Cu")
	)
	(gr_line
		(start 345.780106 -295.689528)
		(end 345.780106 -295.67505)
		(stroke
			(width 0.05715)
			(type default)
		)
		(layer "In13.Cu")
	)
	(gr_line
		(start 345.780106 -295.67505)
		(end 345.825826 -295.62933)
		(stroke
			(width 0.05715)
			(type default)
		)
		(layer "In13.Cu")
	)
	(gr_line
		(start 345.80576 -401.399756)
		(end 345.81719 -401.399756)
		(stroke
			(width 0.07112)
			(type default)
		)
		(layer "In13.Cu")
	)
	(gr_line
		(start 345.80703 -401.116546)
		(end 345.94419 -400.979386)
		(stroke
			(width 0.07112)
			(type default)
		)
		(layer "In13.Cu")
	)
	(gr_line
		(start 345.811856 -411.178502)
		(end 346.172536 -410.576776)
		(stroke
			(width 0.07112)
			(type default)
		)
		(layer "In13.Cu")
	)
	(gr_line
		(start 345.81719 -401.399756)
		(end 345.94419 -401.526756)
		(stroke
			(width 0.07112)
			(type default)
		)
		(layer "In13.Cu")
	)
	(gr_line
		(start 345.870784 -405.182832)
		(end 345.857068 -405.0411)
		(stroke
			(width 0.07112)
			(type default)
		)
		(layer "In13.Cu")
	)
	(gr_line
		(start 345.881198 -423.705782)
		(end 346.56141 -423.535094)
		(stroke
			(width 0.07112)
			(type default)
		)
		(layer "In13.Cu")
	)
	(gr_line
		(start 345.910408 -408.690064)
		(end 345.900756 -408.498294)
		(stroke
			(width 0.07112)
			(type default)
		)
		(layer "In13.Cu")
	)
	(gr_line
		(start 345.932252 -406.737058)
		(end 346.12199 -406.704038)
		(stroke
			(width 0.07112)
			(type default)
		)
		(layer "In13.Cu")
	)
	(gr_line
		(start 345.94419 -401.526756)
		(end 345.94419 -401.674838)
		(stroke
			(width 0.07112)
			(type default)
		)
		(layer "In13.Cu")
	)
	(gr_line
		(start 345.94419 -400.979386)
		(end 345.94419 -400.811238)
		(stroke
			(width 0.07112)
			(type default)
		)
		(layer "In13.Cu")
	)
	(gr_line
		(start 345.951048 -423.980102)
		(end 346.116148 -424.078908)
		(stroke
			(width 0.07112)
			(type default)
		)
		(layer "In13.Cu")
	)
	(gr_line
		(start 345.981782 -422.553892)
		(end 345.981782 -422.553638)
		(stroke
			(width 0.07112)
			(type default)
		)
		(layer "In13.Cu")
	)
	(gr_line
		(start 345.981782 -422.553638)
		(end 346.65793 -422.366694)
		(stroke
			(width 0.07112)
			(type default)
		)
		(layer "In13.Cu")
	)
	(gr_line
		(start 346.055442 -411.323028)
		(end 346.242132 -411.276292)
		(stroke
			(width 0.07112)
			(type default)
		)
		(layer "In13.Cu")
	)
	(gr_line
		(start 346.057982 -422.826434)
		(end 346.22613 -422.92143)
		(stroke
			(width 0.07112)
			(type default)
		)
		(layer "In13.Cu")
	)
	(gr_arc
		(start 346.058236 -286.588962)
		(mid 346.056837 -286.590102)
		(end 346.055442 -286.591248)
		(stroke
			(width 0.05715)
			(type default)
		)
		(layer "In13.Cu")
	)
	(gr_line
		(start 346.059252 -286.588454)
		(end 346.05976 -286.587946)
		(stroke
			(width 0.05715)
			(type default)
		)
		(layer "In13.Cu")
	)
	(gr_line
		(start 346.05976 -286.587946)
		(end 346.060014 -286.587692)
		(stroke
			(width 0.05715)
			(type default)
		)
		(layer "In13.Cu")
	)
	(gr_line
		(start 346.060014 -286.587692)
		(end 346.066872 -286.58312)
		(stroke
			(width 0.05715)
			(type default)
		)
		(layer "In13.Cu")
	)
	(gr_line
		(start 346.062046 -295.689528)
		(end 346.062046 -295.67505)
		(stroke
			(width 0.05715)
			(type default)
		)
		(layer "In13.Cu")
	)
	(gr_line
		(start 346.062046 -295.67505)
		(end 346.016326 -295.62933)
		(stroke
			(width 0.05715)
			(type default)
		)
		(layer "In13.Cu")
	)
	(gr_line
		(start 346.066872 -286.58312)
		(end 346.067888 -286.582358)
		(stroke
			(width 0.05715)
			(type default)
		)
		(layer "In13.Cu")
	)
	(gr_line
		(start 346.071444 -286.579818)
		(end 346.078302 -286.576008)
		(stroke
			(width 0.05715)
			(type default)
		)
		(layer "In13.Cu")
	)
	(gr_line
		(start 346.116148 -424.078908)
		(end 346.530422 -423.975276)
		(stroke
			(width 0.07112)
			(type default)
		)
		(layer "In13.Cu")
	)
	(gr_line
		(start 346.12199 -406.704038)
		(end 346.367862 -406.354788)
		(stroke
			(width 0.07112)
			(type default)
		)
		(layer "In13.Cu")
	)
	(gr_line
		(start 346.173806 -286.741108)
		(end 346.173806 -286.740854)
		(stroke
			(width 0.05715)
			(type default)
		)
		(layer "In13.Cu")
	)
	(gr_line
		(start 346.204032 -272.143474)
		(end 346.20454 -272.14322)
		(stroke
			(width 0.05715)
			(type default)
		)
		(layer "In13.Cu")
	)
	(gr_line
		(start 346.219018 -273.27606)
		(end 345.921076 -273.27606)
		(stroke
			(width 0.05715)
			(type default)
		)
		(layer "In13.Cu")
	)
	(gr_line
		(start 346.219018 -271.656048)
		(end 345.921076 -271.656048)
		(stroke
			(width 0.05715)
			(type default)
		)
		(layer "In13.Cu")
	)
	(gr_line
		(start 346.219018 -270.036036)
		(end 345.921076 -270.036036)
		(stroke
			(width 0.05715)
			(type default)
		)
		(layer "In13.Cu")
	)
	(gr_line
		(start 346.22613 -422.92143)
		(end 346.63761 -422.807638)
		(stroke
			(width 0.07112)
			(type default)
		)
		(layer "In13.Cu")
	)
	(gr_line
		(start 346.234512 -272.125694)
		(end 346.235274 -272.125186)
		(stroke
			(width 0.05715)
			(type default)
		)
		(layer "In13.Cu")
	)
	(gr_line
		(start 346.235274 -272.125186)
		(end 346.243148 -272.120614)
		(stroke
			(width 0.05715)
			(type default)
		)
		(layer "In13.Cu")
	)
	(gr_line
		(start 346.242132 -411.276292)
		(end 346.461588 -410.910024)
		(stroke
			(width 0.07112)
			(type default)
		)
		(layer "In13.Cu")
	)
	(gr_arc
		(start 346.244164 -272.119852)
		(mid 346.243656 -272.120233)
		(end 346.243148 -272.120614)
		(stroke
			(width 0.05715)
			(type default)
		)
		(layer "In13.Cu")
	)
	(gr_arc
		(start 346.245688 -272.118836)
		(mid 346.248871 -272.116561)
		(end 346.252038 -272.114264)
		(stroke
			(width 0.05715)
			(type default)
		)
		(layer "In13.Cu")
	)
	(gr_line
		(start 346.28836 -273.345402)
		(end 346.219018 -273.27606)
		(stroke
			(width 0.05715)
			(type default)
		)
		(layer "In13.Cu")
	)
	(gr_line
		(start 346.28836 -271.72539)
		(end 346.219018 -271.656048)
		(stroke
			(width 0.05715)
			(type default)
		)
		(layer "In13.Cu")
	)
	(gr_line
		(start 346.301822 -270.11884)
		(end 346.219018 -270.036036)
		(stroke
			(width 0.05715)
			(type default)
		)
		(layer "In13.Cu")
	)
	(gr_arc
		(start 346.301822 -270.11884)
		(mid 346.303613 -270.130162)
		(end 346.305632 -270.141446)
		(stroke
			(width 0.05715)
			(type default)
		)
		(layer "In13.Cu")
	)
	(gr_line
		(start 346.349828 -405.652478)
		(end 346.753688 -405.0792)
		(stroke
			(width 0.07112)
			(type default)
		)
		(layer "In13.Cu")
	)
	(gr_line
		(start 346.367862 -406.354788)
		(end 346.335096 -406.16505)
		(stroke
			(width 0.07112)
			(type default)
		)
		(layer "In13.Cu")
	)
	(gr_line
		(start 346.403168 -403.495002)
		(end 346.403168 -402.793962)
		(stroke
			(width 0.07112)
			(type default)
		)
		(layer "In13.Cu")
	)
	(gr_line
		(start 346.461588 -410.910024)
		(end 346.414852 -410.723588)
		(stroke
			(width 0.07112)
			(type default)
		)
		(layer "In13.Cu")
	)
	(gr_line
		(start 346.474034 -372.911624)
		(end 346.474034 -372.911878)
		(stroke
			(width 0.07112)
			(type default)
		)
		(layer "In13.Cu")
	)
	(gr_arc
		(start 346.476574 -273.381724)
		(mid 346.478596 -273.370313)
		(end 346.480384 -273.358864)
		(stroke
			(width 0.05715)
			(type default)
		)
		(layer "In13.Cu")
	)
	(gr_arc
		(start 346.476574 -271.761712)
		(mid 346.478595 -271.750301)
		(end 346.480384 -271.738852)
		(stroke
			(width 0.05715)
			(type default)
		)
		(layer "In13.Cu")
	)
	(gr_line
		(start 346.480384 -273.358864)
		(end 346.563188 -273.27606)
		(stroke
			(width 0.05715)
			(type default)
		)
		(layer "In13.Cu")
	)
	(gr_line
		(start 346.480384 -271.738852)
		(end 346.563188 -271.656048)
		(stroke
			(width 0.05715)
			(type default)
		)
		(layer "In13.Cu")
	)
	(gr_line
		(start 346.493846 -270.105378)
		(end 346.563188 -270.036036)
		(stroke
			(width 0.05715)
			(type default)
		)
		(layer "In13.Cu")
	)
	(gr_line
		(start 346.530422 -423.975276)
		(end 346.628974 -423.810176)
		(stroke
			(width 0.07112)
			(type default)
		)
		(layer "In13.Cu")
	)
	(gr_line
		(start 346.55125 -409.945078)
		(end 346.911676 -409.343352)
		(stroke
			(width 0.07112)
			(type default)
		)
		(layer "In13.Cu")
	)
	(gr_line
		(start 346.563188 -273.27606)
		(end 346.86113 -273.27606)
		(stroke
			(width 0.05715)
			(type default)
		)
		(layer "In13.Cu")
	)
	(gr_line
		(start 346.563188 -271.656048)
		(end 346.86113 -271.656048)
		(stroke
			(width 0.05715)
			(type default)
		)
		(layer "In13.Cu")
	)
	(gr_line
		(start 346.563188 -270.036036)
		(end 346.86113 -270.036036)
		(stroke
			(width 0.05715)
			(type default)
		)
		(layer "In13.Cu")
	)
	(gr_line
		(start 346.58173 -405.814784)
		(end 346.771468 -405.781764)
		(stroke
			(width 0.07112)
			(type default)
		)
		(layer "In13.Cu")
	)
	(gr_line
		(start 346.586048 -270.528034)
		(end 346.584524 -270.527272)
		(stroke
			(width 0.05715)
			(type default)
		)
		(layer "In13.Cu")
	)
	(gr_line
		(start 346.63761 -422.807638)
		(end 346.732606 -422.639744)
		(stroke
			(width 0.07112)
			(type default)
		)
		(layer "In13.Cu")
	)
	(gr_line
		(start 346.686378 -403.493732)
		(end 346.822268 -403.357842)
		(stroke
			(width 0.07112)
			(type default)
		)
		(layer "In13.Cu")
	)
	(gr_line
		(start 346.714826 -295.88968)
		(end 346.714826 -295.861232)
		(stroke
			(width 0.05715)
			(type default)
		)
		(layer "In13.Cu")
	)
	(gr_line
		(start 346.714826 -295.861232)
		(end 346.760546 -295.815512)
		(stroke
			(width 0.05715)
			(type default)
		)
		(layer "In13.Cu")
	)
	(gr_line
		(start 346.771468 -405.781764)
		(end 347.01734 -405.432768)
		(stroke
			(width 0.07112)
			(type default)
		)
		(layer "In13.Cu")
	)
	(gr_line
		(start 346.794582 -410.089604)
		(end 346.981526 -410.042868)
		(stroke
			(width 0.07112)
			(type default)
		)
		(layer "In13.Cu")
	)
	(gr_line
		(start 346.822268 -403.357842)
		(end 346.822268 -402.931122)
		(stroke
			(width 0.07112)
			(type default)
		)
		(layer "In13.Cu")
	)
	(gr_line
		(start 346.822268 -402.931122)
		(end 346.686378 -402.795232)
		(stroke
			(width 0.07112)
			(type default)
		)
		(layer "In13.Cu")
	)
	(gr_line
		(start 346.956634 -288.66592)
		(end 346.95638 -288.66592)
		(stroke
			(width 0.05715)
			(type default)
		)
		(layer "In13.Cu")
	)
	(gr_line
		(start 346.970096 -417.930584)
		(end 346.970096 -417.229544)
		(stroke
			(width 0.07112)
			(type default)
		)
		(layer "In13.Cu")
	)
	(gr_line
		(start 346.970096 -416.802824)
		(end 346.970096 -416.101784)
		(stroke
			(width 0.07112)
			(type default)
		)
		(layer "In13.Cu")
	)
	(gr_line
		(start 346.981526 -410.042868)
		(end 347.200728 -409.6766)
		(stroke
			(width 0.07112)
			(type default)
		)
		(layer "In13.Cu")
	)
	(gr_arc
		(start 346.996004 -276.870922)
		(mid 346.994478 -276.872063)
		(end 346.992956 -276.873208)
		(stroke
			(width 0.05715)
			(type default)
		)
		(layer "In13.Cu")
	)
	(gr_line
		(start 346.996766 -295.88968)
		(end 346.996766 -295.861232)
		(stroke
			(width 0.05715)
			(type default)
		)
		(layer "In13.Cu")
	)
	(gr_line
		(start 346.996766 -295.861232)
		(end 346.951046 -295.815512)
		(stroke
			(width 0.05715)
			(type default)
		)
		(layer "In13.Cu")
	)
	(gr_arc
		(start 347.001084 -279.402286)
		(mid 347.004125 -279.404455)
		(end 347.00718 -279.406604)
		(stroke
			(width 0.05715)
			(type default)
		)
		(layer "In13.Cu")
	)
	(gr_arc
		(start 347.003878 -277.7871)
		(mid 347.01045 -277.791592)
		(end 347.017086 -277.79599)
		(stroke
			(width 0.05715)
			(type default)
		)
		(layer "In13.Cu")
	)
	(gr_line
		(start 347.005148 -404.722076)
		(end 347.409008 -404.148544)
		(stroke
			(width 0.07112)
			(type default)
		)
		(layer "In13.Cu")
	)
	(gr_line
		(start 347.005656 -401.399756)
		(end 347.017086 -401.399756)
		(stroke
			(width 0.07112)
			(type default)
		)
		(layer "In13.Cu")
	)
	(gr_line
		(start 347.006926 -401.116546)
		(end 347.144086 -400.979386)
		(stroke
			(width 0.07112)
			(type default)
		)
		(layer "In13.Cu")
	)
	(gr_arc
		(start 347.009212 -271.30756)
		(mid 347.012253 -271.309602)
		(end 347.015308 -271.311624)
		(stroke
			(width 0.05715)
			(type default)
		)
		(layer "In13.Cu")
	)
	(gr_arc
		(start 347.009974 -281.723592)
		(mid 347.006408 -281.726118)
		(end 347.002862 -281.728672)
		(stroke
			(width 0.05715)
			(type default)
		)
		(layer "In13.Cu")
	)
	(gr_arc
		(start 347.011752 -276.859746)
		(mid 347.004729 -276.864646)
		(end 346.997782 -276.869652)
		(stroke
			(width 0.05715)
			(type default)
		)
		(layer "In13.Cu")
	)
	(gr_line
		(start 347.011752 -276.859746)
		(end 347.013022 -276.86)
		(stroke
			(width 0.05715)
			(type default)
		)
		(layer "In13.Cu")
	)
	(gr_line
		(start 347.013022 -276.86)
		(end 347.014038 -276.859492)
		(stroke
			(width 0.05715)
			(type default)
		)
		(layer "In13.Cu")
	)
	(gr_arc
		(start 347.014546 -289.82035)
		(mid 347.005595 -289.826615)
		(end 346.996766 -289.83305)
		(stroke
			(width 0.05715)
			(type default)
		)
		(layer "In13.Cu")
	)
	(gr_line
		(start 347.015308 -281.72029)
		(end 347.015054 -281.720544)
		(stroke
			(width 0.05715)
			(type default)
		)
		(layer "In13.Cu")
	)
	(gr_line
		(start 347.017086 -401.399756)
		(end 347.144086 -401.526756)
		(stroke
			(width 0.07112)
			(type default)
		)
		(layer "In13.Cu")
	)
	(gr_line
		(start 347.01734 -405.432768)
		(end 346.984574 -405.24303)
		(stroke
			(width 0.07112)
			(type default)
		)
		(layer "In13.Cu")
	)
	(gr_line
		(start 347.017594 -271.313148)
		(end 347.015308 -271.311624)
		(stroke
			(width 0.05715)
			(type default)
		)
		(layer "In13.Cu")
	)
	(gr_line
		(start 347.021658 -289.816032)
		(end 347.048074 -289.798252)
		(stroke
			(width 0.05715)
			(type default)
		)
		(layer "In13.Cu")
	)
	(gr_line
		(start 347.024452 -271.317212)
		(end 347.017594 -271.313148)
		(stroke
			(width 0.05715)
			(type default)
		)
		(layer "In13.Cu")
	)
	(gr_arc
		(start 347.02496 -277.801324)
		(mid 347.051712 -277.817445)
		(end 347.079316 -277.832058)
		(stroke
			(width 0.05715)
			(type default)
		)
		(layer "In13.Cu")
	)
	(gr_line
		(start 347.038168 -281.704796)
		(end 347.048074 -281.698192)
		(stroke
			(width 0.05715)
			(type default)
		)
		(layer "In13.Cu")
	)
	(gr_line
		(start 347.03893 -273.604482)
		(end 347.048328 -273.598386)
		(stroke
			(width 0.05715)
			(type default)
		)
		(layer "In13.Cu")
	)
	(gr_line
		(start 347.042486 -279.429972)
		(end 347.04274 -279.430226)
		(stroke
			(width 0.05715)
			(type default)
		)
		(layer "In13.Cu")
	)
	(gr_line
		(start 347.04274 -279.430226)
		(end 347.038168 -279.427178)
		(stroke
			(width 0.05715)
			(type default)
		)
		(layer "In13.Cu")
	)
	(gr_line
		(start 347.04401 -275.220684)
		(end 347.050106 -275.217128)
		(stroke
			(width 0.05715)
			(type default)
		)
		(layer "In13.Cu")
	)
	(gr_line
		(start 347.046296 -280.079958)
		(end 347.050614 -280.077164)
		(stroke
			(width 0.05715)
			(type default)
		)
		(layer "In13.Cu")
	)
	(gr_line
		(start 347.048074 -289.798252)
		(end 347.049598 -289.79749)
		(stroke
			(width 0.05715)
			(type default)
		)
		(layer "In13.Cu")
	)
	(gr_line
		(start 347.048074 -281.698192)
		(end 347.053154 -281.695652)
		(stroke
			(width 0.05715)
			(type default)
		)
		(layer "In13.Cu")
	)
	(gr_line
		(start 347.048074 -279.433274)
		(end 347.042486 -279.429972)
		(stroke
			(width 0.05715)
			(type default)
		)
		(layer "In13.Cu")
	)
	(gr_line
		(start 347.048328 -284.93847)
		(end 347.051122 -284.936946)
		(stroke
			(width 0.05715)
			(type default)
		)
		(layer "In13.Cu")
	)
	(gr_line
		(start 347.048328 -284.295342)
		(end 347.044772 -284.29331)
		(stroke
			(width 0.05715)
			(type default)
		)
		(layer "In13.Cu")
	)
	(gr_line
		(start 347.048328 -283.318458)
		(end 347.049852 -283.317696)
		(stroke
			(width 0.05715)
			(type default)
		)
		(layer "In13.Cu")
	)
	(gr_line
		(start 347.048328 -273.598386)
		(end 347.049598 -273.597624)
		(stroke
			(width 0.05715)
			(type default)
		)
		(layer "In13.Cu")
	)
	(gr_line
		(start 347.048582 -283.318712)
		(end 347.048328 -283.318458)
		(stroke
			(width 0.05715)
			(type default)
		)
		(layer "In13.Cu")
	)
	(gr_line
		(start 347.049344 -290.778184)
		(end 347.048328 -290.777676)
		(stroke
			(width 0.05715)
			(type default)
		)
		(layer "In13.Cu")
	)
	(gr_line
		(start 347.049598 -289.79749)
		(end 347.053662 -289.79749)
		(stroke
			(width 0.05715)
			(type default)
		)
		(layer "In13.Cu")
	)
	(gr_line
		(start 347.049598 -273.597624)
		(end 347.058488 -273.593306)
		(stroke
			(width 0.05715)
			(type default)
		)
		(layer "In13.Cu")
	)
	(gr_line
		(start 347.049852 -283.317696)
		(end 347.051122 -283.316934)
		(stroke
			(width 0.05715)
			(type default)
		)
		(layer "In13.Cu")
	)
	(gr_line
		(start 347.05036 -280.077164)
		(end 347.05671 -280.073608)
		(stroke
			(width 0.05715)
			(type default)
		)
		(layer "In13.Cu")
	)
	(gr_line
		(start 347.050614 -280.077164)
		(end 347.05036 -280.077164)
		(stroke
			(width 0.05715)
			(type default)
		)
		(layer "In13.Cu")
	)
	(gr_line
		(start 347.051122 -284.936946)
		(end 347.058488 -284.93339)
		(stroke
			(width 0.05715)
			(type default)
		)
		(layer "In13.Cu")
	)
	(gr_line
		(start 347.051122 -283.316934)
		(end 347.052646 -283.316172)
		(stroke
			(width 0.05715)
			(type default)
		)
		(layer "In13.Cu")
	)
	(gr_line
		(start 347.052646 -288.176208)
		(end 347.052646 -288.176462)
		(stroke
			(width 0.05715)
			(type default)
		)
		(layer "In13.Cu")
	)
	(gr_line
		(start 347.053154 -281.695652)
		(end 347.057472 -281.693366)
		(stroke
			(width 0.05715)
			(type default)
		)
		(layer "In13.Cu")
	)
	(gr_line
		(start 347.053662 -291.41547)
		(end 347.062044 -291.41039)
		(stroke
			(width 0.05715)
			(type default)
		)
		(layer "In13.Cu")
	)
	(gr_line
		(start 347.061028 -278.44877)
		(end 347.073474 -278.441658)
		(stroke
			(width 0.05715)
			(type default)
		)
		(layer "In13.Cu")
	)
	(gr_line
		(start 347.062806 -291.409882)
		(end 347.06433 -291.408866)
		(stroke
			(width 0.05715)
			(type default)
		)
		(layer "In13.Cu")
	)
	(gr_line
		(start 347.063314 -281.689556)
		(end 347.064584 -281.688286)
		(stroke
			(width 0.05715)
			(type default)
		)
		(layer "In13.Cu")
	)
	(gr_line
		(start 347.064584 -281.688286)
		(end 347.065854 -281.688286)
		(stroke
			(width 0.05715)
			(type default)
		)
		(layer "In13.Cu")
	)
	(gr_line
		(start 347.069156 -422.252902)
		(end 347.745304 -422.065704)
		(stroke
			(width 0.07112)
			(type default)
		)
		(layer "In13.Cu")
	)
	(gr_arc
		(start 347.072966 -291.40404)
		(mid 347.073347 -291.403914)
		(end 347.073728 -291.403786)
		(stroke
			(width 0.05715)
			(type default)
		)
		(layer "In13.Cu")
	)
	(gr_line
		(start 347.082618 -294.633904)
		(end 347.098366 -294.62476)
		(stroke
			(width 0.05715)
			(type default)
		)
		(layer "In13.Cu")
	)
	(gr_line
		(start 347.089476 -291.393118)
		(end 347.088968 -291.393372)
		(stroke
			(width 0.05715)
			(type default)
		)
		(layer "In13.Cu")
	)
	(gr_line
		(start 347.119448 -289.980878)
		(end 347.150944 -289.96259)
		(stroke
			(width 0.05715)
			(type default)
		)
		(layer "In13.Cu")
	)
	(gr_line
		(start 347.12021 -281.879548)
		(end 347.124274 -281.876754)
		(stroke
			(width 0.05715)
			(type default)
		)
		(layer "In13.Cu")
	)
	(gr_line
		(start 347.125798 -279.25649)
		(end 347.121734 -279.253696)
		(stroke
			(width 0.05715)
			(type default)
		)
		(layer "In13.Cu")
	)
	(gr_line
		(start 347.131132 -408.977592)
		(end 347.491558 -408.37612)
		(stroke
			(width 0.07112)
			(type default)
		)
		(layer "In13.Cu")
	)
	(gr_line
		(start 347.142562 -284.129226)
		(end 347.142054 -284.128972)
		(stroke
			(width 0.05715)
			(type default)
		)
		(layer "In13.Cu")
	)
	(gr_line
		(start 347.143578 -277.64867)
		(end 347.126052 -277.638256)
		(stroke
			(width 0.05715)
			(type default)
		)
		(layer "In13.Cu")
	)
	(gr_line
		(start 347.144086 -401.526756)
		(end 347.144086 -401.674838)
		(stroke
			(width 0.07112)
			(type default)
		)
		(layer "In13.Cu")
	)
	(gr_line
		(start 347.144086 -400.979386)
		(end 347.144086 -400.811238)
		(stroke
			(width 0.07112)
			(type default)
		)
		(layer "In13.Cu")
	)
	(gr_line
		(start 347.144086 -276.028658)
		(end 347.143324 -276.02815)
		(stroke
			(width 0.05715)
			(type default)
		)
		(layer "In13.Cu")
	)
	(gr_line
		(start 347.14434 -422.524936)
		(end 347.14434 -422.52519)
		(stroke
			(width 0.07112)
			(type default)
		)
		(layer "In13.Cu")
	)
	(gr_line
		(start 347.145102 -276.029166)
		(end 347.144086 -276.028658)
		(stroke
			(width 0.05715)
			(type default)
		)
		(layer "In13.Cu")
	)
	(gr_line
		(start 347.145356 -284.131004)
		(end 347.142562 -284.129226)
		(stroke
			(width 0.05715)
			(type default)
		)
		(layer "In13.Cu")
	)
	(gr_line
		(start 347.145356 -277.64867)
		(end 347.143578 -277.64867)
		(stroke
			(width 0.05715)
			(type default)
		)
		(layer "In13.Cu")
	)
	(gr_line
		(start 347.145864 -422.525444)
		(end 347.313758 -422.62044)
		(stroke
			(width 0.07112)
			(type default)
		)
		(layer "In13.Cu")
	)
	(gr_line
		(start 347.145864 -288.342578)
		(end 347.148658 -288.341054)
		(stroke
			(width 0.05715)
			(type default)
		)
		(layer "In13.Cu")
	)
	(gr_line
		(start 347.146626 -291.582856)
		(end 347.14815 -291.58184)
		(stroke
			(width 0.05715)
			(type default)
		)
		(layer "In13.Cu")
	)
	(gr_line
		(start 347.146626 -276.030436)
		(end 347.146626 -276.030182)
		(stroke
			(width 0.05715)
			(type default)
		)
		(layer "In13.Cu")
	)
	(gr_line
		(start 347.146626 -276.030182)
		(end 347.145102 -276.029166)
		(stroke
			(width 0.05715)
			(type default)
		)
		(layer "In13.Cu")
	)
	(gr_line
		(start 347.148404 -276.031452)
		(end 347.146626 -276.030436)
		(stroke
			(width 0.05715)
			(type default)
		)
		(layer "In13.Cu")
	)
	(gr_line
		(start 347.148658 -284.133036)
		(end 347.145356 -284.131004)
		(stroke
			(width 0.05715)
			(type default)
		)
		(layer "In13.Cu")
	)
	(gr_line
		(start 347.15069 -283.479748)
		(end 347.15323 -283.478478)
		(stroke
			(width 0.05715)
			(type default)
		)
		(layer "In13.Cu")
	)
	(gr_line
		(start 347.153992 -276.035008)
		(end 347.148404 -276.031452)
		(stroke
			(width 0.05715)
			(type default)
		)
		(layer "In13.Cu")
	)
	(gr_line
		(start 347.154246 -283.477716)
		(end 347.158056 -283.475684)
		(stroke
			(width 0.05715)
			(type default)
		)
		(layer "In13.Cu")
	)
	(gr_line
		(start 347.155262 -281.857958)
		(end 347.156532 -281.85745)
		(stroke
			(width 0.05715)
			(type default)
		)
		(layer "In13.Cu")
	)
	(gr_line
		(start 347.156532 -281.85745)
		(end 347.159834 -281.855418)
		(stroke
			(width 0.05715)
			(type default)
		)
		(layer "In13.Cu")
	)
	(gr_line
		(start 347.157548 -278.614632)
		(end 347.158564 -278.614124)
		(stroke
			(width 0.05715)
			(type default)
		)
		(layer "In13.Cu")
	)
	(gr_line
		(start 347.158564 -278.614124)
		(end 347.161358 -278.612346)
		(stroke
			(width 0.05715)
			(type default)
		)
		(layer "In13.Cu")
	)
	(gr_line
		(start 347.159834 -281.855418)
		(end 347.16085 -281.85491)
		(stroke
			(width 0.05715)
			(type default)
		)
		(layer "In13.Cu")
	)
	(gr_line
		(start 347.16085 -281.85491)
		(end 347.164914 -281.85237)
		(stroke
			(width 0.05715)
			(type default)
		)
		(layer "In13.Cu")
	)
	(gr_line
		(start 347.161358 -278.612346)
		(end 347.169486 -278.60752)
		(stroke
			(width 0.05715)
			(type default)
		)
		(layer "In13.Cu")
	)
	(gr_line
		(start 347.164914 -281.85237)
		(end 347.16593 -281.851862)
		(stroke
			(width 0.05715)
			(type default)
		)
		(layer "In13.Cu")
	)
	(gr_line
		(start 347.170756 -280.22804)
		(end 347.180154 -280.222706)
		(stroke
			(width 0.05715)
			(type default)
		)
		(layer "In13.Cu")
	)
	(gr_line
		(start 347.1799 -278.601424)
		(end 347.182186 -278.600154)
		(stroke
			(width 0.05715)
			(type default)
		)
		(layer "In13.Cu")
	)
	(gr_arc
		(start 347.180154 -280.222706)
		(mid 347.181678 -280.221691)
		(end 347.183202 -280.220674)
		(stroke
			(width 0.05715)
			(type default)
		)
		(layer "In13.Cu")
	)
	(gr_line
		(start 347.182186 -278.600154)
		(end 347.182948 -278.599646)
		(stroke
			(width 0.05715)
			(type default)
		)
		(layer "In13.Cu")
	)
	(gr_arc
		(start 347.182948 -278.599646)
		(mid 347.189457 -278.59512)
		(end 347.195902 -278.590502)
		(stroke
			(width 0.05715)
			(type default)
		)
		(layer "In13.Cu")
	)
	(gr_line
		(start 347.182948 -277.670514)
		(end 347.145356 -277.64867)
		(stroke
			(width 0.05715)
			(type default)
		)
		(layer "In13.Cu")
	)
	(gr_arc
		(start 347.183202 -280.220674)
		(mid 347.187151 -280.217897)
		(end 347.191076 -280.215086)
		(stroke
			(width 0.05715)
			(type default)
		)
		(layer "In13.Cu")
	)
	(gr_arc
		(start 347.188536 -274.438618)
		(mid 347.185748 -274.436577)
		(end 347.182948 -274.434554)
		(stroke
			(width 0.05715)
			(type default)
		)
		(layer "In13.Cu")
	)
	(gr_arc
		(start 347.19006 -273.738848)
		(mid 347.19401 -273.735817)
		(end 347.197934 -273.732752)
		(stroke
			(width 0.05715)
			(type default)
		)
		(layer "In13.Cu")
	)
	(gr_arc
		(start 347.1926 -285.077662)
		(mid 347.196678 -285.074632)
		(end 347.200728 -285.071566)
		(stroke
			(width 0.05715)
			(type default)
		)
		(layer "In13.Cu")
	)
	(gr_arc
		(start 347.19768 -278.589232)
		(mid 347.199715 -278.587713)
		(end 347.201744 -278.586184)
		(stroke
			(width 0.05715)
			(type default)
		)
		(layer "In13.Cu")
	)
	(gr_arc
		(start 347.198188 -277.681436)
		(mid 347.190613 -277.675913)
		(end 347.182948 -277.670514)
		(stroke
			(width 0.05715)
			(type default)
		)
		(layer "In13.Cu")
	)
	(gr_line
		(start 347.200728 -409.6766)
		(end 347.154246 -409.48991)
		(stroke
			(width 0.07112)
			(type default)
		)
		(layer "In13.Cu")
	)
	(gr_line
		(start 347.205808 -291.543994)
		(end 347.207332 -291.542978)
		(stroke
			(width 0.05715)
			(type default)
		)
		(layer "In13.Cu")
	)
	(gr_line
		(start 347.208856 -292.271958)
		(end 347.208856 -292.271704)
		(stroke
			(width 0.05715)
			(type default)
		)
		(layer "In13.Cu")
	)
	(gr_line
		(start 347.237304 -404.884128)
		(end 347.427042 -404.851108)
		(stroke
			(width 0.07112)
			(type default)
		)
		(layer "In13.Cu")
	)
	(gr_line
		(start 347.253306 -417.929314)
		(end 347.389196 -417.793424)
		(stroke
			(width 0.07112)
			(type default)
		)
		(layer "In13.Cu")
	)
	(gr_line
		(start 347.253306 -416.801554)
		(end 347.389196 -416.665664)
		(stroke
			(width 0.07112)
			(type default)
		)
		(layer "In13.Cu")
	)
	(gr_line
		(start 347.313758 -422.62044)
		(end 347.725238 -422.506648)
		(stroke
			(width 0.07112)
			(type default)
		)
		(layer "In13.Cu")
	)
	(gr_line
		(start 347.374464 -409.122118)
		(end 347.561408 -409.075382)
		(stroke
			(width 0.07112)
			(type default)
		)
		(layer "In13.Cu")
	)
	(gr_line
		(start 347.389196 -417.793424)
		(end 347.389196 -417.366704)
		(stroke
			(width 0.07112)
			(type default)
		)
		(layer "In13.Cu")
	)
	(gr_line
		(start 347.389196 -417.366704)
		(end 347.253306 -417.230814)
		(stroke
			(width 0.07112)
			(type default)
		)
		(layer "In13.Cu")
	)
	(gr_line
		(start 347.389196 -416.665664)
		(end 347.389196 -416.238944)
		(stroke
			(width 0.07112)
			(type default)
		)
		(layer "In13.Cu")
	)
	(gr_line
		(start 347.389196 -416.238944)
		(end 347.253306 -416.103054)
		(stroke
			(width 0.07112)
			(type default)
		)
		(layer "In13.Cu")
	)
	(gr_line
		(start 347.424502 -271.652746)
		(end 347.424248 -271.653)
		(stroke
			(width 0.05715)
			(type default)
		)
		(layer "In13.Cu")
	)
	(gr_line
		(start 347.427042 -404.851108)
		(end 347.672914 -404.502112)
		(stroke
			(width 0.07112)
			(type default)
		)
		(layer "In13.Cu")
	)
	(gr_line
		(start 347.491558 -408.375866)
		(end 347.491558 -408.37612)
		(stroke
			(width 0.07112)
			(type default)
		)
		(layer "In13.Cu")
	)
	(gr_line
		(start 347.491812 -408.375866)
		(end 347.491558 -408.375866)
		(stroke
			(width 0.07112)
			(type default)
		)
		(layer "In13.Cu")
	)
	(gr_arc
		(start 347.51137 -272.13941)
		(mid 347.512512 -272.140173)
		(end 347.513656 -272.140934)
		(stroke
			(width 0.05715)
			(type default)
		)
		(layer "In13.Cu")
	)
	(gr_line
		(start 347.51772 -272.14322)
		(end 347.513656 -272.140934)
		(stroke
			(width 0.05715)
			(type default)
		)
		(layer "In13.Cu")
	)
	(gr_line
		(start 347.561408 -409.075382)
		(end 347.780864 -408.709114)
		(stroke
			(width 0.07112)
			(type default)
		)
		(layer "In13.Cu")
	)
	(gr_line
		(start 347.610938 -272.955258)
		(end 347.6117 -272.95475)
		(stroke
			(width 0.05715)
			(type default)
		)
		(layer "In13.Cu")
	)
	(gr_arc
		(start 347.655642 -272.928842)
		(mid 347.658441 -272.926945)
		(end 347.66123 -272.925032)
		(stroke
			(width 0.05715)
			(type default)
		)
		(layer "In13.Cu")
	)
	(gr_line
		(start 347.660214 -295.853358)
		(end 347.660214 -295.83888)
		(stroke
			(width 0.05715)
			(type default)
		)
		(layer "In13.Cu")
	)
	(gr_line
		(start 347.660214 -295.83888)
		(end 347.705934 -295.79316)
		(stroke
			(width 0.05715)
			(type default)
		)
		(layer "In13.Cu")
	)
	(gr_line
		(start 347.672914 -404.502112)
		(end 347.639894 -404.312628)
		(stroke
			(width 0.07112)
			(type default)
		)
		(layer "In13.Cu")
	)
	(gr_line
		(start 347.680026 -423.223182)
		(end 348.346014 -423.003218)
		(stroke
			(width 0.07112)
			(type default)
		)
		(layer "In13.Cu")
	)
	(gr_line
		(start 347.705934 -295.131236)
		(end 347.705934 -295.112186)
		(stroke
			(width 0.05715)
			(type default)
		)
		(layer "In13.Cu")
	)
	(gr_line
		(start 347.705934 -295.108884)
		(end 347.705934 -295.101264)
		(stroke
			(width 0.05715)
			(type default)
		)
		(layer "In13.Cu")
	)
	(gr_line
		(start 347.705934 -295.101264)
		(end 347.70695 -295.099232)
		(stroke
			(width 0.05715)
			(type default)
		)
		(layer "In13.Cu")
	)
	(gr_line
		(start 347.711268 -408.010106)
		(end 348.071948 -407.408634)
		(stroke
			(width 0.07112)
			(type default)
		)
		(layer "In13.Cu")
	)
	(gr_line
		(start 347.711268 -405.64181)
		(end 348.100904 -405.058626)
		(stroke
			(width 0.07112)
			(type default)
		)
		(layer "In13.Cu")
	)
	(gr_line
		(start 347.725238 -422.506648)
		(end 347.81998 -422.338754)
		(stroke
			(width 0.07112)
			(type default)
		)
		(layer "In13.Cu")
	)
	(gr_line
		(start 347.769688 -423.491914)
		(end 347.941646 -423.578274)
		(stroke
			(width 0.07112)
			(type default)
		)
		(layer "In13.Cu")
	)
	(gr_line
		(start 347.780864 -408.709114)
		(end 347.734128 -408.522424)
		(stroke
			(width 0.07112)
			(type default)
		)
		(layer "In13.Cu")
	)
	(gr_line
		(start 347.897704 -295.118536)
		(end 347.898212 -295.113456)
		(stroke
			(width 0.05715)
			(type default)
		)
		(layer "In13.Cu")
	)
	(gr_line
		(start 347.922596 -286.600392)
		(end 347.923104 -286.600138)
		(stroke
			(width 0.05715)
			(type default)
		)
		(layer "In13.Cu")
	)
	(gr_line
		(start 347.941646 -423.578274)
		(end 348.34703 -423.444416)
		(stroke
			(width 0.07112)
			(type default)
		)
		(layer "In13.Cu")
	)
	(gr_line
		(start 347.942154 -295.853358)
		(end 347.942154 -295.83888)
		(stroke
			(width 0.05715)
			(type default)
		)
		(layer "In13.Cu")
	)
	(gr_line
		(start 347.942154 -295.83888)
		(end 347.896434 -295.79316)
		(stroke
			(width 0.05715)
			(type default)
		)
		(layer "In13.Cu")
	)
	(gr_line
		(start 347.942408 -298.07535)
		(end 347.942154 -298.075604)
		(stroke
			(width 0.07112)
			(type default)
		)
		(layer "In13.Cu")
	)
	(gr_line
		(start 347.947234 -405.798274)
		(end 348.135956 -405.760682)
		(stroke
			(width 0.07112)
			(type default)
		)
		(layer "In13.Cu")
	)
	(gr_line
		(start 347.9546 -408.154632)
		(end 348.14129 -408.107896)
		(stroke
			(width 0.07112)
			(type default)
		)
		(layer "In13.Cu")
	)
	(gr_line
		(start 348.135956 -405.760682)
		(end 348.373446 -405.40559)
		(stroke
			(width 0.07112)
			(type default)
		)
		(layer "In13.Cu")
	)
	(gr_line
		(start 348.14129 -408.107896)
		(end 348.360746 -407.741882)
		(stroke
			(width 0.07112)
			(type default)
		)
		(layer "In13.Cu")
	)
	(gr_line
		(start 348.205806 -401.399756)
		(end 348.217236 -401.399756)
		(stroke
			(width 0.07112)
			(type default)
		)
		(layer "In13.Cu")
	)
	(gr_line
		(start 348.207076 -401.116546)
		(end 348.344236 -400.979386)
		(stroke
			(width 0.07112)
			(type default)
		)
		(layer "In13.Cu")
	)
	(gr_line
		(start 348.217236 -401.399756)
		(end 348.344236 -401.526756)
		(stroke
			(width 0.07112)
			(type default)
		)
		(layer "In13.Cu")
	)
	(gr_line
		(start 348.29115 -407.042874)
		(end 348.65183 -406.441402)
		(stroke
			(width 0.07112)
			(type default)
		)
		(layer "In13.Cu")
	)
	(gr_line
		(start 348.344236 -401.526756)
		(end 348.344236 -401.674838)
		(stroke
			(width 0.07112)
			(type default)
		)
		(layer "In13.Cu")
	)
	(gr_line
		(start 348.344236 -400.979386)
		(end 348.344236 -400.811238)
		(stroke
			(width 0.07112)
			(type default)
		)
		(layer "In13.Cu")
	)
	(gr_line
		(start 348.34703 -423.444416)
		(end 348.433644 -423.272458)
		(stroke
			(width 0.07112)
			(type default)
		)
		(layer "In13.Cu")
	)
	(gr_line
		(start 348.360746 -407.741882)
		(end 348.314264 -407.555192)
		(stroke
			(width 0.07112)
			(type default)
		)
		(layer "In13.Cu")
	)
	(gr_line
		(start 348.373446 -405.40559)
		(end 348.335854 -405.216614)
		(stroke
			(width 0.07112)
			(type default)
		)
		(layer "In13.Cu")
	)
	(gr_line
		(start 348.534736 -407.1874)
		(end 348.721426 -407.140664)
		(stroke
			(width 0.07112)
			(type default)
		)
		(layer "In13.Cu")
	)
	(gr_line
		(start 348.600268 -296.367962)
		(end 348.600268 -296.339514)
		(stroke
			(width 0.05715)
			(type default)
		)
		(layer "In13.Cu")
	)
	(gr_line
		(start 348.600268 -296.339514)
		(end 348.645988 -296.293794)
		(stroke
			(width 0.05715)
			(type default)
		)
		(layer "In13.Cu")
	)
	(gr_line
		(start 348.643956 -272.55724)
		(end 348.643956 -272.556732)
		(stroke
			(width 0.05715)
			(type default)
		)
		(layer "In13.Cu")
	)
	(gr_line
		(start 348.64421 -411.482794)
		(end 348.781116 -410.794962)
		(stroke
			(width 0.07112)
			(type default)
		)
		(layer "In13.Cu")
	)
	(gr_line
		(start 348.721426 -407.140664)
		(end 348.940882 -406.774396)
		(stroke
			(width 0.07112)
			(type default)
		)
		(layer "In13.Cu")
	)
	(gr_line
		(start 348.751144 -422.86936)
		(end 349.417132 -422.649396)
		(stroke
			(width 0.07112)
			(type default)
		)
		(layer "In13.Cu")
	)
	(gr_line
		(start 348.799404 -272.718784)
		(end 348.79915 -272.719546)
		(stroke
			(width 0.05715)
			(type default)
		)
		(layer "In13.Cu")
	)
	(gr_line
		(start 348.799658 -272.718276)
		(end 348.799404 -272.718784)
		(stroke
			(width 0.05715)
			(type default)
		)
		(layer "In13.Cu")
	)
	(gr_line
		(start 348.803214 -403.548088)
		(end 348.803214 -402.847048)
		(stroke
			(width 0.07112)
			(type default)
		)
		(layer "In13.Cu")
	)
	(gr_line
		(start 348.840806 -423.138092)
		(end 349.012764 -423.224452)
		(stroke
			(width 0.07112)
			(type default)
		)
		(layer "In13.Cu")
	)
	(gr_line
		(start 348.864174 -410.376624)
		(end 349.000826 -409.688792)
		(stroke
			(width 0.07112)
			(type default)
		)
		(layer "In13.Cu")
	)
	(gr_line
		(start 348.882208 -296.367962)
		(end 348.882208 -296.339514)
		(stroke
			(width 0.05715)
			(type default)
		)
		(layer "In13.Cu")
	)
	(gr_line
		(start 348.882208 -296.339514)
		(end 348.836488 -296.293794)
		(stroke
			(width 0.05715)
			(type default)
		)
		(layer "In13.Cu")
	)
	(gr_arc
		(start 348.88932 -286.581342)
		(mid 348.884604 -286.584619)
		(end 348.879922 -286.587946)
		(stroke
			(width 0.05715)
			(type default)
		)
		(layer "In13.Cu")
	)
	(gr_line
		(start 348.88932 -286.581342)
		(end 348.891352 -286.579818)
		(stroke
			(width 0.05715)
			(type default)
		)
		(layer "In13.Cu")
	)
	(gr_line
		(start 348.891352 -286.579818)
		(end 348.896178 -286.577024)
		(stroke
			(width 0.05715)
			(type default)
		)
		(layer "In13.Cu")
	)
	(gr_line
		(start 348.91853 -405.996902)
		(end 349.27921 -405.39543)
		(stroke
			(width 0.07112)
			(type default)
		)
		(layer "In13.Cu")
	)
	(gr_line
		(start 348.92234 -411.536642)
		(end 349.08236 -411.429962)
		(stroke
			(width 0.07112)
			(type default)
		)
		(layer "In13.Cu")
	)
	(gr_line
		(start 348.927928 -294.658542)
		(end 348.930214 -294.657272)
		(stroke
			(width 0.05715)
			(type default)
		)
		(layer "In13.Cu")
	)
	(gr_line
		(start 348.940882 -406.774396)
		(end 348.8944 -406.58796)
		(stroke
			(width 0.07112)
			(type default)
		)
		(layer "In13.Cu")
	)
	(gr_line
		(start 349.012764 -423.224452)
		(end 349.418148 -423.090848)
		(stroke
			(width 0.07112)
			(type default)
		)
		(layer "In13.Cu")
	)
	(gr_line
		(start 349.023686 -286.723836)
		(end 349.024194 -286.723582)
		(stroke
			(width 0.05715)
			(type default)
		)
		(layer "In13.Cu")
	)
	(gr_line
		(start 349.024194 -294.823134)
		(end 349.026734 -294.821864)
		(stroke
			(width 0.05715)
			(type default)
		)
		(layer "In13.Cu")
	)
	(gr_arc
		(start 349.026734 -294.821864)
		(mid 349.028387 -294.820851)
		(end 349.030036 -294.819832)
		(stroke
			(width 0.05715)
			(type default)
		)
		(layer "In13.Cu")
	)
	(gr_line
		(start 349.03918 -273.27606)
		(end 348.741238 -273.27606)
		(stroke
			(width 0.05715)
			(type default)
		)
		(layer "In13.Cu")
	)
	(gr_line
		(start 349.03918 -271.656048)
		(end 348.741238 -271.656048)
		(stroke
			(width 0.05715)
			(type default)
		)
		(layer "In13.Cu")
	)
	(gr_line
		(start 349.03918 -270.036036)
		(end 348.741238 -270.036036)
		(stroke
			(width 0.05715)
			(type default)
		)
		(layer "In13.Cu")
	)
	(gr_arc
		(start 349.06585 -272.118836)
		(mid 349.069033 -272.116561)
		(end 349.0722 -272.114264)
		(stroke
			(width 0.05715)
			(type default)
		)
		(layer "In13.Cu")
	)
	(gr_line
		(start 349.08236 -411.429962)
		(end 349.165418 -411.011116)
		(stroke
			(width 0.07112)
			(type default)
		)
		(layer "In13.Cu")
	)
	(gr_line
		(start 349.086424 -403.546818)
		(end 349.222314 -403.410928)
		(stroke
			(width 0.07112)
			(type default)
		)
		(layer "In13.Cu")
	)
	(gr_line
		(start 349.108522 -273.345402)
		(end 349.03918 -273.27606)
		(stroke
			(width 0.05715)
			(type default)
		)
		(layer "In13.Cu")
	)
	(gr_line
		(start 349.108522 -271.72539)
		(end 349.03918 -271.656048)
		(stroke
			(width 0.05715)
			(type default)
		)
		(layer "In13.Cu")
	)
	(gr_line
		(start 349.121984 -270.11884)
		(end 349.03918 -270.036036)
		(stroke
			(width 0.05715)
			(type default)
		)
		(layer "In13.Cu")
	)
	(gr_arc
		(start 349.121984 -270.11884)
		(mid 349.123774 -270.130162)
		(end 349.125794 -270.141446)
		(stroke
			(width 0.05715)
			(type default)
		)
		(layer "In13.Cu")
	)
	(gr_line
		(start 349.142304 -410.430472)
		(end 349.302324 -410.323792)
		(stroke
			(width 0.07112)
			(type default)
		)
		(layer "In13.Cu")
	)
	(gr_line
		(start 349.162116 -406.141428)
		(end 349.348806 -406.094946)
		(stroke
			(width 0.07112)
			(type default)
		)
		(layer "In13.Cu")
	)
	(gr_line
		(start 349.165418 -411.011116)
		(end 349.058738 -410.851096)
		(stroke
			(width 0.07112)
			(type default)
		)
		(layer "In13.Cu")
	)
	(gr_line
		(start 349.222314 -403.410928)
		(end 349.222314 -402.984208)
		(stroke
			(width 0.07112)
			(type default)
		)
		(layer "In13.Cu")
	)
	(gr_line
		(start 349.222314 -402.984208)
		(end 349.086424 -402.848318)
		(stroke
			(width 0.07112)
			(type default)
		)
		(layer "In13.Cu")
	)
	(gr_line
		(start 349.24492 -408.784298)
		(end 349.48114 -408.124152)
		(stroke
			(width 0.07112)
			(type default)
		)
		(layer "In13.Cu")
	)
	(gr_arc
		(start 349.296736 -273.381724)
		(mid 349.298758 -273.370313)
		(end 349.300546 -273.358864)
		(stroke
			(width 0.05715)
			(type default)
		)
		(layer "In13.Cu")
	)
	(gr_arc
		(start 349.296736 -271.761712)
		(mid 349.298757 -271.750301)
		(end 349.300546 -271.738852)
		(stroke
			(width 0.05715)
			(type default)
		)
		(layer "In13.Cu")
	)
	(gr_line
		(start 349.300546 -273.358864)
		(end 349.38335 -273.27606)
		(stroke
			(width 0.05715)
			(type default)
		)
		(layer "In13.Cu")
	)
	(gr_line
		(start 349.300546 -271.738852)
		(end 349.38335 -271.656048)
		(stroke
			(width 0.05715)
			(type default)
		)
		(layer "In13.Cu")
	)
	(gr_line
		(start 349.302324 -410.323792)
		(end 349.385382 -409.904946)
		(stroke
			(width 0.07112)
			(type default)
		)
		(layer "In13.Cu")
	)
	(gr_line
		(start 349.312992 -270.105886)
		(end 349.313246 -270.105886)
		(stroke
			(width 0.05715)
			(type default)
		)
		(layer "In13.Cu")
	)
	(gr_line
		(start 349.314008 -270.105124)
		(end 349.383096 -270.036036)
		(stroke
			(width 0.05715)
			(type default)
		)
		(layer "In13.Cu")
	)
	(gr_line
		(start 349.348806 -406.094946)
		(end 349.568262 -405.728678)
		(stroke
			(width 0.07112)
			(type default)
		)
		(layer "In13.Cu")
	)
	(gr_line
		(start 349.383096 -270.036036)
		(end 349.681038 -270.036036)
		(stroke
			(width 0.05715)
			(type default)
		)
		(layer "In13.Cu")
	)
	(gr_line
		(start 349.38335 -273.27606)
		(end 349.681038 -273.27606)
		(stroke
			(width 0.05715)
			(type default)
		)
		(layer "In13.Cu")
	)
	(gr_line
		(start 349.38335 -271.656048)
		(end 349.681038 -271.656048)
		(stroke
			(width 0.05715)
			(type default)
		)
		(layer "In13.Cu")
	)
	(gr_line
		(start 349.385382 -409.904946)
		(end 349.278448 -409.744926)
		(stroke
			(width 0.07112)
			(type default)
		)
		(layer "In13.Cu")
	)
	(gr_line
		(start 349.400876 -270.52651)
		(end 349.399606 -270.525748)
		(stroke
			(width 0.05715)
			(type default)
		)
		(layer "In13.Cu")
	)
	(gr_line
		(start 349.404178 -270.528288)
		(end 349.400876 -270.52651)
		(stroke
			(width 0.05715)
			(type default)
		)
		(layer "In13.Cu")
	)
	(gr_line
		(start 349.405702 -401.399756)
		(end 349.417132 -401.399756)
		(stroke
			(width 0.07112)
			(type default)
		)
		(layer "In13.Cu")
	)
	(gr_line
		(start 349.406972 -401.116546)
		(end 349.544132 -400.979386)
		(stroke
			(width 0.07112)
			(type default)
		)
		(layer "In13.Cu")
	)
	(gr_line
		(start 349.417132 -422.649396)
		(end 349.435674 -422.6433)
		(stroke
			(width 0.07112)
			(type default)
		)
		(layer "In13.Cu")
	)
	(gr_line
		(start 349.417132 -401.399756)
		(end 349.544132 -401.526756)
		(stroke
			(width 0.07112)
			(type default)
		)
		(layer "In13.Cu")
	)
	(gr_line
		(start 349.418148 -423.090848)
		(end 349.504762 -422.918636)
		(stroke
			(width 0.07112)
			(type default)
		)
		(layer "In13.Cu")
	)
	(gr_line
		(start 349.49765 -270.362172)
		(end 349.495364 -270.360648)
		(stroke
			(width 0.05715)
			(type default)
		)
		(layer "In13.Cu")
	)
	(gr_line
		(start 349.500698 -270.36395)
		(end 349.49892 -270.362934)
		(stroke
			(width 0.05715)
			(type default)
		)
		(layer "In13.Cu")
	)
	(gr_line
		(start 349.505524 -422.917112)
		(end 349.524066 -422.911016)
		(stroke
			(width 0.07112)
			(type default)
		)
		(layer "In13.Cu")
	)
	(gr_line
		(start 349.511874 -408.87904)
		(end 349.686118 -408.79649)
		(stroke
			(width 0.07112)
			(type default)
		)
		(layer "In13.Cu")
	)
	(gr_line
		(start 349.544132 -401.526756)
		(end 349.544132 -401.674838)
		(stroke
			(width 0.07112)
			(type default)
		)
		(layer "In13.Cu")
	)
	(gr_line
		(start 349.544132 -400.979386)
		(end 349.544132 -400.811238)
		(stroke
			(width 0.07112)
			(type default)
		)
		(layer "In13.Cu")
	)
	(gr_line
		(start 349.568262 -405.728678)
		(end 349.521526 -405.541988)
		(stroke
			(width 0.07112)
			(type default)
		)
		(layer "In13.Cu")
	)
	(gr_line
		(start 349.624904 -407.722578)
		(end 349.861124 -407.062178)
		(stroke
			(width 0.07112)
			(type default)
		)
		(layer "In13.Cu")
	)
	(gr_line
		(start 349.686118 -408.79649)
		(end 349.829882 -408.394408)
		(stroke
			(width 0.07112)
			(type default)
		)
		(layer "In13.Cu")
	)
	(gr_line
		(start 349.829882 -408.394408)
		(end 349.747586 -408.220672)
		(stroke
			(width 0.07112)
			(type default)
		)
		(layer "In13.Cu")
	)
	(gr_line
		(start 349.891858 -407.817066)
		(end 350.066102 -407.734516)
		(stroke
			(width 0.07112)
			(type default)
		)
		(layer "In13.Cu")
	)
	(gr_line
		(start 350.004888 -406.660604)
		(end 350.241362 -406.000204)
		(stroke
			(width 0.07112)
			(type default)
		)
		(layer "In13.Cu")
	)
	(gr_line
		(start 350.006666 -294.798242)
		(end 350.012508 -294.793924)
		(stroke
			(width 0.05715)
			(type default)
		)
		(layer "In13.Cu")
	)
	(gr_line
		(start 350.010222 -296.436034)
		(end 350.010222 -296.421556)
		(stroke
			(width 0.05715)
			(type default)
		)
		(layer "In13.Cu")
	)
	(gr_line
		(start 350.010222 -296.421556)
		(end 350.055942 -296.375836)
		(stroke
			(width 0.05715)
			(type default)
		)
		(layer "In13.Cu")
	)
	(gr_line
		(start 350.033336 -417.83508)
		(end 350.033336 -417.13404)
		(stroke
			(width 0.07112)
			(type default)
		)
		(layer "In13.Cu")
	)
	(gr_line
		(start 350.033336 -416.70732)
		(end 350.033336 -416.00628)
		(stroke
			(width 0.07112)
			(type default)
		)
		(layer "In13.Cu")
	)
	(gr_line
		(start 350.066102 -407.734516)
		(end 350.209866 -407.332434)
		(stroke
			(width 0.07112)
			(type default)
		)
		(layer "In13.Cu")
	)
	(gr_line
		(start 350.209866 -407.332434)
		(end 350.12757 -407.158698)
		(stroke
			(width 0.07112)
			(type default)
		)
		(layer "In13.Cu")
	)
	(gr_line
		(start 350.271842 -406.754838)
		(end 350.446086 -406.672542)
		(stroke
			(width 0.07112)
			(type default)
		)
		(layer "In13.Cu")
	)
	(gr_line
		(start 350.292162 -296.436034)
		(end 350.292162 -296.421556)
		(stroke
			(width 0.05715)
			(type default)
		)
		(layer "In13.Cu")
	)
	(gr_line
		(start 350.292162 -296.421556)
		(end 350.246442 -296.375836)
		(stroke
			(width 0.05715)
			(type default)
		)
		(layer "In13.Cu")
	)
	(gr_line
		(start 350.316546 -417.83381)
		(end 350.452436 -417.69792)
		(stroke
			(width 0.07112)
			(type default)
		)
		(layer "In13.Cu")
	)
	(gr_line
		(start 350.316546 -416.70605)
		(end 350.452436 -416.57016)
		(stroke
			(width 0.07112)
			(type default)
		)
		(layer "In13.Cu")
	)
	(gr_line
		(start 350.384872 -405.59863)
		(end 350.61906 -404.943818)
		(stroke
			(width 0.07112)
			(type default)
		)
		(layer "In13.Cu")
	)
	(gr_line
		(start 350.446086 -406.672542)
		(end 350.58985 -406.27046)
		(stroke
			(width 0.07112)
			(type default)
		)
		(layer "In13.Cu")
	)
	(gr_line
		(start 350.452436 -417.69792)
		(end 350.452436 -417.2712)
		(stroke
			(width 0.07112)
			(type default)
		)
		(layer "In13.Cu")
	)
	(gr_line
		(start 350.452436 -417.2712)
		(end 350.316546 -417.13531)
		(stroke
			(width 0.07112)
			(type default)
		)
		(layer "In13.Cu")
	)
	(gr_line
		(start 350.452436 -416.57016)
		(end 350.452436 -416.14344)
		(stroke
			(width 0.07112)
			(type default)
		)
		(layer "In13.Cu")
	)
	(gr_line
		(start 350.452436 -416.14344)
		(end 350.316546 -416.00755)
		(stroke
			(width 0.07112)
			(type default)
		)
		(layer "In13.Cu")
	)
	(gr_line
		(start 350.58985 -406.27046)
		(end 350.507554 -406.096724)
		(stroke
			(width 0.07112)
			(type default)
		)
		(layer "In13.Cu")
	)
	(gr_line
		(start 350.605598 -401.399756)
		(end 350.617028 -401.399756)
		(stroke
			(width 0.07112)
			(type default)
		)
		(layer "In13.Cu")
	)
	(gr_line
		(start 350.606868 -401.116546)
		(end 350.744028 -400.979386)
		(stroke
			(width 0.07112)
			(type default)
		)
		(layer "In13.Cu")
	)
	(gr_line
		(start 350.617028 -401.399756)
		(end 350.744028 -401.526756)
		(stroke
			(width 0.07112)
			(type default)
		)
		(layer "In13.Cu")
	)
	(gr_line
		(start 350.651826 -405.692864)
		(end 350.82607 -405.610568)
		(stroke
			(width 0.07112)
			(type default)
		)
		(layer "In13.Cu")
	)
	(gr_line
		(start 350.716342 -295.053004)
		(end 350.716596 -295.053258)
		(stroke
			(width 0.05715)
			(type default)
		)
		(layer "In13.Cu")
	)
	(gr_line
		(start 350.744028 -401.526756)
		(end 350.744028 -401.674838)
		(stroke
			(width 0.07112)
			(type default)
		)
		(layer "In13.Cu")
	)
	(gr_line
		(start 350.744028 -400.979386)
		(end 350.744028 -400.811238)
		(stroke
			(width 0.07112)
			(type default)
		)
		(layer "In13.Cu")
	)
	(gr_line
		(start 350.82607 -405.610568)
		(end 350.969834 -405.20874)
		(stroke
			(width 0.07112)
			(type default)
		)
		(layer "In13.Cu")
	)
	(gr_line
		(start 350.887538 -405.031448)
		(end 350.887792 -405.03094)
		(stroke
			(width 0.07112)
			(type default)
		)
		(layer "In13.Cu")
	)
	(gr_line
		(start 350.90862 -294.820848)
		(end 350.90862 -294.820594)
		(stroke
			(width 0.05715)
			(type default)
		)
		(layer "In13.Cu")
	)
	(gr_line
		(start 350.969834 -405.20874)
		(end 350.887538 -405.034496)
		(stroke
			(width 0.07112)
			(type default)
		)
		(layer "In13.Cu")
	)
	(gr_line
		(start 351.017332 -296.61231)
		(end 351.017332 -296.583862)
		(stroke
			(width 0.05715)
			(type default)
		)
		(layer "In13.Cu")
	)
	(gr_line
		(start 351.017332 -296.583862)
		(end 351.061782 -296.539412)
		(stroke
			(width 0.05715)
			(type default)
		)
		(layer "In13.Cu")
	)
	(gr_line
		(start 351.017586 -296.612564)
		(end 351.017332 -296.61231)
		(stroke
			(width 0.05715)
			(type default)
		)
		(layer "In13.Cu")
	)
	(gr_line
		(start 351.203006 -403.552152)
		(end 351.203006 -402.851112)
		(stroke
			(width 0.07112)
			(type default)
		)
		(layer "In13.Cu")
	)
	(gr_line
		(start 351.253552 -296.552112)
		(end 351.253552 -296.538142)
		(stroke
			(width 0.05715)
			(type default)
		)
		(layer "In13.Cu")
	)
	(gr_line
		(start 351.299272 -296.61231)
		(end 351.299272 -296.597832)
		(stroke
			(width 0.05715)
			(type default)
		)
		(layer "In13.Cu")
	)
	(gr_line
		(start 351.299272 -296.597832)
		(end 351.253552 -296.552112)
		(stroke
			(width 0.05715)
			(type default)
		)
		(layer "In13.Cu")
	)
	(gr_line
		(start 351.299526 -296.612564)
		(end 351.299272 -296.61231)
		(stroke
			(width 0.07112)
			(type default)
		)
		(layer "In13.Cu")
	)
	(gr_arc
		(start 351.37852 -272.95094)
		(mid 351.378139 -272.951194)
		(end 351.377758 -272.951448)
		(stroke
			(width 0.05715)
			(type default)
		)
		(layer "In13.Cu")
	)
	(gr_line
		(start 351.486216 -403.550882)
		(end 351.622106 -403.414992)
		(stroke
			(width 0.07112)
			(type default)
		)
		(layer "In13.Cu")
	)
	(gr_line
		(start 351.584768 -413.100012)
		(end 351.597214 -412.971234)
		(stroke
			(width 0.07112)
			(type default)
		)
		(layer "In13.Cu")
	)
	(gr_line
		(start 351.597214 -412.971234)
		(end 351.666048 -412.272988)
		(stroke
			(width 0.07112)
			(type default)
		)
		(layer "In13.Cu")
	)
	(gr_line
		(start 351.622106 -403.414992)
		(end 351.622106 -402.988272)
		(stroke
			(width 0.07112)
			(type default)
		)
		(layer "In13.Cu")
	)
	(gr_line
		(start 351.622106 -402.988272)
		(end 351.486216 -402.852382)
		(stroke
			(width 0.07112)
			(type default)
		)
		(layer "In13.Cu")
	)
	(gr_line
		(start 351.656396 -295.146222)
		(end 351.65665 -295.145968)
		(stroke
			(width 0.05715)
			(type default)
		)
		(layer "In13.Cu")
	)
	(gr_line
		(start 351.66808 -421.36441)
		(end 352.079052 -420.796212)
		(stroke
			(width 0.07112)
			(type default)
		)
		(layer "In13.Cu")
	)
	(gr_line
		(start 351.707958 -411.848808)
		(end 351.776538 -411.150562)
		(stroke
			(width 0.07112)
			(type default)
		)
		(layer "In13.Cu")
	)
	(gr_arc
		(start 351.709228 -286.581342)
		(mid 351.704512 -286.584619)
		(end 351.69983 -286.587946)
		(stroke
			(width 0.05715)
			(type default)
		)
		(layer "In13.Cu")
	)
	(gr_line
		(start 351.709228 -286.581342)
		(end 351.71126 -286.579818)
		(stroke
			(width 0.05715)
			(type default)
		)
		(layer "In13.Cu")
	)
	(gr_line
		(start 351.71126 -286.579818)
		(end 351.716086 -286.577024)
		(stroke
			(width 0.05715)
			(type default)
		)
		(layer "In13.Cu")
	)
	(gr_line
		(start 351.805494 -401.399756)
		(end 351.816924 -401.399756)
		(stroke
			(width 0.07112)
			(type default)
		)
		(layer "In13.Cu")
	)
	(gr_line
		(start 351.806764 -401.116546)
		(end 351.943924 -400.979386)
		(stroke
			(width 0.07112)
			(type default)
		)
		(layer "In13.Cu")
	)
	(gr_line
		(start 351.816924 -401.399756)
		(end 351.943924 -401.526756)
		(stroke
			(width 0.07112)
			(type default)
		)
		(layer "In13.Cu")
	)
	(gr_line
		(start 351.818448 -410.726382)
		(end 351.887028 -410.028136)
		(stroke
			(width 0.07112)
			(type default)
		)
		(layer "In13.Cu")
	)
	(gr_arc
		(start 351.842578 -272.14449)
		(mid 351.841052 -272.145375)
		(end 351.83953 -272.146268)
		(stroke
			(width 0.05715)
			(type default)
		)
		(layer "In13.Cu")
	)
	(gr_line
		(start 351.843594 -286.723836)
		(end 351.844102 -286.723582)
		(stroke
			(width 0.05715)
			(type default)
		)
		(layer "In13.Cu")
	)
	(gr_line
		(start 351.859088 -273.27606)
		(end 351.561146 -273.27606)
		(stroke
			(width 0.05715)
			(type default)
		)
		(layer "In13.Cu")
	)
	(gr_line
		(start 351.859088 -271.656048)
		(end 351.561146 -271.656048)
		(stroke
			(width 0.05715)
			(type default)
		)
		(layer "In13.Cu")
	)
	(gr_line
		(start 351.879408 -412.997396)
		(end 352.027998 -412.875476)
		(stroke
			(width 0.07112)
			(type default)
		)
		(layer "In13.Cu")
	)
	(gr_line
		(start 351.898204 -421.52951)
		(end 352.088196 -421.49903)
		(stroke
			(width 0.07112)
			(type default)
		)
		(layer "In13.Cu")
	)
	(gr_line
		(start 351.92843 -273.345402)
		(end 351.859088 -273.27606)
		(stroke
			(width 0.05715)
			(type default)
		)
		(layer "In13.Cu")
	)
	(gr_line
		(start 351.92843 -271.72539)
		(end 351.859088 -271.656048)
		(stroke
			(width 0.05715)
			(type default)
		)
		(layer "In13.Cu")
	)
	(gr_line
		(start 351.928938 -409.603956)
		(end 351.997518 -408.90571)
		(stroke
			(width 0.07112)
			(type default)
		)
		(layer "In13.Cu")
	)
	(gr_line
		(start 351.943924 -401.526756)
		(end 351.943924 -401.674838)
		(stroke
			(width 0.07112)
			(type default)
		)
		(layer "In13.Cu")
	)
	(gr_line
		(start 351.943924 -400.979386)
		(end 351.943924 -400.811238)
		(stroke
			(width 0.07112)
			(type default)
		)
		(layer "In13.Cu")
	)
	(gr_line
		(start 351.989898 -411.875224)
		(end 352.138742 -411.75305)
		(stroke
			(width 0.07112)
			(type default)
		)
		(layer "In13.Cu")
	)
	(gr_line
		(start 352.027998 -412.875476)
		(end 352.069908 -412.450534)
		(stroke
			(width 0.07112)
			(type default)
		)
		(layer "In13.Cu")
	)
	(gr_line
		(start 352.039428 -408.48153)
		(end 352.108008 -407.783284)
		(stroke
			(width 0.07112)
			(type default)
		)
		(layer "In13.Cu")
	)
	(gr_line
		(start 352.069908 -412.450534)
		(end 351.947734 -412.30169)
		(stroke
			(width 0.07112)
			(type default)
		)
		(layer "In13.Cu")
	)
	(gr_line
		(start 352.088196 -421.49903)
		(end 352.338386 -421.153082)
		(stroke
			(width 0.07112)
			(type default)
		)
		(layer "In13.Cu")
	)
	(gr_line
		(start 352.100388 -410.752798)
		(end 352.249232 -410.630624)
		(stroke
			(width 0.07112)
			(type default)
		)
		(layer "In13.Cu")
	)
	(gr_line
		(start 352.105976 -296.502328)
		(end 352.105976 -296.47388)
		(stroke
			(width 0.05715)
			(type default)
		)
		(layer "In13.Cu")
	)
	(gr_line
		(start 352.105976 -296.47388)
		(end 352.151696 -296.42816)
		(stroke
			(width 0.05715)
			(type default)
		)
		(layer "In13.Cu")
	)
	(gr_arc
		(start 352.116644 -273.381724)
		(mid 352.118666 -273.370313)
		(end 352.120454 -273.358864)
		(stroke
			(width 0.05715)
			(type default)
		)
		(layer "In13.Cu")
	)
	(gr_arc
		(start 352.116644 -271.761712)
		(mid 352.118665 -271.750301)
		(end 352.120454 -271.738852)
		(stroke
			(width 0.05715)
			(type default)
		)
		(layer "In13.Cu")
	)
	(gr_line
		(start 352.120454 -273.358864)
		(end 352.203258 -273.27606)
		(stroke
			(width 0.05715)
			(type default)
		)
		(layer "In13.Cu")
	)
	(gr_line
		(start 352.120454 -271.738852)
		(end 352.203258 -271.656048)
		(stroke
			(width 0.05715)
			(type default)
		)
		(layer "In13.Cu")
	)
	(gr_line
		(start 352.138742 -411.75305)
		(end 352.180652 -411.328108)
		(stroke
			(width 0.07112)
			(type default)
		)
		(layer "In13.Cu")
	)
	(gr_line
		(start 352.149918 -407.359104)
		(end 352.218498 -406.660858)
		(stroke
			(width 0.07112)
			(type default)
		)
		(layer "In13.Cu")
	)
	(gr_line
		(start 352.180652 -411.328108)
		(end 352.058224 -411.179264)
		(stroke
			(width 0.07112)
			(type default)
		)
		(layer "In13.Cu")
	)
	(gr_line
		(start 352.203258 -273.27606)
		(end 352.5012 -273.27606)
		(stroke
			(width 0.05715)
			(type default)
		)
		(layer "In13.Cu")
	)
	(gr_line
		(start 352.203258 -271.656048)
		(end 352.5012 -271.656048)
		(stroke
			(width 0.05715)
			(type default)
		)
		(layer "In13.Cu")
	)
	(gr_line
		(start 352.210878 -409.630372)
		(end 352.359722 -409.508198)
		(stroke
			(width 0.07112)
			(type default)
		)
		(layer "In13.Cu")
	)
	(gr_line
		(start 352.249232 -410.630624)
		(end 352.291142 -410.205682)
		(stroke
			(width 0.07112)
			(type default)
		)
		(layer "In13.Cu")
	)
	(gr_line
		(start 352.291142 -410.205682)
		(end 352.168968 -410.056838)
		(stroke
			(width 0.07112)
			(type default)
		)
		(layer "In13.Cu")
	)
	(gr_line
		(start 352.321368 -408.507946)
		(end 352.470212 -408.385772)
		(stroke
			(width 0.07112)
			(type default)
		)
		(layer "In13.Cu")
	)
	(gr_line
		(start 352.338386 -421.153082)
		(end 352.307906 -420.96309)
		(stroke
			(width 0.07112)
			(type default)
		)
		(layer "In13.Cu")
	)
	(gr_line
		(start 352.359722 -409.508198)
		(end 352.401632 -409.083256)
		(stroke
			(width 0.07112)
			(type default)
		)
		(layer "In13.Cu")
	)
	(gr_line
		(start 352.387916 -296.502328)
		(end 352.387916 -296.47388)
		(stroke
			(width 0.05715)
			(type default)
		)
		(layer "In13.Cu")
	)
	(gr_line
		(start 352.387916 -296.47388)
		(end 352.342196 -296.42816)
		(stroke
			(width 0.05715)
			(type default)
		)
		(layer "In13.Cu")
	)
	(gr_line
		(start 352.401632 -409.083256)
		(end 352.279458 -408.934412)
		(stroke
			(width 0.07112)
			(type default)
		)
		(layer "In13.Cu")
	)
	(gr_line
		(start 352.403156 -403.509226)
		(end 352.403156 -402.808186)
		(stroke
			(width 0.07112)
			(type default)
		)
		(layer "In13.Cu")
	)
	(gr_line
		(start 352.431858 -407.38552)
		(end 352.580702 -407.263346)
		(stroke
			(width 0.07112)
			(type default)
		)
		(layer "In13.Cu")
	)
	(gr_line
		(start 352.470212 -408.385772)
		(end 352.512122 -407.96083)
		(stroke
			(width 0.07112)
			(type default)
		)
		(layer "In13.Cu")
	)
	(gr_line
		(start 352.512122 -407.96083)
		(end 352.389948 -407.811986)
		(stroke
			(width 0.07112)
			(type default)
		)
		(layer "In13.Cu")
	)
	(gr_line
		(start 352.580702 -407.263346)
		(end 352.622612 -406.838404)
		(stroke
			(width 0.07112)
			(type default)
		)
		(layer "In13.Cu")
	)
	(gr_line
		(start 352.622612 -406.838404)
		(end 352.500438 -406.689814)
		(stroke
			(width 0.07112)
			(type default)
		)
		(layer "In13.Cu")
	)
	(gr_line
		(start 352.686366 -403.507956)
		(end 352.822256 -403.372066)
		(stroke
			(width 0.07112)
			(type default)
		)
		(layer "In13.Cu")
	)
	(gr_line
		(start 352.76155 -419.711886)
		(end 353.045776 -419.070536)
		(stroke
			(width 0.07112)
			(type default)
		)
		(layer "In13.Cu")
	)
	(gr_line
		(start 352.822256 -403.372066)
		(end 352.822256 -402.945346)
		(stroke
			(width 0.07112)
			(type default)
		)
		(layer "In13.Cu")
	)
	(gr_line
		(start 352.822256 -402.945346)
		(end 352.686366 -402.809456)
		(stroke
			(width 0.07112)
			(type default)
		)
		(layer "In13.Cu")
	)
	(gr_line
		(start 353.005644 -401.399756)
		(end 353.017074 -401.399756)
		(stroke
			(width 0.07112)
			(type default)
		)
		(layer "In13.Cu")
	)
	(gr_line
		(start 353.006914 -401.116546)
		(end 353.144074 -400.979386)
		(stroke
			(width 0.07112)
			(type default)
		)
		(layer "In13.Cu")
	)
	(gr_line
		(start 353.017074 -401.399756)
		(end 353.144074 -401.526756)
		(stroke
			(width 0.07112)
			(type default)
		)
		(layer "In13.Cu")
	)
	(gr_line
		(start 353.021138 -419.825424)
		(end 353.200716 -419.756336)
		(stroke
			(width 0.07112)
			(type default)
		)
		(layer "In13.Cu")
	)
	(gr_line
		(start 353.144074 -401.526756)
		(end 353.144074 -401.674838)
		(stroke
			(width 0.07112)
			(type default)
		)
		(layer "In13.Cu")
	)
	(gr_line
		(start 353.144074 -400.979386)
		(end 353.144074 -400.811238)
		(stroke
			(width 0.07112)
			(type default)
		)
		(layer "In13.Cu")
	)
	(gr_line
		(start 353.200716 -419.756336)
		(end 353.373436 -419.365938)
		(stroke
			(width 0.07112)
			(type default)
		)
		(layer "In13.Cu")
	)
	(gr_line
		(start 353.373436 -419.365938)
		(end 353.304094 -419.18636)
		(stroke
			(width 0.07112)
			(type default)
		)
		(layer "In13.Cu")
	)
	(gr_line
		(start 353.603052 -417.192714)
		(end 353.603052 -416.491674)
		(stroke
			(width 0.07112)
			(type default)
		)
		(layer "In13.Cu")
	)
	(gr_line
		(start 353.603052 -416.064954)
		(end 353.603052 -415.363914)
		(stroke
			(width 0.07112)
			(type default)
		)
		(layer "In13.Cu")
	)
	(gr_line
		(start 353.603052 -414.937194)
		(end 353.603052 -414.236154)
		(stroke
			(width 0.07112)
			(type default)
		)
		(layer "In13.Cu")
	)
	(gr_line
		(start 353.603052 -413.809434)
		(end 353.603052 -413.108394)
		(stroke
			(width 0.07112)
			(type default)
		)
		(layer "In13.Cu")
	)
	(gr_line
		(start 353.603052 -412.681674)
		(end 353.603052 -411.980634)
		(stroke
			(width 0.07112)
			(type default)
		)
		(layer "In13.Cu")
	)
	(gr_line
		(start 353.886262 -417.191444)
		(end 354.022152 -417.055554)
		(stroke
			(width 0.07112)
			(type default)
		)
		(layer "In13.Cu")
	)
	(gr_line
		(start 353.886262 -416.063684)
		(end 354.022152 -415.927794)
		(stroke
			(width 0.07112)
			(type default)
		)
		(layer "In13.Cu")
	)
	(gr_line
		(start 353.886262 -414.935924)
		(end 354.022152 -414.800034)
		(stroke
			(width 0.07112)
			(type default)
		)
		(layer "In13.Cu")
	)
	(gr_line
		(start 353.886262 -413.808164)
		(end 354.022152 -413.672274)
		(stroke
			(width 0.07112)
			(type default)
		)
		(layer "In13.Cu")
	)
	(gr_line
		(start 353.886262 -412.680404)
		(end 354.022152 -412.544514)
		(stroke
			(width 0.07112)
			(type default)
		)
		(layer "In13.Cu")
	)
	(gr_line
		(start 354.022152 -417.055554)
		(end 354.022152 -416.628834)
		(stroke
			(width 0.07112)
			(type default)
		)
		(layer "In13.Cu")
	)
	(gr_line
		(start 354.022152 -416.628834)
		(end 353.886262 -416.492944)
		(stroke
			(width 0.07112)
			(type default)
		)
		(layer "In13.Cu")
	)
	(gr_line
		(start 354.022152 -415.927794)
		(end 354.022152 -415.501074)
		(stroke
			(width 0.07112)
			(type default)
		)
		(layer "In13.Cu")
	)
	(gr_line
		(start 354.022152 -415.501074)
		(end 353.886262 -415.365184)
		(stroke
			(width 0.07112)
			(type default)
		)
		(layer "In13.Cu")
	)
	(gr_line
		(start 354.022152 -414.800034)
		(end 354.022152 -414.373314)
		(stroke
			(width 0.07112)
			(type default)
		)
		(layer "In13.Cu")
	)
	(gr_line
		(start 354.022152 -414.373314)
		(end 353.886262 -414.237424)
		(stroke
			(width 0.07112)
			(type default)
		)
		(layer "In13.Cu")
	)
	(gr_line
		(start 354.022152 -413.672274)
		(end 354.022152 -413.245554)
		(stroke
			(width 0.07112)
			(type default)
		)
		(layer "In13.Cu")
	)
	(gr_line
		(start 354.022152 -413.245554)
		(end 353.886262 -413.109664)
		(stroke
			(width 0.07112)
			(type default)
		)
		(layer "In13.Cu")
	)
	(gr_line
		(start 354.022152 -412.544514)
		(end 354.022152 -412.117794)
		(stroke
			(width 0.07112)
			(type default)
		)
		(layer "In13.Cu")
	)
	(gr_line
		(start 354.022152 -412.117794)
		(end 353.886262 -411.981904)
		(stroke
			(width 0.07112)
			(type default)
		)
		(layer "In13.Cu")
	)
	(gr_line
		(start 354.20554 -401.399756)
		(end 354.21697 -401.399756)
		(stroke
			(width 0.07112)
			(type default)
		)
		(layer "In13.Cu")
	)
	(gr_line
		(start 354.20681 -401.116546)
		(end 354.34397 -400.979386)
		(stroke
			(width 0.07112)
			(type default)
		)
		(layer "In13.Cu")
	)
	(gr_line
		(start 354.21697 -401.399756)
		(end 354.34397 -401.526756)
		(stroke
			(width 0.07112)
			(type default)
		)
		(layer "In13.Cu")
	)
	(gr_line
		(start 354.34397 -401.526756)
		(end 354.34397 -401.674838)
		(stroke
			(width 0.07112)
			(type default)
		)
		(layer "In13.Cu")
	)
	(gr_line
		(start 354.34397 -400.979386)
		(end 354.34397 -400.811238)
		(stroke
			(width 0.07112)
			(type default)
		)
		(layer "In13.Cu")
	)
	(gr_line
		(start 354.831142 -307.480716)
		(end 354.831396 -307.480716)
		(stroke
			(width 0.07112)
			(type default)
		)
		(layer "In13.Cu")
	)
	(gr_line
		(start 356.51821 -309.536338)
		(end 356.51821 -309.536592)
		(stroke
			(width 0.07112)
			(type default)
		)
		(layer "In13.Cu")
	)
	(gr_arc
		(start 357.457248 -384.814826)
		(mid 357.458137 -384.814827)
		(end 357.459026 -384.814826)
		(stroke
			(width 0.07112)
			(type default)
		)
		(layer "In13.Cu")
	)
	(gr_arc
		(start 357.457502 -384.532886)
		(mid 357.45801 -384.532887)
		(end 357.458518 -384.532886)
		(stroke
			(width 0.07112)
			(type default)
		)
		(layer "In13.Cu")
	)
	(gr_line
		(start 359.53954 -370.944394)
		(end 360.24058 -370.944394)
		(stroke
			(width 0.07112)
			(type default)
		)
		(layer "In13.Cu")
	)
	(gr_line
		(start 359.54081 -370.661184)
		(end 359.6767 -370.525294)
		(stroke
			(width 0.07112)
			(type default)
		)
		(layer "In13.Cu")
	)
	(gr_line
		(start 359.6767 -370.525294)
		(end 360.10342 -370.525294)
		(stroke
			(width 0.07112)
			(type default)
		)
		(layer "In13.Cu")
	)
	(gr_line
		(start 360.10342 -370.525294)
		(end 360.23931 -370.661184)
		(stroke
			(width 0.07112)
			(type default)
		)
		(layer "In13.Cu")
	)
	(gr_line
		(start 360.6673 -370.944394)
		(end 361.36834 -370.944394)
		(stroke
			(width 0.07112)
			(type default)
		)
		(layer "In13.Cu")
	)
	(gr_line
		(start 360.66857 -370.661184)
		(end 360.80446 -370.525294)
		(stroke
			(width 0.07112)
			(type default)
		)
		(layer "In13.Cu")
	)
	(gr_line
		(start 360.66984 -295.221152)
		(end 360.66984 -295.2496)
		(stroke
			(width 0.05715)
			(type default)
		)
		(layer "In13.Cu")
	)
	(gr_line
		(start 360.71556 -295.175432)
		(end 360.66984 -295.221152)
		(stroke
			(width 0.05715)
			(type default)
		)
		(layer "In13.Cu")
	)
	(gr_line
		(start 360.80446 -370.525294)
		(end 361.23118 -370.525294)
		(stroke
			(width 0.07112)
			(type default)
		)
		(layer "In13.Cu")
	)
	(gr_line
		(start 360.90606 -295.175432)
		(end 360.95178 -295.221152)
		(stroke
			(width 0.05715)
			(type default)
		)
		(layer "In13.Cu")
	)
	(gr_line
		(start 360.95178 -295.221152)
		(end 360.95178 -295.2496)
		(stroke
			(width 0.05715)
			(type default)
		)
		(layer "In13.Cu")
	)
	(gr_line
		(start 361.23118 -370.525294)
		(end 361.36707 -370.661184)
		(stroke
			(width 0.07112)
			(type default)
		)
		(layer "In13.Cu")
	)
	(gr_line
		(start 361.329478 -286.236156)
		(end 361.329732 -286.236156)
		(stroke
			(width 0.05715)
			(type default)
		)
		(layer "In13.Cu")
	)
	(gr_arc
		(start 361.329986 -286.215328)
		(mid 361.329847 -286.218884)
		(end 361.329732 -286.22244)
		(stroke
			(width 0.05715)
			(type default)
		)
		(layer "In13.Cu")
	)
	(gr_arc
		(start 361.599226 -285.096204)
		(mid 361.601256 -285.097351)
		(end 361.60329 -285.09849)
		(stroke
			(width 0.05715)
			(type default)
		)
		(layer "In13.Cu")
	)
	(gr_arc
		(start 361.602782 -293.198296)
		(mid 361.603671 -293.198805)
		(end 361.60456 -293.199312)
		(stroke
			(width 0.05715)
			(type default)
		)
		(layer "In13.Cu")
	)
	(gr_arc
		(start 361.60456 -292.232588)
		(mid 361.60367 -292.233095)
		(end 361.602782 -292.233604)
		(stroke
			(width 0.05715)
			(type default)
		)
		(layer "In13.Cu")
	)
	(gr_line
		(start 361.608116 -283.481272)
		(end 361.612688 -283.484066)
		(stroke
			(width 0.05715)
			(type default)
		)
		(layer "In13.Cu")
	)
	(gr_line
		(start 361.608116 -281.86126)
		(end 361.612688 -281.864054)
		(stroke
			(width 0.05715)
			(type default)
		)
		(layer "In13.Cu")
	)
	(gr_line
		(start 361.611418 -280.888948)
		(end 361.608116 -280.89098)
		(stroke
			(width 0.05715)
			(type default)
		)
		(layer "In13.Cu")
	)
	(gr_line
		(start 361.611672 -285.10357)
		(end 361.611926 -285.10357)
		(stroke
			(width 0.05715)
			(type default)
		)
		(layer "In13.Cu")
	)
	(gr_line
		(start 361.611926 -284.128718)
		(end 361.611672 -284.128972)
		(stroke
			(width 0.05715)
			(type default)
		)
		(layer "In13.Cu")
	)
	(gr_line
		(start 361.611926 -282.508706)
		(end 361.608116 -282.510992)
		(stroke
			(width 0.05715)
			(type default)
		)
		(layer "In13.Cu")
	)
	(gr_line
		(start 361.612688 -283.484066)
		(end 361.613196 -283.48432)
		(stroke
			(width 0.05715)
			(type default)
		)
		(layer "In13.Cu")
	)
	(gr_line
		(start 361.612688 -281.864054)
		(end 361.613196 -281.864308)
		(stroke
			(width 0.05715)
			(type default)
		)
		(layer "In13.Cu")
	)
	(gr_line
		(start 361.612942 -282.508198)
		(end 361.611926 -282.508706)
		(stroke
			(width 0.05715)
			(type default)
		)
		(layer "In13.Cu")
	)
	(gr_line
		(start 361.62615 -288.979864)
		(end 361.623102 -288.981896)
		(stroke
			(width 0.05715)
			(type default)
		)
		(layer "In13.Cu")
	)
	(gr_line
		(start 361.642406 -280.261568)
		(end 361.642406 -280.261314)
		(stroke
			(width 0.05715)
			(type default)
		)
		(layer "In13.Cu")
	)
	(gr_line
		(start 361.705398 -293.03726)
		(end 361.710732 -293.040308)
		(stroke
			(width 0.05715)
			(type default)
		)
		(layer "In13.Cu")
	)
	(gr_line
		(start 361.70616 -281.054556)
		(end 361.704382 -281.055572)
		(stroke
			(width 0.05715)
			(type default)
		)
		(layer "In13.Cu")
	)
	(gr_line
		(start 361.706414 -288.177732)
		(end 361.709462 -288.17951)
		(stroke
			(width 0.05715)
			(type default)
		)
		(layer "In13.Cu")
	)
	(gr_line
		(start 361.7087 -284.293056)
		(end 361.707938 -284.293564)
		(stroke
			(width 0.05715)
			(type default)
		)
		(layer "In13.Cu")
	)
	(gr_line
		(start 361.710478 -292.391592)
		(end 361.705398 -292.39464)
		(stroke
			(width 0.05715)
			(type default)
		)
		(layer "In13.Cu")
	)
	(gr_line
		(start 361.710732 -293.040308)
		(end 361.711494 -293.040816)
		(stroke
			(width 0.05715)
			(type default)
		)
		(layer "In13.Cu")
	)
	(gr_line
		(start 361.712256 -289.150806)
		(end 361.707684 -289.153346)
		(stroke
			(width 0.05715)
			(type default)
		)
		(layer "In13.Cu")
	)
	(gr_line
		(start 361.727242 -289.141408)
		(end 361.726734 -289.141662)
		(stroke
			(width 0.05715)
			(type default)
		)
		(layer "In13.Cu")
	)
	(gr_line
		(start 361.738164 -283.336492)
		(end 361.745276 -283.340556)
		(stroke
			(width 0.05715)
			(type default)
		)
		(layer "In13.Cu")
	)
	(gr_line
		(start 361.738164 -281.71648)
		(end 361.745276 -281.720544)
		(stroke
			(width 0.05715)
			(type default)
		)
		(layer "In13.Cu")
	)
	(gr_line
		(start 361.738418 -284.956504)
		(end 361.745276 -284.960568)
		(stroke
			(width 0.05715)
			(type default)
		)
		(layer "In13.Cu")
	)
	(gr_line
		(start 361.738926 -293.056818)
		(end 361.746038 -293.060882)
		(stroke
			(width 0.05715)
			(type default)
		)
		(layer "In13.Cu")
	)
	(gr_arc
		(start 361.746038 -293.060882)
		(mid 361.746419 -293.061136)
		(end 361.7468 -293.06139)
		(stroke
			(width 0.05715)
			(type default)
		)
		(layer "In13.Cu")
	)
	(gr_arc
		(start 361.7468 -284.961584)
		(mid 361.746038 -284.961075)
		(end 361.745276 -284.960568)
		(stroke
			(width 0.05715)
			(type default)
		)
		(layer "In13.Cu")
	)
	(gr_arc
		(start 361.7468 -283.341572)
		(mid 361.746038 -283.341063)
		(end 361.745276 -283.340556)
		(stroke
			(width 0.05715)
			(type default)
		)
		(layer "In13.Cu")
	)
	(gr_arc
		(start 361.7468 -281.72156)
		(mid 361.746038 -281.721051)
		(end 361.745276 -281.720544)
		(stroke
			(width 0.05715)
			(type default)
		)
		(layer "In13.Cu")
	)
	(gr_arc
		(start 361.75315 -284.966156)
		(mid 361.749983 -284.963859)
		(end 361.7468 -284.961584)
		(stroke
			(width 0.05715)
			(type default)
		)
		(layer "In13.Cu")
	)
	(gr_arc
		(start 361.75315 -283.346144)
		(mid 361.749983 -283.343847)
		(end 361.7468 -283.341572)
		(stroke
			(width 0.05715)
			(type default)
		)
		(layer "In13.Cu")
	)
	(gr_arc
		(start 361.75315 -281.726132)
		(mid 361.749983 -281.723835)
		(end 361.7468 -281.72156)
		(stroke
			(width 0.05715)
			(type default)
		)
		(layer "In13.Cu")
	)
	(gr_arc
		(start 361.754674 -293.066978)
		(mid 361.750749 -293.064167)
		(end 361.7468 -293.06139)
		(stroke
			(width 0.05715)
			(type default)
		)
		(layer "In13.Cu")
	)
	(gr_line
		(start 361.799378 -295.145968)
		(end 361.799632 -295.145968)
		(stroke
			(width 0.05715)
			(type default)
		)
		(layer "In13.Cu")
	)
	(gr_line
		(start 362.079286 -271.980152)
		(end 362.075476 -271.982438)
		(stroke
			(width 0.05715)
			(type default)
		)
		(layer "In13.Cu")
	)
	(gr_line
		(start 362.08081 -271.979136)
		(end 362.079286 -271.980152)
		(stroke
			(width 0.05715)
			(type default)
		)
		(layer "In13.Cu")
	)
	(gr_line
		(start 362.081826 -271.978628)
		(end 362.08081 -271.979136)
		(stroke
			(width 0.05715)
			(type default)
		)
		(layer "In13.Cu")
	)
	(gr_line
		(start 362.082588 -270.358108)
		(end 362.081826 -270.358616)
		(stroke
			(width 0.05715)
			(type default)
		)
		(layer "In13.Cu")
	)
	(gr_line
		(start 362.172504 -272.146522)
		(end 362.171742 -272.14703)
		(stroke
			(width 0.05715)
			(type default)
		)
		(layer "In13.Cu")
	)
	(gr_line
		(start 362.17352 -272.146014)
		(end 362.172504 -272.146522)
		(stroke
			(width 0.05715)
			(type default)
		)
		(layer "In13.Cu")
	)
	(gr_line
		(start 362.174282 -272.145506)
		(end 362.17352 -272.146014)
		(stroke
			(width 0.05715)
			(type default)
		)
		(layer "In13.Cu")
	)
	(gr_line
		(start 362.177076 -272.143982)
		(end 362.174282 -272.145506)
		(stroke
			(width 0.05715)
			(type default)
		)
		(layer "In13.Cu")
	)
	(gr_line
		(start 362.177584 -272.143728)
		(end 362.177076 -272.143982)
		(stroke
			(width 0.05715)
			(type default)
		)
		(layer "In13.Cu")
	)
	(gr_line
		(start 362.178854 -270.5227)
		(end 362.177838 -270.523462)
		(stroke
			(width 0.05715)
			(type default)
		)
		(layer "In13.Cu")
	)
	(gr_line
		(start 362.203238 -296.545762)
		(end 362.203238 -296.57421)
		(stroke
			(width 0.05715)
			(type default)
		)
		(layer "In13.Cu")
	)
	(gr_line
		(start 362.248958 -296.500042)
		(end 362.203238 -296.545762)
		(stroke
			(width 0.05715)
			(type default)
		)
		(layer "In13.Cu")
	)
	(gr_arc
		(start 362.27004 -271.639284)
		(mid 362.269574 -271.644993)
		(end 362.269278 -271.650714)
		(stroke
			(width 0.05715)
			(type default)
		)
		(layer "In13.Cu")
	)
	(gr_line
		(start 362.364782 -274.086066)
		(end 362.662724 -274.086066)
		(stroke
			(width 0.05715)
			(type default)
		)
		(layer "In13.Cu")
	)
	(gr_line
		(start 362.364782 -272.466054)
		(end 362.662724 -272.466054)
		(stroke
			(width 0.05715)
			(type default)
		)
		(layer "In13.Cu")
	)
	(gr_line
		(start 362.364782 -270.846042)
		(end 362.662724 -270.846042)
		(stroke
			(width 0.05715)
			(type default)
		)
		(layer "In13.Cu")
	)
	(gr_line
		(start 362.364782 -269.22603)
		(end 362.662724 -269.22603)
		(stroke
			(width 0.05715)
			(type default)
		)
		(layer "In13.Cu")
	)
	(gr_line
		(start 362.439458 -296.500042)
		(end 362.485178 -296.545762)
		(stroke
			(width 0.05715)
			(type default)
		)
		(layer "In13.Cu")
	)
	(gr_arc
		(start 362.439458 -295.857422)
		(mid 362.439458 -295.857803)
		(end 362.439458 -295.858184)
		(stroke
			(width 0.05715)
			(type default)
		)
		(layer "In13.Cu")
	)
	(gr_arc
		(start 362.459778 -271.663414)
		(mid 362.45992 -271.659223)
		(end 362.460032 -271.655032)
		(stroke
			(width 0.05715)
			(type default)
		)
		(layer "In13.Cu")
	)
	(gr_line
		(start 362.485178 -296.545762)
		(end 362.485178 -296.57421)
		(stroke
			(width 0.05715)
			(type default)
		)
		(layer "In13.Cu")
	)
	(gr_arc
		(start 362.492544 -271.206468)
		(mid 362.490253 -271.208495)
		(end 362.487972 -271.210532)
		(stroke
			(width 0.05715)
			(type default)
		)
		(layer "In13.Cu")
	)
	(gr_arc
		(start 362.492544 -271.206468)
		(mid 362.493052 -271.206087)
		(end 362.49356 -271.205706)
		(stroke
			(width 0.05715)
			(type default)
		)
		(layer "In13.Cu")
	)
	(gr_line
		(start 362.535978 -293.845742)
		(end 362.5342 -293.846758)
		(stroke
			(width 0.05715)
			(type default)
		)
		(layer "In13.Cu")
	)
	(gr_arc
		(start 362.541058 -281.85745)
		(mid 362.540677 -281.857196)
		(end 362.540296 -281.856942)
		(stroke
			(width 0.05715)
			(type default)
		)
		(layer "In13.Cu")
	)
	(gr_arc
		(start 362.542836 -285.09849)
		(mid 362.544105 -285.099254)
		(end 362.545376 -285.100014)
		(stroke
			(width 0.05715)
			(type default)
		)
		(layer "In13.Cu")
	)
	(gr_arc
		(start 362.54309 -293.84117)
		(mid 362.539525 -293.843443)
		(end 362.535978 -293.845742)
		(stroke
			(width 0.05715)
			(type default)
		)
		(layer "In13.Cu")
	)
	(gr_arc
		(start 362.544614 -284.132782)
		(mid 362.543724 -284.133289)
		(end 362.542836 -284.133798)
		(stroke
			(width 0.05715)
			(type default)
		)
		(layer "In13.Cu")
	)
	(gr_line
		(start 362.544614 -283.479494)
		(end 362.5469 -283.480764)
		(stroke
			(width 0.05715)
			(type default)
		)
		(layer "In13.Cu")
	)
	(gr_arc
		(start 362.547154 -286.721042)
		(mid 362.548296 -286.721678)
		(end 362.54944 -286.722312)
		(stroke
			(width 0.05715)
			(type default)
		)
		(layer "In13.Cu")
	)
	(gr_line
		(start 362.547408 -292.231064)
		(end 362.545376 -292.232334)
		(stroke
			(width 0.05715)
			(type default)
		)
		(layer "In13.Cu")
	)
	(gr_line
		(start 362.549186 -292.229794)
		(end 362.548678 -292.230302)
		(stroke
			(width 0.05715)
			(type default)
		)
		(layer "In13.Cu")
	)
	(gr_line
		(start 362.54944 -286.722312)
		(end 362.550202 -286.72282)
		(stroke
			(width 0.05715)
			(type default)
		)
		(layer "In13.Cu")
	)
	(gr_arc
		(start 362.54944 -285.75)
		(mid 362.548551 -285.750507)
		(end 362.547662 -285.751016)
		(stroke
			(width 0.05715)
			(type default)
		)
		(layer "In13.Cu")
	)
	(gr_line
		(start 362.54944 -285.749746)
		(end 362.54944 -285.75)
		(stroke
			(width 0.05715)
			(type default)
		)
		(layer "In13.Cu")
	)
	(gr_line
		(start 362.549948 -282.509468)
		(end 362.54563 -282.512008)
		(stroke
			(width 0.05715)
			(type default)
		)
		(layer "In13.Cu")
	)
	(gr_line
		(start 362.550202 -285.749238)
		(end 362.54944 -285.749746)
		(stroke
			(width 0.05715)
			(type default)
		)
		(layer "In13.Cu")
	)
	(gr_line
		(start 362.551726 -280.243534)
		(end 362.552234 -280.243788)
		(stroke
			(width 0.05715)
			(type default)
		)
		(layer "In13.Cu")
	)
	(gr_line
		(start 362.551726 -271.168622)
		(end 362.551218 -271.168876)
		(stroke
			(width 0.05715)
			(type default)
		)
		(layer "In13.Cu")
	)
	(gr_line
		(start 362.552234 -271.168368)
		(end 362.551726 -271.168622)
		(stroke
			(width 0.05715)
			(type default)
		)
		(layer "In13.Cu")
	)
	(gr_line
		(start 362.552996 -269.547848)
		(end 362.550456 -269.549372)
		(stroke
			(width 0.05715)
			(type default)
		)
		(layer "In13.Cu")
	)
	(gr_line
		(start 362.554012 -269.54734)
		(end 362.552996 -269.547848)
		(stroke
			(width 0.05715)
			(type default)
		)
		(layer "In13.Cu")
	)
	(gr_line
		(start 362.554266 -292.227)
		(end 362.55198 -292.22827)
		(stroke
			(width 0.05715)
			(type default)
		)
		(layer "In13.Cu")
	)
	(gr_line
		(start 362.554266 -283.485082)
		(end 362.555282 -283.48559)
		(stroke
			(width 0.05715)
			(type default)
		)
		(layer "In13.Cu")
	)
	(gr_line
		(start 362.55579 -293.205662)
		(end 362.559346 -293.207694)
		(stroke
			(width 0.05715)
			(type default)
		)
		(layer "In13.Cu")
	)
	(gr_line
		(start 362.559346 -293.207694)
		(end 362.560362 -293.208202)
		(stroke
			(width 0.05715)
			(type default)
		)
		(layer "In13.Cu")
	)
	(gr_line
		(start 362.583222 -289.98164)
		(end 362.583476 -289.98164)
		(stroke
			(width 0.05715)
			(type default)
		)
		(layer "In13.Cu")
	)
	(gr_line
		(start 362.643674 -286.556704)
		(end 362.643674 -286.55645)
		(stroke
			(width 0.05715)
			(type default)
		)
		(layer "In13.Cu")
	)
	(gr_line
		(start 362.645452 -284.937454)
		(end 362.648754 -284.939486)
		(stroke
			(width 0.05715)
			(type default)
		)
		(layer "In13.Cu")
	)
	(gr_line
		(start 362.647738 -271.333468)
		(end 362.64723 -271.333468)
		(stroke
			(width 0.05715)
			(type default)
		)
		(layer "In13.Cu")
	)
	(gr_line
		(start 362.648246 -269.713202)
		(end 362.645452 -269.714726)
		(stroke
			(width 0.05715)
			(type default)
		)
		(layer "In13.Cu")
	)
	(gr_line
		(start 362.648754 -271.33296)
		(end 362.647738 -271.333468)
		(stroke
			(width 0.05715)
			(type default)
		)
		(layer "In13.Cu")
	)
	(gr_line
		(start 362.650532 -284.29204)
		(end 362.645452 -284.294834)
		(stroke
			(width 0.05715)
			(type default)
		)
		(layer "In13.Cu")
	)
	(gr_line
		(start 362.65104 -292.391338)
		(end 362.650278 -292.391846)
		(stroke
			(width 0.05715)
			(type default)
		)
		(layer "In13.Cu")
	)
	(gr_line
		(start 362.662724 -274.086066)
		(end 362.732066 -274.155408)
		(stroke
			(width 0.05715)
			(type default)
		)
		(layer "In13.Cu")
	)
	(gr_line
		(start 362.662724 -272.466054)
		(end 362.745528 -272.548858)
		(stroke
			(width 0.05715)
			(type default)
		)
		(layer "In13.Cu")
	)
	(gr_line
		(start 362.662724 -270.846042)
		(end 362.732066 -270.915384)
		(stroke
			(width 0.05715)
			(type default)
		)
		(layer "In13.Cu")
	)
	(gr_line
		(start 362.662724 -269.22603)
		(end 362.732066 -269.295372)
		(stroke
			(width 0.05715)
			(type default)
		)
		(layer "In13.Cu")
	)
	(gr_line
		(start 362.67644 -294.675306)
		(end 362.686092 -294.680894)
		(stroke
			(width 0.05715)
			(type default)
		)
		(layer "In13.Cu")
	)
	(gr_line
		(start 362.678472 -281.716734)
		(end 362.686092 -281.721052)
		(stroke
			(width 0.05715)
			(type default)
		)
		(layer "In13.Cu")
	)
	(gr_line
		(start 362.678726 -284.956758)
		(end 362.686092 -284.961076)
		(stroke
			(width 0.05715)
			(type default)
		)
		(layer "In13.Cu")
	)
	(gr_line
		(start 362.678726 -283.336746)
		(end 362.679488 -283.337254)
		(stroke
			(width 0.05715)
			(type default)
		)
		(layer "In13.Cu")
	)
	(gr_line
		(start 362.679488 -283.337254)
		(end 362.686092 -283.341064)
		(stroke
			(width 0.05715)
			(type default)
		)
		(layer "In13.Cu")
	)
	(gr_arc
		(start 362.686092 -294.680894)
		(mid 362.686473 -294.681148)
		(end 362.686854 -294.681402)
		(stroke
			(width 0.05715)
			(type default)
		)
		(layer "In13.Cu")
	)
	(gr_arc
		(start 362.686092 -284.961076)
		(mid 362.686473 -284.96133)
		(end 362.686854 -284.961584)
		(stroke
			(width 0.05715)
			(type default)
		)
		(layer "In13.Cu")
	)
	(gr_arc
		(start 362.686092 -283.341064)
		(mid 362.686473 -283.341318)
		(end 362.686854 -283.341572)
		(stroke
			(width 0.05715)
			(type default)
		)
		(layer "In13.Cu")
	)
	(gr_arc
		(start 362.686092 -281.721052)
		(mid 362.686473 -281.721306)
		(end 362.686854 -281.72156)
		(stroke
			(width 0.05715)
			(type default)
		)
		(layer "In13.Cu")
	)
	(gr_line
		(start 362.686854 -284.961584)
		(end 362.688886 -284.962854)
		(stroke
			(width 0.05715)
			(type default)
		)
		(layer "In13.Cu")
	)
	(gr_arc
		(start 362.688886 -284.962854)
		(mid 362.689267 -284.963108)
		(end 362.689648 -284.963362)
		(stroke
			(width 0.05715)
			(type default)
		)
		(layer "In13.Cu")
	)
	(gr_arc
		(start 362.694474 -294.686736)
		(mid 362.690675 -294.684054)
		(end 362.686854 -294.681402)
		(stroke
			(width 0.05715)
			(type default)
		)
		(layer "In13.Cu")
	)
	(gr_arc
		(start 362.694728 -283.34716)
		(mid 362.690803 -283.344349)
		(end 362.686854 -283.341572)
		(stroke
			(width 0.05715)
			(type default)
		)
		(layer "In13.Cu")
	)
	(gr_arc
		(start 362.694728 -281.727148)
		(mid 362.690803 -281.724337)
		(end 362.686854 -281.72156)
		(stroke
			(width 0.05715)
			(type default)
		)
		(layer "In13.Cu")
	)
	(gr_arc
		(start 362.69549 -284.967426)
		(mid 362.692955 -284.96564)
		(end 362.69041 -284.96387)
		(stroke
			(width 0.05715)
			(type default)
		)
		(layer "In13.Cu")
	)
	(gr_arc
		(start 362.745528 -272.548858)
		(mid 362.74732 -272.56018)
		(end 362.749338 -272.571464)
		(stroke
			(width 0.05715)
			(type default)
		)
		(layer "In13.Cu")
	)
	(gr_line
		(start 362.792264 -369.958874)
		(end 362.792264 -369.76685)
		(stroke
			(width 0.07112)
			(type default)
		)
		(layer "In13.Cu")
	)
	(gr_line
		(start 362.792264 -369.76685)
		(end 363.09427 -369.464844)
		(stroke
			(width 0.07112)
			(type default)
		)
		(layer "In13.Cu")
	)
	(gr_arc
		(start 362.92028 -274.19173)
		(mid 362.922302 -274.180319)
		(end 362.92409 -274.16887)
		(stroke
			(width 0.05715)
			(type default)
		)
		(layer "In13.Cu")
	)
	(gr_arc
		(start 362.92028 -270.951706)
		(mid 362.922301 -270.940295)
		(end 362.92409 -270.928846)
		(stroke
			(width 0.05715)
			(type default)
		)
		(layer "In13.Cu")
	)
	(gr_arc
		(start 362.92028 -269.331694)
		(mid 362.922301 -269.320283)
		(end 362.92409 -269.308834)
		(stroke
			(width 0.05715)
			(type default)
		)
		(layer "In13.Cu")
	)
	(gr_line
		(start 362.991654 -370.160042)
		(end 363.487462 -369.664234)
		(stroke
			(width 0.07112)
			(type default)
		)
		(layer "In13.Cu")
	)
	(gr_line
		(start 363.006894 -274.086066)
		(end 362.92409 -274.16887)
		(stroke
			(width 0.05715)
			(type default)
		)
		(layer "In13.Cu")
	)
	(gr_line
		(start 363.006894 -272.466054)
		(end 362.937552 -272.535396)
		(stroke
			(width 0.05715)
			(type default)
		)
		(layer "In13.Cu")
	)
	(gr_line
		(start 363.006894 -270.846042)
		(end 362.92409 -270.928846)
		(stroke
			(width 0.05715)
			(type default)
		)
		(layer "In13.Cu")
	)
	(gr_line
		(start 363.006894 -269.22603)
		(end 362.92409 -269.308834)
		(stroke
			(width 0.05715)
			(type default)
		)
		(layer "In13.Cu")
	)
	(gr_line
		(start 363.09427 -369.464844)
		(end 363.286294 -369.464844)
		(stroke
			(width 0.07112)
			(type default)
		)
		(layer "In13.Cu")
	)
	(gr_line
		(start 363.14253 -296.281348)
		(end 363.14253 -296.309796)
		(stroke
			(width 0.05715)
			(type default)
		)
		(layer "In13.Cu")
	)
	(gr_line
		(start 363.18825 -296.235628)
		(end 363.14253 -296.281348)
		(stroke
			(width 0.05715)
			(type default)
		)
		(layer "In13.Cu")
	)
	(gr_line
		(start 363.304836 -274.086066)
		(end 363.006894 -274.086066)
		(stroke
			(width 0.05715)
			(type default)
		)
		(layer "In13.Cu")
	)
	(gr_line
		(start 363.304836 -272.466054)
		(end 363.006894 -272.466054)
		(stroke
			(width 0.05715)
			(type default)
		)
		(layer "In13.Cu")
	)
	(gr_line
		(start 363.304836 -270.846042)
		(end 363.006894 -270.846042)
		(stroke
			(width 0.05715)
			(type default)
		)
		(layer "In13.Cu")
	)
	(gr_line
		(start 363.304836 -269.22603)
		(end 363.006894 -269.22603)
		(stroke
			(width 0.05715)
			(type default)
		)
		(layer "In13.Cu")
	)
	(gr_line
		(start 363.37875 -296.235628)
		(end 363.42447 -296.281348)
		(stroke
			(width 0.05715)
			(type default)
		)
		(layer "In13.Cu")
	)
	(gr_line
		(start 363.42447 -296.281348)
		(end 363.42447 -296.309796)
		(stroke
			(width 0.05715)
			(type default)
		)
		(layer "In13.Cu")
	)
	(gr_line
		(start 363.492034 -273.76374)
		(end 363.492542 -273.763994)
		(stroke
			(width 0.05715)
			(type default)
		)
		(layer "In13.Cu")
	)
	(gr_line
		(start 363.492542 -273.763994)
		(end 363.493812 -273.764756)
		(stroke
			(width 0.05715)
			(type default)
		)
		(layer "In13.Cu")
	)
	(gr_line
		(start 363.588046 -273.59864)
		(end 363.588808 -273.599148)
		(stroke
			(width 0.05715)
			(type default)
		)
		(layer "In13.Cu")
	)
	(gr_line
		(start 364.07471 -296.34561)
		(end 364.07471 -296.374058)
		(stroke
			(width 0.05715)
			(type default)
		)
		(layer "In13.Cu")
	)
	(gr_line
		(start 364.12043 -296.29989)
		(end 364.07471 -296.34561)
		(stroke
			(width 0.05715)
			(type default)
		)
		(layer "In13.Cu")
	)
	(gr_line
		(start 364.31093 -296.29989)
		(end 364.35665 -296.34561)
		(stroke
			(width 0.05715)
			(type default)
		)
		(layer "In13.Cu")
	)
	(gr_line
		(start 364.35665 -296.34561)
		(end 364.35665 -296.374058)
		(stroke
			(width 0.05715)
			(type default)
		)
		(layer "In13.Cu")
	)
	(gr_arc
		(start 364.38205 -286.693102)
		(mid 364.385216 -286.6954)
		(end 364.3884 -286.697674)
		(stroke
			(width 0.05715)
			(type default)
		)
		(layer "In13.Cu")
	)
	(gr_arc
		(start 364.384844 -293.174928)
		(mid 364.388769 -293.177739)
		(end 364.392718 -293.180516)
		(stroke
			(width 0.05715)
			(type default)
		)
		(layer "In13.Cu")
	)
	(gr_arc
		(start 364.384844 -291.554916)
		(mid 364.388769 -291.557727)
		(end 364.392718 -291.560504)
		(stroke
			(width 0.05715)
			(type default)
		)
		(layer "In13.Cu")
	)
	(gr_arc
		(start 364.384844 -289.934904)
		(mid 364.388769 -289.937715)
		(end 364.392718 -289.940492)
		(stroke
			(width 0.05715)
			(type default)
		)
		(layer "In13.Cu")
	)
	(gr_arc
		(start 364.384844 -281.835098)
		(mid 364.388769 -281.837909)
		(end 364.392718 -281.840686)
		(stroke
			(width 0.05715)
			(type default)
		)
		(layer "In13.Cu")
	)
	(gr_arc
		(start 364.384844 -280.215086)
		(mid 364.388769 -280.217897)
		(end 364.392718 -280.220674)
		(stroke
			(width 0.05715)
			(type default)
		)
		(layer "In13.Cu")
	)
	(gr_arc
		(start 364.384844 -276.975062)
		(mid 364.388769 -276.977873)
		(end 364.392718 -276.98065)
		(stroke
			(width 0.05715)
			(type default)
		)
		(layer "In13.Cu")
	)
	(gr_line
		(start 364.392718 -293.180516)
		(end 364.399576 -293.18458)
		(stroke
			(width 0.05715)
			(type default)
		)
		(layer "In13.Cu")
	)
	(gr_line
		(start 364.392718 -291.560504)
		(end 364.399576 -291.564568)
		(stroke
			(width 0.05715)
			(type default)
		)
		(layer "In13.Cu")
	)
	(gr_line
		(start 364.392718 -289.940492)
		(end 364.399576 -289.944556)
		(stroke
			(width 0.05715)
			(type default)
		)
		(layer "In13.Cu")
	)
	(gr_line
		(start 364.392718 -281.840686)
		(end 364.399576 -281.84475)
		(stroke
			(width 0.05715)
			(type default)
		)
		(layer "In13.Cu")
	)
	(gr_arc
		(start 364.392718 -280.911554)
		(mid 364.388769 -280.914331)
		(end 364.384844 -280.917142)
		(stroke
			(width 0.05715)
			(type default)
		)
		(layer "In13.Cu")
	)
	(gr_line
		(start 364.392718 -280.220674)
		(end 364.399576 -280.224738)
		(stroke
			(width 0.05715)
			(type default)
		)
		(layer "In13.Cu")
	)
	(gr_line
		(start 364.392718 -276.98065)
		(end 364.399576 -276.984714)
		(stroke
			(width 0.05715)
			(type default)
		)
		(layer "In13.Cu")
	)
	(gr_line
		(start 364.395512 -280.909522)
		(end 364.392718 -280.911554)
		(stroke
			(width 0.05715)
			(type default)
		)
		(layer "In13.Cu")
	)
	(gr_line
		(start 364.399576 -293.18458)
		(end 364.400338 -293.185088)
		(stroke
			(width 0.05715)
			(type default)
		)
		(layer "In13.Cu")
	)
	(gr_line
		(start 364.399576 -291.564568)
		(end 364.400338 -291.565076)
		(stroke
			(width 0.05715)
			(type default)
		)
		(layer "In13.Cu")
	)
	(gr_line
		(start 364.399576 -289.944556)
		(end 364.400338 -289.945064)
		(stroke
			(width 0.05715)
			(type default)
		)
		(layer "In13.Cu")
	)
	(gr_line
		(start 364.399576 -281.84475)
		(end 364.400338 -281.845258)
		(stroke
			(width 0.05715)
			(type default)
		)
		(layer "In13.Cu")
	)
	(gr_line
		(start 364.399576 -280.224738)
		(end 364.400338 -280.225246)
		(stroke
			(width 0.05715)
			(type default)
		)
		(layer "In13.Cu")
	)
	(gr_line
		(start 364.399576 -276.984714)
		(end 364.400338 -276.985222)
		(stroke
			(width 0.05715)
			(type default)
		)
		(layer "In13.Cu")
	)
	(gr_line
		(start 364.400338 -293.185088)
		(end 364.4011 -293.185596)
		(stroke
			(width 0.05715)
			(type default)
		)
		(layer "In13.Cu")
	)
	(gr_line
		(start 364.400338 -291.565076)
		(end 364.4011 -291.565584)
		(stroke
			(width 0.05715)
			(type default)
		)
		(layer "In13.Cu")
	)
	(gr_line
		(start 364.400338 -289.945064)
		(end 364.4011 -289.945572)
		(stroke
			(width 0.05715)
			(type default)
		)
		(layer "In13.Cu")
	)
	(gr_line
		(start 364.400338 -281.845258)
		(end 364.4011 -281.845766)
		(stroke
			(width 0.05715)
			(type default)
		)
		(layer "In13.Cu")
	)
	(gr_line
		(start 364.400338 -280.225246)
		(end 364.4011 -280.225754)
		(stroke
			(width 0.05715)
			(type default)
		)
		(layer "In13.Cu")
	)
	(gr_line
		(start 364.400338 -276.985222)
		(end 364.4011 -276.98573)
		(stroke
			(width 0.05715)
			(type default)
		)
		(layer "In13.Cu")
	)
	(gr_line
		(start 364.400592 -280.906474)
		(end 364.395512 -280.909522)
		(stroke
			(width 0.05715)
			(type default)
		)
		(layer "In13.Cu")
	)
	(gr_line
		(start 364.418372 -285.095696)
		(end 364.417864 -285.095442)
		(stroke
			(width 0.05715)
			(type default)
		)
		(layer "In13.Cu")
	)
	(gr_arc
		(start 364.419388 -285.096204)
		(mid 364.42015 -285.096713)
		(end 364.420912 -285.09722)
		(stroke
			(width 0.05715)
			(type default)
		)
		(layer "In13.Cu")
	)
	(gr_arc
		(start 364.424468 -285.099252)
		(mid 364.425864 -285.100143)
		(end 364.427262 -285.10103)
		(stroke
			(width 0.05715)
			(type default)
		)
		(layer "In13.Cu")
	)
	(gr_line
		(start 364.425738 -282.512262)
		(end 364.424976 -282.51277)
		(stroke
			(width 0.05715)
			(type default)
		)
		(layer "In13.Cu")
	)
	(gr_line
		(start 364.427008 -283.480764)
		(end 364.428786 -283.48178)
		(stroke
			(width 0.05715)
			(type default)
		)
		(layer "In13.Cu")
	)
	(gr_line
		(start 364.427262 -285.10103)
		(end 364.428278 -285.101538)
		(stroke
			(width 0.05715)
			(type default)
		)
		(layer "In13.Cu")
	)
	(gr_line
		(start 364.42777 -282.511246)
		(end 364.425738 -282.512262)
		(stroke
			(width 0.05715)
			(type default)
		)
		(layer "In13.Cu")
	)
	(gr_line
		(start 364.428278 -285.101538)
		(end 364.429548 -285.1023)
		(stroke
			(width 0.05715)
			(type default)
		)
		(layer "In13.Cu")
	)
	(gr_line
		(start 364.428786 -294.82288)
		(end 364.442248 -294.836342)
		(stroke
			(width 0.05715)
			(type default)
		)
		(layer "In13.Cu")
	)
	(gr_line
		(start 364.428786 -283.48178)
		(end 364.433104 -283.48432)
		(stroke
			(width 0.05715)
			(type default)
		)
		(layer "In13.Cu")
	)
	(gr_line
		(start 364.429294 -292.230048)
		(end 364.425992 -292.23208)
		(stroke
			(width 0.05715)
			(type default)
		)
		(layer "In13.Cu")
	)
	(gr_line
		(start 364.429294 -290.610036)
		(end 364.425992 -290.612068)
		(stroke
			(width 0.05715)
			(type default)
		)
		(layer "In13.Cu")
	)
	(gr_line
		(start 364.429294 -288.990024)
		(end 364.425992 -288.992056)
		(stroke
			(width 0.05715)
			(type default)
		)
		(layer "In13.Cu")
	)
	(gr_line
		(start 364.429294 -285.750254)
		(end 364.425992 -285.752286)
		(stroke
			(width 0.05715)
			(type default)
		)
		(layer "In13.Cu")
	)
	(gr_line
		(start 364.429294 -279.270206)
		(end 364.425992 -279.272238)
		(stroke
			(width 0.05715)
			(type default)
		)
		(layer "In13.Cu")
	)
	(gr_line
		(start 364.429294 -277.650194)
		(end 364.425992 -277.652226)
		(stroke
			(width 0.05715)
			(type default)
		)
		(layer "In13.Cu")
	)
	(gr_line
		(start 364.429294 -276.030182)
		(end 364.425992 -276.032214)
		(stroke
			(width 0.05715)
			(type default)
		)
		(layer "In13.Cu")
	)
	(gr_line
		(start 364.429294 -274.41017)
		(end 364.425992 -274.412202)
		(stroke
			(width 0.05715)
			(type default)
		)
		(layer "In13.Cu")
	)
	(gr_line
		(start 364.429294 -272.790158)
		(end 364.425992 -272.79219)
		(stroke
			(width 0.05715)
			(type default)
		)
		(layer "In13.Cu")
	)
	(gr_line
		(start 364.430056 -284.129734)
		(end 364.428532 -284.13075)
		(stroke
			(width 0.05715)
			(type default)
		)
		(layer "In13.Cu")
	)
	(gr_line
		(start 364.431834 -293.84879)
		(end 364.431834 -293.848536)
		(stroke
			(width 0.05715)
			(type default)
		)
		(layer "In13.Cu")
	)
	(gr_line
		(start 364.431834 -293.848536)
		(end 364.428024 -293.850822)
		(stroke
			(width 0.05715)
			(type default)
		)
		(layer "In13.Cu")
	)
	(gr_line
		(start 364.431834 -292.228778)
		(end 364.431834 -292.228524)
		(stroke
			(width 0.05715)
			(type default)
		)
		(layer "In13.Cu")
	)
	(gr_line
		(start 364.431834 -292.228524)
		(end 364.429294 -292.230048)
		(stroke
			(width 0.05715)
			(type default)
		)
		(layer "In13.Cu")
	)
	(gr_line
		(start 364.431834 -290.608766)
		(end 364.431834 -290.608512)
		(stroke
			(width 0.05715)
			(type default)
		)
		(layer "In13.Cu")
	)
	(gr_line
		(start 364.431834 -290.608512)
		(end 364.429294 -290.610036)
		(stroke
			(width 0.05715)
			(type default)
		)
		(layer "In13.Cu")
	)
	(gr_line
		(start 364.431834 -288.9885)
		(end 364.429294 -288.990024)
		(stroke
			(width 0.05715)
			(type default)
		)
		(layer "In13.Cu")
	)
	(gr_line
		(start 364.431834 -288.34334)
		(end 364.43285 -288.343848)
		(stroke
			(width 0.05715)
			(type default)
		)
		(layer "In13.Cu")
	)
	(gr_line
		(start 364.431834 -285.74873)
		(end 364.429294 -285.750254)
		(stroke
			(width 0.05715)
			(type default)
		)
		(layer "In13.Cu")
	)
	(gr_line
		(start 364.431834 -279.268682)
		(end 364.429294 -279.270206)
		(stroke
			(width 0.05715)
			(type default)
		)
		(layer "In13.Cu")
	)
	(gr_line
		(start 364.431834 -276.028658)
		(end 364.429294 -276.030182)
		(stroke
			(width 0.05715)
			(type default)
		)
		(layer "In13.Cu")
	)
	(gr_line
		(start 364.431834 -274.408646)
		(end 364.429294 -274.41017)
		(stroke
			(width 0.05715)
			(type default)
		)
		(layer "In13.Cu")
	)
	(gr_line
		(start 364.431834 -272.788634)
		(end 364.429294 -272.790158)
		(stroke
			(width 0.05715)
			(type default)
		)
		(layer "In13.Cu")
	)
	(gr_line
		(start 364.432088 -280.243788)
		(end 364.432596 -280.244042)
		(stroke
			(width 0.05715)
			(type default)
		)
		(layer "In13.Cu")
	)
	(gr_line
		(start 364.432088 -277.003764)
		(end 364.432596 -277.004018)
		(stroke
			(width 0.05715)
			(type default)
		)
		(layer "In13.Cu")
	)
	(gr_line
		(start 364.432342 -293.848536)
		(end 364.431834 -293.84879)
		(stroke
			(width 0.05715)
			(type default)
		)
		(layer "In13.Cu")
	)
	(gr_line
		(start 364.432342 -292.228524)
		(end 364.431834 -292.228778)
		(stroke
			(width 0.05715)
			(type default)
		)
		(layer "In13.Cu")
	)
	(gr_line
		(start 364.432342 -290.608512)
		(end 364.431834 -290.608766)
		(stroke
			(width 0.05715)
			(type default)
		)
		(layer "In13.Cu")
	)
	(gr_line
		(start 364.432596 -282.508452)
		(end 364.432596 -282.508198)
		(stroke
			(width 0.05715)
			(type default)
		)
		(layer "In13.Cu")
	)
	(gr_line
		(start 364.432596 -280.244042)
		(end 364.43539 -280.245566)
		(stroke
			(width 0.05715)
			(type default)
		)
		(layer "In13.Cu")
	)
	(gr_line
		(start 364.432596 -277.004018)
		(end 364.43539 -277.005542)
		(stroke
			(width 0.05715)
			(type default)
		)
		(layer "In13.Cu")
	)
	(gr_line
		(start 364.43285 -277.648162)
		(end 364.429294 -277.650194)
		(stroke
			(width 0.05715)
			(type default)
		)
		(layer "In13.Cu")
	)
	(gr_line
		(start 364.433104 -288.987992)
		(end 364.431834 -288.9885)
		(stroke
			(width 0.05715)
			(type default)
		)
		(layer "In13.Cu")
	)
	(gr_line
		(start 364.433612 -284.127956)
		(end 364.430818 -284.129226)
		(stroke
			(width 0.05715)
			(type default)
		)
		(layer "In13.Cu")
	)
	(gr_line
		(start 364.434628 -281.865324)
		(end 364.435136 -281.865324)
		(stroke
			(width 0.05715)
			(type default)
		)
		(layer "In13.Cu")
	)
	(gr_line
		(start 364.434882 -282.506928)
		(end 364.432596 -282.508452)
		(stroke
			(width 0.05715)
			(type default)
		)
		(layer "In13.Cu")
	)
	(gr_line
		(start 364.43539 -282.506928)
		(end 364.434882 -282.506928)
		(stroke
			(width 0.05715)
			(type default)
		)
		(layer "In13.Cu")
	)
	(gr_line
		(start 364.442248 -294.836342)
		(end 364.449614 -294.836342)
		(stroke
			(width 0.05715)
			(type default)
		)
		(layer "In13.Cu")
	)
	(gr_line
		(start 364.446058 -284.12059)
		(end 364.445296 -284.121098)
		(stroke
			(width 0.05715)
			(type default)
		)
		(layer "In13.Cu")
	)
	(gr_line
		(start 364.44682 -284.120082)
		(end 364.446058 -284.12059)
		(stroke
			(width 0.05715)
			(type default)
		)
		(layer "In13.Cu")
	)
	(gr_line
		(start 364.44936 -284.118558)
		(end 364.448598 -284.119066)
		(stroke
			(width 0.05715)
			(type default)
		)
		(layer "In13.Cu")
	)
	(gr_line
		(start 364.450122 -284.11805)
		(end 364.44936 -284.118558)
		(stroke
			(width 0.05715)
			(type default)
		)
		(layer "In13.Cu")
	)
	(gr_line
		(start 364.450122 -283.494226)
		(end 364.450376 -283.494226)
		(stroke
			(width 0.05715)
			(type default)
		)
		(layer "In13.Cu")
	)
	(gr_line
		(start 364.45063 -284.11805)
		(end 364.450122 -284.11805)
		(stroke
			(width 0.05715)
			(type default)
		)
		(layer "In13.Cu")
	)
	(gr_line
		(start 364.483396 -280.856182)
		(end 364.482888 -280.85669)
		(stroke
			(width 0.05715)
			(type default)
		)
		(layer "In13.Cu")
	)
	(gr_line
		(start 364.521242 -283.314902)
		(end 364.522004 -283.31541)
		(stroke
			(width 0.05715)
			(type default)
		)
		(layer "In13.Cu")
	)
	(gr_line
		(start 364.522004 -283.31541)
		(end 364.523528 -283.316172)
		(stroke
			(width 0.05715)
			(type default)
		)
		(layer "In13.Cu")
	)
	(gr_line
		(start 364.522766 -288.175446)
		(end 364.527846 -288.178494)
		(stroke
			(width 0.05715)
			(type default)
		)
		(layer "In13.Cu")
	)
	(gr_line
		(start 364.522766 -282.676092)
		(end 364.521242 -282.677108)
		(stroke
			(width 0.05715)
			(type default)
		)
		(layer "In13.Cu")
	)
	(gr_line
		(start 364.52302 -294.656002)
		(end 364.522512 -294.655748)
		(stroke
			(width 0.05715)
			(type default)
		)
		(layer "In13.Cu")
	)
	(gr_line
		(start 364.52302 -294.656002)
		(end 364.52556 -294.657526)
		(stroke
			(width 0.05715)
			(type default)
		)
		(layer "In13.Cu")
	)
	(gr_line
		(start 364.523528 -283.316172)
		(end 364.52429 -283.31668)
		(stroke
			(width 0.05715)
			(type default)
		)
		(layer "In13.Cu")
	)
	(gr_line
		(start 364.52429 -283.31668)
		(end 364.52556 -283.317442)
		(stroke
			(width 0.05715)
			(type default)
		)
		(layer "In13.Cu")
	)
	(gr_line
		(start 364.524544 -284.936692)
		(end 364.525306 -284.9372)
		(stroke
			(width 0.05715)
			(type default)
		)
		(layer "In13.Cu")
	)
	(gr_line
		(start 364.52556 -294.657526)
		(end 364.525814 -294.657272)
		(stroke
			(width 0.05715)
			(type default)
		)
		(layer "In13.Cu")
	)
	(gr_line
		(start 364.525814 -294.657272)
		(end 364.555786 -294.676576)
		(stroke
			(width 0.05715)
			(type default)
		)
		(layer "In13.Cu")
	)
	(gr_line
		(start 364.526068 -294.014398)
		(end 364.52429 -294.015414)
		(stroke
			(width 0.05715)
			(type default)
		)
		(layer "In13.Cu")
	)
	(gr_line
		(start 364.527084 -292.393878)
		(end 364.525306 -292.394894)
		(stroke
			(width 0.05715)
			(type default)
		)
		(layer "In13.Cu")
	)
	(gr_line
		(start 364.527084 -290.773866)
		(end 364.525306 -290.774882)
		(stroke
			(width 0.05715)
			(type default)
		)
		(layer "In13.Cu")
	)
	(gr_line
		(start 364.527084 -289.153854)
		(end 364.525306 -289.15487)
		(stroke
			(width 0.05715)
			(type default)
		)
		(layer "In13.Cu")
	)
	(gr_line
		(start 364.527084 -285.914084)
		(end 364.525306 -285.9151)
		(stroke
			(width 0.05715)
			(type default)
		)
		(layer "In13.Cu")
	)
	(gr_line
		(start 364.527084 -284.938216)
		(end 364.527846 -284.938724)
		(stroke
			(width 0.05715)
			(type default)
		)
		(layer "In13.Cu")
	)
	(gr_line
		(start 364.527084 -283.318458)
		(end 364.527084 -283.318204)
		(stroke
			(width 0.05715)
			(type default)
		)
		(layer "In13.Cu")
	)
	(gr_line
		(start 364.527084 -279.434036)
		(end 364.525306 -279.435052)
		(stroke
			(width 0.05715)
			(type default)
		)
		(layer "In13.Cu")
	)
	(gr_line
		(start 364.527084 -276.194012)
		(end 364.525306 -276.195028)
		(stroke
			(width 0.05715)
			(type default)
		)
		(layer "In13.Cu")
	)
	(gr_line
		(start 364.527084 -274.574)
		(end 364.525306 -274.575016)
		(stroke
			(width 0.05715)
			(type default)
		)
		(layer "In13.Cu")
	)
	(gr_line
		(start 364.527084 -272.953988)
		(end 364.525306 -272.955004)
		(stroke
			(width 0.05715)
			(type default)
		)
		(layer "In13.Cu")
	)
	(gr_line
		(start 364.527338 -278.458422)
		(end 364.527846 -278.458676)
		(stroke
			(width 0.05715)
			(type default)
		)
		(layer "In13.Cu")
	)
	(gr_line
		(start 364.527846 -292.39337)
		(end 364.527084 -292.393878)
		(stroke
			(width 0.05715)
			(type default)
		)
		(layer "In13.Cu")
	)
	(gr_line
		(start 364.527846 -290.773358)
		(end 364.527084 -290.773866)
		(stroke
			(width 0.05715)
			(type default)
		)
		(layer "In13.Cu")
	)
	(gr_line
		(start 364.527846 -288.178494)
		(end 364.528608 -288.179002)
		(stroke
			(width 0.05715)
			(type default)
		)
		(layer "In13.Cu")
	)
	(gr_line
		(start 364.527846 -285.913576)
		(end 364.527084 -285.914084)
		(stroke
			(width 0.05715)
			(type default)
		)
		(layer "In13.Cu")
	)
	(gr_line
		(start 364.527846 -282.673552)
		(end 364.527592 -282.673806)
		(stroke
			(width 0.05715)
			(type default)
		)
		(layer "In13.Cu")
	)
	(gr_line
		(start 364.527846 -281.6987)
		(end 364.530894 -281.700478)
		(stroke
			(width 0.05715)
			(type default)
		)
		(layer "In13.Cu")
	)
	(gr_line
		(start 364.527846 -279.433528)
		(end 364.527084 -279.434036)
		(stroke
			(width 0.05715)
			(type default)
		)
		(layer "In13.Cu")
	)
	(gr_line
		(start 364.527846 -276.193504)
		(end 364.527084 -276.194012)
		(stroke
			(width 0.05715)
			(type default)
		)
		(layer "In13.Cu")
	)
	(gr_line
		(start 364.527846 -274.573492)
		(end 364.527084 -274.574)
		(stroke
			(width 0.05715)
			(type default)
		)
		(layer "In13.Cu")
	)
	(gr_line
		(start 364.527846 -272.95348)
		(end 364.527084 -272.953988)
		(stroke
			(width 0.05715)
			(type default)
		)
		(layer "In13.Cu")
	)
	(gr_line
		(start 364.530132 -284.292294)
		(end 364.524544 -284.295342)
		(stroke
			(width 0.05715)
			(type default)
		)
		(layer "In13.Cu")
	)
	(gr_line
		(start 364.530894 -282.671774)
		(end 364.529878 -282.672282)
		(stroke
			(width 0.05715)
			(type default)
		)
		(layer "In13.Cu")
	)
	(gr_line
		(start 364.54334 -284.284674)
		(end 364.541562 -284.28569)
		(stroke
			(width 0.05715)
			(type default)
		)
		(layer "In13.Cu")
	)
	(gr_line
		(start 364.543594 -283.327856)
		(end 364.545372 -283.328872)
		(stroke
			(width 0.05715)
			(type default)
		)
		(layer "In13.Cu")
	)
	(gr_line
		(start 364.544102 -284.284166)
		(end 364.54334 -284.284674)
		(stroke
			(width 0.05715)
			(type default)
		)
		(layer "In13.Cu")
	)
	(gr_line
		(start 364.545372 -283.328872)
		(end 364.546134 -283.32938)
		(stroke
			(width 0.05715)
			(type default)
		)
		(layer "In13.Cu")
	)
	(gr_line
		(start 364.546134 -284.282896)
		(end 364.544102 -284.284166)
		(stroke
			(width 0.05715)
			(type default)
		)
		(layer "In13.Cu")
	)
	(gr_line
		(start 364.71479 -273.27606)
		(end 365.012732 -273.27606)
		(stroke
			(width 0.05715)
			(type default)
		)
		(layer "In13.Cu")
	)
	(gr_line
		(start 364.71479 -271.656048)
		(end 365.012732 -271.656048)
		(stroke
			(width 0.05715)
			(type default)
		)
		(layer "In13.Cu")
	)
	(gr_line
		(start 364.71479 -270.036036)
		(end 365.012732 -270.036036)
		(stroke
			(width 0.05715)
			(type default)
		)
		(layer "In13.Cu")
	)
	(gr_line
		(start 364.810802 7.190994)
		(end 364.519972 7.481824)
		(stroke
			(width 0.07112)
			(type default)
		)
		(layer "In13.Cu")
	)
	(gr_line
		(start 364.810802 8.054594)
		(end 364.519972 7.763764)
		(stroke
			(width 0.07112)
			(type default)
		)
		(layer "In13.Cu")
	)
	(gr_line
		(start 364.891828 -270.364458)
		(end 364.89132 -270.364712)
		(stroke
			(width 0.05715)
			(type default)
		)
		(layer "In13.Cu")
	)
	(gr_line
		(start 364.987332 -270.529304)
		(end 364.987078 -270.529558)
		(stroke
			(width 0.05715)
			(type default)
		)
		(layer "In13.Cu")
	)
	(gr_line
		(start 365.012732 -273.27606)
		(end 365.095536 -273.358864)
		(stroke
			(width 0.05715)
			(type default)
		)
		(layer "In13.Cu")
	)
	(gr_line
		(start 365.012732 -271.656048)
		(end 365.095536 -271.738852)
		(stroke
			(width 0.05715)
			(type default)
		)
		(layer "In13.Cu")
	)
	(gr_line
		(start 365.012732 -270.036036)
		(end 365.082074 -270.105378)
		(stroke
			(width 0.05715)
			(type default)
		)
		(layer "In13.Cu")
	)
	(gr_line
		(start 365.034322 -296.479976)
		(end 365.034322 -296.508424)
		(stroke
			(width 0.05715)
			(type default)
		)
		(layer "In13.Cu")
	)
	(gr_line
		(start 365.079788 -296.43451)
		(end 365.034322 -296.479976)
		(stroke
			(width 0.05715)
			(type default)
		)
		(layer "In13.Cu")
	)
	(gr_arc
		(start 365.095536 -273.358864)
		(mid 365.097323 -273.370314)
		(end 365.099346 -273.381724)
		(stroke
			(width 0.05715)
			(type default)
		)
		(layer "In13.Cu")
	)
	(gr_arc
		(start 365.095536 -271.738852)
		(mid 365.097328 -271.750174)
		(end 365.099346 -271.761458)
		(stroke
			(width 0.05715)
			(type default)
		)
		(layer "In13.Cu")
	)
	(gr_arc
		(start 365.270288 -270.1417)
		(mid 365.272309 -270.130289)
		(end 365.274098 -270.11884)
		(stroke
			(width 0.05715)
			(type default)
		)
		(layer "In13.Cu")
	)
	(gr_line
		(start 365.270542 -296.43451)
		(end 365.316262 -296.48023)
		(stroke
			(width 0.05715)
			(type default)
		)
		(layer "In13.Cu")
	)
	(gr_line
		(start 365.316262 -296.48023)
		(end 365.316262 -296.508678)
		(stroke
			(width 0.05715)
			(type default)
		)
		(layer "In13.Cu")
	)
	(gr_arc
		(start 365.322104 -288.313114)
		(mid 365.32527 -288.315413)
		(end 365.328454 -288.317686)
		(stroke
			(width 0.05715)
			(type default)
		)
		(layer "In13.Cu")
	)
	(gr_arc
		(start 365.324898 -293.174928)
		(mid 365.328823 -293.177739)
		(end 365.332772 -293.180516)
		(stroke
			(width 0.05715)
			(type default)
		)
		(layer "In13.Cu")
	)
	(gr_arc
		(start 365.324898 -283.45511)
		(mid 365.328823 -283.457921)
		(end 365.332772 -283.460698)
		(stroke
			(width 0.05715)
			(type default)
		)
		(layer "In13.Cu")
	)
	(gr_arc
		(start 365.329216 -288.318194)
		(mid 365.330992 -288.319467)
		(end 365.332772 -288.320734)
		(stroke
			(width 0.05715)
			(type default)
		)
		(layer "In13.Cu")
	)
	(gr_line
		(start 365.332772 -293.180516)
		(end 365.33963 -293.18458)
		(stroke
			(width 0.05715)
			(type default)
		)
		(layer "In13.Cu")
	)
	(gr_line
		(start 365.332772 -288.320734)
		(end 365.338868 -288.32429)
		(stroke
			(width 0.05715)
			(type default)
		)
		(layer "In13.Cu")
	)
	(gr_line
		(start 365.332772 -283.460698)
		(end 365.33963 -283.464762)
		(stroke
			(width 0.05715)
			(type default)
		)
		(layer "In13.Cu")
	)
	(gr_arc
		(start 365.332772 -280.911554)
		(mid 365.328823 -280.914331)
		(end 365.324898 -280.917142)
		(stroke
			(width 0.05715)
			(type default)
		)
		(layer "In13.Cu")
	)
	(gr_line
		(start 365.33328 -280.9113)
		(end 365.332772 -280.911554)
		(stroke
			(width 0.05715)
			(type default)
		)
		(layer "In13.Cu")
	)
	(gr_line
		(start 365.338868 -288.32429)
		(end 365.339122 -288.32429)
		(stroke
			(width 0.05715)
			(type default)
		)
		(layer "In13.Cu")
	)
	(gr_line
		(start 365.33963 -293.18458)
		(end 365.340392 -293.185088)
		(stroke
			(width 0.05715)
			(type default)
		)
		(layer "In13.Cu")
	)
	(gr_line
		(start 365.33963 -283.464762)
		(end 365.340392 -283.46527)
		(stroke
			(width 0.05715)
			(type default)
		)
		(layer "In13.Cu")
	)
	(gr_line
		(start 365.340392 -293.185088)
		(end 365.341408 -293.185596)
		(stroke
			(width 0.05715)
			(type default)
		)
		(layer "In13.Cu")
	)
	(gr_line
		(start 365.340392 -283.46527)
		(end 365.341154 -283.465778)
		(stroke
			(width 0.05715)
			(type default)
		)
		(layer "In13.Cu")
	)
	(gr_line
		(start 365.340392 -280.906982)
		(end 365.33328 -280.9113)
		(stroke
			(width 0.05715)
			(type default)
		)
		(layer "In13.Cu")
	)
	(gr_line
		(start 365.356902 -273.27606)
		(end 365.28756 -273.345402)
		(stroke
			(width 0.05715)
			(type default)
		)
		(layer "In13.Cu")
	)
	(gr_line
		(start 365.356902 -271.656048)
		(end 365.28756 -271.72539)
		(stroke
			(width 0.05715)
			(type default)
		)
		(layer "In13.Cu")
	)
	(gr_line
		(start 365.356902 -270.036036)
		(end 365.274098 -270.11884)
		(stroke
			(width 0.05715)
			(type default)
		)
		(layer "In13.Cu")
	)
	(gr_line
		(start 365.370618 -293.847266)
		(end 365.369348 -293.848028)
		(stroke
			(width 0.05715)
			(type default)
		)
		(layer "In13.Cu")
	)
	(gr_line
		(start 365.37265 -293.203884)
		(end 365.37392 -293.204646)
		(stroke
			(width 0.05715)
			(type default)
		)
		(layer "In13.Cu")
	)
	(gr_line
		(start 365.37265 -291.583872)
		(end 365.37392 -291.584634)
		(stroke
			(width 0.05715)
			(type default)
		)
		(layer "In13.Cu")
	)
	(gr_line
		(start 365.374682 -289.96513)
		(end 365.37519 -289.96513)
		(stroke
			(width 0.05715)
			(type default)
		)
		(layer "In13.Cu")
	)
	(gr_line
		(start 365.374682 -285.105348)
		(end 365.37519 -285.105348)
		(stroke
			(width 0.05715)
			(type default)
		)
		(layer "In13.Cu")
	)
	(gr_line
		(start 365.374682 -283.485336)
		(end 365.37519 -283.485336)
		(stroke
			(width 0.05715)
			(type default)
		)
		(layer "In13.Cu")
	)
	(gr_line
		(start 365.374682 -281.865324)
		(end 365.37519 -281.865324)
		(stroke
			(width 0.05715)
			(type default)
		)
		(layer "In13.Cu")
	)
	(gr_line
		(start 365.374936 -288.345118)
		(end 365.37519 -288.345118)
		(stroke
			(width 0.05715)
			(type default)
		)
		(layer "In13.Cu")
	)
	(gr_line
		(start 365.464852 -294.012874)
		(end 365.463328 -294.013636)
		(stroke
			(width 0.05715)
			(type default)
		)
		(layer "In13.Cu")
	)
	(gr_line
		(start 365.467138 -293.038022)
		(end 365.467646 -293.038276)
		(stroke
			(width 0.05715)
			(type default)
		)
		(layer "In13.Cu")
	)
	(gr_line
		(start 365.467392 -291.418264)
		(end 365.4679 -291.418518)
		(stroke
			(width 0.05715)
			(type default)
		)
		(layer "In13.Cu")
	)
	(gr_line
		(start 365.467392 -289.798252)
		(end 365.4679 -289.798506)
		(stroke
			(width 0.05715)
			(type default)
		)
		(layer "In13.Cu")
	)
	(gr_line
		(start 365.467392 -284.93847)
		(end 365.4679 -284.938724)
		(stroke
			(width 0.05715)
			(type default)
		)
		(layer "In13.Cu")
	)
	(gr_line
		(start 365.467392 -281.698446)
		(end 365.4679 -281.6987)
		(stroke
			(width 0.05715)
			(type default)
		)
		(layer "In13.Cu")
	)
	(gr_line
		(start 365.467646 -293.038276)
		(end 365.470186 -293.0398)
		(stroke
			(width 0.05715)
			(type default)
		)
		(layer "In13.Cu")
	)
	(gr_line
		(start 365.467646 -292.393624)
		(end 365.462312 -292.396672)
		(stroke
			(width 0.05715)
			(type default)
		)
		(layer "In13.Cu")
	)
	(gr_line
		(start 365.4679 -291.418518)
		(end 365.4679 -291.418772)
		(stroke
			(width 0.05715)
			(type default)
		)
		(layer "In13.Cu")
	)
	(gr_line
		(start 365.4679 -289.798506)
		(end 365.470948 -289.800284)
		(stroke
			(width 0.05715)
			(type default)
		)
		(layer "In13.Cu")
	)
	(gr_line
		(start 365.4679 -284.938724)
		(end 365.470948 -284.940502)
		(stroke
			(width 0.05715)
			(type default)
		)
		(layer "In13.Cu")
	)
	(gr_line
		(start 365.4679 -283.318712)
		(end 365.470948 -283.32049)
		(stroke
			(width 0.05715)
			(type default)
		)
		(layer "In13.Cu")
	)
	(gr_line
		(start 365.4679 -281.6987)
		(end 365.470948 -281.700478)
		(stroke
			(width 0.05715)
			(type default)
		)
		(layer "In13.Cu")
	)
	(gr_line
		(start 365.470948 -290.77158)
		(end 365.467392 -290.773612)
		(stroke
			(width 0.05715)
			(type default)
		)
		(layer "In13.Cu")
	)
	(gr_line
		(start 365.470948 -289.151568)
		(end 365.467392 -289.1536)
		(stroke
			(width 0.05715)
			(type default)
		)
		(layer "In13.Cu")
	)
	(gr_line
		(start 365.470948 -285.911798)
		(end 365.467392 -285.91383)
		(stroke
			(width 0.05715)
			(type default)
		)
		(layer "In13.Cu")
	)
	(gr_line
		(start 365.470948 -284.291786)
		(end 365.467392 -284.293818)
		(stroke
			(width 0.05715)
			(type default)
		)
		(layer "In13.Cu")
	)
	(gr_line
		(start 365.470948 -282.671774)
		(end 365.467392 -282.673806)
		(stroke
			(width 0.05715)
			(type default)
		)
		(layer "In13.Cu")
	)
	(gr_arc
		(start 365.471964 -293.040816)
		(mid 365.471075 -293.040307)
		(end 365.470186 -293.0398)
		(stroke
			(width 0.05715)
			(type default)
		)
		(layer "In13.Cu")
	)
	(gr_line
		(start 365.654844 -273.27606)
		(end 365.356902 -273.27606)
		(stroke
			(width 0.05715)
			(type default)
		)
		(layer "In13.Cu")
	)
	(gr_line
		(start 365.654844 -271.656048)
		(end 365.356902 -271.656048)
		(stroke
			(width 0.05715)
			(type default)
		)
		(layer "In13.Cu")
	)
	(gr_line
		(start 365.654844 -270.036036)
		(end 365.356902 -270.036036)
		(stroke
			(width 0.05715)
			(type default)
		)
		(layer "In13.Cu")
	)
	(gr_line
		(start 365.971582 -296.458894)
		(end 365.971582 -296.487342)
		(stroke
			(width 0.05715)
			(type default)
		)
		(layer "In13.Cu")
	)
	(gr_line
		(start 366.017302 -296.413174)
		(end 365.971582 -296.458894)
		(stroke
			(width 0.05715)
			(type default)
		)
		(layer "In13.Cu")
	)
	(gr_line
		(start 366.207802 -296.413174)
		(end 366.253522 -296.458894)
		(stroke
			(width 0.05715)
			(type default)
		)
		(layer "In13.Cu")
	)
	(gr_line
		(start 366.253522 -296.458894)
		(end 366.253522 -296.487342)
		(stroke
			(width 0.05715)
			(type default)
		)
		(layer "In13.Cu")
	)
	(gr_line
		(start 366.923828 -296.314114)
		(end 366.923828 -296.342562)
		(stroke
			(width 0.05715)
			(type default)
		)
		(layer "In13.Cu")
	)
	(gr_line
		(start 366.969548 -296.268394)
		(end 366.923828 -296.314114)
		(stroke
			(width 0.05715)
			(type default)
		)
		(layer "In13.Cu")
	)
	(gr_line
		(start 367.160048 -296.268394)
		(end 367.205768 -296.314114)
		(stroke
			(width 0.05715)
			(type default)
		)
		(layer "In13.Cu")
	)
	(gr_line
		(start 367.160302 -295.955974)
		(end 367.160048 -295.956228)
		(stroke
			(width 0.05715)
			(type default)
		)
		(layer "In13.Cu")
	)
	(gr_line
		(start 367.205768 -296.314114)
		(end 367.205768 -296.342562)
		(stroke
			(width 0.05715)
			(type default)
		)
		(layer "In13.Cu")
	)
	(gr_arc
		(start 367.240312 -293.196772)
		(mid 367.242468 -293.198047)
		(end 367.24463 -293.199312)
		(stroke
			(width 0.05715)
			(type default)
		)
		(layer "In13.Cu")
	)
	(gr_line
		(start 367.247932 -286.721296)
		(end 367.24717 -286.721042)
		(stroke
			(width 0.05715)
			(type default)
		)
		(layer "In13.Cu")
	)
	(gr_arc
		(start 367.248948 -288.990024)
		(mid 367.24755 -288.990784)
		(end 367.246154 -288.991548)
		(stroke
			(width 0.05715)
			(type default)
		)
		(layer "In13.Cu")
	)
	(gr_arc
		(start 367.248948 -284.127956)
		(mid 367.246913 -284.129221)
		(end 367.244884 -284.130496)
		(stroke
			(width 0.05715)
			(type default)
		)
		(layer "In13.Cu")
	)
	(gr_arc
		(start 367.248948 -282.507944)
		(mid 367.246913 -282.509209)
		(end 367.244884 -282.510484)
		(stroke
			(width 0.05715)
			(type default)
		)
		(layer "In13.Cu")
	)
	(gr_line
		(start 367.249202 -285.75)
		(end 367.249456 -285.75)
		(stroke
			(width 0.05715)
			(type default)
		)
		(layer "In13.Cu")
	)
	(gr_line
		(start 367.249456 -286.722312)
		(end 367.251234 -286.723328)
		(stroke
			(width 0.05715)
			(type default)
		)
		(layer "In13.Cu")
	)
	(gr_arc
		(start 367.249456 -285.75)
		(mid 367.248567 -285.750507)
		(end 367.247678 -285.751016)
		(stroke
			(width 0.05715)
			(type default)
		)
		(layer "In13.Cu")
	)
	(gr_line
		(start 367.249964 -285.749492)
		(end 367.249202 -285.75)
		(stroke
			(width 0.05715)
			(type default)
		)
		(layer "In13.Cu")
	)
	(gr_line
		(start 367.251488 -293.203376)
		(end 367.251742 -293.203376)
		(stroke
			(width 0.05715)
			(type default)
		)
		(layer "In13.Cu")
	)
	(gr_line
		(start 367.251742 -291.583364)
		(end 367.252504 -291.583872)
		(stroke
			(width 0.05715)
			(type default)
		)
		(layer "In13.Cu")
	)
	(gr_line
		(start 367.251742 -280.243534)
		(end 367.25225 -280.243788)
		(stroke
			(width 0.05715)
			(type default)
		)
		(layer "In13.Cu")
	)
	(gr_line
		(start 367.252504 -291.583872)
		(end 367.253774 -291.584634)
		(stroke
			(width 0.05715)
			(type default)
		)
		(layer "In13.Cu")
	)
	(gr_line
		(start 367.252504 -280.888186)
		(end 367.25098 -280.889202)
		(stroke
			(width 0.05715)
			(type default)
		)
		(layer "In13.Cu")
	)
	(gr_line
		(start 367.253774 -280.887424)
		(end 367.252504 -280.888186)
		(stroke
			(width 0.05715)
			(type default)
		)
		(layer "In13.Cu")
	)
	(gr_line
		(start 367.255552 -287.363916)
		(end 367.250726 -287.36671)
		(stroke
			(width 0.05715)
			(type default)
		)
		(layer "In13.Cu")
	)
	(gr_line
		(start 367.259616 -293.207948)
		(end 367.260378 -293.208202)
		(stroke
			(width 0.05715)
			(type default)
		)
		(layer "In13.Cu")
	)
	(gr_line
		(start 367.344706 -289.796728)
		(end 367.347754 -289.798506)
		(stroke
			(width 0.05715)
			(type default)
		)
		(layer "In13.Cu")
	)
	(gr_line
		(start 367.345214 -286.557466)
		(end 367.345976 -286.557974)
		(stroke
			(width 0.05715)
			(type default)
		)
		(layer "In13.Cu")
	)
	(gr_line
		(start 367.345976 -286.557974)
		(end 367.347246 -286.558736)
		(stroke
			(width 0.05715)
			(type default)
		)
		(layer "In13.Cu")
	)
	(gr_line
		(start 367.347246 -293.038276)
		(end 367.354866 -293.042594)
		(stroke
			(width 0.05715)
			(type default)
		)
		(layer "In13.Cu")
	)
	(gr_line
		(start 367.347246 -291.418518)
		(end 367.347754 -291.418518)
		(stroke
			(width 0.05715)
			(type default)
		)
		(layer "In13.Cu")
	)
	(gr_line
		(start 367.347246 -286.558736)
		(end 367.347754 -286.55899)
		(stroke
			(width 0.05715)
			(type default)
		)
		(layer "In13.Cu")
	)
	(gr_arc
		(start 367.347246 -284.291532)
		(mid 367.346611 -284.291913)
		(end 367.345976 -284.292294)
		(stroke
			(width 0.05715)
			(type default)
		)
		(layer "In13.Cu")
	)
	(gr_line
		(start 367.347754 -291.418518)
		(end 367.34877 -291.419026)
		(stroke
			(width 0.05715)
			(type default)
		)
		(layer "In13.Cu")
	)
	(gr_line
		(start 367.347754 -289.798506)
		(end 367.34877 -289.799014)
		(stroke
			(width 0.05715)
			(type default)
		)
		(layer "In13.Cu")
	)
	(gr_line
		(start 367.347754 -281.05354)
		(end 367.346484 -281.054048)
		(stroke
			(width 0.05715)
			(type default)
		)
		(layer "In13.Cu")
	)
	(gr_line
		(start 367.34877 -281.053032)
		(end 367.347754 -281.05354)
		(stroke
			(width 0.05715)
			(type default)
		)
		(layer "In13.Cu")
	)
	(gr_line
		(start 367.350548 -289.151568)
		(end 367.34496 -289.15487)
		(stroke
			(width 0.05715)
			(type default)
		)
		(layer "In13.Cu")
	)
	(gr_line
		(start 367.354866 -293.042594)
		(end 367.35639 -293.04361)
		(stroke
			(width 0.05715)
			(type default)
		)
		(layer "In13.Cu")
	)
	(gr_line
		(start 367.378742 -294.676576)
		(end 367.386108 -294.680894)
		(stroke
			(width 0.05715)
			(type default)
		)
		(layer "In13.Cu")
	)
	(gr_line
		(start 367.379504 -293.057072)
		(end 367.386108 -293.060882)
		(stroke
			(width 0.05715)
			(type default)
		)
		(layer "In13.Cu")
	)
	(gr_arc
		(start 367.386108 -294.680894)
		(mid 367.386489 -294.681148)
		(end 367.38687 -294.681402)
		(stroke
			(width 0.05715)
			(type default)
		)
		(layer "In13.Cu")
	)
	(gr_arc
		(start 367.386108 -293.060882)
		(mid 367.386489 -293.061136)
		(end 367.38687 -293.06139)
		(stroke
			(width 0.05715)
			(type default)
		)
		(layer "In13.Cu")
	)
	(gr_arc
		(start 367.394744 -294.68699)
		(mid 367.390819 -294.684179)
		(end 367.38687 -294.681402)
		(stroke
			(width 0.05715)
			(type default)
		)
		(layer "In13.Cu")
	)
	(gr_arc
		(start 367.394744 -293.066978)
		(mid 367.390819 -293.064167)
		(end 367.38687 -293.06139)
		(stroke
			(width 0.05715)
			(type default)
		)
		(layer "In13.Cu")
	)
	(gr_line
		(start 367.439448 -295.145968)
		(end 367.439702 -295.145968)
		(stroke
			(width 0.05715)
			(type default)
		)
		(layer "In13.Cu")
	)
	(gr_line
		(start 367.534698 -273.27606)
		(end 367.83264 -273.27606)
		(stroke
			(width 0.05715)
			(type default)
		)
		(layer "In13.Cu")
	)
	(gr_line
		(start 367.534698 -271.656048)
		(end 367.83264 -271.656048)
		(stroke
			(width 0.05715)
			(type default)
		)
		(layer "In13.Cu")
	)
	(gr_line
		(start 367.534698 -270.036036)
		(end 367.83264 -270.036036)
		(stroke
			(width 0.05715)
			(type default)
		)
		(layer "In13.Cu")
	)
	(gr_line
		(start 367.83264 -273.27606)
		(end 367.915444 -273.358864)
		(stroke
			(width 0.05715)
			(type default)
		)
		(layer "In13.Cu")
	)
	(gr_line
		(start 367.83264 -271.656048)
		(end 367.915444 -271.738852)
		(stroke
			(width 0.05715)
			(type default)
		)
		(layer "In13.Cu")
	)
	(gr_line
		(start 367.83264 -270.036036)
		(end 367.901982 -270.105378)
		(stroke
			(width 0.05715)
			(type default)
		)
		(layer "In13.Cu")
	)
	(gr_line
		(start 367.873788 -296.336466)
		(end 367.873788 -296.364914)
		(stroke
			(width 0.05715)
			(type default)
		)
		(layer "In13.Cu")
	)
	(gr_arc
		(start 367.915444 -273.358864)
		(mid 367.917236 -273.370186)
		(end 367.919254 -273.38147)
		(stroke
			(width 0.05715)
			(type default)
		)
		(layer "In13.Cu")
	)
	(gr_arc
		(start 367.915444 -271.738852)
		(mid 367.917236 -271.750174)
		(end 367.919254 -271.761458)
		(stroke
			(width 0.05715)
			(type default)
		)
		(layer "In13.Cu")
	)
	(gr_line
		(start 367.919508 -296.290746)
		(end 367.873788 -296.336466)
		(stroke
			(width 0.05715)
			(type default)
		)
		(layer "In13.Cu")
	)
	(gr_arc
		(start 368.090196 -270.1417)
		(mid 368.092217 -270.130289)
		(end 368.094006 -270.11884)
		(stroke
			(width 0.05715)
			(type default)
		)
		(layer "In13.Cu")
	)
	(gr_line
		(start 368.110008 -296.290746)
		(end 368.155728 -296.336466)
		(stroke
			(width 0.05715)
			(type default)
		)
		(layer "In13.Cu")
	)
	(gr_arc
		(start 368.142012 -288.313114)
		(mid 368.145178 -288.315412)
		(end 368.148362 -288.317686)
		(stroke
			(width 0.05715)
			(type default)
		)
		(layer "In13.Cu")
	)
	(gr_arc
		(start 368.144552 -273.735038)
		(mid 368.148604 -273.73785)
		(end 368.15268 -273.740626)
		(stroke
			(width 0.05715)
			(type default)
		)
		(layer "In13.Cu")
	)
	(gr_arc
		(start 368.144552 -272.115026)
		(mid 368.148604 -272.117838)
		(end 368.15268 -272.120614)
		(stroke
			(width 0.05715)
			(type default)
		)
		(layer "In13.Cu")
	)
	(gr_arc
		(start 368.144806 -283.45511)
		(mid 368.148731 -283.457921)
		(end 368.15268 -283.460698)
		(stroke
			(width 0.05715)
			(type default)
		)
		(layer "In13.Cu")
	)
	(gr_arc
		(start 368.144806 -276.975062)
		(mid 368.148731 -276.977873)
		(end 368.15268 -276.98065)
		(stroke
			(width 0.05715)
			(type default)
		)
		(layer "In13.Cu")
	)
	(gr_arc
		(start 368.144806 -275.35505)
		(mid 368.148731 -275.357861)
		(end 368.15268 -275.360638)
		(stroke
			(width 0.05715)
			(type default)
		)
		(layer "In13.Cu")
	)
	(gr_arc
		(start 368.149124 -288.318194)
		(mid 368.1509 -288.319467)
		(end 368.15268 -288.320734)
		(stroke
			(width 0.05715)
			(type default)
		)
		(layer "In13.Cu")
	)
	(gr_line
		(start 368.15268 -288.320734)
		(end 368.158776 -288.32429)
		(stroke
			(width 0.05715)
			(type default)
		)
		(layer "In13.Cu")
	)
	(gr_line
		(start 368.15268 -283.460698)
		(end 368.159538 -283.464762)
		(stroke
			(width 0.05715)
			(type default)
		)
		(layer "In13.Cu")
	)
	(gr_arc
		(start 368.15268 -280.911554)
		(mid 368.148731 -280.914331)
		(end 368.144806 -280.917142)
		(stroke
			(width 0.05715)
			(type default)
		)
		(layer "In13.Cu")
	)
	(gr_line
		(start 368.15268 -276.98065)
		(end 368.159538 -276.984714)
		(stroke
			(width 0.05715)
			(type default)
		)
		(layer "In13.Cu")
	)
	(gr_line
		(start 368.15268 -275.360638)
		(end 368.159538 -275.364702)
		(stroke
			(width 0.05715)
			(type default)
		)
		(layer "In13.Cu")
	)
	(gr_line
		(start 368.15268 -273.740626)
		(end 368.159538 -273.74469)
		(stroke
			(width 0.05715)
			(type default)
		)
		(layer "In13.Cu")
	)
	(gr_line
		(start 368.15268 -272.120614)
		(end 368.159538 -272.124678)
		(stroke
			(width 0.05715)
			(type default)
		)
		(layer "In13.Cu")
	)
	(gr_line
		(start 368.155474 -280.909522)
		(end 368.15268 -280.911554)
		(stroke
			(width 0.05715)
			(type default)
		)
		(layer "In13.Cu")
	)
	(gr_line
		(start 368.155728 -296.336466)
		(end 368.155728 -296.364914)
		(stroke
			(width 0.05715)
			(type default)
		)
		(layer "In13.Cu")
	)
	(gr_line
		(start 368.158776 -288.32429)
		(end 368.15903 -288.32429)
		(stroke
			(width 0.05715)
			(type default)
		)
		(layer "In13.Cu")
	)
	(gr_line
		(start 368.159538 -283.464762)
		(end 368.1603 -283.46527)
		(stroke
			(width 0.05715)
			(type default)
		)
		(layer "In13.Cu")
	)
	(gr_line
		(start 368.159538 -276.984714)
		(end 368.1603 -276.985222)
		(stroke
			(width 0.05715)
			(type default)
		)
		(layer "In13.Cu")
	)
	(gr_line
		(start 368.159538 -275.364702)
		(end 368.1603 -275.36521)
		(stroke
			(width 0.05715)
			(type default)
		)
		(layer "In13.Cu")
	)
	(gr_line
		(start 368.159538 -273.74469)
		(end 368.1603 -273.745198)
		(stroke
			(width 0.05715)
			(type default)
		)
		(layer "In13.Cu")
	)
	(gr_line
		(start 368.159538 -272.124678)
		(end 368.1603 -272.125186)
		(stroke
			(width 0.05715)
			(type default)
		)
		(layer "In13.Cu")
	)
	(gr_line
		(start 368.1603 -283.46527)
		(end 368.161062 -283.465778)
		(stroke
			(width 0.05715)
			(type default)
		)
		(layer "In13.Cu")
	)
	(gr_line
		(start 368.1603 -276.985222)
		(end 368.161062 -276.98573)
		(stroke
			(width 0.05715)
			(type default)
		)
		(layer "In13.Cu")
	)
	(gr_line
		(start 368.1603 -275.36521)
		(end 368.161062 -275.365718)
		(stroke
			(width 0.05715)
			(type default)
		)
		(layer "In13.Cu")
	)
	(gr_line
		(start 368.1603 -273.745198)
		(end 368.161062 -273.745706)
		(stroke
			(width 0.05715)
			(type default)
		)
		(layer "In13.Cu")
	)
	(gr_line
		(start 368.1603 -272.125186)
		(end 368.161062 -272.125694)
		(stroke
			(width 0.05715)
			(type default)
		)
		(layer "In13.Cu")
	)
	(gr_line
		(start 368.160808 -280.906474)
		(end 368.155474 -280.909522)
		(stroke
			(width 0.05715)
			(type default)
		)
		(layer "In13.Cu")
	)
	(gr_line
		(start 368.17681 -273.27606)
		(end 368.107468 -273.345402)
		(stroke
			(width 0.05715)
			(type default)
		)
		(layer "In13.Cu")
	)
	(gr_line
		(start 368.17681 -271.656048)
		(end 368.107468 -271.72539)
		(stroke
			(width 0.05715)
			(type default)
		)
		(layer "In13.Cu")
	)
	(gr_line
		(start 368.17681 -270.036036)
		(end 368.094006 -270.11884)
		(stroke
			(width 0.05715)
			(type default)
		)
		(layer "In13.Cu")
	)
	(gr_line
		(start 368.182652 -279.274016)
		(end 368.181636 -279.274524)
		(stroke
			(width 0.05715)
			(type default)
		)
		(layer "In13.Cu")
	)
	(gr_line
		(start 368.182652 -277.654004)
		(end 368.181636 -277.654512)
		(stroke
			(width 0.05715)
			(type default)
		)
		(layer "In13.Cu")
	)
	(gr_line
		(start 368.182652 -276.033992)
		(end 368.181636 -276.0345)
		(stroke
			(width 0.05715)
			(type default)
		)
		(layer "In13.Cu")
	)
	(gr_line
		(start 368.182652 -274.41398)
		(end 368.181636 -274.414488)
		(stroke
			(width 0.05715)
			(type default)
		)
		(layer "In13.Cu")
	)
	(gr_line
		(start 368.184684 -279.272746)
		(end 368.184176 -279.273)
		(stroke
			(width 0.05715)
			(type default)
		)
		(layer "In13.Cu")
	)
	(gr_line
		(start 368.184684 -277.652734)
		(end 368.184176 -277.652988)
		(stroke
			(width 0.05715)
			(type default)
		)
		(layer "In13.Cu")
	)
	(gr_line
		(start 368.184684 -276.032722)
		(end 368.184176 -276.032976)
		(stroke
			(width 0.05715)
			(type default)
		)
		(layer "In13.Cu")
	)
	(gr_line
		(start 368.184684 -274.41271)
		(end 368.184176 -274.412964)
		(stroke
			(width 0.05715)
			(type default)
		)
		(layer "In13.Cu")
	)
	(gr_line
		(start 368.19078 -279.26919)
		(end 368.189256 -279.270206)
		(stroke
			(width 0.05715)
			(type default)
		)
		(layer "In13.Cu")
	)
	(gr_line
		(start 368.19078 -277.649178)
		(end 368.189256 -277.650194)
		(stroke
			(width 0.05715)
			(type default)
		)
		(layer "In13.Cu")
	)
	(gr_line
		(start 368.19078 -276.029166)
		(end 368.189256 -276.030182)
		(stroke
			(width 0.05715)
			(type default)
		)
		(layer "In13.Cu")
	)
	(gr_line
		(start 368.19078 -274.409154)
		(end 368.189256 -274.41017)
		(stroke
			(width 0.05715)
			(type default)
		)
		(layer "In13.Cu")
	)
	(gr_line
		(start 368.191542 -279.268682)
		(end 368.19078 -279.26919)
		(stroke
			(width 0.05715)
			(type default)
		)
		(layer "In13.Cu")
	)
	(gr_line
		(start 368.191542 -277.64867)
		(end 368.19078 -277.649178)
		(stroke
			(width 0.05715)
			(type default)
		)
		(layer "In13.Cu")
	)
	(gr_line
		(start 368.191542 -276.028658)
		(end 368.19078 -276.029166)
		(stroke
			(width 0.05715)
			(type default)
		)
		(layer "In13.Cu")
	)
	(gr_line
		(start 368.191542 -274.408646)
		(end 368.19078 -274.409154)
		(stroke
			(width 0.05715)
			(type default)
		)
		(layer "In13.Cu")
	)
	(gr_line
		(start 368.191796 -280.243534)
		(end 368.192304 -280.243788)
		(stroke
			(width 0.05715)
			(type default)
		)
		(layer "In13.Cu")
	)
	(gr_line
		(start 368.19205 -277.003764)
		(end 368.192558 -277.004018)
		(stroke
			(width 0.05715)
			(type default)
		)
		(layer "In13.Cu")
	)
	(gr_line
		(start 368.19205 -275.383752)
		(end 368.192558 -275.384006)
		(stroke
			(width 0.05715)
			(type default)
		)
		(layer "In13.Cu")
	)
	(gr_line
		(start 368.19205 -273.76374)
		(end 368.192558 -273.763994)
		(stroke
			(width 0.05715)
			(type default)
		)
		(layer "In13.Cu")
	)
	(gr_line
		(start 368.19205 -272.143728)
		(end 368.192558 -272.143982)
		(stroke
			(width 0.05715)
			(type default)
		)
		(layer "In13.Cu")
	)
	(gr_line
		(start 368.192558 -291.583872)
		(end 368.193828 -291.584634)
		(stroke
			(width 0.05715)
			(type default)
		)
		(layer "In13.Cu")
	)
	(gr_line
		(start 368.192558 -278.62403)
		(end 368.193828 -278.624792)
		(stroke
			(width 0.05715)
			(type default)
		)
		(layer "In13.Cu")
	)
	(gr_line
		(start 368.192558 -277.004018)
		(end 368.195352 -277.005542)
		(stroke
			(width 0.05715)
			(type default)
		)
		(layer "In13.Cu")
	)
	(gr_line
		(start 368.192558 -275.384006)
		(end 368.195352 -275.38553)
		(stroke
			(width 0.05715)
			(type default)
		)
		(layer "In13.Cu")
	)
	(gr_line
		(start 368.192558 -273.763994)
		(end 368.195352 -273.765518)
		(stroke
			(width 0.05715)
			(type default)
		)
		(layer "In13.Cu")
	)
	(gr_line
		(start 368.192558 -272.143982)
		(end 368.193066 -272.144236)
		(stroke
			(width 0.05715)
			(type default)
		)
		(layer "In13.Cu")
	)
	(gr_line
		(start 368.19459 -293.205154)
		(end 368.195098 -293.205154)
		(stroke
			(width 0.05715)
			(type default)
		)
		(layer "In13.Cu")
	)
	(gr_line
		(start 368.19459 -289.96513)
		(end 368.195098 -289.96513)
		(stroke
			(width 0.05715)
			(type default)
		)
		(layer "In13.Cu")
	)
	(gr_line
		(start 368.19459 -285.105348)
		(end 368.195098 -285.105348)
		(stroke
			(width 0.05715)
			(type default)
		)
		(layer "In13.Cu")
	)
	(gr_line
		(start 368.19459 -283.485336)
		(end 368.195098 -283.485336)
		(stroke
			(width 0.05715)
			(type default)
		)
		(layer "In13.Cu")
	)
	(gr_line
		(start 368.19459 -281.865324)
		(end 368.195098 -281.865324)
		(stroke
			(width 0.05715)
			(type default)
		)
		(layer "In13.Cu")
	)
	(gr_line
		(start 368.194844 -288.345118)
		(end 368.195098 -288.345118)
		(stroke
			(width 0.05715)
			(type default)
		)
		(layer "In13.Cu")
	)
	(gr_line
		(start 368.195352 -272.145506)
		(end 368.196114 -272.146014)
		(stroke
			(width 0.05715)
			(type default)
		)
		(layer "In13.Cu")
	)
	(gr_line
		(start 368.196114 -272.146014)
		(end 368.197638 -272.146776)
		(stroke
			(width 0.05715)
			(type default)
		)
		(layer "In13.Cu")
	)
	(gr_line
		(start 368.197638 -272.146776)
		(end 368.1984 -272.147284)
		(stroke
			(width 0.05715)
			(type default)
		)
		(layer "In13.Cu")
	)
	(gr_line
		(start 368.1984 -272.147284)
		(end 368.199416 -272.147792)
		(stroke
			(width 0.05715)
			(type default)
		)
		(layer "In13.Cu")
	)
	(gr_line
		(start 368.278918 -279.438608)
		(end 368.277902 -279.439116)
		(stroke
			(width 0.05715)
			(type default)
		)
		(layer "In13.Cu")
	)
	(gr_line
		(start 368.278918 -277.818596)
		(end 368.277902 -277.819104)
		(stroke
			(width 0.05715)
			(type default)
		)
		(layer "In13.Cu")
	)
	(gr_line
		(start 368.278918 -276.198584)
		(end 368.277902 -276.199092)
		(stroke
			(width 0.05715)
			(type default)
		)
		(layer "In13.Cu")
	)
	(gr_line
		(start 368.278918 -274.578572)
		(end 368.277902 -274.57908)
		(stroke
			(width 0.05715)
			(type default)
		)
		(layer "In13.Cu")
	)
	(gr_line
		(start 368.28222 -279.43683)
		(end 368.28095 -279.437592)
		(stroke
			(width 0.05715)
			(type default)
		)
		(layer "In13.Cu")
	)
	(gr_line
		(start 368.28222 -277.816818)
		(end 368.28095 -277.81758)
		(stroke
			(width 0.05715)
			(type default)
		)
		(layer "In13.Cu")
	)
	(gr_line
		(start 368.28222 -276.196806)
		(end 368.28095 -276.197568)
		(stroke
			(width 0.05715)
			(type default)
		)
		(layer "In13.Cu")
	)
	(gr_line
		(start 368.28222 -274.576794)
		(end 368.28095 -274.577556)
		(stroke
			(width 0.05715)
			(type default)
		)
		(layer "In13.Cu")
	)
	(gr_line
		(start 368.282982 -279.436322)
		(end 368.28222 -279.43683)
		(stroke
			(width 0.05715)
			(type default)
		)
		(layer "In13.Cu")
	)
	(gr_line
		(start 368.282982 -277.81631)
		(end 368.28222 -277.816818)
		(stroke
			(width 0.05715)
			(type default)
		)
		(layer "In13.Cu")
	)
	(gr_line
		(start 368.282982 -276.196298)
		(end 368.28222 -276.196806)
		(stroke
			(width 0.05715)
			(type default)
		)
		(layer "In13.Cu")
	)
	(gr_line
		(start 368.282982 -274.576286)
		(end 368.28222 -274.576794)
		(stroke
			(width 0.05715)
			(type default)
		)
		(layer "In13.Cu")
	)
	(gr_line
		(start 368.284252 -279.43556)
		(end 368.282982 -279.436322)
		(stroke
			(width 0.05715)
			(type default)
		)
		(layer "In13.Cu")
	)
	(gr_line
		(start 368.284252 -277.815548)
		(end 368.282982 -277.81631)
		(stroke
			(width 0.05715)
			(type default)
		)
		(layer "In13.Cu")
	)
	(gr_line
		(start 368.284252 -276.195536)
		(end 368.282982 -276.196298)
		(stroke
			(width 0.05715)
			(type default)
		)
		(layer "In13.Cu")
	)
	(gr_line
		(start 368.284252 -274.575524)
		(end 368.282982 -274.576286)
		(stroke
			(width 0.05715)
			(type default)
		)
		(layer "In13.Cu")
	)
	(gr_line
		(start 368.285268 -279.435052)
		(end 368.284252 -279.43556)
		(stroke
			(width 0.05715)
			(type default)
		)
		(layer "In13.Cu")
	)
	(gr_line
		(start 368.285268 -277.81504)
		(end 368.284252 -277.815548)
		(stroke
			(width 0.05715)
			(type default)
		)
		(layer "In13.Cu")
	)
	(gr_line
		(start 368.285268 -276.195028)
		(end 368.284252 -276.195536)
		(stroke
			(width 0.05715)
			(type default)
		)
		(layer "In13.Cu")
	)
	(gr_line
		(start 368.285268 -274.575016)
		(end 368.284252 -274.575524)
		(stroke
			(width 0.05715)
			(type default)
		)
		(layer "In13.Cu")
	)
	(gr_line
		(start 368.286284 -280.077926)
		(end 368.287046 -280.07818)
		(stroke
			(width 0.05715)
			(type default)
		)
		(layer "In13.Cu")
	)
	(gr_line
		(start 368.287046 -279.434036)
		(end 368.286538 -279.43429)
		(stroke
			(width 0.05715)
			(type default)
		)
		(layer "In13.Cu")
	)
	(gr_line
		(start 368.287046 -277.814024)
		(end 368.286538 -277.814278)
		(stroke
			(width 0.05715)
			(type default)
		)
		(layer "In13.Cu")
	)
	(gr_line
		(start 368.287046 -276.194012)
		(end 368.286538 -276.194266)
		(stroke
			(width 0.05715)
			(type default)
		)
		(layer "In13.Cu")
	)
	(gr_line
		(start 368.287046 -274.574)
		(end 368.286538 -274.574254)
		(stroke
			(width 0.05715)
			(type default)
		)
		(layer "In13.Cu")
	)
	(gr_line
		(start 368.2873 -294.658288)
		(end 368.287808 -294.658542)
		(stroke
			(width 0.05715)
			(type default)
		)
		(layer "In13.Cu")
	)
	(gr_line
		(start 368.2873 -293.038276)
		(end 368.287808 -293.03853)
		(stroke
			(width 0.05715)
			(type default)
		)
		(layer "In13.Cu")
	)
	(gr_line
		(start 368.2873 -291.418264)
		(end 368.287808 -291.418518)
		(stroke
			(width 0.05715)
			(type default)
		)
		(layer "In13.Cu")
	)
	(gr_line
		(start 368.2873 -289.798252)
		(end 368.287808 -289.798506)
		(stroke
			(width 0.05715)
			(type default)
		)
		(layer "In13.Cu")
	)
	(gr_line
		(start 368.2873 -284.93847)
		(end 368.287808 -284.938724)
		(stroke
			(width 0.05715)
			(type default)
		)
		(layer "In13.Cu")
	)
	(gr_line
		(start 368.2873 -281.698446)
		(end 368.287808 -281.6987)
		(stroke
			(width 0.05715)
			(type default)
		)
		(layer "In13.Cu")
	)
	(gr_line
		(start 368.2873 -278.458422)
		(end 368.287808 -278.458676)
		(stroke
			(width 0.05715)
			(type default)
		)
		(layer "In13.Cu")
	)
	(gr_line
		(start 368.287554 -292.393624)
		(end 368.28222 -292.396672)
		(stroke
			(width 0.05715)
			(type default)
		)
		(layer "In13.Cu")
	)
	(gr_line
		(start 368.287554 -279.433782)
		(end 368.287046 -279.434036)
		(stroke
			(width 0.05715)
			(type default)
		)
		(layer "In13.Cu")
	)
	(gr_line
		(start 368.287554 -277.81377)
		(end 368.287046 -277.814024)
		(stroke
			(width 0.05715)
			(type default)
		)
		(layer "In13.Cu")
	)
	(gr_line
		(start 368.287554 -276.193758)
		(end 368.287046 -276.194012)
		(stroke
			(width 0.05715)
			(type default)
		)
		(layer "In13.Cu")
	)
	(gr_line
		(start 368.287554 -274.573746)
		(end 368.287046 -274.574)
		(stroke
			(width 0.05715)
			(type default)
		)
		(layer "In13.Cu")
	)
	(gr_line
		(start 368.287808 -294.658542)
		(end 368.291872 -294.661082)
		(stroke
			(width 0.05715)
			(type default)
		)
		(layer "In13.Cu")
	)
	(gr_line
		(start 368.287808 -293.03853)
		(end 368.290856 -293.040308)
		(stroke
			(width 0.05715)
			(type default)
		)
		(layer "In13.Cu")
	)
	(gr_line
		(start 368.287808 -291.418518)
		(end 368.287808 -291.418772)
		(stroke
			(width 0.05715)
			(type default)
		)
		(layer "In13.Cu")
	)
	(gr_line
		(start 368.287808 -289.798506)
		(end 368.290856 -289.800284)
		(stroke
			(width 0.05715)
			(type default)
		)
		(layer "In13.Cu")
	)
	(gr_line
		(start 368.287808 -284.938724)
		(end 368.290856 -284.940502)
		(stroke
			(width 0.05715)
			(type default)
		)
		(layer "In13.Cu")
	)
	(gr_line
		(start 368.287808 -283.318712)
		(end 368.290856 -283.32049)
		(stroke
			(width 0.05715)
			(type default)
		)
		(layer "In13.Cu")
	)
	(gr_line
		(start 368.287808 -281.6987)
		(end 368.290856 -281.700478)
		(stroke
			(width 0.05715)
			(type default)
		)
		(layer "In13.Cu")
	)
	(gr_line
		(start 368.287808 -278.458676)
		(end 368.288824 -278.459184)
		(stroke
			(width 0.05715)
			(type default)
		)
		(layer "In13.Cu")
	)
	(gr_line
		(start 368.287808 -276.838664)
		(end 368.288824 -276.839172)
		(stroke
			(width 0.05715)
			(type default)
		)
		(layer "In13.Cu")
	)
	(gr_line
		(start 368.287808 -275.218652)
		(end 368.288824 -275.21916)
		(stroke
			(width 0.05715)
			(type default)
		)
		(layer "In13.Cu")
	)
	(gr_line
		(start 368.287808 -273.59864)
		(end 368.288824 -273.599148)
		(stroke
			(width 0.05715)
			(type default)
		)
		(layer "In13.Cu")
	)
	(gr_line
		(start 368.287808 -271.978628)
		(end 368.288824 -271.979136)
		(stroke
			(width 0.05715)
			(type default)
		)
		(layer "In13.Cu")
	)
	(gr_line
		(start 368.288824 -276.839172)
		(end 368.290348 -276.840188)
		(stroke
			(width 0.05715)
			(type default)
		)
		(layer "In13.Cu")
	)
	(gr_line
		(start 368.288824 -275.21916)
		(end 368.290348 -275.220176)
		(stroke
			(width 0.05715)
			(type default)
		)
		(layer "In13.Cu")
	)
	(gr_line
		(start 368.288824 -273.599148)
		(end 368.290348 -273.600164)
		(stroke
			(width 0.05715)
			(type default)
		)
		(layer "In13.Cu")
	)
	(gr_line
		(start 368.288824 -271.979136)
		(end 368.290348 -271.980152)
		(stroke
			(width 0.05715)
			(type default)
		)
		(layer "In13.Cu")
	)
	(gr_line
		(start 368.290348 -276.840188)
		(end 368.291364 -276.840696)
		(stroke
			(width 0.05715)
			(type default)
		)
		(layer "In13.Cu")
	)
	(gr_line
		(start 368.290348 -275.220176)
		(end 368.291364 -275.220684)
		(stroke
			(width 0.05715)
			(type default)
		)
		(layer "In13.Cu")
	)
	(gr_line
		(start 368.290348 -273.600164)
		(end 368.291364 -273.600672)
		(stroke
			(width 0.05715)
			(type default)
		)
		(layer "In13.Cu")
	)
	(gr_line
		(start 368.290348 -271.980152)
		(end 368.291364 -271.98066)
		(stroke
			(width 0.05715)
			(type default)
		)
		(layer "In13.Cu")
	)
	(gr_line
		(start 368.290856 -294.011604)
		(end 368.2873 -294.013636)
		(stroke
			(width 0.05715)
			(type default)
		)
		(layer "In13.Cu")
	)
	(gr_line
		(start 368.290856 -290.77158)
		(end 368.2873 -290.773612)
		(stroke
			(width 0.05715)
			(type default)
		)
		(layer "In13.Cu")
	)
	(gr_line
		(start 368.290856 -289.151568)
		(end 368.2873 -289.1536)
		(stroke
			(width 0.05715)
			(type default)
		)
		(layer "In13.Cu")
	)
	(gr_line
		(start 368.290856 -285.911798)
		(end 368.2873 -285.91383)
		(stroke
			(width 0.05715)
			(type default)
		)
		(layer "In13.Cu")
	)
	(gr_line
		(start 368.290856 -284.291786)
		(end 368.2873 -284.293818)
		(stroke
			(width 0.05715)
			(type default)
		)
		(layer "In13.Cu")
	)
	(gr_line
		(start 368.290856 -282.671774)
		(end 368.2873 -282.673806)
		(stroke
			(width 0.05715)
			(type default)
		)
		(layer "In13.Cu")
	)
	(gr_line
		(start 368.291364 -276.840696)
		(end 368.296444 -276.843744)
		(stroke
			(width 0.05715)
			(type default)
		)
		(layer "In13.Cu")
	)
	(gr_line
		(start 368.291364 -275.220684)
		(end 368.296444 -275.223732)
		(stroke
			(width 0.05715)
			(type default)
		)
		(layer "In13.Cu")
	)
	(gr_line
		(start 368.291364 -273.600672)
		(end 368.296444 -273.60372)
		(stroke
			(width 0.05715)
			(type default)
		)
		(layer "In13.Cu")
	)
	(gr_line
		(start 368.291364 -271.98066)
		(end 368.293904 -271.982184)
		(stroke
			(width 0.05715)
			(type default)
		)
		(layer "In13.Cu")
	)
	(gr_line
		(start 368.293904 -271.982184)
		(end 368.29492 -271.982946)
		(stroke
			(width 0.05715)
			(type default)
		)
		(layer "In13.Cu")
	)
	(gr_line
		(start 368.474752 -273.27606)
		(end 368.17681 -273.27606)
		(stroke
			(width 0.05715)
			(type default)
		)
		(layer "In13.Cu")
	)
	(gr_line
		(start 368.474752 -271.656048)
		(end 368.17681 -271.656048)
		(stroke
			(width 0.05715)
			(type default)
		)
		(layer "In13.Cu")
	)
	(gr_line
		(start 368.474752 -270.036036)
		(end 368.17681 -270.036036)
		(stroke
			(width 0.05715)
			(type default)
		)
		(layer "In13.Cu")
	)
	(gr_line
		(start 368.570002 -295.145968)
		(end 368.570256 -295.145968)
		(stroke
			(width 0.05715)
			(type default)
		)
		(layer "In13.Cu")
	)
	(gr_line
		(start 368.734086 -295.454832)
		(end 368.735102 -295.45534)
		(stroke
			(width 0.05715)
			(type default)
		)
		(layer "In13.Cu")
	)
	(gr_line
		(start 368.767868 -295.47439)
		(end 368.768376 -295.474898)
		(stroke
			(width 0.05715)
			(type default)
		)
		(layer "In13.Cu")
	)
	(gr_arc
		(start 368.796824 -295.491408)
		(mid 368.797205 -295.491662)
		(end 368.797586 -295.491916)
		(stroke
			(width 0.05715)
			(type default)
		)
		(layer "In13.Cu")
	)
	(gr_line
		(start 368.806984 -296.40911)
		(end 368.806984 -296.437558)
		(stroke
			(width 0.05715)
			(type default)
		)
		(layer "In13.Cu")
	)
	(gr_line
		(start 368.852704 -296.36339)
		(end 368.806984 -296.40911)
		(stroke
			(width 0.05715)
			(type default)
		)
		(layer "In13.Cu")
	)
	(gr_line
		(start 369.043204 -296.36339)
		(end 369.088924 -296.40911)
		(stroke
			(width 0.05715)
			(type default)
		)
		(layer "In13.Cu")
	)
	(gr_arc
		(start 369.08486 -280.215086)
		(mid 369.088785 -280.217897)
		(end 369.092734 -280.220674)
		(stroke
			(width 0.05715)
			(type default)
		)
		(layer "In13.Cu")
	)
	(gr_arc
		(start 369.08486 -278.595074)
		(mid 369.088785 -278.597885)
		(end 369.092734 -278.600662)
		(stroke
			(width 0.05715)
			(type default)
		)
		(layer "In13.Cu")
	)
	(gr_arc
		(start 369.08486 -276.975062)
		(mid 369.088785 -276.977873)
		(end 369.092734 -276.98065)
		(stroke
			(width 0.05715)
			(type default)
		)
		(layer "In13.Cu")
	)
	(gr_arc
		(start 369.08486 -275.35505)
		(mid 369.088785 -275.357861)
		(end 369.092734 -275.360638)
		(stroke
			(width 0.05715)
			(type default)
		)
		(layer "In13.Cu")
	)
	(gr_arc
		(start 369.08486 -273.735038)
		(mid 369.088785 -273.737849)
		(end 369.092734 -273.740626)
		(stroke
			(width 0.05715)
			(type default)
		)
		(layer "In13.Cu")
	)
	(gr_line
		(start 369.088924 -296.40911)
		(end 369.088924 -296.437558)
		(stroke
			(width 0.05715)
			(type default)
		)
		(layer "In13.Cu")
	)
	(gr_arc
		(start 369.092734 -280.911554)
		(mid 369.090444 -280.9132)
		(end 369.088162 -280.914856)
		(stroke
			(width 0.05715)
			(type default)
		)
		(layer "In13.Cu")
	)
	(gr_line
		(start 369.092734 -280.220674)
		(end 369.099592 -280.224738)
		(stroke
			(width 0.05715)
			(type default)
		)
		(layer "In13.Cu")
	)
	(gr_line
		(start 369.092734 -278.600662)
		(end 369.099592 -278.604726)
		(stroke
			(width 0.05715)
			(type default)
		)
		(layer "In13.Cu")
	)
	(gr_line
		(start 369.092734 -276.98065)
		(end 369.099592 -276.984714)
		(stroke
			(width 0.05715)
			(type default)
		)
		(layer "In13.Cu")
	)
	(gr_line
		(start 369.092734 -275.360638)
		(end 369.099592 -275.364702)
		(stroke
			(width 0.05715)
			(type default)
		)
		(layer "In13.Cu")
	)
	(gr_line
		(start 369.092734 -273.740626)
		(end 369.099592 -273.74469)
		(stroke
			(width 0.05715)
			(type default)
		)
		(layer "In13.Cu")
	)
	(gr_line
		(start 369.095528 -280.909522)
		(end 369.092734 -280.911554)
		(stroke
			(width 0.05715)
			(type default)
		)
		(layer "In13.Cu")
	)
	(gr_line
		(start 369.099592 -280.224738)
		(end 369.100354 -280.225246)
		(stroke
			(width 0.05715)
			(type default)
		)
		(layer "In13.Cu")
	)
	(gr_line
		(start 369.099592 -278.604726)
		(end 369.100354 -278.605234)
		(stroke
			(width 0.05715)
			(type default)
		)
		(layer "In13.Cu")
	)
	(gr_line
		(start 369.099592 -276.984714)
		(end 369.100354 -276.985222)
		(stroke
			(width 0.05715)
			(type default)
		)
		(layer "In13.Cu")
	)
	(gr_line
		(start 369.099592 -275.364702)
		(end 369.100354 -275.36521)
		(stroke
			(width 0.05715)
			(type default)
		)
		(layer "In13.Cu")
	)
	(gr_line
		(start 369.099592 -273.74469)
		(end 369.100354 -273.745198)
		(stroke
			(width 0.05715)
			(type default)
		)
		(layer "In13.Cu")
	)
	(gr_line
		(start 369.100354 -280.225246)
		(end 369.101116 -280.225754)
		(stroke
			(width 0.05715)
			(type default)
		)
		(layer "In13.Cu")
	)
	(gr_line
		(start 369.100354 -278.605234)
		(end 369.101116 -278.605742)
		(stroke
			(width 0.05715)
			(type default)
		)
		(layer "In13.Cu")
	)
	(gr_line
		(start 369.100354 -276.985222)
		(end 369.101116 -276.98573)
		(stroke
			(width 0.05715)
			(type default)
		)
		(layer "In13.Cu")
	)
	(gr_line
		(start 369.100354 -275.36521)
		(end 369.101116 -275.365718)
		(stroke
			(width 0.05715)
			(type default)
		)
		(layer "In13.Cu")
	)
	(gr_line
		(start 369.100354 -273.745198)
		(end 369.101116 -273.745706)
		(stroke
			(width 0.05715)
			(type default)
		)
		(layer "In13.Cu")
	)
	(gr_line
		(start 369.10391 -280.904696)
		(end 369.095528 -280.909522)
		(stroke
			(width 0.05715)
			(type default)
		)
		(layer "In13.Cu")
	)
	(gr_line
		(start 369.13185 -279.268682)
		(end 369.130834 -279.26919)
		(stroke
			(width 0.05715)
			(type default)
		)
		(layer "In13.Cu")
	)
	(gr_line
		(start 369.13185 -277.64867)
		(end 369.130834 -277.649178)
		(stroke
			(width 0.05715)
			(type default)
		)
		(layer "In13.Cu")
	)
	(gr_line
		(start 369.13185 -276.028658)
		(end 369.130834 -276.029166)
		(stroke
			(width 0.05715)
			(type default)
		)
		(layer "In13.Cu")
	)
	(gr_line
		(start 369.13185 -274.408646)
		(end 369.130834 -274.409154)
		(stroke
			(width 0.05715)
			(type default)
		)
		(layer "In13.Cu")
	)
	(gr_line
		(start 369.132104 -280.243788)
		(end 369.132612 -280.244042)
		(stroke
			(width 0.05715)
			(type default)
		)
		(layer "In13.Cu")
	)
	(gr_line
		(start 369.132104 -278.623776)
		(end 369.132612 -278.62403)
		(stroke
			(width 0.05715)
			(type default)
		)
		(layer "In13.Cu")
	)
	(gr_line
		(start 369.132612 -280.244042)
		(end 369.135406 -280.245566)
		(stroke
			(width 0.05715)
			(type default)
		)
		(layer "In13.Cu")
	)
	(gr_line
		(start 369.132612 -279.268174)
		(end 369.13185 -279.268682)
		(stroke
			(width 0.05715)
			(type default)
		)
		(layer "In13.Cu")
	)
	(gr_line
		(start 369.132612 -278.62403)
		(end 369.135406 -278.625554)
		(stroke
			(width 0.05715)
			(type default)
		)
		(layer "In13.Cu")
	)
	(gr_line
		(start 369.133882 -279.267412)
		(end 369.132612 -279.268174)
		(stroke
			(width 0.05715)
			(type default)
		)
		(layer "In13.Cu")
	)
	(gr_line
		(start 369.183412 -280.856182)
		(end 369.182904 -280.85669)
		(stroke
			(width 0.05715)
			(type default)
		)
		(layer "In13.Cu")
	)
	(gr_line
		(start 369.2271 -279.434036)
		(end 369.22583 -279.434798)
		(stroke
			(width 0.05715)
			(type default)
		)
		(layer "In13.Cu")
	)
	(gr_line
		(start 369.2271 -277.814024)
		(end 369.22583 -277.814786)
		(stroke
			(width 0.05715)
			(type default)
		)
		(layer "In13.Cu")
	)
	(gr_line
		(start 369.2271 -276.194012)
		(end 369.22583 -276.194774)
		(stroke
			(width 0.05715)
			(type default)
		)
		(layer "In13.Cu")
	)
	(gr_line
		(start 369.2271 -274.574)
		(end 369.22583 -274.574762)
		(stroke
			(width 0.05715)
			(type default)
		)
		(layer "In13.Cu")
	)
	(gr_line
		(start 369.227608 -279.433782)
		(end 369.2271 -279.434036)
		(stroke
			(width 0.05715)
			(type default)
		)
		(layer "In13.Cu")
	)
	(gr_line
		(start 369.227608 -277.81377)
		(end 369.2271 -277.814024)
		(stroke
			(width 0.05715)
			(type default)
		)
		(layer "In13.Cu")
	)
	(gr_line
		(start 369.227608 -276.193758)
		(end 369.2271 -276.194012)
		(stroke
			(width 0.05715)
			(type default)
		)
		(layer "In13.Cu")
	)
	(gr_line
		(start 369.227608 -274.573746)
		(end 369.2271 -274.574)
		(stroke
			(width 0.05715)
			(type default)
		)
		(layer "In13.Cu")
	)
	(gr_line
		(start 369.319302 -295.145968)
		(end 369.319556 -295.145968)
		(stroke
			(width 0.05715)
			(type default)
		)
		(layer "In13.Cu")
	)
	(gr_line
		(start 369.74399 -296.463974)
		(end 369.74399 -296.492422)
		(stroke
			(width 0.05715)
			(type default)
		)
		(layer "In13.Cu")
	)
	(gr_line
		(start 369.7859 -372.01475)
		(end 370.48694 -372.01475)
		(stroke
			(width 0.07112)
			(type default)
		)
		(layer "In13.Cu")
	)
	(gr_line
		(start 369.78717 -371.73154)
		(end 369.92306 -371.59565)
		(stroke
			(width 0.07112)
			(type default)
		)
		(layer "In13.Cu")
	)
	(gr_line
		(start 369.78971 -296.418254)
		(end 369.74399 -296.463974)
		(stroke
			(width 0.05715)
			(type default)
		)
		(layer "In13.Cu")
	)
	(gr_arc
		(start 369.85194 -295.597834)
		(mid 369.849536 -295.595032)
		(end 369.847114 -295.592246)
		(stroke
			(width 0.05715)
			(type default)
		)
		(layer "In13.Cu")
	)
	(gr_line
		(start 369.871752 -411.474158)
		(end 370.042186 -410.793946)
		(stroke
			(width 0.07112)
			(type default)
		)
		(layer "In13.Cu")
	)
	(gr_line
		(start 369.92306 -371.59565)
		(end 370.34978 -371.59565)
		(stroke
			(width 0.07112)
			(type default)
		)
		(layer "In13.Cu")
	)
	(gr_line
		(start 369.98021 -296.418254)
		(end 370.02593 -296.463974)
		(stroke
			(width 0.05715)
			(type default)
		)
		(layer "In13.Cu")
	)
	(gr_line
		(start 370.02593 -296.463974)
		(end 370.02593 -296.492422)
		(stroke
			(width 0.05715)
			(type default)
		)
		(layer "In13.Cu")
	)
	(gr_arc
		(start 370.032788 -280.911554)
		(mid 370.028839 -280.914331)
		(end 370.024914 -280.917142)
		(stroke
			(width 0.05715)
			(type default)
		)
		(layer "In13.Cu")
	)
	(gr_line
		(start 370.033296 -280.9113)
		(end 370.032788 -280.911554)
		(stroke
			(width 0.05715)
			(type default)
		)
		(layer "In13.Cu")
	)
	(gr_line
		(start 370.040154 -280.907236)
		(end 370.033296 -280.9113)
		(stroke
			(width 0.05715)
			(type default)
		)
		(layer "In13.Cu")
	)
	(gr_line
		(start 370.071904 -292.228524)
		(end 370.070888 -292.229032)
		(stroke
			(width 0.05715)
			(type default)
		)
		(layer "In13.Cu")
	)
	(gr_line
		(start 370.071904 -290.608512)
		(end 370.070888 -290.60902)
		(stroke
			(width 0.05715)
			(type default)
		)
		(layer "In13.Cu")
	)
	(gr_line
		(start 370.071904 -288.9885)
		(end 370.070888 -288.989008)
		(stroke
			(width 0.05715)
			(type default)
		)
		(layer "In13.Cu")
	)
	(gr_line
		(start 370.071904 -285.74873)
		(end 370.070888 -285.749238)
		(stroke
			(width 0.05715)
			(type default)
		)
		(layer "In13.Cu")
	)
	(gr_line
		(start 370.071904 -284.128718)
		(end 370.070888 -284.129226)
		(stroke
			(width 0.05715)
			(type default)
		)
		(layer "In13.Cu")
	)
	(gr_line
		(start 370.071904 -282.508706)
		(end 370.070888 -282.509214)
		(stroke
			(width 0.05715)
			(type default)
		)
		(layer "In13.Cu")
	)
	(gr_line
		(start 370.072666 -292.228016)
		(end 370.071904 -292.228524)
		(stroke
			(width 0.05715)
			(type default)
		)
		(layer "In13.Cu")
	)
	(gr_line
		(start 370.072666 -290.608004)
		(end 370.071904 -290.608512)
		(stroke
			(width 0.05715)
			(type default)
		)
		(layer "In13.Cu")
	)
	(gr_line
		(start 370.072666 -288.987992)
		(end 370.071904 -288.9885)
		(stroke
			(width 0.05715)
			(type default)
		)
		(layer "In13.Cu")
	)
	(gr_line
		(start 370.072666 -285.748222)
		(end 370.071904 -285.74873)
		(stroke
			(width 0.05715)
			(type default)
		)
		(layer "In13.Cu")
	)
	(gr_line
		(start 370.072666 -284.12821)
		(end 370.071904 -284.128718)
		(stroke
			(width 0.05715)
			(type default)
		)
		(layer "In13.Cu")
	)
	(gr_line
		(start 370.072666 -282.508198)
		(end 370.071904 -282.508706)
		(stroke
			(width 0.05715)
			(type default)
		)
		(layer "In13.Cu")
	)
	(gr_line
		(start 370.073936 -292.227254)
		(end 370.072666 -292.228016)
		(stroke
			(width 0.05715)
			(type default)
		)
		(layer "In13.Cu")
	)
	(gr_line
		(start 370.073936 -290.607242)
		(end 370.072666 -290.608004)
		(stroke
			(width 0.05715)
			(type default)
		)
		(layer "In13.Cu")
	)
	(gr_line
		(start 370.073936 -288.98723)
		(end 370.072666 -288.987992)
		(stroke
			(width 0.05715)
			(type default)
		)
		(layer "In13.Cu")
	)
	(gr_line
		(start 370.073936 -285.74746)
		(end 370.072666 -285.748222)
		(stroke
			(width 0.05715)
			(type default)
		)
		(layer "In13.Cu")
	)
	(gr_line
		(start 370.073936 -284.127448)
		(end 370.072666 -284.12821)
		(stroke
			(width 0.05715)
			(type default)
		)
		(layer "In13.Cu")
	)
	(gr_line
		(start 370.073936 -282.507436)
		(end 370.072666 -282.508198)
		(stroke
			(width 0.05715)
			(type default)
		)
		(layer "In13.Cu")
	)
	(gr_line
		(start 370.07673 -294.826182)
		(end 370.077492 -294.82669)
		(stroke
			(width 0.05715)
			(type default)
		)
		(layer "In13.Cu")
	)
	(gr_line
		(start 370.07673 -293.20617)
		(end 370.077492 -293.206678)
		(stroke
			(width 0.05715)
			(type default)
		)
		(layer "In13.Cu")
	)
	(gr_line
		(start 370.07673 -289.966146)
		(end 370.077492 -289.966654)
		(stroke
			(width 0.05715)
			(type default)
		)
		(layer "In13.Cu")
	)
	(gr_line
		(start 370.07673 -281.86634)
		(end 370.077492 -281.866848)
		(stroke
			(width 0.05715)
			(type default)
		)
		(layer "In13.Cu")
	)
	(gr_line
		(start 370.077492 -294.82669)
		(end 370.078508 -294.827198)
		(stroke
			(width 0.05715)
			(type default)
		)
		(layer "In13.Cu")
	)
	(gr_line
		(start 370.077492 -293.206678)
		(end 370.078508 -293.207186)
		(stroke
			(width 0.05715)
			(type default)
		)
		(layer "In13.Cu")
	)
	(gr_line
		(start 370.077492 -289.966654)
		(end 370.078508 -289.967162)
		(stroke
			(width 0.05715)
			(type default)
		)
		(layer "In13.Cu")
	)
	(gr_line
		(start 370.077492 -281.866848)
		(end 370.078508 -281.867356)
		(stroke
			(width 0.05715)
			(type default)
		)
		(layer "In13.Cu")
	)
	(gr_line
		(start 370.079778 -294.82796)
		(end 370.080794 -294.828468)
		(stroke
			(width 0.05715)
			(type default)
		)
		(layer "In13.Cu")
	)
	(gr_line
		(start 370.079778 -293.207948)
		(end 370.080794 -293.208456)
		(stroke
			(width 0.05715)
			(type default)
		)
		(layer "In13.Cu")
	)
	(gr_line
		(start 370.079778 -289.967924)
		(end 370.080794 -289.968432)
		(stroke
			(width 0.05715)
			(type default)
		)
		(layer "In13.Cu")
	)
	(gr_line
		(start 370.079778 -281.868118)
		(end 370.080794 -281.868626)
		(stroke
			(width 0.05715)
			(type default)
		)
		(layer "In13.Cu")
	)
	(gr_line
		(start 370.146834 -411.541722)
		(end 370.311934 -411.44317)
		(stroke
			(width 0.07112)
			(type default)
		)
		(layer "In13.Cu")
	)
	(gr_line
		(start 370.16309 -292.396164)
		(end 370.160296 -292.397688)
		(stroke
			(width 0.05715)
			(type default)
		)
		(layer "In13.Cu")
	)
	(gr_line
		(start 370.16309 -290.776152)
		(end 370.160296 -290.777676)
		(stroke
			(width 0.05715)
			(type default)
		)
		(layer "In13.Cu")
	)
	(gr_line
		(start 370.16309 -289.15614)
		(end 370.160296 -289.157664)
		(stroke
			(width 0.05715)
			(type default)
		)
		(layer "In13.Cu")
	)
	(gr_line
		(start 370.16309 -285.91637)
		(end 370.160296 -285.917894)
		(stroke
			(width 0.05715)
			(type default)
		)
		(layer "In13.Cu")
	)
	(gr_line
		(start 370.16309 -284.296358)
		(end 370.160296 -284.297882)
		(stroke
			(width 0.05715)
			(type default)
		)
		(layer "In13.Cu")
	)
	(gr_line
		(start 370.16309 -282.676346)
		(end 370.160296 -282.67787)
		(stroke
			(width 0.05715)
			(type default)
		)
		(layer "In13.Cu")
	)
	(gr_line
		(start 370.167662 -294.658288)
		(end 370.170964 -294.66032)
		(stroke
			(width 0.05715)
			(type default)
		)
		(layer "In13.Cu")
	)
	(gr_line
		(start 370.167662 -293.038276)
		(end 370.170964 -293.040308)
		(stroke
			(width 0.05715)
			(type default)
		)
		(layer "In13.Cu")
	)
	(gr_line
		(start 370.167662 -289.798252)
		(end 370.170964 -289.800284)
		(stroke
			(width 0.05715)
			(type default)
		)
		(layer "In13.Cu")
	)
	(gr_line
		(start 370.167662 -281.698446)
		(end 370.170964 -281.700478)
		(stroke
			(width 0.05715)
			(type default)
		)
		(layer "In13.Cu")
	)
	(gr_line
		(start 370.168678 -292.392862)
		(end 370.16563 -292.39464)
		(stroke
			(width 0.05715)
			(type default)
		)
		(layer "In13.Cu")
	)
	(gr_line
		(start 370.168678 -290.77285)
		(end 370.16563 -290.774628)
		(stroke
			(width 0.05715)
			(type default)
		)
		(layer "In13.Cu")
	)
	(gr_line
		(start 370.168678 -289.152838)
		(end 370.16563 -289.154616)
		(stroke
			(width 0.05715)
			(type default)
		)
		(layer "In13.Cu")
	)
	(gr_line
		(start 370.168678 -285.913068)
		(end 370.16563 -285.914846)
		(stroke
			(width 0.05715)
			(type default)
		)
		(layer "In13.Cu")
	)
	(gr_line
		(start 370.168678 -284.293056)
		(end 370.16563 -284.294834)
		(stroke
			(width 0.05715)
			(type default)
		)
		(layer "In13.Cu")
	)
	(gr_line
		(start 370.168678 -282.673044)
		(end 370.16563 -282.674822)
		(stroke
			(width 0.05715)
			(type default)
		)
		(layer "In13.Cu")
	)
	(gr_line
		(start 370.17452 -294.662352)
		(end 370.175282 -294.66286)
		(stroke
			(width 0.05715)
			(type default)
		)
		(layer "In13.Cu")
	)
	(gr_line
		(start 370.17452 -293.04234)
		(end 370.175282 -293.042848)
		(stroke
			(width 0.05715)
			(type default)
		)
		(layer "In13.Cu")
	)
	(gr_line
		(start 370.17452 -289.802316)
		(end 370.175282 -289.802824)
		(stroke
			(width 0.05715)
			(type default)
		)
		(layer "In13.Cu")
	)
	(gr_line
		(start 370.17452 -281.70251)
		(end 370.175282 -281.703018)
		(stroke
			(width 0.05715)
			(type default)
		)
		(layer "In13.Cu")
	)
	(gr_line
		(start 370.175536 -409.64104)
		(end 370.175536 -408.94)
		(stroke
			(width 0.07112)
			(type default)
		)
		(layer "In13.Cu")
	)
	(gr_line
		(start 370.175536 -408.51328)
		(end 370.175536 -407.81224)
		(stroke
			(width 0.07112)
			(type default)
		)
		(layer "In13.Cu")
	)
	(gr_line
		(start 370.175536 -407.38552)
		(end 370.175536 -406.68448)
		(stroke
			(width 0.07112)
			(type default)
		)
		(layer "In13.Cu")
	)
	(gr_line
		(start 370.175536 -406.25776)
		(end 370.175536 -405.55672)
		(stroke
			(width 0.07112)
			(type default)
		)
		(layer "In13.Cu")
	)
	(gr_line
		(start 370.175536 -405.13)
		(end 370.175536 -404.42896)
		(stroke
			(width 0.07112)
			(type default)
		)
		(layer "In13.Cu")
	)
	(gr_line
		(start 370.175536 -404.00224)
		(end 370.175536 -403.3012)
		(stroke
			(width 0.07112)
			(type default)
		)
		(layer "In13.Cu")
	)
	(gr_line
		(start 370.25961 -295.145968)
		(end 370.259356 -295.145968)
		(stroke
			(width 0.05715)
			(type default)
		)
		(layer "In13.Cu")
	)
	(gr_line
		(start 370.311934 -411.44317)
		(end 370.415566 -411.028896)
		(stroke
			(width 0.07112)
			(type default)
		)
		(layer "In13.Cu")
	)
	(gr_line
		(start 370.34978 -371.59565)
		(end 370.48567 -371.73154)
		(stroke
			(width 0.07112)
			(type default)
		)
		(layer "In13.Cu")
	)
	(gr_line
		(start 370.35486 -273.27606)
		(end 370.652802 -273.27606)
		(stroke
			(width 0.05715)
			(type default)
		)
		(layer "In13.Cu")
	)
	(gr_line
		(start 370.35486 -271.656048)
		(end 370.652802 -271.656048)
		(stroke
			(width 0.05715)
			(type default)
		)
		(layer "In13.Cu")
	)
	(gr_line
		(start 370.35486 -270.036036)
		(end 370.652802 -270.036036)
		(stroke
			(width 0.05715)
			(type default)
		)
		(layer "In13.Cu")
	)
	(gr_line
		(start 370.415566 -411.028896)
		(end 370.31676 -410.863796)
		(stroke
			(width 0.07112)
			(type default)
		)
		(layer "In13.Cu")
	)
	(gr_line
		(start 370.450364 -295.145968)
		(end 370.45011 -295.145968)
		(stroke
			(width 0.05715)
			(type default)
		)
		(layer "In13.Cu")
	)
	(gr_line
		(start 370.458746 -409.63977)
		(end 370.594636 -409.50388)
		(stroke
			(width 0.07112)
			(type default)
		)
		(layer "In13.Cu")
	)
	(gr_line
		(start 370.458746 -408.51201)
		(end 370.594636 -408.37612)
		(stroke
			(width 0.07112)
			(type default)
		)
		(layer "In13.Cu")
	)
	(gr_line
		(start 370.458746 -407.38425)
		(end 370.594636 -407.24836)
		(stroke
			(width 0.07112)
			(type default)
		)
		(layer "In13.Cu")
	)
	(gr_line
		(start 370.458746 -406.25649)
		(end 370.594636 -406.1206)
		(stroke
			(width 0.07112)
			(type default)
		)
		(layer "In13.Cu")
	)
	(gr_line
		(start 370.458746 -405.12873)
		(end 370.594636 -404.99284)
		(stroke
			(width 0.07112)
			(type default)
		)
		(layer "In13.Cu")
	)
	(gr_line
		(start 370.458746 -404.00097)
		(end 370.594636 -403.86508)
		(stroke
			(width 0.07112)
			(type default)
		)
		(layer "In13.Cu")
	)
	(gr_line
		(start 370.530882 -270.364966)
		(end 370.529104 -270.365982)
		(stroke
			(width 0.05715)
			(type default)
		)
		(layer "In13.Cu")
	)
	(gr_line
		(start 370.53266 -270.36395)
		(end 370.531898 -270.364458)
		(stroke
			(width 0.05715)
			(type default)
		)
		(layer "In13.Cu")
	)
	(gr_line
		(start 370.5352 -270.362426)
		(end 370.534438 -270.362934)
		(stroke
			(width 0.05715)
			(type default)
		)
		(layer "In13.Cu")
	)
	(gr_line
		(start 370.537486 -270.360902)
		(end 370.536216 -270.361918)
		(stroke
			(width 0.05715)
			(type default)
		)
		(layer "In13.Cu")
	)
	(gr_line
		(start 370.541042 -270.35887)
		(end 370.538756 -270.36014)
		(stroke
			(width 0.05715)
			(type default)
		)
		(layer "In13.Cu")
	)
	(gr_line
		(start 370.542566 -295.633902)
		(end 370.54536 -295.635426)
		(stroke
			(width 0.05715)
			(type default)
		)
		(layer "In13.Cu")
	)
	(gr_line
		(start 370.594636 -409.50388)
		(end 370.594636 -409.07716)
		(stroke
			(width 0.07112)
			(type default)
		)
		(layer "In13.Cu")
	)
	(gr_line
		(start 370.594636 -409.07716)
		(end 370.458746 -408.94127)
		(stroke
			(width 0.07112)
			(type default)
		)
		(layer "In13.Cu")
	)
	(gr_line
		(start 370.594636 -408.37612)
		(end 370.594636 -407.9494)
		(stroke
			(width 0.07112)
			(type default)
		)
		(layer "In13.Cu")
	)
	(gr_line
		(start 370.594636 -407.9494)
		(end 370.458746 -407.81351)
		(stroke
			(width 0.07112)
			(type default)
		)
		(layer "In13.Cu")
	)
	(gr_line
		(start 370.594636 -407.24836)
		(end 370.594636 -406.82164)
		(stroke
			(width 0.07112)
			(type default)
		)
		(layer "In13.Cu")
	)
	(gr_line
		(start 370.594636 -406.82164)
		(end 370.458746 -406.68575)
		(stroke
			(width 0.07112)
			(type default)
		)
		(layer "In13.Cu")
	)
	(gr_line
		(start 370.594636 -406.1206)
		(end 370.594636 -405.69388)
		(stroke
			(width 0.07112)
			(type default)
		)
		(layer "In13.Cu")
	)
	(gr_line
		(start 370.594636 -405.69388)
		(end 370.458746 -405.55799)
		(stroke
			(width 0.07112)
			(type default)
		)
		(layer "In13.Cu")
	)
	(gr_line
		(start 370.594636 -404.99284)
		(end 370.594636 -404.56612)
		(stroke
			(width 0.07112)
			(type default)
		)
		(layer "In13.Cu")
	)
	(gr_line
		(start 370.594636 -404.56612)
		(end 370.458746 -404.43023)
		(stroke
			(width 0.07112)
			(type default)
		)
		(layer "In13.Cu")
	)
	(gr_line
		(start 370.594636 -403.86508)
		(end 370.594636 -403.43836)
		(stroke
			(width 0.07112)
			(type default)
		)
		(layer "In13.Cu")
	)
	(gr_line
		(start 370.594636 -403.43836)
		(end 370.458746 -403.30247)
		(stroke
			(width 0.07112)
			(type default)
		)
		(layer "In13.Cu")
	)
	(gr_line
		(start 370.630958 -270.527526)
		(end 370.628164 -270.528796)
		(stroke
			(width 0.05715)
			(type default)
		)
		(layer "In13.Cu")
	)
	(gr_line
		(start 370.632228 -270.526764)
		(end 370.630958 -270.527526)
		(stroke
			(width 0.05715)
			(type default)
		)
		(layer "In13.Cu")
	)
	(gr_line
		(start 370.63299 -270.526256)
		(end 370.632228 -270.526764)
		(stroke
			(width 0.05715)
			(type default)
		)
		(layer "In13.Cu")
	)
	(gr_line
		(start 370.63426 -270.525494)
		(end 370.63299 -270.526256)
		(stroke
			(width 0.05715)
			(type default)
		)
		(layer "In13.Cu")
	)
	(gr_line
		(start 370.637308 -295.468294)
		(end 370.637816 -295.468548)
		(stroke
			(width 0.05715)
			(type default)
		)
		(layer "In13.Cu")
	)
	(gr_line
		(start 370.637816 -295.468548)
		(end 370.638832 -295.469056)
		(stroke
			(width 0.05715)
			(type default)
		)
		(layer "In13.Cu")
	)
	(gr_line
		(start 370.638832 -295.469056)
		(end 370.640356 -295.470072)
		(stroke
			(width 0.05715)
			(type default)
		)
		(layer "In13.Cu")
	)
	(gr_line
		(start 370.640356 -295.470072)
		(end 370.641372 -295.47058)
		(stroke
			(width 0.05715)
			(type default)
		)
		(layer "In13.Cu")
	)
	(gr_line
		(start 370.641372 -295.47058)
		(end 370.646452 -295.473628)
		(stroke
			(width 0.05715)
			(type default)
		)
		(layer "In13.Cu")
	)
	(gr_line
		(start 370.652802 -273.27606)
		(end 370.735606 -273.358864)
		(stroke
			(width 0.05715)
			(type default)
		)
		(layer "In13.Cu")
	)
	(gr_line
		(start 370.652802 -271.656048)
		(end 370.735606 -271.738852)
		(stroke
			(width 0.05715)
			(type default)
		)
		(layer "In13.Cu")
	)
	(gr_line
		(start 370.652802 -270.036036)
		(end 370.722144 -270.105378)
		(stroke
			(width 0.05715)
			(type default)
		)
		(layer "In13.Cu")
	)
	(gr_line
		(start 370.684044 -296.463466)
		(end 370.684044 -296.491914)
		(stroke
			(width 0.05715)
			(type default)
		)
		(layer "In13.Cu")
	)
	(gr_line
		(start 370.729764 -296.417746)
		(end 370.684044 -296.463466)
		(stroke
			(width 0.05715)
			(type default)
		)
		(layer "In13.Cu")
	)
	(gr_arc
		(start 370.735606 -273.358864)
		(mid 370.737393 -273.370314)
		(end 370.739416 -273.381724)
		(stroke
			(width 0.05715)
			(type default)
		)
		(layer "In13.Cu")
	)
	(gr_arc
		(start 370.735606 -271.738852)
		(mid 370.737392 -271.750302)
		(end 370.739416 -271.761712)
		(stroke
			(width 0.05715)
			(type default)
		)
		(layer "In13.Cu")
	)
	(gr_line
		(start 370.777008 -401.089622)
		(end 370.789454 -401.089622)
		(stroke
			(width 0.07112)
			(type default)
		)
		(layer "In13.Cu")
	)
	(gr_line
		(start 370.778278 -401.372832)
		(end 370.916454 -401.511008)
		(stroke
			(width 0.07112)
			(type default)
		)
		(layer "In13.Cu")
	)
	(gr_line
		(start 370.787168 -295.591738)
		(end 370.786914 -295.591738)
		(stroke
			(width 0.05715)
			(type default)
		)
		(layer "In13.Cu")
	)
	(gr_line
		(start 370.789454 -401.089622)
		(end 370.916454 -400.962622)
		(stroke
			(width 0.07112)
			(type default)
		)
		(layer "In13.Cu")
	)
	(gr_arc
		(start 370.910358 -270.1417)
		(mid 370.912379 -270.130289)
		(end 370.914168 -270.11884)
		(stroke
			(width 0.05715)
			(type default)
		)
		(layer "In13.Cu")
	)
	(gr_line
		(start 370.91366 -372.01475)
		(end 371.6147 -372.01475)
		(stroke
			(width 0.07112)
			(type default)
		)
		(layer "In13.Cu")
	)
	(gr_line
		(start 370.91493 -371.73154)
		(end 371.05082 -371.59565)
		(stroke
			(width 0.07112)
			(type default)
		)
		(layer "In13.Cu")
	)
	(gr_line
		(start 370.916454 -401.511008)
		(end 370.916454 -401.674838)
		(stroke
			(width 0.07112)
			(type default)
		)
		(layer "In13.Cu")
	)
	(gr_line
		(start 370.916454 -400.962622)
		(end 370.916454 -400.811238)
		(stroke
			(width 0.07112)
			(type default)
		)
		(layer "In13.Cu")
	)
	(gr_line
		(start 370.920264 -296.417746)
		(end 370.965984 -296.463466)
		(stroke
			(width 0.05715)
			(type default)
		)
		(layer "In13.Cu")
	)
	(gr_arc
		(start 370.962174 -288.313114)
		(mid 370.965341 -288.315411)
		(end 370.968524 -288.317686)
		(stroke
			(width 0.05715)
			(type default)
		)
		(layer "In13.Cu")
	)
	(gr_arc
		(start 370.964968 -283.45511)
		(mid 370.968893 -283.457921)
		(end 370.972842 -283.460698)
		(stroke
			(width 0.05715)
			(type default)
		)
		(layer "In13.Cu")
	)
	(gr_line
		(start 370.965984 -296.463466)
		(end 370.965984 -296.491914)
		(stroke
			(width 0.05715)
			(type default)
		)
		(layer "In13.Cu")
	)
	(gr_line
		(start 370.972842 -283.460698)
		(end 370.9797 -283.464762)
		(stroke
			(width 0.05715)
			(type default)
		)
		(layer "In13.Cu")
	)
	(gr_arc
		(start 370.972842 -280.911554)
		(mid 370.968893 -280.914331)
		(end 370.964968 -280.917142)
		(stroke
			(width 0.05715)
			(type default)
		)
		(layer "In13.Cu")
	)
	(gr_line
		(start 370.97335 -280.9113)
		(end 370.972842 -280.911554)
		(stroke
			(width 0.05715)
			(type default)
		)
		(layer "In13.Cu")
	)
	(gr_line
		(start 370.9797 -283.464762)
		(end 370.980462 -283.46527)
		(stroke
			(width 0.05715)
			(type default)
		)
		(layer "In13.Cu")
	)
	(gr_line
		(start 370.980208 -280.907236)
		(end 370.97335 -280.9113)
		(stroke
			(width 0.05715)
			(type default)
		)
		(layer "In13.Cu")
	)
	(gr_line
		(start 370.980462 -283.46527)
		(end 370.981224 -283.465778)
		(stroke
			(width 0.05715)
			(type default)
		)
		(layer "In13.Cu")
	)
	(gr_line
		(start 370.988844 -294.08247)
		(end 370.98859 -294.08247)
		(stroke
			(width 0.05715)
			(type default)
		)
		(layer "In13.Cu")
	)
	(gr_line
		(start 370.996972 -273.27606)
		(end 370.92763 -273.345402)
		(stroke
			(width 0.05715)
			(type default)
		)
		(layer "In13.Cu")
	)
	(gr_line
		(start 370.996972 -271.656048)
		(end 370.92763 -271.72539)
		(stroke
			(width 0.05715)
			(type default)
		)
		(layer "In13.Cu")
	)
	(gr_line
		(start 370.996972 -270.036036)
		(end 370.914168 -270.11884)
		(stroke
			(width 0.05715)
			(type default)
		)
		(layer "In13.Cu")
	)
	(gr_line
		(start 371.01272 -291.583872)
		(end 371.01399 -291.584634)
		(stroke
			(width 0.05715)
			(type default)
		)
		(layer "In13.Cu")
	)
	(gr_line
		(start 371.014752 -283.485336)
		(end 371.01526 -283.485336)
		(stroke
			(width 0.05715)
			(type default)
		)
		(layer "In13.Cu")
	)
	(gr_line
		(start 371.015006 -288.345118)
		(end 371.01526 -288.345118)
		(stroke
			(width 0.05715)
			(type default)
		)
		(layer "In13.Cu")
	)
	(gr_line
		(start 371.05082 -371.59565)
		(end 371.47754 -371.59565)
		(stroke
			(width 0.07112)
			(type default)
		)
		(layer "In13.Cu")
	)
	(gr_line
		(start 371.104414 -292.395402)
		(end 371.102382 -292.396672)
		(stroke
			(width 0.05715)
			(type default)
		)
		(layer "In13.Cu")
	)
	(gr_line
		(start 371.107462 -293.038276)
		(end 371.111018 -293.040308)
		(stroke
			(width 0.05715)
			(type default)
		)
		(layer "In13.Cu")
	)
	(gr_line
		(start 371.107462 -289.798252)
		(end 371.111018 -289.800284)
		(stroke
			(width 0.05715)
			(type default)
		)
		(layer "In13.Cu")
	)
	(gr_line
		(start 371.107462 -284.93847)
		(end 371.111018 -284.940502)
		(stroke
			(width 0.05715)
			(type default)
		)
		(layer "In13.Cu")
	)
	(gr_line
		(start 371.107462 -281.698446)
		(end 371.111018 -281.700478)
		(stroke
			(width 0.05715)
			(type default)
		)
		(layer "In13.Cu")
	)
	(gr_line
		(start 371.10797 -283.318712)
		(end 371.111018 -283.32049)
		(stroke
			(width 0.05715)
			(type default)
		)
		(layer "In13.Cu")
	)
	(gr_line
		(start 371.111018 -293.040308)
		(end 371.110764 -293.040308)
		(stroke
			(width 0.05715)
			(type default)
		)
		(layer "In13.Cu")
	)
	(gr_line
		(start 371.111018 -290.77158)
		(end 371.107462 -290.773612)
		(stroke
			(width 0.05715)
			(type default)
		)
		(layer "In13.Cu")
	)
	(gr_line
		(start 371.111018 -289.151568)
		(end 371.107462 -289.1536)
		(stroke
			(width 0.05715)
			(type default)
		)
		(layer "In13.Cu")
	)
	(gr_line
		(start 371.111018 -285.911798)
		(end 371.107462 -285.91383)
		(stroke
			(width 0.05715)
			(type default)
		)
		(layer "In13.Cu")
	)
	(gr_line
		(start 371.111018 -284.291786)
		(end 371.107462 -284.293818)
		(stroke
			(width 0.05715)
			(type default)
		)
		(layer "In13.Cu")
	)
	(gr_line
		(start 371.111018 -282.671774)
		(end 371.107462 -282.673806)
		(stroke
			(width 0.05715)
			(type default)
		)
		(layer "In13.Cu")
	)
	(gr_line
		(start 371.184932 -417.636452)
		(end 371.184932 -416.935412)
		(stroke
			(width 0.07112)
			(type default)
		)
		(layer "In13.Cu")
	)
	(gr_line
		(start 371.184932 -416.508692)
		(end 371.184932 -415.807652)
		(stroke
			(width 0.07112)
			(type default)
		)
		(layer "In13.Cu")
	)
	(gr_line
		(start 371.294914 -273.27606)
		(end 370.996972 -273.27606)
		(stroke
			(width 0.05715)
			(type default)
		)
		(layer "In13.Cu")
	)
	(gr_line
		(start 371.294914 -271.656048)
		(end 370.996972 -271.656048)
		(stroke
			(width 0.05715)
			(type default)
		)
		(layer "In13.Cu")
	)
	(gr_line
		(start 371.294914 -270.036036)
		(end 370.996972 -270.036036)
		(stroke
			(width 0.05715)
			(type default)
		)
		(layer "In13.Cu")
	)
	(gr_line
		(start 371.341904 -356.849934)
		(end 371.341904 -356.65791)
		(stroke
			(width 0.07112)
			(type default)
		)
		(layer "In13.Cu")
	)
	(gr_line
		(start 371.341904 -356.65791)
		(end 371.64391 -356.355904)
		(stroke
			(width 0.07112)
			(type default)
		)
		(layer "In13.Cu")
	)
	(gr_line
		(start 371.375432 -407.92019)
		(end 371.375432 -407.21915)
		(stroke
			(width 0.07112)
			(type default)
		)
		(layer "In13.Cu")
	)
	(gr_line
		(start 371.375432 -406.79243)
		(end 371.375432 -406.09139)
		(stroke
			(width 0.07112)
			(type default)
		)
		(layer "In13.Cu")
	)
	(gr_line
		(start 371.375432 -405.66467)
		(end 371.375432 -404.96363)
		(stroke
			(width 0.07112)
			(type default)
		)
		(layer "In13.Cu")
	)
	(gr_line
		(start 371.375432 -404.53691)
		(end 371.375432 -403.83587)
		(stroke
			(width 0.07112)
			(type default)
		)
		(layer "In13.Cu")
	)
	(gr_line
		(start 371.375432 -403.40915)
		(end 371.375432 -402.70811)
		(stroke
			(width 0.07112)
			(type default)
		)
		(layer "In13.Cu")
	)
	(gr_line
		(start 371.468142 -417.635182)
		(end 371.604032 -417.499292)
		(stroke
			(width 0.07112)
			(type default)
		)
		(layer "In13.Cu")
	)
	(gr_line
		(start 371.468142 -416.507422)
		(end 371.604032 -416.371532)
		(stroke
			(width 0.07112)
			(type default)
		)
		(layer "In13.Cu")
	)
	(gr_line
		(start 371.47754 -371.59565)
		(end 371.61343 -371.73154)
		(stroke
			(width 0.07112)
			(type default)
		)
		(layer "In13.Cu")
	)
	(gr_line
		(start 371.48135 -272.953226)
		(end 371.481858 -272.95348)
		(stroke
			(width 0.05715)
			(type default)
		)
		(layer "In13.Cu")
	)
	(gr_line
		(start 371.481858 -272.95348)
		(end 371.48262 -272.953988)
		(stroke
			(width 0.05715)
			(type default)
		)
		(layer "In13.Cu")
	)
	(gr_line
		(start 371.541294 -357.051102)
		(end 372.037102 -356.555294)
		(stroke
			(width 0.07112)
			(type default)
		)
		(layer "In13.Cu")
	)
	(gr_line
		(start 371.559836 -409.221686)
		(end 371.56009 -409.221686)
		(stroke
			(width 0.07112)
			(type default)
		)
		(layer "In13.Cu")
	)
	(gr_line
		(start 371.604032 -417.499292)
		(end 371.604032 -417.072572)
		(stroke
			(width 0.07112)
			(type default)
		)
		(layer "In13.Cu")
	)
	(gr_line
		(start 371.604032 -417.072572)
		(end 371.468142 -416.936682)
		(stroke
			(width 0.07112)
			(type default)
		)
		(layer "In13.Cu")
	)
	(gr_line
		(start 371.604032 -416.371532)
		(end 371.604032 -415.944812)
		(stroke
			(width 0.07112)
			(type default)
		)
		(layer "In13.Cu")
	)
	(gr_line
		(start 371.604032 -415.944812)
		(end 371.468142 -415.808922)
		(stroke
			(width 0.07112)
			(type default)
		)
		(layer "In13.Cu")
	)
	(gr_line
		(start 371.623844 -296.583862)
		(end 371.623844 -296.61231)
		(stroke
			(width 0.05715)
			(type default)
		)
		(layer "In13.Cu")
	)
	(gr_line
		(start 371.64391 -356.355904)
		(end 371.835934 -356.355904)
		(stroke
			(width 0.07112)
			(type default)
		)
		(layer "In13.Cu")
	)
	(gr_line
		(start 371.658642 -407.91892)
		(end 371.794532 -407.78303)
		(stroke
			(width 0.07112)
			(type default)
		)
		(layer "In13.Cu")
	)
	(gr_line
		(start 371.658642 -406.79116)
		(end 371.794532 -406.65527)
		(stroke
			(width 0.07112)
			(type default)
		)
		(layer "In13.Cu")
	)
	(gr_line
		(start 371.658642 -405.6634)
		(end 371.794532 -405.52751)
		(stroke
			(width 0.07112)
			(type default)
		)
		(layer "In13.Cu")
	)
	(gr_line
		(start 371.658642 -404.53564)
		(end 371.794532 -404.39975)
		(stroke
			(width 0.07112)
			(type default)
		)
		(layer "In13.Cu")
	)
	(gr_line
		(start 371.658642 -403.40788)
		(end 371.794532 -403.27199)
		(stroke
			(width 0.07112)
			(type default)
		)
		(layer "In13.Cu")
	)
	(gr_line
		(start 371.669564 -296.538142)
		(end 371.623844 -296.583862)
		(stroke
			(width 0.05715)
			(type default)
		)
		(layer "In13.Cu")
	)
	(gr_arc
		(start 371.673374 -273.310096)
		(mid 371.6735 -273.310985)
		(end 371.673628 -273.311874)
		(stroke
			(width 0.05715)
			(type default)
		)
		(layer "In13.Cu")
	)
	(gr_line
		(start 371.673882 -273.313144)
		(end 371.673628 -273.311874)
		(stroke
			(width 0.05715)
			(type default)
		)
		(layer "In13.Cu")
	)
	(gr_line
		(start 371.794532 -407.78303)
		(end 371.794532 -407.35631)
		(stroke
			(width 0.07112)
			(type default)
		)
		(layer "In13.Cu")
	)
	(gr_line
		(start 371.794532 -407.35631)
		(end 371.658642 -407.22042)
		(stroke
			(width 0.07112)
			(type default)
		)
		(layer "In13.Cu")
	)
	(gr_line
		(start 371.794532 -406.65527)
		(end 371.794532 -406.22855)
		(stroke
			(width 0.07112)
			(type default)
		)
		(layer "In13.Cu")
	)
	(gr_line
		(start 371.794532 -406.22855)
		(end 371.658642 -406.09266)
		(stroke
			(width 0.07112)
			(type default)
		)
		(layer "In13.Cu")
	)
	(gr_line
		(start 371.794532 -405.52751)
		(end 371.794532 -405.10079)
		(stroke
			(width 0.07112)
			(type default)
		)
		(layer "In13.Cu")
	)
	(gr_line
		(start 371.794532 -405.10079)
		(end 371.658642 -404.9649)
		(stroke
			(width 0.07112)
			(type default)
		)
		(layer "In13.Cu")
	)
	(gr_line
		(start 371.794532 -404.39975)
		(end 371.794532 -403.97303)
		(stroke
			(width 0.07112)
			(type default)
		)
		(layer "In13.Cu")
	)
	(gr_line
		(start 371.794532 -403.97303)
		(end 371.658642 -403.83714)
		(stroke
			(width 0.07112)
			(type default)
		)
		(layer "In13.Cu")
	)
	(gr_line
		(start 371.794532 -403.27199)
		(end 371.794532 -402.84527)
		(stroke
			(width 0.07112)
			(type default)
		)
		(layer "In13.Cu")
	)
	(gr_line
		(start 371.794532 -402.84527)
		(end 371.658642 -402.70938)
		(stroke
			(width 0.07112)
			(type default)
		)
		(layer "In13.Cu")
	)
	(gr_line
		(start 371.828568 -409.869894)
		(end 371.56009 -409.221686)
		(stroke
			(width 0.07112)
			(type default)
		)
		(layer "In13.Cu")
	)
	(gr_line
		(start 371.860064 -296.538142)
		(end 371.905784 -296.583862)
		(stroke
			(width 0.05715)
			(type default)
		)
		(layer "In13.Cu")
	)
	(gr_line
		(start 371.905784 -296.583862)
		(end 371.905784 -296.61231)
		(stroke
			(width 0.05715)
			(type default)
		)
		(layer "In13.Cu")
	)
	(gr_arc
		(start 371.911372 -280.91257)
		(mid 371.908954 -280.914342)
		(end 371.906546 -280.916126)
		(stroke
			(width 0.05715)
			(type default)
		)
		(layer "In13.Cu")
	)
	(gr_line
		(start 371.951758 -280.243534)
		(end 371.952266 -280.243788)
		(stroke
			(width 0.05715)
			(type default)
		)
		(layer "In13.Cu")
	)
	(gr_line
		(start 371.976904 -401.089622)
		(end 371.98935 -401.089622)
		(stroke
			(width 0.07112)
			(type default)
		)
		(layer "In13.Cu")
	)
	(gr_line
		(start 371.978174 -401.372832)
		(end 372.11635 -401.511008)
		(stroke
			(width 0.07112)
			(type default)
		)
		(layer "In13.Cu")
	)
	(gr_line
		(start 371.983254 -275.401786)
		(end 371.983508 -275.401786)
		(stroke
			(width 0.05715)
			(type default)
		)
		(layer "In13.Cu")
	)
	(gr_line
		(start 371.98935 -401.089622)
		(end 372.11635 -400.962622)
		(stroke
			(width 0.07112)
			(type default)
		)
		(layer "In13.Cu")
	)
	(gr_line
		(start 371.991636 -410.263848)
		(end 371.947948 -410.15793)
		(stroke
			(width 0.07112)
			(type default)
		)
		(layer "In13.Cu")
	)
	(gr_line
		(start 372.000018 -409.188158)
		(end 371.822472 -409.114752)
		(stroke
			(width 0.07112)
			(type default)
		)
		(layer "In13.Cu")
	)
	(gr_line
		(start 372.08968 -409.76042)
		(end 372.16334 -409.58262)
		(stroke
			(width 0.07112)
			(type default)
		)
		(layer "In13.Cu")
	)
	(gr_line
		(start 372.11635 -401.511008)
		(end 372.11635 -401.674838)
		(stroke
			(width 0.07112)
			(type default)
		)
		(layer "In13.Cu")
	)
	(gr_line
		(start 372.11635 -400.962622)
		(end 372.11635 -400.811238)
		(stroke
			(width 0.07112)
			(type default)
		)
		(layer "In13.Cu")
	)
	(gr_line
		(start 372.16334 -409.58262)
		(end 372.000018 -409.188158)
		(stroke
			(width 0.07112)
			(type default)
		)
		(layer "In13.Cu")
	)
	(gr_line
		(start 372.17096 -372.01475)
		(end 372.872 -372.01475)
		(stroke
			(width 0.07112)
			(type default)
		)
		(layer "In13.Cu")
	)
	(gr_line
		(start 372.17223 -371.73154)
		(end 372.30812 -371.59565)
		(stroke
			(width 0.07112)
			(type default)
		)
		(layer "In13.Cu")
	)
	(gr_line
		(start 372.206774 -355.985064)
		(end 372.206774 -355.79304)
		(stroke
			(width 0.07112)
			(type default)
		)
		(layer "In13.Cu")
	)
	(gr_line
		(start 372.206774 -355.79304)
		(end 372.50878 -355.491034)
		(stroke
			(width 0.07112)
			(type default)
		)
		(layer "In13.Cu")
	)
	(gr_line
		(start 372.260114 -410.912056)
		(end 371.991636 -410.263848)
		(stroke
			(width 0.07112)
			(type default)
		)
		(layer "In13.Cu")
	)
	(gr_line
		(start 372.30812 -371.59565)
		(end 372.73484 -371.59565)
		(stroke
			(width 0.07112)
			(type default)
		)
		(layer "In13.Cu")
	)
	(gr_line
		(start 372.406164 -356.186232)
		(end 372.901972 -355.690424)
		(stroke
			(width 0.07112)
			(type default)
		)
		(layer "In13.Cu")
	)
	(gr_line
		(start 372.431818 -410.23032)
		(end 372.254018 -410.156914)
		(stroke
			(width 0.07112)
			(type default)
		)
		(layer "In13.Cu")
	)
	(gr_line
		(start 372.468902 -295.663874)
		(end 372.469156 -295.66362)
		(stroke
			(width 0.05715)
			(type default)
		)
		(layer "In13.Cu")
	)
	(gr_line
		(start 372.50878 -355.491034)
		(end 372.700804 -355.491034)
		(stroke
			(width 0.07112)
			(type default)
		)
		(layer "In13.Cu")
	)
	(gr_line
		(start 372.52148 -410.802582)
		(end 372.59514 -410.624782)
		(stroke
			(width 0.07112)
			(type default)
		)
		(layer "In13.Cu")
	)
	(gr_line
		(start 372.563898 -296.56659)
		(end 372.563898 -296.595038)
		(stroke
			(width 0.05715)
			(type default)
		)
		(layer "In13.Cu")
	)
	(gr_line
		(start 372.575582 -407.01087)
		(end 372.575582 -406.30983)
		(stroke
			(width 0.07112)
			(type default)
		)
		(layer "In13.Cu")
	)
	(gr_line
		(start 372.575582 -405.88311)
		(end 372.575582 -405.18207)
		(stroke
			(width 0.07112)
			(type default)
		)
		(layer "In13.Cu")
	)
	(gr_line
		(start 372.575582 -404.75535)
		(end 372.575582 -404.05431)
		(stroke
			(width 0.07112)
			(type default)
		)
		(layer "In13.Cu")
	)
	(gr_line
		(start 372.575582 -403.62759)
		(end 372.575582 -402.92655)
		(stroke
			(width 0.07112)
			(type default)
		)
		(layer "In13.Cu")
	)
	(gr_line
		(start 372.59514 -410.624782)
		(end 372.431818 -410.23032)
		(stroke
			(width 0.07112)
			(type default)
		)
		(layer "In13.Cu")
	)
	(gr_line
		(start 372.609618 -296.52087)
		(end 372.563898 -296.56659)
		(stroke
			(width 0.05715)
			(type default)
		)
		(layer "In13.Cu")
	)
	(gr_line
		(start 372.73484 -371.59565)
		(end 372.87073 -371.73154)
		(stroke
			(width 0.07112)
			(type default)
		)
		(layer "In13.Cu")
	)
	(gr_line
		(start 372.800118 -296.52087)
		(end 372.845838 -296.56659)
		(stroke
			(width 0.05715)
			(type default)
		)
		(layer "In13.Cu")
	)
	(gr_arc
		(start 372.844822 -294.79494)
		(mid 372.848747 -294.797751)
		(end 372.852696 -294.800528)
		(stroke
			(width 0.05715)
			(type default)
		)
		(layer "In13.Cu")
	)
	(gr_arc
		(start 372.844822 -293.174928)
		(mid 372.848747 -293.177739)
		(end 372.852696 -293.180516)
		(stroke
			(width 0.05715)
			(type default)
		)
		(layer "In13.Cu")
	)
	(gr_arc
		(start 372.844822 -289.934904)
		(mid 372.848747 -289.937715)
		(end 372.852696 -289.940492)
		(stroke
			(width 0.05715)
			(type default)
		)
		(layer "In13.Cu")
	)
	(gr_arc
		(start 372.844822 -281.835098)
		(mid 372.848747 -281.837909)
		(end 372.852696 -281.840686)
		(stroke
			(width 0.05715)
			(type default)
		)
		(layer "In13.Cu")
	)
	(gr_arc
		(start 372.844822 -278.595074)
		(mid 372.848747 -278.597885)
		(end 372.852696 -278.600662)
		(stroke
			(width 0.05715)
			(type default)
		)
		(layer "In13.Cu")
	)
	(gr_arc
		(start 372.844822 -276.975062)
		(mid 372.848747 -276.977873)
		(end 372.852696 -276.98065)
		(stroke
			(width 0.05715)
			(type default)
		)
		(layer "In13.Cu")
	)
	(gr_arc
		(start 372.844822 -275.35505)
		(mid 372.848747 -275.357861)
		(end 372.852696 -275.360638)
		(stroke
			(width 0.05715)
			(type default)
		)
		(layer "In13.Cu")
	)
	(gr_arc
		(start 372.844822 -273.735038)
		(mid 372.848747 -273.737849)
		(end 372.852696 -273.740626)
		(stroke
			(width 0.05715)
			(type default)
		)
		(layer "In13.Cu")
	)
	(gr_arc
		(start 372.844822 -272.115026)
		(mid 372.848747 -272.117837)
		(end 372.852696 -272.120614)
		(stroke
			(width 0.05715)
			(type default)
		)
		(layer "In13.Cu")
	)
	(gr_line
		(start 372.845838 -296.56659)
		(end 372.845838 -296.595038)
		(stroke
			(width 0.05715)
			(type default)
		)
		(layer "In13.Cu")
	)
	(gr_line
		(start 372.852696 -294.800528)
		(end 372.859554 -294.804592)
		(stroke
			(width 0.05715)
			(type default)
		)
		(layer "In13.Cu")
	)
	(gr_line
		(start 372.852696 -293.180516)
		(end 372.859554 -293.18458)
		(stroke
			(width 0.05715)
			(type default)
		)
		(layer "In13.Cu")
	)
	(gr_line
		(start 372.852696 -289.940492)
		(end 372.859554 -289.944556)
		(stroke
			(width 0.05715)
			(type default)
		)
		(layer "In13.Cu")
	)
	(gr_line
		(start 372.852696 -281.840686)
		(end 372.859554 -281.84475)
		(stroke
			(width 0.05715)
			(type default)
		)
		(layer "In13.Cu")
	)
	(gr_arc
		(start 372.852696 -280.911554)
		(mid 372.848747 -280.914331)
		(end 372.844822 -280.917142)
		(stroke
			(width 0.05715)
			(type default)
		)
		(layer "In13.Cu")
	)
	(gr_line
		(start 372.852696 -278.600662)
		(end 372.859554 -278.604726)
		(stroke
			(width 0.05715)
			(type default)
		)
		(layer "In13.Cu")
	)
	(gr_line
		(start 372.852696 -276.98065)
		(end 372.859554 -276.984714)
		(stroke
			(width 0.05715)
			(type default)
		)
		(layer "In13.Cu")
	)
	(gr_line
		(start 372.852696 -275.360638)
		(end 372.859554 -275.364702)
		(stroke
			(width 0.05715)
			(type default)
		)
		(layer "In13.Cu")
	)
	(gr_line
		(start 372.852696 -273.740626)
		(end 372.859554 -273.74469)
		(stroke
			(width 0.05715)
			(type default)
		)
		(layer "In13.Cu")
	)
	(gr_line
		(start 372.852696 -272.120614)
		(end 372.859554 -272.124678)
		(stroke
			(width 0.05715)
			(type default)
		)
		(layer "In13.Cu")
	)
	(gr_line
		(start 372.85549 -280.909522)
		(end 372.852696 -280.911554)
		(stroke
			(width 0.05715)
			(type default)
		)
		(layer "In13.Cu")
	)
	(gr_line
		(start 372.858792 -407.0096)
		(end 372.994682 -406.87371)
		(stroke
			(width 0.07112)
			(type default)
		)
		(layer "In13.Cu")
	)
	(gr_line
		(start 372.858792 -405.88184)
		(end 372.994682 -405.74595)
		(stroke
			(width 0.07112)
			(type default)
		)
		(layer "In13.Cu")
	)
	(gr_line
		(start 372.858792 -404.75408)
		(end 372.994682 -404.61819)
		(stroke
			(width 0.07112)
			(type default)
		)
		(layer "In13.Cu")
	)
	(gr_line
		(start 372.858792 -403.62632)
		(end 372.994682 -403.49043)
		(stroke
			(width 0.07112)
			(type default)
		)
		(layer "In13.Cu")
	)
	(gr_line
		(start 372.859554 -294.804592)
		(end 372.860316 -294.8051)
		(stroke
			(width 0.05715)
			(type default)
		)
		(layer "In13.Cu")
	)
	(gr_line
		(start 372.859554 -293.18458)
		(end 372.860316 -293.185088)
		(stroke
			(width 0.05715)
			(type default)
		)
		(layer "In13.Cu")
	)
	(gr_line
		(start 372.859554 -289.944556)
		(end 372.860316 -289.945064)
		(stroke
			(width 0.05715)
			(type default)
		)
		(layer "In13.Cu")
	)
	(gr_line
		(start 372.859554 -281.84475)
		(end 372.860316 -281.845258)
		(stroke
			(width 0.05715)
			(type default)
		)
		(layer "In13.Cu")
	)
	(gr_line
		(start 372.859554 -278.604726)
		(end 372.860316 -278.605234)
		(stroke
			(width 0.05715)
			(type default)
		)
		(layer "In13.Cu")
	)
	(gr_line
		(start 372.859554 -276.984714)
		(end 372.860316 -276.985222)
		(stroke
			(width 0.05715)
			(type default)
		)
		(layer "In13.Cu")
	)
	(gr_line
		(start 372.859554 -275.364702)
		(end 372.860316 -275.36521)
		(stroke
			(width 0.05715)
			(type default)
		)
		(layer "In13.Cu")
	)
	(gr_line
		(start 372.859554 -273.74469)
		(end 372.860316 -273.745198)
		(stroke
			(width 0.05715)
			(type default)
		)
		(layer "In13.Cu")
	)
	(gr_line
		(start 372.859554 -272.124678)
		(end 372.860316 -272.125186)
		(stroke
			(width 0.05715)
			(type default)
		)
		(layer "In13.Cu")
	)
	(gr_line
		(start 372.860316 -294.8051)
		(end 372.861078 -294.805608)
		(stroke
			(width 0.05715)
			(type default)
		)
		(layer "In13.Cu")
	)
	(gr_line
		(start 372.860316 -293.185088)
		(end 372.861078 -293.185596)
		(stroke
			(width 0.05715)
			(type default)
		)
		(layer "In13.Cu")
	)
	(gr_line
		(start 372.860316 -289.945064)
		(end 372.861078 -289.945572)
		(stroke
			(width 0.05715)
			(type default)
		)
		(layer "In13.Cu")
	)
	(gr_line
		(start 372.860316 -281.845258)
		(end 372.861078 -281.845766)
		(stroke
			(width 0.05715)
			(type default)
		)
		(layer "In13.Cu")
	)
	(gr_line
		(start 372.860316 -278.605234)
		(end 372.861078 -278.605742)
		(stroke
			(width 0.05715)
			(type default)
		)
		(layer "In13.Cu")
	)
	(gr_line
		(start 372.860316 -276.985222)
		(end 372.861078 -276.98573)
		(stroke
			(width 0.05715)
			(type default)
		)
		(layer "In13.Cu")
	)
	(gr_line
		(start 372.860316 -275.36521)
		(end 372.861078 -275.365718)
		(stroke
			(width 0.05715)
			(type default)
		)
		(layer "In13.Cu")
	)
	(gr_line
		(start 372.860316 -273.745198)
		(end 372.861078 -273.745706)
		(stroke
			(width 0.05715)
			(type default)
		)
		(layer "In13.Cu")
	)
	(gr_line
		(start 372.860316 -272.125186)
		(end 372.861078 -272.125694)
		(stroke
			(width 0.05715)
			(type default)
		)
		(layer "In13.Cu")
	)
	(gr_line
		(start 372.860824 -280.906474)
		(end 372.85549 -280.909522)
		(stroke
			(width 0.05715)
			(type default)
		)
		(layer "In13.Cu")
	)
	(gr_line
		(start 372.886224 -279.271984)
		(end 372.885462 -279.272492)
		(stroke
			(width 0.05715)
			(type default)
		)
		(layer "In13.Cu")
	)
	(gr_line
		(start 372.886224 -277.651972)
		(end 372.885462 -277.65248)
		(stroke
			(width 0.05715)
			(type default)
		)
		(layer "In13.Cu")
	)
	(gr_line
		(start 372.886224 -276.03196)
		(end 372.885462 -276.032468)
		(stroke
			(width 0.05715)
			(type default)
		)
		(layer "In13.Cu")
	)
	(gr_line
		(start 372.886224 -274.411948)
		(end 372.885462 -274.412456)
		(stroke
			(width 0.05715)
			(type default)
		)
		(layer "In13.Cu")
	)
	(gr_line
		(start 372.886224 -272.791936)
		(end 372.885462 -272.792444)
		(stroke
			(width 0.05715)
			(type default)
		)
		(layer "In13.Cu")
	)
	(gr_line
		(start 372.886224 -271.171924)
		(end 372.885462 -271.172432)
		(stroke
			(width 0.05715)
			(type default)
		)
		(layer "In13.Cu")
	)
	(gr_line
		(start 372.887494 -292.231064)
		(end 372.884954 -292.232588)
		(stroke
			(width 0.05715)
			(type default)
		)
		(layer "In13.Cu")
	)
	(gr_line
		(start 372.887494 -290.611052)
		(end 372.884954 -290.612576)
		(stroke
			(width 0.05715)
			(type default)
		)
		(layer "In13.Cu")
	)
	(gr_line
		(start 372.887494 -288.99104)
		(end 372.884954 -288.992564)
		(stroke
			(width 0.05715)
			(type default)
		)
		(layer "In13.Cu")
	)
	(gr_line
		(start 372.887494 -285.75127)
		(end 372.884954 -285.752794)
		(stroke
			(width 0.05715)
			(type default)
		)
		(layer "In13.Cu")
	)
	(gr_line
		(start 372.887494 -284.131258)
		(end 372.884954 -284.132782)
		(stroke
			(width 0.05715)
			(type default)
		)
		(layer "In13.Cu")
	)
	(gr_line
		(start 372.887494 -282.511246)
		(end 372.884954 -282.51277)
		(stroke
			(width 0.05715)
			(type default)
		)
		(layer "In13.Cu")
	)
	(gr_line
		(start 372.887494 -279.271222)
		(end 372.886224 -279.271984)
		(stroke
			(width 0.05715)
			(type default)
		)
		(layer "In13.Cu")
	)
	(gr_line
		(start 372.887494 -277.65121)
		(end 372.886224 -277.651972)
		(stroke
			(width 0.05715)
			(type default)
		)
		(layer "In13.Cu")
	)
	(gr_line
		(start 372.887494 -276.031198)
		(end 372.886224 -276.03196)
		(stroke
			(width 0.05715)
			(type default)
		)
		(layer "In13.Cu")
	)
	(gr_line
		(start 372.887494 -274.411186)
		(end 372.886224 -274.411948)
		(stroke
			(width 0.05715)
			(type default)
		)
		(layer "In13.Cu")
	)
	(gr_line
		(start 372.887494 -272.791174)
		(end 372.886224 -272.791936)
		(stroke
			(width 0.05715)
			(type default)
		)
		(layer "In13.Cu")
	)
	(gr_line
		(start 372.887494 -271.171162)
		(end 372.886224 -271.171924)
		(stroke
			(width 0.05715)
			(type default)
		)
		(layer "In13.Cu")
	)
	(gr_line
		(start 372.890796 -292.229032)
		(end 372.889272 -292.230048)
		(stroke
			(width 0.05715)
			(type default)
		)
		(layer "In13.Cu")
	)
	(gr_line
		(start 372.890796 -290.60902)
		(end 372.889272 -290.610036)
		(stroke
			(width 0.05715)
			(type default)
		)
		(layer "In13.Cu")
	)
	(gr_line
		(start 372.890796 -288.989008)
		(end 372.889272 -288.990024)
		(stroke
			(width 0.05715)
			(type default)
		)
		(layer "In13.Cu")
	)
	(gr_line
		(start 372.890796 -285.749238)
		(end 372.889272 -285.750254)
		(stroke
			(width 0.05715)
			(type default)
		)
		(layer "In13.Cu")
	)
	(gr_line
		(start 372.890796 -284.129226)
		(end 372.889272 -284.130242)
		(stroke
			(width 0.05715)
			(type default)
		)
		(layer "In13.Cu")
	)
	(gr_line
		(start 372.890796 -282.509214)
		(end 372.889272 -282.51023)
		(stroke
			(width 0.05715)
			(type default)
		)
		(layer "In13.Cu")
	)
	(gr_line
		(start 372.890796 -279.26919)
		(end 372.889272 -279.270206)
		(stroke
			(width 0.05715)
			(type default)
		)
		(layer "In13.Cu")
	)
	(gr_line
		(start 372.890796 -277.649178)
		(end 372.889272 -277.650194)
		(stroke
			(width 0.05715)
			(type default)
		)
		(layer "In13.Cu")
	)
	(gr_line
		(start 372.890796 -276.029166)
		(end 372.889272 -276.030182)
		(stroke
			(width 0.05715)
			(type default)
		)
		(layer "In13.Cu")
	)
	(gr_line
		(start 372.890796 -274.409154)
		(end 372.889272 -274.41017)
		(stroke
			(width 0.05715)
			(type default)
		)
		(layer "In13.Cu")
	)
	(gr_line
		(start 372.890796 -272.789142)
		(end 372.889272 -272.790158)
		(stroke
			(width 0.05715)
			(type default)
		)
		(layer "In13.Cu")
	)
	(gr_line
		(start 372.890796 -271.16913)
		(end 372.889272 -271.170146)
		(stroke
			(width 0.05715)
			(type default)
		)
		(layer "In13.Cu")
	)
	(gr_line
		(start 372.891558 -279.268682)
		(end 372.890796 -279.26919)
		(stroke
			(width 0.05715)
			(type default)
		)
		(layer "In13.Cu")
	)
	(gr_line
		(start 372.891558 -277.64867)
		(end 372.890796 -277.649178)
		(stroke
			(width 0.05715)
			(type default)
		)
		(layer "In13.Cu")
	)
	(gr_line
		(start 372.891558 -276.028658)
		(end 372.890796 -276.029166)
		(stroke
			(width 0.05715)
			(type default)
		)
		(layer "In13.Cu")
	)
	(gr_line
		(start 372.891558 -274.408646)
		(end 372.890796 -274.409154)
		(stroke
			(width 0.05715)
			(type default)
		)
		(layer "In13.Cu")
	)
	(gr_line
		(start 372.891558 -272.788634)
		(end 372.890796 -272.789142)
		(stroke
			(width 0.05715)
			(type default)
		)
		(layer "In13.Cu")
	)
	(gr_line
		(start 372.891558 -271.168622)
		(end 372.890796 -271.16913)
		(stroke
			(width 0.05715)
			(type default)
		)
		(layer "In13.Cu")
	)
	(gr_line
		(start 372.891812 -293.848536)
		(end 372.890796 -293.849044)
		(stroke
			(width 0.05715)
			(type default)
		)
		(layer "In13.Cu")
	)
	(gr_line
		(start 372.891812 -292.228524)
		(end 372.890796 -292.229032)
		(stroke
			(width 0.05715)
			(type default)
		)
		(layer "In13.Cu")
	)
	(gr_line
		(start 372.891812 -290.608512)
		(end 372.890796 -290.60902)
		(stroke
			(width 0.05715)
			(type default)
		)
		(layer "In13.Cu")
	)
	(gr_line
		(start 372.891812 -288.9885)
		(end 372.890796 -288.989008)
		(stroke
			(width 0.05715)
			(type default)
		)
		(layer "In13.Cu")
	)
	(gr_line
		(start 372.891812 -285.74873)
		(end 372.890796 -285.749238)
		(stroke
			(width 0.05715)
			(type default)
		)
		(layer "In13.Cu")
	)
	(gr_line
		(start 372.891812 -284.128718)
		(end 372.890796 -284.129226)
		(stroke
			(width 0.05715)
			(type default)
		)
		(layer "In13.Cu")
	)
	(gr_line
		(start 372.891812 -282.508706)
		(end 372.890796 -282.509214)
		(stroke
			(width 0.05715)
			(type default)
		)
		(layer "In13.Cu")
	)
	(gr_line
		(start 372.891812 -280.243534)
		(end 372.89232 -280.243788)
		(stroke
			(width 0.05715)
			(type default)
		)
		(layer "In13.Cu")
	)
	(gr_line
		(start 372.892066 -294.823642)
		(end 372.892574 -294.823896)
		(stroke
			(width 0.05715)
			(type default)
		)
		(layer "In13.Cu")
	)
	(gr_line
		(start 372.892066 -293.20363)
		(end 372.892574 -293.203884)
		(stroke
			(width 0.05715)
			(type default)
		)
		(layer "In13.Cu")
	)
	(gr_line
		(start 372.892066 -289.963606)
		(end 372.892574 -289.96386)
		(stroke
			(width 0.05715)
			(type default)
		)
		(layer "In13.Cu")
	)
	(gr_line
		(start 372.892066 -281.8638)
		(end 372.892574 -281.864054)
		(stroke
			(width 0.05715)
			(type default)
		)
		(layer "In13.Cu")
	)
	(gr_line
		(start 372.892066 -278.623776)
		(end 372.892574 -278.62403)
		(stroke
			(width 0.05715)
			(type default)
		)
		(layer "In13.Cu")
	)
	(gr_line
		(start 372.892066 -277.003764)
		(end 372.892574 -277.004018)
		(stroke
			(width 0.05715)
			(type default)
		)
		(layer "In13.Cu")
	)
	(gr_line
		(start 372.892066 -275.383752)
		(end 372.892574 -275.384006)
		(stroke
			(width 0.05715)
			(type default)
		)
		(layer "In13.Cu")
	)
	(gr_line
		(start 372.892066 -273.76374)
		(end 372.892574 -273.763994)
		(stroke
			(width 0.05715)
			(type default)
		)
		(layer "In13.Cu")
	)
	(gr_line
		(start 372.892066 -272.143728)
		(end 372.892574 -272.143982)
		(stroke
			(width 0.05715)
			(type default)
		)
		(layer "In13.Cu")
	)
	(gr_line
		(start 372.89232 -293.848282)
		(end 372.891812 -293.848536)
		(stroke
			(width 0.05715)
			(type default)
		)
		(layer "In13.Cu")
	)
	(gr_line
		(start 372.892574 -294.823896)
		(end 372.893844 -294.824658)
		(stroke
			(width 0.05715)
			(type default)
		)
		(layer "In13.Cu")
	)
	(gr_line
		(start 372.892574 -293.203884)
		(end 372.893844 -293.204646)
		(stroke
			(width 0.05715)
			(type default)
		)
		(layer "In13.Cu")
	)
	(gr_line
		(start 372.892574 -292.228016)
		(end 372.891812 -292.228524)
		(stroke
			(width 0.05715)
			(type default)
		)
		(layer "In13.Cu")
	)
	(gr_line
		(start 372.892574 -291.583872)
		(end 372.893844 -291.584634)
		(stroke
			(width 0.05715)
			(type default)
		)
		(layer "In13.Cu")
	)
	(gr_line
		(start 372.892574 -290.608004)
		(end 372.891812 -290.608512)
		(stroke
			(width 0.05715)
			(type default)
		)
		(layer "In13.Cu")
	)
	(gr_line
		(start 372.892574 -289.96386)
		(end 372.893844 -289.964622)
		(stroke
			(width 0.05715)
			(type default)
		)
		(layer "In13.Cu")
	)
	(gr_line
		(start 372.892574 -288.987992)
		(end 372.891812 -288.9885)
		(stroke
			(width 0.05715)
			(type default)
		)
		(layer "In13.Cu")
	)
	(gr_line
		(start 372.892574 -285.748222)
		(end 372.891812 -285.74873)
		(stroke
			(width 0.05715)
			(type default)
		)
		(layer "In13.Cu")
	)
	(gr_line
		(start 372.892574 -285.104078)
		(end 372.893844 -285.10484)
		(stroke
			(width 0.05715)
			(type default)
		)
		(layer "In13.Cu")
	)
	(gr_line
		(start 372.892574 -284.12821)
		(end 372.891812 -284.128718)
		(stroke
			(width 0.05715)
			(type default)
		)
		(layer "In13.Cu")
	)
	(gr_line
		(start 372.892574 -283.484066)
		(end 372.893844 -283.484828)
		(stroke
			(width 0.05715)
			(type default)
		)
		(layer "In13.Cu")
	)
	(gr_line
		(start 372.892574 -282.508198)
		(end 372.891812 -282.508706)
		(stroke
			(width 0.05715)
			(type default)
		)
		(layer "In13.Cu")
	)
	(gr_line
		(start 372.892574 -281.864054)
		(end 372.893844 -281.864816)
		(stroke
			(width 0.05715)
			(type default)
		)
		(layer "In13.Cu")
	)
	(gr_line
		(start 372.892574 -278.62403)
		(end 372.895368 -278.625554)
		(stroke
			(width 0.05715)
			(type default)
		)
		(layer "In13.Cu")
	)
	(gr_line
		(start 372.892574 -277.004018)
		(end 372.895368 -277.005542)
		(stroke
			(width 0.05715)
			(type default)
		)
		(layer "In13.Cu")
	)
	(gr_line
		(start 372.892574 -275.384006)
		(end 372.895368 -275.38553)
		(stroke
			(width 0.05715)
			(type default)
		)
		(layer "In13.Cu")
	)
	(gr_line
		(start 372.892574 -273.763994)
		(end 372.895368 -273.765518)
		(stroke
			(width 0.05715)
			(type default)
		)
		(layer "In13.Cu")
	)
	(gr_line
		(start 372.892574 -272.143982)
		(end 372.895368 -272.145506)
		(stroke
			(width 0.05715)
			(type default)
		)
		(layer "In13.Cu")
	)
	(gr_line
		(start 372.893844 -294.824658)
		(end 372.895368 -294.82542)
		(stroke
			(width 0.05715)
			(type default)
		)
		(layer "In13.Cu")
	)
	(gr_line
		(start 372.893844 -293.204646)
		(end 372.895368 -293.205408)
		(stroke
			(width 0.05715)
			(type default)
		)
		(layer "In13.Cu")
	)
	(gr_line
		(start 372.893844 -292.227254)
		(end 372.892574 -292.228016)
		(stroke
			(width 0.05715)
			(type default)
		)
		(layer "In13.Cu")
	)
	(gr_line
		(start 372.893844 -290.607242)
		(end 372.892574 -290.608004)
		(stroke
			(width 0.05715)
			(type default)
		)
		(layer "In13.Cu")
	)
	(gr_line
		(start 372.893844 -289.964622)
		(end 372.895368 -289.965384)
		(stroke
			(width 0.05715)
			(type default)
		)
		(layer "In13.Cu")
	)
	(gr_line
		(start 372.893844 -288.98723)
		(end 372.892574 -288.987992)
		(stroke
			(width 0.05715)
			(type default)
		)
		(layer "In13.Cu")
	)
	(gr_line
		(start 372.893844 -285.74746)
		(end 372.892574 -285.748222)
		(stroke
			(width 0.05715)
			(type default)
		)
		(layer "In13.Cu")
	)
	(gr_line
		(start 372.893844 -284.127448)
		(end 372.892574 -284.12821)
		(stroke
			(width 0.05715)
			(type default)
		)
		(layer "In13.Cu")
	)
	(gr_line
		(start 372.893844 -282.507436)
		(end 372.892574 -282.508198)
		(stroke
			(width 0.05715)
			(type default)
		)
		(layer "In13.Cu")
	)
	(gr_line
		(start 372.893844 -281.864816)
		(end 372.895368 -281.865578)
		(stroke
			(width 0.05715)
			(type default)
		)
		(layer "In13.Cu")
	)
	(gr_line
		(start 372.981982 -292.396672)
		(end 372.98122 -292.39718)
		(stroke
			(width 0.05715)
			(type default)
		)
		(layer "In13.Cu")
	)
	(gr_line
		(start 372.981982 -290.77666)
		(end 372.98122 -290.777168)
		(stroke
			(width 0.05715)
			(type default)
		)
		(layer "In13.Cu")
	)
	(gr_line
		(start 372.981982 -289.156648)
		(end 372.98122 -289.157156)
		(stroke
			(width 0.05715)
			(type default)
		)
		(layer "In13.Cu")
	)
	(gr_line
		(start 372.981982 -285.916878)
		(end 372.98122 -285.917386)
		(stroke
			(width 0.05715)
			(type default)
		)
		(layer "In13.Cu")
	)
	(gr_line
		(start 372.981982 -284.296866)
		(end 372.98122 -284.297374)
		(stroke
			(width 0.05715)
			(type default)
		)
		(layer "In13.Cu")
	)
	(gr_line
		(start 372.981982 -282.676854)
		(end 372.98122 -282.677362)
		(stroke
			(width 0.05715)
			(type default)
		)
		(layer "In13.Cu")
	)
	(gr_line
		(start 372.981982 -279.43683)
		(end 372.981474 -279.437084)
		(stroke
			(width 0.05715)
			(type default)
		)
		(layer "In13.Cu")
	)
	(gr_line
		(start 372.981982 -277.816818)
		(end 372.981474 -277.817072)
		(stroke
			(width 0.05715)
			(type default)
		)
		(layer "In13.Cu")
	)
	(gr_line
		(start 372.981982 -276.196806)
		(end 372.981474 -276.19706)
		(stroke
			(width 0.05715)
			(type default)
		)
		(layer "In13.Cu")
	)
	(gr_line
		(start 372.981982 -274.576794)
		(end 372.981474 -274.577048)
		(stroke
			(width 0.05715)
			(type default)
		)
		(layer "In13.Cu")
	)
	(gr_line
		(start 372.981982 -272.956782)
		(end 372.981474 -272.957036)
		(stroke
			(width 0.05715)
			(type default)
		)
		(layer "In13.Cu")
	)
	(gr_line
		(start 372.981982 -271.33677)
		(end 372.981474 -271.337024)
		(stroke
			(width 0.05715)
			(type default)
		)
		(layer "In13.Cu")
	)
	(gr_line
		(start 372.982998 -292.396164)
		(end 372.981982 -292.396672)
		(stroke
			(width 0.05715)
			(type default)
		)
		(layer "In13.Cu")
	)
	(gr_line
		(start 372.982998 -290.776152)
		(end 372.981982 -290.77666)
		(stroke
			(width 0.05715)
			(type default)
		)
		(layer "In13.Cu")
	)
	(gr_line
		(start 372.982998 -289.15614)
		(end 372.981982 -289.156648)
		(stroke
			(width 0.05715)
			(type default)
		)
		(layer "In13.Cu")
	)
	(gr_line
		(start 372.982998 -285.91637)
		(end 372.981982 -285.916878)
		(stroke
			(width 0.05715)
			(type default)
		)
		(layer "In13.Cu")
	)
	(gr_line
		(start 372.982998 -284.296358)
		(end 372.981982 -284.296866)
		(stroke
			(width 0.05715)
			(type default)
		)
		(layer "In13.Cu")
	)
	(gr_line
		(start 372.982998 -282.676346)
		(end 372.981982 -282.676854)
		(stroke
			(width 0.05715)
			(type default)
		)
		(layer "In13.Cu")
	)
	(gr_line
		(start 372.984268 -279.43556)
		(end 372.983506 -279.436068)
		(stroke
			(width 0.05715)
			(type default)
		)
		(layer "In13.Cu")
	)
	(gr_line
		(start 372.984268 -277.815548)
		(end 372.983506 -277.816056)
		(stroke
			(width 0.05715)
			(type default)
		)
		(layer "In13.Cu")
	)
	(gr_line
		(start 372.984268 -276.195536)
		(end 372.983506 -276.196044)
		(stroke
			(width 0.05715)
			(type default)
		)
		(layer "In13.Cu")
	)
	(gr_line
		(start 372.984268 -274.575524)
		(end 372.983506 -274.576032)
		(stroke
			(width 0.05715)
			(type default)
		)
		(layer "In13.Cu")
	)
	(gr_line
		(start 372.984268 -272.955512)
		(end 372.983506 -272.95602)
		(stroke
			(width 0.05715)
			(type default)
		)
		(layer "In13.Cu")
	)
	(gr_line
		(start 372.984268 -271.3355)
		(end 372.983506 -271.336008)
		(stroke
			(width 0.05715)
			(type default)
		)
		(layer "In13.Cu")
	)
	(gr_line
		(start 372.9863 -280.077926)
		(end 372.987062 -280.07818)
		(stroke
			(width 0.05715)
			(type default)
		)
		(layer "In13.Cu")
	)
	(gr_line
		(start 372.987062 -294.01389)
		(end 372.985792 -294.014652)
		(stroke
			(width 0.05715)
			(type default)
		)
		(layer "In13.Cu")
	)
	(gr_line
		(start 372.987062 -292.393878)
		(end 372.985792 -292.39464)
		(stroke
			(width 0.05715)
			(type default)
		)
		(layer "In13.Cu")
	)
	(gr_line
		(start 372.987062 -290.773866)
		(end 372.985792 -290.774628)
		(stroke
			(width 0.05715)
			(type default)
		)
		(layer "In13.Cu")
	)
	(gr_line
		(start 372.987062 -289.153854)
		(end 372.985792 -289.154616)
		(stroke
			(width 0.05715)
			(type default)
		)
		(layer "In13.Cu")
	)
	(gr_line
		(start 372.987062 -285.914084)
		(end 372.985792 -285.914846)
		(stroke
			(width 0.05715)
			(type default)
		)
		(layer "In13.Cu")
	)
	(gr_line
		(start 372.987062 -284.294072)
		(end 372.985792 -284.294834)
		(stroke
			(width 0.05715)
			(type default)
		)
		(layer "In13.Cu")
	)
	(gr_line
		(start 372.987062 -282.67406)
		(end 372.985792 -282.674822)
		(stroke
			(width 0.05715)
			(type default)
		)
		(layer "In13.Cu")
	)
	(gr_line
		(start 372.987062 -279.434036)
		(end 372.985792 -279.434798)
		(stroke
			(width 0.05715)
			(type default)
		)
		(layer "In13.Cu")
	)
	(gr_line
		(start 372.987062 -277.814024)
		(end 372.985792 -277.814786)
		(stroke
			(width 0.05715)
			(type default)
		)
		(layer "In13.Cu")
	)
	(gr_line
		(start 372.987062 -276.194012)
		(end 372.985792 -276.194774)
		(stroke
			(width 0.05715)
			(type default)
		)
		(layer "In13.Cu")
	)
	(gr_line
		(start 372.987062 -274.574)
		(end 372.985792 -274.574762)
		(stroke
			(width 0.05715)
			(type default)
		)
		(layer "In13.Cu")
	)
	(gr_line
		(start 372.987062 -272.953988)
		(end 372.985792 -272.95475)
		(stroke
			(width 0.05715)
			(type default)
		)
		(layer "In13.Cu")
	)
	(gr_line
		(start 372.987062 -271.333976)
		(end 372.985792 -271.334738)
		(stroke
			(width 0.05715)
			(type default)
		)
		(layer "In13.Cu")
	)
	(gr_line
		(start 372.987316 -291.418264)
		(end 372.987824 -291.418518)
		(stroke
			(width 0.05715)
			(type default)
		)
		(layer "In13.Cu")
	)
	(gr_line
		(start 372.987316 -284.93847)
		(end 372.987824 -284.938724)
		(stroke
			(width 0.05715)
			(type default)
		)
		(layer "In13.Cu")
	)
	(gr_line
		(start 372.987316 -283.318458)
		(end 372.987824 -283.318712)
		(stroke
			(width 0.05715)
			(type default)
		)
		(layer "In13.Cu")
	)
	(gr_line
		(start 372.98757 -279.433782)
		(end 372.987062 -279.434036)
		(stroke
			(width 0.05715)
			(type default)
		)
		(layer "In13.Cu")
	)
	(gr_line
		(start 372.98757 -277.81377)
		(end 372.987062 -277.814024)
		(stroke
			(width 0.05715)
			(type default)
		)
		(layer "In13.Cu")
	)
	(gr_line
		(start 372.98757 -276.193758)
		(end 372.987062 -276.194012)
		(stroke
			(width 0.05715)
			(type default)
		)
		(layer "In13.Cu")
	)
	(gr_line
		(start 372.98757 -274.573746)
		(end 372.987062 -274.574)
		(stroke
			(width 0.05715)
			(type default)
		)
		(layer "In13.Cu")
	)
	(gr_line
		(start 372.98757 -272.953734)
		(end 372.987062 -272.953988)
		(stroke
			(width 0.05715)
			(type default)
		)
		(layer "In13.Cu")
	)
	(gr_line
		(start 372.98757 -271.333722)
		(end 372.987062 -271.333976)
		(stroke
			(width 0.05715)
			(type default)
		)
		(layer "In13.Cu")
	)
	(gr_line
		(start 372.987824 -294.658542)
		(end 372.98884 -294.65905)
		(stroke
			(width 0.05715)
			(type default)
		)
		(layer "In13.Cu")
	)
	(gr_line
		(start 372.987824 -293.03853)
		(end 372.98884 -293.039038)
		(stroke
			(width 0.05715)
			(type default)
		)
		(layer "In13.Cu")
	)
	(gr_line
		(start 372.987824 -292.39337)
		(end 372.987062 -292.393878)
		(stroke
			(width 0.05715)
			(type default)
		)
		(layer "In13.Cu")
	)
	(gr_line
		(start 372.987824 -291.418518)
		(end 372.98884 -291.419026)
		(stroke
			(width 0.05715)
			(type default)
		)
		(layer "In13.Cu")
	)
	(gr_line
		(start 372.987824 -290.773358)
		(end 372.987062 -290.773866)
		(stroke
			(width 0.05715)
			(type default)
		)
		(layer "In13.Cu")
	)
	(gr_line
		(start 372.987824 -289.798506)
		(end 372.98884 -289.799014)
		(stroke
			(width 0.05715)
			(type default)
		)
		(layer "In13.Cu")
	)
	(gr_line
		(start 372.987824 -289.153346)
		(end 372.987062 -289.153854)
		(stroke
			(width 0.05715)
			(type default)
		)
		(layer "In13.Cu")
	)
	(gr_line
		(start 372.987824 -285.913576)
		(end 372.987062 -285.914084)
		(stroke
			(width 0.05715)
			(type default)
		)
		(layer "In13.Cu")
	)
	(gr_line
		(start 372.987824 -284.938724)
		(end 372.98884 -284.939232)
		(stroke
			(width 0.05715)
			(type default)
		)
		(layer "In13.Cu")
	)
	(gr_line
		(start 372.987824 -284.293564)
		(end 372.987062 -284.294072)
		(stroke
			(width 0.05715)
			(type default)
		)
		(layer "In13.Cu")
	)
	(gr_line
		(start 372.987824 -283.318712)
		(end 372.98884 -283.31922)
		(stroke
			(width 0.05715)
			(type default)
		)
		(layer "In13.Cu")
	)
	(gr_line
		(start 372.987824 -282.673552)
		(end 372.987062 -282.67406)
		(stroke
			(width 0.05715)
			(type default)
		)
		(layer "In13.Cu")
	)
	(gr_line
		(start 372.987824 -281.6987)
		(end 372.98884 -281.699208)
		(stroke
			(width 0.05715)
			(type default)
		)
		(layer "In13.Cu")
	)
	(gr_line
		(start 372.987824 -278.458676)
		(end 372.98884 -278.459184)
		(stroke
			(width 0.05715)
			(type default)
		)
		(layer "In13.Cu")
	)
	(gr_line
		(start 372.987824 -276.838664)
		(end 372.98884 -276.839172)
		(stroke
			(width 0.05715)
			(type default)
		)
		(layer "In13.Cu")
	)
	(gr_line
		(start 372.987824 -275.218652)
		(end 372.98884 -275.21916)
		(stroke
			(width 0.05715)
			(type default)
		)
		(layer "In13.Cu")
	)
	(gr_line
		(start 372.987824 -273.59864)
		(end 372.98884 -273.599148)
		(stroke
			(width 0.05715)
			(type default)
		)
		(layer "In13.Cu")
	)
	(gr_line
		(start 372.987824 -271.978628)
		(end 372.98884 -271.979136)
		(stroke
			(width 0.05715)
			(type default)
		)
		(layer "In13.Cu")
	)
	(gr_line
		(start 372.98884 -294.65905)
		(end 372.990364 -294.660066)
		(stroke
			(width 0.05715)
			(type default)
		)
		(layer "In13.Cu")
	)
	(gr_line
		(start 372.98884 -293.039038)
		(end 372.990364 -293.040054)
		(stroke
			(width 0.05715)
			(type default)
		)
		(layer "In13.Cu")
	)
	(gr_line
		(start 372.98884 -292.392862)
		(end 372.987824 -292.39337)
		(stroke
			(width 0.05715)
			(type default)
		)
		(layer "In13.Cu")
	)
	(gr_line
		(start 372.98884 -290.77285)
		(end 372.987824 -290.773358)
		(stroke
			(width 0.05715)
			(type default)
		)
		(layer "In13.Cu")
	)
	(gr_line
		(start 372.98884 -289.799014)
		(end 372.990364 -289.80003)
		(stroke
			(width 0.05715)
			(type default)
		)
		(layer "In13.Cu")
	)
	(gr_line
		(start 372.98884 -289.152838)
		(end 372.987824 -289.153346)
		(stroke
			(width 0.05715)
			(type default)
		)
		(layer "In13.Cu")
	)
	(gr_line
		(start 372.98884 -285.913068)
		(end 372.987824 -285.913576)
		(stroke
			(width 0.05715)
			(type default)
		)
		(layer "In13.Cu")
	)
	(gr_line
		(start 372.98884 -284.293056)
		(end 372.987824 -284.293564)
		(stroke
			(width 0.05715)
			(type default)
		)
		(layer "In13.Cu")
	)
	(gr_line
		(start 372.98884 -282.673044)
		(end 372.987824 -282.673552)
		(stroke
			(width 0.05715)
			(type default)
		)
		(layer "In13.Cu")
	)
	(gr_line
		(start 372.98884 -281.699208)
		(end 372.990364 -281.700224)
		(stroke
			(width 0.05715)
			(type default)
		)
		(layer "In13.Cu")
	)
	(gr_line
		(start 372.98884 -278.459184)
		(end 372.990364 -278.4602)
		(stroke
			(width 0.05715)
			(type default)
		)
		(layer "In13.Cu")
	)
	(gr_line
		(start 372.98884 -276.839172)
		(end 372.990364 -276.840188)
		(stroke
			(width 0.05715)
			(type default)
		)
		(layer "In13.Cu")
	)
	(gr_line
		(start 372.98884 -275.21916)
		(end 372.990364 -275.220176)
		(stroke
			(width 0.05715)
			(type default)
		)
		(layer "In13.Cu")
	)
	(gr_line
		(start 372.98884 -273.599148)
		(end 372.990364 -273.600164)
		(stroke
			(width 0.05715)
			(type default)
		)
		(layer "In13.Cu")
	)
	(gr_line
		(start 372.98884 -271.979136)
		(end 372.990364 -271.980152)
		(stroke
			(width 0.05715)
			(type default)
		)
		(layer "In13.Cu")
	)
	(gr_line
		(start 372.990364 -278.4602)
		(end 372.99138 -278.460708)
		(stroke
			(width 0.05715)
			(type default)
		)
		(layer "In13.Cu")
	)
	(gr_line
		(start 372.990364 -276.840188)
		(end 372.99138 -276.840696)
		(stroke
			(width 0.05715)
			(type default)
		)
		(layer "In13.Cu")
	)
	(gr_line
		(start 372.990364 -275.220176)
		(end 372.99138 -275.220684)
		(stroke
			(width 0.05715)
			(type default)
		)
		(layer "In13.Cu")
	)
	(gr_line
		(start 372.990364 -273.600164)
		(end 372.99138 -273.600672)
		(stroke
			(width 0.05715)
			(type default)
		)
		(layer "In13.Cu")
	)
	(gr_line
		(start 372.990364 -271.980152)
		(end 372.99138 -271.98066)
		(stroke
			(width 0.05715)
			(type default)
		)
		(layer "In13.Cu")
	)
	(gr_line
		(start 372.99138 -278.460708)
		(end 372.99646 -278.463756)
		(stroke
			(width 0.05715)
			(type default)
		)
		(layer "In13.Cu")
	)
	(gr_line
		(start 372.99138 -276.840696)
		(end 372.99646 -276.843744)
		(stroke
			(width 0.05715)
			(type default)
		)
		(layer "In13.Cu")
	)
	(gr_line
		(start 372.99138 -275.220684)
		(end 372.99646 -275.223732)
		(stroke
			(width 0.05715)
			(type default)
		)
		(layer "In13.Cu")
	)
	(gr_line
		(start 372.99138 -273.600672)
		(end 372.99646 -273.60372)
		(stroke
			(width 0.05715)
			(type default)
		)
		(layer "In13.Cu")
	)
	(gr_line
		(start 372.99138 -271.98066)
		(end 372.99646 -271.983708)
		(stroke
			(width 0.05715)
			(type default)
		)
		(layer "In13.Cu")
	)
	(gr_line
		(start 372.992142 -294.661082)
		(end 372.993412 -294.661844)
		(stroke
			(width 0.05715)
			(type default)
		)
		(layer "In13.Cu")
	)
	(gr_line
		(start 372.992142 -293.04107)
		(end 372.993412 -293.041832)
		(stroke
			(width 0.05715)
			(type default)
		)
		(layer "In13.Cu")
	)
	(gr_line
		(start 372.992142 -289.801046)
		(end 372.993412 -289.801808)
		(stroke
			(width 0.05715)
			(type default)
		)
		(layer "In13.Cu")
	)
	(gr_line
		(start 372.992142 -281.70124)
		(end 372.993412 -281.702002)
		(stroke
			(width 0.05715)
			(type default)
		)
		(layer "In13.Cu")
	)
	(gr_line
		(start 372.994682 -406.87371)
		(end 372.994682 -406.44699)
		(stroke
			(width 0.07112)
			(type default)
		)
		(layer "In13.Cu")
	)
	(gr_line
		(start 372.994682 -406.44699)
		(end 372.858792 -406.3111)
		(stroke
			(width 0.07112)
			(type default)
		)
		(layer "In13.Cu")
	)
	(gr_line
		(start 372.994682 -405.74595)
		(end 372.994682 -405.31923)
		(stroke
			(width 0.07112)
			(type default)
		)
		(layer "In13.Cu")
	)
	(gr_line
		(start 372.994682 -405.31923)
		(end 372.858792 -405.18334)
		(stroke
			(width 0.07112)
			(type default)
		)
		(layer "In13.Cu")
	)
	(gr_line
		(start 372.994682 -404.61819)
		(end 372.994682 -404.19147)
		(stroke
			(width 0.07112)
			(type default)
		)
		(layer "In13.Cu")
	)
	(gr_line
		(start 372.994682 -404.19147)
		(end 372.858792 -404.05558)
		(stroke
			(width 0.07112)
			(type default)
		)
		(layer "In13.Cu")
	)
	(gr_line
		(start 372.994682 -403.49043)
		(end 372.994682 -403.06371)
		(stroke
			(width 0.07112)
			(type default)
		)
		(layer "In13.Cu")
	)
	(gr_line
		(start 372.994682 -403.06371)
		(end 372.858792 -402.92782)
		(stroke
			(width 0.07112)
			(type default)
		)
		(layer "In13.Cu")
	)
	(gr_line
		(start 372.994682 -294.662606)
		(end 372.99646 -294.663622)
		(stroke
			(width 0.05715)
			(type default)
		)
		(layer "In13.Cu")
	)
	(gr_line
		(start 372.994682 -293.042594)
		(end 372.99646 -293.04361)
		(stroke
			(width 0.05715)
			(type default)
		)
		(layer "In13.Cu")
	)
	(gr_line
		(start 372.994682 -289.80257)
		(end 372.99646 -289.803586)
		(stroke
			(width 0.05715)
			(type default)
		)
		(layer "In13.Cu")
	)
	(gr_line
		(start 372.994682 -281.702764)
		(end 372.99646 -281.70378)
		(stroke
			(width 0.05715)
			(type default)
		)
		(layer "In13.Cu")
	)
	(gr_line
		(start 373.14886 -354.0125)
		(end 373.14886 -353.58578)
		(stroke
			(width 0.07112)
			(type default)
		)
		(layer "In13.Cu")
	)
	(gr_line
		(start 373.14886 -353.58578)
		(end 373.28475 -353.44989)
		(stroke
			(width 0.07112)
			(type default)
		)
		(layer "In13.Cu")
	)
	(gr_line
		(start 373.174768 -273.27606)
		(end 373.47271 -273.27606)
		(stroke
			(width 0.05715)
			(type default)
		)
		(layer "In13.Cu")
	)
	(gr_line
		(start 373.174768 -271.656048)
		(end 373.47271 -271.656048)
		(stroke
			(width 0.05715)
			(type default)
		)
		(layer "In13.Cu")
	)
	(gr_line
		(start 373.174768 -270.036036)
		(end 373.47271 -270.036036)
		(stroke
			(width 0.05715)
			(type default)
		)
		(layer "In13.Cu")
	)
	(gr_line
		(start 373.177054 -401.089622)
		(end 373.1895 -401.089622)
		(stroke
			(width 0.07112)
			(type default)
		)
		(layer "In13.Cu")
	)
	(gr_line
		(start 373.178324 -401.372832)
		(end 373.3165 -401.511008)
		(stroke
			(width 0.07112)
			(type default)
		)
		(layer "In13.Cu")
	)
	(gr_line
		(start 373.1895 -401.089622)
		(end 373.3165 -400.962622)
		(stroke
			(width 0.07112)
			(type default)
		)
		(layer "In13.Cu")
	)
	(gr_line
		(start 373.28475 -354.14839)
		(end 373.14886 -354.0125)
		(stroke
			(width 0.07112)
			(type default)
		)
		(layer "In13.Cu")
	)
	(gr_line
		(start 373.3165 -401.511008)
		(end 373.3165 -401.674838)
		(stroke
			(width 0.07112)
			(type default)
		)
		(layer "In13.Cu")
	)
	(gr_line
		(start 373.3165 -400.962622)
		(end 373.3165 -400.811238)
		(stroke
			(width 0.07112)
			(type default)
		)
		(layer "In13.Cu")
	)
	(gr_line
		(start 373.344948 -408.347164)
		(end 373.153432 -408.328368)
		(stroke
			(width 0.07112)
			(type default)
		)
		(layer "In13.Cu")
	)
	(gr_line
		(start 373.361712 -295.633394)
		(end 373.361966 -295.633394)
		(stroke
			(width 0.05715)
			(type default)
		)
		(layer "In13.Cu")
	)
	(gr_line
		(start 373.37873 -409.048966)
		(end 372.933722 -408.50693)
		(stroke
			(width 0.07112)
			(type default)
		)
		(layer "In13.Cu")
	)
	(gr_line
		(start 373.40794 -295.662858)
		(end 373.408448 -295.663366)
		(stroke
			(width 0.05715)
			(type default)
		)
		(layer "In13.Cu")
	)
	(gr_line
		(start 373.408448 -295.663366)
		(end 373.408956 -295.663874)
		(stroke
			(width 0.05715)
			(type default)
		)
		(layer "In13.Cu")
	)
	(gr_line
		(start 373.45747 -295.468548)
		(end 373.458232 -295.468802)
		(stroke
			(width 0.05715)
			(type default)
		)
		(layer "In13.Cu")
	)
	(gr_line
		(start 373.47271 -273.27606)
		(end 373.555514 -273.358864)
		(stroke
			(width 0.05715)
			(type default)
		)
		(layer "In13.Cu")
	)
	(gr_line
		(start 373.47271 -271.656048)
		(end 373.555514 -271.738852)
		(stroke
			(width 0.05715)
			(type default)
		)
		(layer "In13.Cu")
	)
	(gr_line
		(start 373.47271 -270.036036)
		(end 373.542052 -270.105378)
		(stroke
			(width 0.05715)
			(type default)
		)
		(layer "In13.Cu")
	)
	(gr_line
		(start 373.503952 -296.583862)
		(end 373.503952 -296.61231)
		(stroke
			(width 0.05715)
			(type default)
		)
		(layer "In13.Cu")
	)
	(gr_arc
		(start 373.505222 -295.497504)
		(mid 373.502308 -295.495335)
		(end 373.49938 -295.493186)
		(stroke
			(width 0.05715)
			(type default)
		)
		(layer "In13.Cu")
	)
	(gr_line
		(start 373.549672 -296.538142)
		(end 373.503952 -296.583862)
		(stroke
			(width 0.05715)
			(type default)
		)
		(layer "In13.Cu")
	)
	(gr_arc
		(start 373.555514 -273.358864)
		(mid 373.557306 -273.370186)
		(end 373.559324 -273.38147)
		(stroke
			(width 0.05715)
			(type default)
		)
		(layer "In13.Cu")
	)
	(gr_arc
		(start 373.555514 -271.738852)
		(mid 373.5573 -271.750302)
		(end 373.559324 -271.761712)
		(stroke
			(width 0.05715)
			(type default)
		)
		(layer "In13.Cu")
	)
	(gr_line
		(start 373.56796 -354.14966)
		(end 373.56796 -353.44862)
		(stroke
			(width 0.07112)
			(type default)
		)
		(layer "In13.Cu")
	)
	(gr_line
		(start 373.596916 -408.868626)
		(end 373.615712 -408.67711)
		(stroke
			(width 0.07112)
			(type default)
		)
		(layer "In13.Cu")
	)
	(gr_line
		(start 373.615712 -408.67711)
		(end 373.344948 -408.347164)
		(stroke
			(width 0.07112)
			(type default)
		)
		(layer "In13.Cu")
	)
	(gr_arc
		(start 373.730266 -270.1417)
		(mid 373.732287 -270.130289)
		(end 373.734076 -270.11884)
		(stroke
			(width 0.05715)
			(type default)
		)
		(layer "In13.Cu")
	)
	(gr_line
		(start 373.740172 -296.538142)
		(end 373.785892 -296.583862)
		(stroke
			(width 0.05715)
			(type default)
		)
		(layer "In13.Cu")
	)
	(gr_line
		(start 373.775478 -405.711406)
		(end 373.775478 -405.010366)
		(stroke
			(width 0.07112)
			(type default)
		)
		(layer "In13.Cu")
	)
	(gr_line
		(start 373.775478 -404.583646)
		(end 373.775478 -403.882606)
		(stroke
			(width 0.07112)
			(type default)
		)
		(layer "In13.Cu")
	)
	(gr_line
		(start 373.775478 -403.455886)
		(end 373.775478 -402.754846)
		(stroke
			(width 0.07112)
			(type default)
		)
		(layer "In13.Cu")
	)
	(gr_arc
		(start 373.782082 -288.313114)
		(mid 373.785248 -288.315412)
		(end 373.788432 -288.317686)
		(stroke
			(width 0.05715)
			(type default)
		)
		(layer "In13.Cu")
	)
	(gr_arc
		(start 373.784622 -273.735038)
		(mid 373.788674 -273.73785)
		(end 373.79275 -273.740626)
		(stroke
			(width 0.05715)
			(type default)
		)
		(layer "In13.Cu")
	)
	(gr_arc
		(start 373.784876 -283.45511)
		(mid 373.788801 -283.457921)
		(end 373.79275 -283.460698)
		(stroke
			(width 0.05715)
			(type default)
		)
		(layer "In13.Cu")
	)
	(gr_arc
		(start 373.784876 -280.215086)
		(mid 373.788801 -280.217897)
		(end 373.79275 -280.220674)
		(stroke
			(width 0.05715)
			(type default)
		)
		(layer "In13.Cu")
	)
	(gr_arc
		(start 373.784876 -278.595074)
		(mid 373.788801 -278.597885)
		(end 373.79275 -278.600662)
		(stroke
			(width 0.05715)
			(type default)
		)
		(layer "In13.Cu")
	)
	(gr_arc
		(start 373.784876 -276.975062)
		(mid 373.788801 -276.977873)
		(end 373.79275 -276.98065)
		(stroke
			(width 0.05715)
			(type default)
		)
		(layer "In13.Cu")
	)
	(gr_arc
		(start 373.784876 -275.35505)
		(mid 373.788801 -275.357861)
		(end 373.79275 -275.360638)
		(stroke
			(width 0.05715)
			(type default)
		)
		(layer "In13.Cu")
	)
	(gr_line
		(start 373.785892 -296.583862)
		(end 373.785892 -296.61231)
		(stroke
			(width 0.05715)
			(type default)
		)
		(layer "In13.Cu")
	)
	(gr_arc
		(start 373.789194 -288.318194)
		(mid 373.79097 -288.319467)
		(end 373.79275 -288.320734)
		(stroke
			(width 0.05715)
			(type default)
		)
		(layer "In13.Cu")
	)
	(gr_line
		(start 373.79275 -288.320734)
		(end 373.798846 -288.32429)
		(stroke
			(width 0.05715)
			(type default)
		)
		(layer "In13.Cu")
	)
	(gr_line
		(start 373.79275 -283.460698)
		(end 373.799608 -283.464762)
		(stroke
			(width 0.05715)
			(type default)
		)
		(layer "In13.Cu")
	)
	(gr_arc
		(start 373.79275 -280.911554)
		(mid 373.788801 -280.914331)
		(end 373.784876 -280.917142)
		(stroke
			(width 0.05715)
			(type default)
		)
		(layer "In13.Cu")
	)
	(gr_line
		(start 373.79275 -280.220674)
		(end 373.795544 -280.222706)
		(stroke
			(width 0.05715)
			(type default)
		)
		(layer "In13.Cu")
	)
	(gr_line
		(start 373.79275 -278.600662)
		(end 373.799608 -278.604726)
		(stroke
			(width 0.05715)
			(type default)
		)
		(layer "In13.Cu")
	)
	(gr_line
		(start 373.79275 -276.98065)
		(end 373.799608 -276.984714)
		(stroke
			(width 0.05715)
			(type default)
		)
		(layer "In13.Cu")
	)
	(gr_line
		(start 373.79275 -275.360638)
		(end 373.799608 -275.364702)
		(stroke
			(width 0.05715)
			(type default)
		)
		(layer "In13.Cu")
	)
	(gr_line
		(start 373.79275 -273.740626)
		(end 373.799608 -273.74469)
		(stroke
			(width 0.05715)
			(type default)
		)
		(layer "In13.Cu")
	)
	(gr_line
		(start 373.79402 -384.894328)
		(end 374.49506 -384.894328)
		(stroke
			(width 0.07112)
			(type default)
		)
		(layer "In13.Cu")
	)
	(gr_line
		(start 373.79529 -384.611118)
		(end 373.93118 -384.475228)
		(stroke
			(width 0.07112)
			(type default)
		)
		(layer "In13.Cu")
	)
	(gr_line
		(start 373.795544 -280.909522)
		(end 373.79275 -280.911554)
		(stroke
			(width 0.05715)
			(type default)
		)
		(layer "In13.Cu")
	)
	(gr_line
		(start 373.795544 -280.222706)
		(end 373.800878 -280.225754)
		(stroke
			(width 0.05715)
			(type default)
		)
		(layer "In13.Cu")
	)
	(gr_line
		(start 373.798846 -288.32429)
		(end 373.7991 -288.32429)
		(stroke
			(width 0.05715)
			(type default)
		)
		(layer "In13.Cu")
	)
	(gr_line
		(start 373.799608 -283.464762)
		(end 373.80037 -283.46527)
		(stroke
			(width 0.05715)
			(type default)
		)
		(layer "In13.Cu")
	)
	(gr_line
		(start 373.799608 -278.604726)
		(end 373.80037 -278.605234)
		(stroke
			(width 0.05715)
			(type default)
		)
		(layer "In13.Cu")
	)
	(gr_line
		(start 373.799608 -276.984714)
		(end 373.80037 -276.985222)
		(stroke
			(width 0.05715)
			(type default)
		)
		(layer "In13.Cu")
	)
	(gr_line
		(start 373.799608 -275.364702)
		(end 373.80037 -275.36521)
		(stroke
			(width 0.05715)
			(type default)
		)
		(layer "In13.Cu")
	)
	(gr_line
		(start 373.799608 -273.74469)
		(end 373.80037 -273.745198)
		(stroke
			(width 0.05715)
			(type default)
		)
		(layer "In13.Cu")
	)
	(gr_line
		(start 373.80037 -283.46527)
		(end 373.801132 -283.465778)
		(stroke
			(width 0.05715)
			(type default)
		)
		(layer "In13.Cu")
	)
	(gr_line
		(start 373.80037 -278.605234)
		(end 373.801132 -278.605742)
		(stroke
			(width 0.05715)
			(type default)
		)
		(layer "In13.Cu")
	)
	(gr_line
		(start 373.80037 -276.985222)
		(end 373.801132 -276.98573)
		(stroke
			(width 0.05715)
			(type default)
		)
		(layer "In13.Cu")
	)
	(gr_line
		(start 373.80037 -275.36521)
		(end 373.801132 -275.365718)
		(stroke
			(width 0.05715)
			(type default)
		)
		(layer "In13.Cu")
	)
	(gr_line
		(start 373.80037 -273.745198)
		(end 373.801132 -273.745706)
		(stroke
			(width 0.05715)
			(type default)
		)
		(layer "In13.Cu")
	)
	(gr_line
		(start 373.800878 -280.906474)
		(end 373.795544 -280.909522)
		(stroke
			(width 0.05715)
			(type default)
		)
		(layer "In13.Cu")
	)
	(gr_line
		(start 373.81688 -273.27606)
		(end 373.747538 -273.345402)
		(stroke
			(width 0.05715)
			(type default)
		)
		(layer "In13.Cu")
	)
	(gr_line
		(start 373.81688 -271.656048)
		(end 373.747538 -271.72539)
		(stroke
			(width 0.05715)
			(type default)
		)
		(layer "In13.Cu")
	)
	(gr_line
		(start 373.81688 -270.036036)
		(end 373.734076 -270.11884)
		(stroke
			(width 0.05715)
			(type default)
		)
		(layer "In13.Cu")
	)
	(gr_line
		(start 373.820944 -279.275032)
		(end 373.817388 -279.277064)
		(stroke
			(width 0.05715)
			(type default)
		)
		(layer "In13.Cu")
	)
	(gr_line
		(start 373.820944 -277.65502)
		(end 373.817388 -277.657052)
		(stroke
			(width 0.05715)
			(type default)
		)
		(layer "In13.Cu")
	)
	(gr_line
		(start 373.820944 -276.035008)
		(end 373.817388 -276.03704)
		(stroke
			(width 0.05715)
			(type default)
		)
		(layer "In13.Cu")
	)
	(gr_line
		(start 373.820944 -274.414996)
		(end 373.817388 -274.417028)
		(stroke
			(width 0.05715)
			(type default)
		)
		(layer "In13.Cu")
	)
	(gr_line
		(start 373.8245 -293.8526)
		(end 373.821706 -293.854378)
		(stroke
			(width 0.05715)
			(type default)
		)
		(layer "In13.Cu")
	)
	(gr_line
		(start 373.8245 -290.612576)
		(end 373.821706 -290.614354)
		(stroke
			(width 0.05715)
			(type default)
		)
		(layer "In13.Cu")
	)
	(gr_line
		(start 373.8245 -288.992564)
		(end 373.821706 -288.994342)
		(stroke
			(width 0.05715)
			(type default)
		)
		(layer "In13.Cu")
	)
	(gr_line
		(start 373.8245 -285.752794)
		(end 373.821706 -285.754572)
		(stroke
			(width 0.05715)
			(type default)
		)
		(layer "In13.Cu")
	)
	(gr_line
		(start 373.8245 -284.132782)
		(end 373.821706 -284.13456)
		(stroke
			(width 0.05715)
			(type default)
		)
		(layer "In13.Cu")
	)
	(gr_line
		(start 373.8245 -282.51277)
		(end 373.821706 -282.514548)
		(stroke
			(width 0.05715)
			(type default)
		)
		(layer "In13.Cu")
	)
	(gr_line
		(start 373.825008 -279.272492)
		(end 373.822976 -279.273762)
		(stroke
			(width 0.05715)
			(type default)
		)
		(layer "In13.Cu")
	)
	(gr_line
		(start 373.825008 -277.65248)
		(end 373.822976 -277.65375)
		(stroke
			(width 0.05715)
			(type default)
		)
		(layer "In13.Cu")
	)
	(gr_line
		(start 373.825262 -293.852092)
		(end 373.8245 -293.8526)
		(stroke
			(width 0.05715)
			(type default)
		)
		(layer "In13.Cu")
	)
	(gr_line
		(start 373.825262 -290.612068)
		(end 373.8245 -290.612576)
		(stroke
			(width 0.05715)
			(type default)
		)
		(layer "In13.Cu")
	)
	(gr_line
		(start 373.825262 -288.992056)
		(end 373.8245 -288.992564)
		(stroke
			(width 0.05715)
			(type default)
		)
		(layer "In13.Cu")
	)
	(gr_line
		(start 373.825262 -285.752286)
		(end 373.8245 -285.752794)
		(stroke
			(width 0.05715)
			(type default)
		)
		(layer "In13.Cu")
	)
	(gr_line
		(start 373.825262 -284.132274)
		(end 373.8245 -284.132782)
		(stroke
			(width 0.05715)
			(type default)
		)
		(layer "In13.Cu")
	)
	(gr_line
		(start 373.825262 -282.512262)
		(end 373.8245 -282.51277)
		(stroke
			(width 0.05715)
			(type default)
		)
		(layer "In13.Cu")
	)
	(gr_line
		(start 373.82577 -293.200074)
		(end 373.826786 -293.200582)
		(stroke
			(width 0.05715)
			(type default)
		)
		(layer "In13.Cu")
	)
	(gr_line
		(start 373.826024 -294.820086)
		(end 373.827802 -294.821102)
		(stroke
			(width 0.05715)
			(type default)
		)
		(layer "In13.Cu")
	)
	(gr_line
		(start 373.826024 -291.580062)
		(end 373.826786 -291.58057)
		(stroke
			(width 0.05715)
			(type default)
		)
		(layer "In13.Cu")
	)
	(gr_line
		(start 373.826024 -289.96005)
		(end 373.826786 -289.960558)
		(stroke
			(width 0.05715)
			(type default)
		)
		(layer "In13.Cu")
	)
	(gr_line
		(start 373.826024 -285.100268)
		(end 373.826786 -285.100776)
		(stroke
			(width 0.05715)
			(type default)
		)
		(layer "In13.Cu")
	)
	(gr_line
		(start 373.826024 -281.860244)
		(end 373.826786 -281.860752)
		(stroke
			(width 0.05715)
			(type default)
		)
		(layer "In13.Cu")
	)
	(gr_line
		(start 373.827294 -293.850822)
		(end 373.825262 -293.852092)
		(stroke
			(width 0.05715)
			(type default)
		)
		(layer "In13.Cu")
	)
	(gr_line
		(start 373.827294 -290.610798)
		(end 373.825262 -290.612068)
		(stroke
			(width 0.05715)
			(type default)
		)
		(layer "In13.Cu")
	)
	(gr_line
		(start 373.827294 -288.990786)
		(end 373.825262 -288.992056)
		(stroke
			(width 0.05715)
			(type default)
		)
		(layer "In13.Cu")
	)
	(gr_line
		(start 373.827294 -285.751016)
		(end 373.825262 -285.752286)
		(stroke
			(width 0.05715)
			(type default)
		)
		(layer "In13.Cu")
	)
	(gr_line
		(start 373.827294 -284.131004)
		(end 373.825262 -284.132274)
		(stroke
			(width 0.05715)
			(type default)
		)
		(layer "In13.Cu")
	)
	(gr_line
		(start 373.827294 -282.510992)
		(end 373.825262 -282.512262)
		(stroke
			(width 0.05715)
			(type default)
		)
		(layer "In13.Cu")
	)
	(gr_line
		(start 373.831104 -293.203122)
		(end 373.831866 -293.203376)
		(stroke
			(width 0.05715)
			(type default)
		)
		(layer "In13.Cu")
	)
	(gr_line
		(start 373.831104 -291.58311)
		(end 373.831866 -291.583364)
		(stroke
			(width 0.05715)
			(type default)
		)
		(layer "In13.Cu")
	)
	(gr_line
		(start 373.831104 -289.963098)
		(end 373.831866 -289.963352)
		(stroke
			(width 0.05715)
			(type default)
		)
		(layer "In13.Cu")
	)
	(gr_line
		(start 373.831104 -285.103316)
		(end 373.831866 -285.10357)
		(stroke
			(width 0.05715)
			(type default)
		)
		(layer "In13.Cu")
	)
	(gr_line
		(start 373.831104 -281.863292)
		(end 373.831866 -281.863546)
		(stroke
			(width 0.05715)
			(type default)
		)
		(layer "In13.Cu")
	)
	(gr_line
		(start 373.831866 -291.583364)
		(end 373.832628 -291.583872)
		(stroke
			(width 0.05715)
			(type default)
		)
		(layer "In13.Cu")
	)
	(gr_line
		(start 373.83212 -278.623776)
		(end 373.832628 -278.62403)
		(stroke
			(width 0.05715)
			(type default)
		)
		(layer "In13.Cu")
	)
	(gr_line
		(start 373.83212 -277.003764)
		(end 373.832628 -277.004018)
		(stroke
			(width 0.05715)
			(type default)
		)
		(layer "In13.Cu")
	)
	(gr_line
		(start 373.832628 -278.62403)
		(end 373.835422 -278.625554)
		(stroke
			(width 0.05715)
			(type default)
		)
		(layer "In13.Cu")
	)
	(gr_line
		(start 373.832628 -277.004018)
		(end 373.835422 -277.005542)
		(stroke
			(width 0.05715)
			(type default)
		)
		(layer "In13.Cu")
	)
	(gr_line
		(start 373.83466 -293.205154)
		(end 373.835168 -293.205154)
		(stroke
			(width 0.05715)
			(type default)
		)
		(layer "In13.Cu")
	)
	(gr_line
		(start 373.83466 -289.96513)
		(end 373.835168 -289.96513)
		(stroke
			(width 0.05715)
			(type default)
		)
		(layer "In13.Cu")
	)
	(gr_line
		(start 373.83466 -285.105348)
		(end 373.835168 -285.105348)
		(stroke
			(width 0.05715)
			(type default)
		)
		(layer "In13.Cu")
	)
	(gr_line
		(start 373.83466 -283.485336)
		(end 373.835168 -283.485336)
		(stroke
			(width 0.05715)
			(type default)
		)
		(layer "In13.Cu")
	)
	(gr_line
		(start 373.83466 -281.865324)
		(end 373.835168 -281.865324)
		(stroke
			(width 0.05715)
			(type default)
		)
		(layer "In13.Cu")
	)
	(gr_line
		(start 373.834914 -288.345118)
		(end 373.835168 -288.345118)
		(stroke
			(width 0.05715)
			(type default)
		)
		(layer "In13.Cu")
	)
	(gr_line
		(start 373.850408 -272.154142)
		(end 373.851678 -272.154904)
		(stroke
			(width 0.05715)
			(type default)
		)
		(layer "In13.Cu")
	)
	(gr_line
		(start 373.878348 -292.424612)
		(end 373.877586 -292.42512)
		(stroke
			(width 0.05715)
			(type default)
		)
		(layer "In13.Cu")
	)
	(gr_line
		(start 373.908574 -293.027354)
		(end 373.909082 -293.027608)
		(stroke
			(width 0.05715)
			(type default)
		)
		(layer "In13.Cu")
	)
	(gr_line
		(start 373.910606 -422.023794)
		(end 373.736108 -422.096184)
		(stroke
			(width 0.07112)
			(type default)
		)
		(layer "In13.Cu")
	)
	(gr_line
		(start 373.916448 -292.399974)
		(end 373.91467 -292.40099)
		(stroke
			(width 0.05715)
			(type default)
		)
		(layer "In13.Cu")
	)
	(gr_line
		(start 373.917718 -292.399212)
		(end 373.917464 -292.399466)
		(stroke
			(width 0.05715)
			(type default)
		)
		(layer "In13.Cu")
	)
	(gr_line
		(start 373.921274 -294.017192)
		(end 373.918226 -294.018716)
		(stroke
			(width 0.05715)
			(type default)
		)
		(layer "In13.Cu")
	)
	(gr_line
		(start 373.921274 -290.777168)
		(end 373.918226 -290.778692)
		(stroke
			(width 0.05715)
			(type default)
		)
		(layer "In13.Cu")
	)
	(gr_line
		(start 373.921274 -289.157156)
		(end 373.918226 -289.15868)
		(stroke
			(width 0.05715)
			(type default)
		)
		(layer "In13.Cu")
	)
	(gr_line
		(start 373.921274 -285.917386)
		(end 373.918226 -285.91891)
		(stroke
			(width 0.05715)
			(type default)
		)
		(layer "In13.Cu")
	)
	(gr_line
		(start 373.921274 -284.297374)
		(end 373.918226 -284.298898)
		(stroke
			(width 0.05715)
			(type default)
		)
		(layer "In13.Cu")
	)
	(gr_line
		(start 373.921274 -282.677362)
		(end 373.918226 -282.678886)
		(stroke
			(width 0.05715)
			(type default)
		)
		(layer "In13.Cu")
	)
	(gr_line
		(start 373.921782 -292.396926)
		(end 373.920258 -292.397688)
		(stroke
			(width 0.05715)
			(type default)
		)
		(layer "In13.Cu")
	)
	(gr_line
		(start 373.923306 -279.436322)
		(end 373.922544 -279.43683)
		(stroke
			(width 0.05715)
			(type default)
		)
		(layer "In13.Cu")
	)
	(gr_line
		(start 373.923306 -277.81631)
		(end 373.922544 -277.816818)
		(stroke
			(width 0.05715)
			(type default)
		)
		(layer "In13.Cu")
	)
	(gr_line
		(start 373.923306 -276.196298)
		(end 373.922544 -276.196806)
		(stroke
			(width 0.05715)
			(type default)
		)
		(layer "In13.Cu")
	)
	(gr_line
		(start 373.923306 -274.576286)
		(end 373.922544 -274.576794)
		(stroke
			(width 0.05715)
			(type default)
		)
		(layer "In13.Cu")
	)
	(gr_line
		(start 373.924068 -293.036244)
		(end 373.927878 -293.03853)
		(stroke
			(width 0.05715)
			(type default)
		)
		(layer "In13.Cu")
	)
	(gr_line
		(start 373.926608 -294.014144)
		(end 373.924576 -294.01516)
		(stroke
			(width 0.05715)
			(type default)
		)
		(layer "In13.Cu")
	)
	(gr_line
		(start 373.926608 -290.77412)
		(end 373.924576 -290.775136)
		(stroke
			(width 0.05715)
			(type default)
		)
		(layer "In13.Cu")
	)
	(gr_line
		(start 373.926608 -289.154108)
		(end 373.924576 -289.155124)
		(stroke
			(width 0.05715)
			(type default)
		)
		(layer "In13.Cu")
	)
	(gr_line
		(start 373.926608 -285.914338)
		(end 373.924576 -285.915354)
		(stroke
			(width 0.05715)
			(type default)
		)
		(layer "In13.Cu")
	)
	(gr_line
		(start 373.926608 -284.294326)
		(end 373.924576 -284.295342)
		(stroke
			(width 0.05715)
			(type default)
		)
		(layer "In13.Cu")
	)
	(gr_line
		(start 373.926608 -282.674314)
		(end 373.924576 -282.67533)
		(stroke
			(width 0.05715)
			(type default)
		)
		(layer "In13.Cu")
	)
	(gr_line
		(start 373.927116 -279.434036)
		(end 373.923306 -279.436322)
		(stroke
			(width 0.05715)
			(type default)
		)
		(layer "In13.Cu")
	)
	(gr_line
		(start 373.927116 -277.814024)
		(end 373.923306 -277.81631)
		(stroke
			(width 0.05715)
			(type default)
		)
		(layer "In13.Cu")
	)
	(gr_line
		(start 373.927116 -276.194012)
		(end 373.923306 -276.196298)
		(stroke
			(width 0.05715)
			(type default)
		)
		(layer "In13.Cu")
	)
	(gr_line
		(start 373.927116 -274.574)
		(end 373.923306 -274.576286)
		(stroke
			(width 0.05715)
			(type default)
		)
		(layer "In13.Cu")
	)
	(gr_line
		(start 373.92737 -294.658288)
		(end 373.931434 -294.660574)
		(stroke
			(width 0.05715)
			(type default)
		)
		(layer "In13.Cu")
	)
	(gr_line
		(start 373.92737 -291.418264)
		(end 373.927878 -291.418518)
		(stroke
			(width 0.05715)
			(type default)
		)
		(layer "In13.Cu")
	)
	(gr_line
		(start 373.92737 -289.798252)
		(end 373.927878 -289.798506)
		(stroke
			(width 0.05715)
			(type default)
		)
		(layer "In13.Cu")
	)
	(gr_line
		(start 373.92737 -284.93847)
		(end 373.927878 -284.938724)
		(stroke
			(width 0.05715)
			(type default)
		)
		(layer "In13.Cu")
	)
	(gr_line
		(start 373.92737 -281.698446)
		(end 373.927878 -281.6987)
		(stroke
			(width 0.05715)
			(type default)
		)
		(layer "In13.Cu")
	)
	(gr_line
		(start 373.927624 -279.433782)
		(end 373.927116 -279.434036)
		(stroke
			(width 0.05715)
			(type default)
		)
		(layer "In13.Cu")
	)
	(gr_line
		(start 373.927624 -277.81377)
		(end 373.927116 -277.814024)
		(stroke
			(width 0.05715)
			(type default)
		)
		(layer "In13.Cu")
	)
	(gr_line
		(start 373.927624 -276.193758)
		(end 373.927116 -276.194012)
		(stroke
			(width 0.05715)
			(type default)
		)
		(layer "In13.Cu")
	)
	(gr_line
		(start 373.927624 -274.573746)
		(end 373.927116 -274.574)
		(stroke
			(width 0.05715)
			(type default)
		)
		(layer "In13.Cu")
	)
	(gr_line
		(start 373.927878 -293.03853)
		(end 373.930926 -293.040308)
		(stroke
			(width 0.05715)
			(type default)
		)
		(layer "In13.Cu")
	)
	(gr_line
		(start 373.927878 -291.418518)
		(end 373.927878 -291.418772)
		(stroke
			(width 0.05715)
			(type default)
		)
		(layer "In13.Cu")
	)
	(gr_line
		(start 373.927878 -289.798506)
		(end 373.930926 -289.800284)
		(stroke
			(width 0.05715)
			(type default)
		)
		(layer "In13.Cu")
	)
	(gr_line
		(start 373.927878 -284.938724)
		(end 373.930926 -284.940502)
		(stroke
			(width 0.05715)
			(type default)
		)
		(layer "In13.Cu")
	)
	(gr_line
		(start 373.927878 -283.318712)
		(end 373.930926 -283.32049)
		(stroke
			(width 0.05715)
			(type default)
		)
		(layer "In13.Cu")
	)
	(gr_line
		(start 373.927878 -281.6987)
		(end 373.930926 -281.700478)
		(stroke
			(width 0.05715)
			(type default)
		)
		(layer "In13.Cu")
	)
	(gr_line
		(start 373.928132 -292.39337)
		(end 373.924322 -292.395402)
		(stroke
			(width 0.05715)
			(type default)
		)
		(layer "In13.Cu")
	)
	(gr_line
		(start 373.930672 -294.011858)
		(end 373.92864 -294.012874)
		(stroke
			(width 0.05715)
			(type default)
		)
		(layer "In13.Cu")
	)
	(gr_line
		(start 373.930672 -290.771834)
		(end 373.92864 -290.77285)
		(stroke
			(width 0.05715)
			(type default)
		)
		(layer "In13.Cu")
	)
	(gr_line
		(start 373.930672 -289.151822)
		(end 373.92864 -289.152838)
		(stroke
			(width 0.05715)
			(type default)
		)
		(layer "In13.Cu")
	)
	(gr_line
		(start 373.930672 -285.912052)
		(end 373.92864 -285.913068)
		(stroke
			(width 0.05715)
			(type default)
		)
		(layer "In13.Cu")
	)
	(gr_line
		(start 373.930672 -284.29204)
		(end 373.92864 -284.293056)
		(stroke
			(width 0.05715)
			(type default)
		)
		(layer "In13.Cu")
	)
	(gr_line
		(start 373.930672 -282.672028)
		(end 373.92864 -282.673044)
		(stroke
			(width 0.05715)
			(type default)
		)
		(layer "In13.Cu")
	)
	(gr_line
		(start 373.93118 -384.475228)
		(end 374.3579 -384.475228)
		(stroke
			(width 0.07112)
			(type default)
		)
		(layer "In13.Cu")
	)
	(gr_line
		(start 374.058688 -405.710136)
		(end 374.194578 -405.574246)
		(stroke
			(width 0.07112)
			(type default)
		)
		(layer "In13.Cu")
	)
	(gr_line
		(start 374.058688 -404.582376)
		(end 374.194578 -404.446486)
		(stroke
			(width 0.07112)
			(type default)
		)
		(layer "In13.Cu")
	)
	(gr_line
		(start 374.058688 -403.454616)
		(end 374.194578 -403.318726)
		(stroke
			(width 0.07112)
			(type default)
		)
		(layer "In13.Cu")
	)
	(gr_line
		(start 374.060212 -409.218892)
		(end 373.86895 -409.200096)
		(stroke
			(width 0.07112)
			(type default)
		)
		(layer "In13.Cu")
	)
	(gr_line
		(start 374.094248 -409.920948)
		(end 373.64924 -409.378658)
		(stroke
			(width 0.07112)
			(type default)
		)
		(layer "In13.Cu")
	)
	(gr_line
		(start 374.114822 -273.27606)
		(end 373.81688 -273.27606)
		(stroke
			(width 0.05715)
			(type default)
		)
		(layer "In13.Cu")
	)
	(gr_line
		(start 374.114822 -271.656048)
		(end 373.81688 -271.656048)
		(stroke
			(width 0.05715)
			(type default)
		)
		(layer "In13.Cu")
	)
	(gr_line
		(start 374.114822 -270.036036)
		(end 373.81688 -270.036036)
		(stroke
			(width 0.05715)
			(type default)
		)
		(layer "In13.Cu")
	)
	(gr_line
		(start 374.194578 -405.574246)
		(end 374.194578 -405.147526)
		(stroke
			(width 0.07112)
			(type default)
		)
		(layer "In13.Cu")
	)
	(gr_line
		(start 374.194578 -405.147526)
		(end 374.058688 -405.011636)
		(stroke
			(width 0.07112)
			(type default)
		)
		(layer "In13.Cu")
	)
	(gr_line
		(start 374.194578 -404.446486)
		(end 374.194578 -404.019766)
		(stroke
			(width 0.07112)
			(type default)
		)
		(layer "In13.Cu")
	)
	(gr_line
		(start 374.194578 -404.019766)
		(end 374.058688 -403.883876)
		(stroke
			(width 0.07112)
			(type default)
		)
		(layer "In13.Cu")
	)
	(gr_line
		(start 374.194578 -403.318726)
		(end 374.194578 -402.892006)
		(stroke
			(width 0.07112)
			(type default)
		)
		(layer "In13.Cu")
	)
	(gr_line
		(start 374.194578 -402.892006)
		(end 374.058688 -402.756116)
		(stroke
			(width 0.07112)
			(type default)
		)
		(layer "In13.Cu")
	)
	(gr_line
		(start 374.248172 -417.796218)
		(end 374.248172 -417.095178)
		(stroke
			(width 0.07112)
			(type default)
		)
		(layer "In13.Cu")
	)
	(gr_line
		(start 374.248172 -416.579304)
		(end 374.248172 -415.878264)
		(stroke
			(width 0.07112)
			(type default)
		)
		(layer "In13.Cu")
	)
	(gr_line
		(start 374.270016 -422.623996)
		(end 373.626634 -422.357296)
		(stroke
			(width 0.07112)
			(type default)
		)
		(layer "In13.Cu")
	)
	(gr_arc
		(start 374.294146 -272.949162)
		(mid 374.295542 -272.949926)
		(end 374.29694 -272.950686)
		(stroke
			(width 0.05715)
			(type default)
		)
		(layer "In13.Cu")
	)
	(gr_line
		(start 374.298972 -272.951956)
		(end 374.301766 -272.95348)
		(stroke
			(width 0.05715)
			(type default)
		)
		(layer "In13.Cu")
	)
	(gr_line
		(start 374.303798 -295.63441)
		(end 374.304814 -295.634918)
		(stroke
			(width 0.05715)
			(type default)
		)
		(layer "In13.Cu")
	)
	(gr_line
		(start 374.305068 -422.18737)
		(end 373.910606 -422.023794)
		(stroke
			(width 0.07112)
			(type default)
		)
		(layer "In13.Cu")
	)
	(gr_line
		(start 374.312434 -409.740354)
		(end 374.33123 -409.549092)
		(stroke
			(width 0.07112)
			(type default)
		)
		(layer "In13.Cu")
	)
	(gr_line
		(start 374.33123 -409.549092)
		(end 374.060212 -409.218892)
		(stroke
			(width 0.07112)
			(type default)
		)
		(layer "In13.Cu")
	)
	(gr_line
		(start 374.3579 -384.475228)
		(end 374.49379 -384.611118)
		(stroke
			(width 0.07112)
			(type default)
		)
		(layer "In13.Cu")
	)
	(gr_line
		(start 374.37695 -401.089622)
		(end 374.389396 -401.089622)
		(stroke
			(width 0.07112)
			(type default)
		)
		(layer "In13.Cu")
	)
	(gr_line
		(start 374.377458 -422.362122)
		(end 374.305068 -422.18737)
		(stroke
			(width 0.07112)
			(type default)
		)
		(layer "In13.Cu")
	)
	(gr_line
		(start 374.37822 -401.372832)
		(end 374.516396 -401.511008)
		(stroke
			(width 0.07112)
			(type default)
		)
		(layer "In13.Cu")
	)
	(gr_line
		(start 374.389396 -401.089622)
		(end 374.516396 -400.962622)
		(stroke
			(width 0.07112)
			(type default)
		)
		(layer "In13.Cu")
	)
	(gr_line
		(start 374.39473 -272.78711)
		(end 374.397016 -272.78838)
		(stroke
			(width 0.05715)
			(type default)
		)
		(layer "In13.Cu")
	)
	(gr_line
		(start 374.444006 -296.583862)
		(end 374.444006 -296.61231)
		(stroke
			(width 0.05715)
			(type default)
		)
		(layer "In13.Cu")
	)
	(gr_line
		(start 374.489726 -296.538142)
		(end 374.444006 -296.583862)
		(stroke
			(width 0.05715)
			(type default)
		)
		(layer "In13.Cu")
	)
	(gr_line
		(start 374.516396 -401.511008)
		(end 374.516396 -401.674838)
		(stroke
			(width 0.07112)
			(type default)
		)
		(layer "In13.Cu")
	)
	(gr_line
		(start 374.516396 -400.962622)
		(end 374.516396 -400.811238)
		(stroke
			(width 0.07112)
			(type default)
		)
		(layer "In13.Cu")
	)
	(gr_line
		(start 374.531382 -417.794948)
		(end 374.667272 -417.659058)
		(stroke
			(width 0.07112)
			(type default)
		)
		(layer "In13.Cu")
	)
	(gr_line
		(start 374.531382 -416.578034)
		(end 374.667272 -416.442144)
		(stroke
			(width 0.07112)
			(type default)
		)
		(layer "In13.Cu")
	)
	(gr_line
		(start 374.552972 -407.415238)
		(end 374.360694 -407.415238)
		(stroke
			(width 0.07112)
			(type default)
		)
		(layer "In13.Cu")
	)
	(gr_line
		(start 374.655588 -408.11069)
		(end 374.159526 -407.614628)
		(stroke
			(width 0.07112)
			(type default)
		)
		(layer "In13.Cu")
	)
	(gr_line
		(start 374.667272 -417.659058)
		(end 374.667272 -417.232338)
		(stroke
			(width 0.07112)
			(type default)
		)
		(layer "In13.Cu")
	)
	(gr_line
		(start 374.667272 -417.232338)
		(end 374.531382 -417.096448)
		(stroke
			(width 0.07112)
			(type default)
		)
		(layer "In13.Cu")
	)
	(gr_line
		(start 374.667272 -416.442144)
		(end 374.667272 -416.015424)
		(stroke
			(width 0.07112)
			(type default)
		)
		(layer "In13.Cu")
	)
	(gr_line
		(start 374.667272 -416.015424)
		(end 374.531382 -415.879534)
		(stroke
			(width 0.07112)
			(type default)
		)
		(layer "In13.Cu")
	)
	(gr_line
		(start 374.680226 -296.538142)
		(end 374.725946 -296.583862)
		(stroke
			(width 0.05715)
			(type default)
		)
		(layer "In13.Cu")
	)
	(gr_arc
		(start 374.724676 -294.794686)
		(mid 374.728727 -294.797625)
		(end 374.732804 -294.800528)
		(stroke
			(width 0.05715)
			(type default)
		)
		(layer "In13.Cu")
	)
	(gr_line
		(start 374.725946 -296.583862)
		(end 374.725946 -296.61231)
		(stroke
			(width 0.05715)
			(type default)
		)
		(layer "In13.Cu")
	)
	(gr_line
		(start 374.732804 -294.800528)
		(end 374.733312 -294.800782)
		(stroke
			(width 0.05715)
			(type default)
		)
		(layer "In13.Cu")
	)
	(gr_line
		(start 374.733312 -294.800782)
		(end 374.739916 -294.804592)
		(stroke
			(width 0.05715)
			(type default)
		)
		(layer "In13.Cu")
	)
	(gr_line
		(start 374.771412 -293.203122)
		(end 374.77192 -293.203376)
		(stroke
			(width 0.05715)
			(type default)
		)
		(layer "In13.Cu")
	)
	(gr_line
		(start 374.771412 -291.58311)
		(end 374.77192 -291.583364)
		(stroke
			(width 0.05715)
			(type default)
		)
		(layer "In13.Cu")
	)
	(gr_line
		(start 374.771412 -289.963098)
		(end 374.77192 -289.963352)
		(stroke
			(width 0.05715)
			(type default)
		)
		(layer "In13.Cu")
	)
	(gr_line
		(start 374.771412 -285.103316)
		(end 374.77192 -285.10357)
		(stroke
			(width 0.05715)
			(type default)
		)
		(layer "In13.Cu")
	)
	(gr_line
		(start 374.771412 -283.483304)
		(end 374.77192 -283.483558)
		(stroke
			(width 0.05715)
			(type default)
		)
		(layer "In13.Cu")
	)
	(gr_line
		(start 374.771412 -281.863292)
		(end 374.77192 -281.863546)
		(stroke
			(width 0.05715)
			(type default)
		)
		(layer "In13.Cu")
	)
	(gr_line
		(start 374.771412 -280.24328)
		(end 374.77192 -280.243534)
		(stroke
			(width 0.05715)
			(type default)
		)
		(layer "In13.Cu")
	)
	(gr_line
		(start 374.771412 -278.623268)
		(end 374.77192 -278.623522)
		(stroke
			(width 0.05715)
			(type default)
		)
		(layer "In13.Cu")
	)
	(gr_line
		(start 374.771412 -277.003256)
		(end 374.77192 -277.00351)
		(stroke
			(width 0.05715)
			(type default)
		)
		(layer "In13.Cu")
	)
	(gr_line
		(start 374.771412 -275.383244)
		(end 374.77192 -275.383498)
		(stroke
			(width 0.05715)
			(type default)
		)
		(layer "In13.Cu")
	)
	(gr_line
		(start 374.771412 -273.763232)
		(end 374.77192 -273.763486)
		(stroke
			(width 0.05715)
			(type default)
		)
		(layer "In13.Cu")
	)
	(gr_line
		(start 374.77192 -293.848536)
		(end 374.771412 -293.84879)
		(stroke
			(width 0.05715)
			(type default)
		)
		(layer "In13.Cu")
	)
	(gr_line
		(start 374.77192 -293.203376)
		(end 374.772428 -293.20363)
		(stroke
			(width 0.05715)
			(type default)
		)
		(layer "In13.Cu")
	)
	(gr_line
		(start 374.77192 -292.228524)
		(end 374.771412 -292.228778)
		(stroke
			(width 0.05715)
			(type default)
		)
		(layer "In13.Cu")
	)
	(gr_line
		(start 374.77192 -291.583364)
		(end 374.772428 -291.583618)
		(stroke
			(width 0.05715)
			(type default)
		)
		(layer "In13.Cu")
	)
	(gr_line
		(start 374.77192 -290.608512)
		(end 374.771412 -290.608766)
		(stroke
			(width 0.05715)
			(type default)
		)
		(layer "In13.Cu")
	)
	(gr_line
		(start 374.77192 -289.963352)
		(end 374.772428 -289.963606)
		(stroke
			(width 0.05715)
			(type default)
		)
		(layer "In13.Cu")
	)
	(gr_line
		(start 374.77192 -288.9885)
		(end 374.771412 -288.988754)
		(stroke
			(width 0.05715)
			(type default)
		)
		(layer "In13.Cu")
	)
	(gr_line
		(start 374.77192 -288.343594)
		(end 374.772936 -288.344102)
		(stroke
			(width 0.05715)
			(type default)
		)
		(layer "In13.Cu")
	)
	(gr_line
		(start 374.77192 -286.723582)
		(end 374.772936 -286.72409)
		(stroke
			(width 0.05715)
			(type default)
		)
		(layer "In13.Cu")
	)
	(gr_line
		(start 374.77192 -285.74873)
		(end 374.770904 -285.749238)
		(stroke
			(width 0.05715)
			(type default)
		)
		(layer "In13.Cu")
	)
	(gr_line
		(start 374.77192 -285.10357)
		(end 374.772428 -285.103824)
		(stroke
			(width 0.05715)
			(type default)
		)
		(layer "In13.Cu")
	)
	(gr_line
		(start 374.77192 -284.128718)
		(end 374.771412 -284.128972)
		(stroke
			(width 0.05715)
			(type default)
		)
		(layer "In13.Cu")
	)
	(gr_line
		(start 374.77192 -283.483558)
		(end 374.772428 -283.483812)
		(stroke
			(width 0.05715)
			(type default)
		)
		(layer "In13.Cu")
	)
	(gr_line
		(start 374.77192 -282.508706)
		(end 374.771412 -282.50896)
		(stroke
			(width 0.05715)
			(type default)
		)
		(layer "In13.Cu")
	)
	(gr_line
		(start 374.77192 -281.863546)
		(end 374.772428 -281.8638)
		(stroke
			(width 0.05715)
			(type default)
		)
		(layer "In13.Cu")
	)
	(gr_line
		(start 374.77192 -280.888694)
		(end 374.771412 -280.888948)
		(stroke
			(width 0.05715)
			(type default)
		)
		(layer "In13.Cu")
	)
	(gr_line
		(start 374.77192 -280.243534)
		(end 374.772428 -280.243788)
		(stroke
			(width 0.05715)
			(type default)
		)
		(layer "In13.Cu")
	)
	(gr_line
		(start 374.77192 -279.268682)
		(end 374.771412 -279.268936)
		(stroke
			(width 0.05715)
			(type default)
		)
		(layer "In13.Cu")
	)
	(gr_line
		(start 374.77192 -278.623522)
		(end 374.772428 -278.623776)
		(stroke
			(width 0.05715)
			(type default)
		)
		(layer "In13.Cu")
	)
	(gr_line
		(start 374.77192 -277.64867)
		(end 374.771412 -277.648924)
		(stroke
			(width 0.05715)
			(type default)
		)
		(layer "In13.Cu")
	)
	(gr_line
		(start 374.77192 -277.00351)
		(end 374.772428 -277.003764)
		(stroke
			(width 0.05715)
			(type default)
		)
		(layer "In13.Cu")
	)
	(gr_line
		(start 374.77192 -276.028658)
		(end 374.771412 -276.028912)
		(stroke
			(width 0.05715)
			(type default)
		)
		(layer "In13.Cu")
	)
	(gr_line
		(start 374.77192 -275.383498)
		(end 374.772428 -275.383752)
		(stroke
			(width 0.05715)
			(type default)
		)
		(layer "In13.Cu")
	)
	(gr_line
		(start 374.77192 -274.408646)
		(end 374.771412 -274.4089)
		(stroke
			(width 0.05715)
			(type default)
		)
		(layer "In13.Cu")
	)
	(gr_line
		(start 374.77192 -273.763486)
		(end 374.772428 -273.76374)
		(stroke
			(width 0.05715)
			(type default)
		)
		(layer "In13.Cu")
	)
	(gr_line
		(start 374.772428 -293.848282)
		(end 374.77192 -293.848536)
		(stroke
			(width 0.05715)
			(type default)
		)
		(layer "In13.Cu")
	)
	(gr_line
		(start 374.772428 -292.22827)
		(end 374.77192 -292.228524)
		(stroke
			(width 0.05715)
			(type default)
		)
		(layer "In13.Cu")
	)
	(gr_line
		(start 374.772428 -290.608258)
		(end 374.77192 -290.608512)
		(stroke
			(width 0.05715)
			(type default)
		)
		(layer "In13.Cu")
	)
	(gr_line
		(start 374.772428 -288.988246)
		(end 374.77192 -288.9885)
		(stroke
			(width 0.05715)
			(type default)
		)
		(layer "In13.Cu")
	)
	(gr_line
		(start 374.772428 -285.748476)
		(end 374.77192 -285.74873)
		(stroke
			(width 0.05715)
			(type default)
		)
		(layer "In13.Cu")
	)
	(gr_line
		(start 374.772428 -284.128464)
		(end 374.77192 -284.128718)
		(stroke
			(width 0.05715)
			(type default)
		)
		(layer "In13.Cu")
	)
	(gr_line
		(start 374.772428 -282.508452)
		(end 374.77192 -282.508706)
		(stroke
			(width 0.05715)
			(type default)
		)
		(layer "In13.Cu")
	)
	(gr_line
		(start 374.772428 -280.88844)
		(end 374.77192 -280.888694)
		(stroke
			(width 0.05715)
			(type default)
		)
		(layer "In13.Cu")
	)
	(gr_line
		(start 374.772428 -279.268428)
		(end 374.77192 -279.268682)
		(stroke
			(width 0.05715)
			(type default)
		)
		(layer "In13.Cu")
	)
	(gr_line
		(start 374.772428 -277.648416)
		(end 374.77192 -277.64867)
		(stroke
			(width 0.05715)
			(type default)
		)
		(layer "In13.Cu")
	)
	(gr_line
		(start 374.772428 -276.028404)
		(end 374.77192 -276.028658)
		(stroke
			(width 0.05715)
			(type default)
		)
		(layer "In13.Cu")
	)
	(gr_line
		(start 374.772428 -274.408392)
		(end 374.77192 -274.408646)
		(stroke
			(width 0.05715)
			(type default)
		)
		(layer "In13.Cu")
	)
	(gr_line
		(start 374.854978 -407.909522)
		(end 374.854978 -407.717244)
		(stroke
			(width 0.07112)
			(type default)
		)
		(layer "In13.Cu")
	)
	(gr_line
		(start 374.854978 -407.717244)
		(end 374.552972 -407.415238)
		(stroke
			(width 0.07112)
			(type default)
		)
		(layer "In13.Cu")
	)
	(gr_line
		(start 374.92178 -384.894328)
		(end 375.62282 -384.894328)
		(stroke
			(width 0.07112)
			(type default)
		)
		(layer "In13.Cu")
	)
	(gr_line
		(start 374.92305 -384.611118)
		(end 375.05894 -384.475228)
		(stroke
			(width 0.07112)
			(type default)
		)
		(layer "In13.Cu")
	)
	(gr_line
		(start 374.975628 -405.680164)
		(end 374.975628 -404.979124)
		(stroke
			(width 0.07112)
			(type default)
		)
		(layer "In13.Cu")
	)
	(gr_line
		(start 374.975628 -404.552404)
		(end 374.975628 -403.851364)
		(stroke
			(width 0.07112)
			(type default)
		)
		(layer "In13.Cu")
	)
	(gr_line
		(start 374.975628 -403.424644)
		(end 374.975628 -402.723604)
		(stroke
			(width 0.07112)
			(type default)
		)
		(layer "In13.Cu")
	)
	(gr_line
		(start 375.034048 -410.405326)
		(end 374.842532 -410.38653)
		(stroke
			(width 0.07112)
			(type default)
		)
		(layer "In13.Cu")
	)
	(gr_line
		(start 375.05894 -384.475228)
		(end 375.48566 -384.475228)
		(stroke
			(width 0.07112)
			(type default)
		)
		(layer "In13.Cu")
	)
	(gr_line
		(start 375.068084 -411.107636)
		(end 374.623076 -410.565346)
		(stroke
			(width 0.07112)
			(type default)
		)
		(layer "In13.Cu")
	)
	(gr_line
		(start 375.258838 -405.678894)
		(end 375.394728 -405.543004)
		(stroke
			(width 0.07112)
			(type default)
		)
		(layer "In13.Cu")
	)
	(gr_line
		(start 375.258838 -404.551134)
		(end 375.394728 -404.415244)
		(stroke
			(width 0.07112)
			(type default)
		)
		(layer "In13.Cu")
	)
	(gr_line
		(start 375.258838 -403.423374)
		(end 375.394728 -403.287484)
		(stroke
			(width 0.07112)
			(type default)
		)
		(layer "In13.Cu")
	)
	(gr_line
		(start 375.28627 -410.927042)
		(end 375.305066 -410.735526)
		(stroke
			(width 0.07112)
			(type default)
		)
		(layer "In13.Cu")
	)
	(gr_line
		(start 375.305066 -410.735526)
		(end 375.034048 -410.405326)
		(stroke
			(width 0.07112)
			(type default)
		)
		(layer "In13.Cu")
	)
	(gr_line
		(start 375.350532 -408.212798)
		(end 375.158254 -408.212798)
		(stroke
			(width 0.07112)
			(type default)
		)
		(layer "In13.Cu")
	)
	(gr_line
		(start 375.394728 -405.543004)
		(end 375.394728 -405.116284)
		(stroke
			(width 0.07112)
			(type default)
		)
		(layer "In13.Cu")
	)
	(gr_line
		(start 375.394728 -405.116284)
		(end 375.258838 -404.980394)
		(stroke
			(width 0.07112)
			(type default)
		)
		(layer "In13.Cu")
	)
	(gr_line
		(start 375.394728 -404.415244)
		(end 375.394728 -403.988524)
		(stroke
			(width 0.07112)
			(type default)
		)
		(layer "In13.Cu")
	)
	(gr_line
		(start 375.394728 -403.988524)
		(end 375.258838 -403.852634)
		(stroke
			(width 0.07112)
			(type default)
		)
		(layer "In13.Cu")
	)
	(gr_line
		(start 375.394728 -403.287484)
		(end 375.394728 -402.860764)
		(stroke
			(width 0.07112)
			(type default)
		)
		(layer "In13.Cu")
	)
	(gr_line
		(start 375.394728 -402.860764)
		(end 375.258838 -402.724874)
		(stroke
			(width 0.07112)
			(type default)
		)
		(layer "In13.Cu")
	)
	(gr_line
		(start 375.4247 -296.583862)
		(end 375.4247 -296.61231)
		(stroke
			(width 0.05715)
			(type default)
		)
		(layer "In13.Cu")
	)
	(gr_line
		(start 375.453148 -408.90825)
		(end 374.957086 -408.412188)
		(stroke
			(width 0.07112)
			(type default)
		)
		(layer "In13.Cu")
	)
	(gr_line
		(start 375.47042 -296.538142)
		(end 375.4247 -296.583862)
		(stroke
			(width 0.05715)
			(type default)
		)
		(layer "In13.Cu")
	)
	(gr_line
		(start 375.48566 -384.475228)
		(end 375.62155 -384.611118)
		(stroke
			(width 0.07112)
			(type default)
		)
		(layer "In13.Cu")
	)
	(gr_line
		(start 375.5771 -401.089622)
		(end 375.589546 -401.089622)
		(stroke
			(width 0.07112)
			(type default)
		)
		(layer "In13.Cu")
	)
	(gr_line
		(start 375.57837 -401.372832)
		(end 375.716546 -401.511008)
		(stroke
			(width 0.07112)
			(type default)
		)
		(layer "In13.Cu")
	)
	(gr_line
		(start 375.589546 -401.089622)
		(end 375.716546 -400.962622)
		(stroke
			(width 0.07112)
			(type default)
		)
		(layer "In13.Cu")
	)
	(gr_line
		(start 375.652538 -408.707082)
		(end 375.652538 -408.514804)
		(stroke
			(width 0.07112)
			(type default)
		)
		(layer "In13.Cu")
	)
	(gr_line
		(start 375.652538 -408.514804)
		(end 375.350532 -408.212798)
		(stroke
			(width 0.07112)
			(type default)
		)
		(layer "In13.Cu")
	)
	(gr_line
		(start 375.66092 -296.538142)
		(end 375.70664 -296.583862)
		(stroke
			(width 0.05715)
			(type default)
		)
		(layer "In13.Cu")
	)
	(gr_line
		(start 375.70664 -296.583862)
		(end 375.70664 -296.61231)
		(stroke
			(width 0.05715)
			(type default)
		)
		(layer "In13.Cu")
	)
	(gr_line
		(start 375.716546 -401.511008)
		(end 375.716546 -401.674838)
		(stroke
			(width 0.07112)
			(type default)
		)
		(layer "In13.Cu")
	)
	(gr_line
		(start 375.716546 -400.962622)
		(end 375.716546 -400.811238)
		(stroke
			(width 0.07112)
			(type default)
		)
		(layer "In13.Cu")
	)
	(gr_line
		(start 375.753122 -407.0858)
		(end 375.560844 -407.0858)
		(stroke
			(width 0.07112)
			(type default)
		)
		(layer "In13.Cu")
	)
	(gr_line
		(start 375.855738 -407.781252)
		(end 375.359676 -407.28519)
		(stroke
			(width 0.07112)
			(type default)
		)
		(layer "In13.Cu")
	)
	(gr_line
		(start 376.047762 -422.82872)
		(end 375.869708 -422.90238)
		(stroke
			(width 0.07112)
			(type default)
		)
		(layer "In13.Cu")
	)
	(gr_line
		(start 376.04954 -384.894328)
		(end 376.75058 -384.894328)
		(stroke
			(width 0.07112)
			(type default)
		)
		(layer "In13.Cu")
	)
	(gr_line
		(start 376.05081 -384.611118)
		(end 376.1867 -384.475228)
		(stroke
			(width 0.07112)
			(type default)
		)
		(layer "In13.Cu")
	)
	(gr_line
		(start 376.055128 -407.580084)
		(end 376.055128 -407.387806)
		(stroke
			(width 0.07112)
			(type default)
		)
		(layer "In13.Cu")
	)
	(gr_line
		(start 376.055128 -407.387806)
		(end 375.753122 -407.0858)
		(stroke
			(width 0.07112)
			(type default)
		)
		(layer "In13.Cu")
	)
	(gr_line
		(start 376.148092 -409.010358)
		(end 375.955814 -409.010358)
		(stroke
			(width 0.07112)
			(type default)
		)
		(layer "In13.Cu")
	)
	(gr_line
		(start 376.175524 -405.071072)
		(end 376.175524 -404.370032)
		(stroke
			(width 0.07112)
			(type default)
		)
		(layer "In13.Cu")
	)
	(gr_line
		(start 376.175524 -403.869398)
		(end 376.175524 -403.168358)
		(stroke
			(width 0.07112)
			(type default)
		)
		(layer "In13.Cu")
	)
	(gr_line
		(start 376.1867 -384.475228)
		(end 376.61342 -384.475228)
		(stroke
			(width 0.07112)
			(type default)
		)
		(layer "In13.Cu")
	)
	(gr_line
		(start 376.250708 -409.70581)
		(end 375.754646 -409.209748)
		(stroke
			(width 0.07112)
			(type default)
		)
		(layer "In13.Cu")
	)
	(gr_line
		(start 376.408696 -423.432224)
		(end 375.760742 -423.163746)
		(stroke
			(width 0.07112)
			(type default)
		)
		(layer "In13.Cu")
	)
	(gr_line
		(start 376.442224 -422.992042)
		(end 376.047762 -422.82872)
		(stroke
			(width 0.07112)
			(type default)
		)
		(layer "In13.Cu")
	)
	(gr_line
		(start 376.450098 -409.504642)
		(end 376.450098 -409.312364)
		(stroke
			(width 0.07112)
			(type default)
		)
		(layer "In13.Cu")
	)
	(gr_line
		(start 376.450098 -409.312364)
		(end 376.148092 -409.010358)
		(stroke
			(width 0.07112)
			(type default)
		)
		(layer "In13.Cu")
	)
	(gr_line
		(start 376.458734 -405.069802)
		(end 376.594624 -404.933912)
		(stroke
			(width 0.07112)
			(type default)
		)
		(layer "In13.Cu")
	)
	(gr_line
		(start 376.458734 -403.868128)
		(end 376.594624 -403.732238)
		(stroke
			(width 0.07112)
			(type default)
		)
		(layer "In13.Cu")
	)
	(gr_line
		(start 376.515884 -423.170096)
		(end 376.442224 -422.992042)
		(stroke
			(width 0.07112)
			(type default)
		)
		(layer "In13.Cu")
	)
	(gr_line
		(start 376.550682 -407.88336)
		(end 376.358404 -407.88336)
		(stroke
			(width 0.07112)
			(type default)
		)
		(layer "In13.Cu")
	)
	(gr_line
		(start 376.594624 -404.933912)
		(end 376.594624 -404.507192)
		(stroke
			(width 0.07112)
			(type default)
		)
		(layer "In13.Cu")
	)
	(gr_line
		(start 376.594624 -404.507192)
		(end 376.458734 -404.371302)
		(stroke
			(width 0.07112)
			(type default)
		)
		(layer "In13.Cu")
	)
	(gr_line
		(start 376.594624 -403.732238)
		(end 376.594624 -403.305518)
		(stroke
			(width 0.07112)
			(type default)
		)
		(layer "In13.Cu")
	)
	(gr_line
		(start 376.594624 -403.305518)
		(end 376.458734 -403.169628)
		(stroke
			(width 0.07112)
			(type default)
		)
		(layer "In13.Cu")
	)
	(gr_line
		(start 376.61342 -384.475228)
		(end 376.74931 -384.611118)
		(stroke
			(width 0.07112)
			(type default)
		)
		(layer "In13.Cu")
	)
	(gr_line
		(start 376.653298 -408.578812)
		(end 376.157236 -408.08275)
		(stroke
			(width 0.07112)
			(type default)
		)
		(layer "In13.Cu")
	)
	(gr_line
		(start 376.776996 -401.089622)
		(end 376.789442 -401.089622)
		(stroke
			(width 0.07112)
			(type default)
		)
		(layer "In13.Cu")
	)
	(gr_line
		(start 376.778266 -401.372832)
		(end 376.916442 -401.511008)
		(stroke
			(width 0.07112)
			(type default)
		)
		(layer "In13.Cu")
	)
	(gr_line
		(start 376.789442 -401.089622)
		(end 376.916442 -400.962622)
		(stroke
			(width 0.07112)
			(type default)
		)
		(layer "In13.Cu")
	)
	(gr_line
		(start 376.852688 -408.377644)
		(end 376.852688 -408.185366)
		(stroke
			(width 0.07112)
			(type default)
		)
		(layer "In13.Cu")
	)
	(gr_line
		(start 376.852688 -408.185366)
		(end 376.550682 -407.88336)
		(stroke
			(width 0.07112)
			(type default)
		)
		(layer "In13.Cu")
	)
	(gr_line
		(start 376.916442 -401.511008)
		(end 376.916442 -401.674838)
		(stroke
			(width 0.07112)
			(type default)
		)
		(layer "In13.Cu")
	)
	(gr_line
		(start 376.916442 -400.962622)
		(end 376.916442 -400.811238)
		(stroke
			(width 0.07112)
			(type default)
		)
		(layer "In13.Cu")
	)
	(gr_line
		(start 376.945652 -409.807918)
		(end 376.753374 -409.807918)
		(stroke
			(width 0.07112)
			(type default)
		)
		(layer "In13.Cu")
	)
	(gr_line
		(start 376.953018 -406.655778)
		(end 376.76074 -406.655778)
		(stroke
			(width 0.07112)
			(type default)
		)
		(layer "In13.Cu")
	)
	(gr_line
		(start 377.048268 -410.50337)
		(end 376.552206 -410.007308)
		(stroke
			(width 0.07112)
			(type default)
		)
		(layer "In13.Cu")
	)
	(gr_line
		(start 377.055634 -407.35123)
		(end 376.559572 -406.855168)
		(stroke
			(width 0.07112)
			(type default)
		)
		(layer "In13.Cu")
	)
	(gr_line
		(start 377.247658 -410.302202)
		(end 377.247658 -410.109924)
		(stroke
			(width 0.07112)
			(type default)
		)
		(layer "In13.Cu")
	)
	(gr_line
		(start 377.247658 -410.109924)
		(end 376.945652 -409.807918)
		(stroke
			(width 0.07112)
			(type default)
		)
		(layer "In13.Cu")
	)
	(gr_line
		(start 377.255024 -407.150062)
		(end 377.255024 -406.957784)
		(stroke
			(width 0.07112)
			(type default)
		)
		(layer "In13.Cu")
	)
	(gr_line
		(start 377.255024 -406.957784)
		(end 376.953018 -406.655778)
		(stroke
			(width 0.07112)
			(type default)
		)
		(layer "In13.Cu")
	)
	(gr_line
		(start 377.311412 -417.967922)
		(end 377.311412 -417.266882)
		(stroke
			(width 0.07112)
			(type default)
		)
		(layer "In13.Cu")
	)
	(gr_line
		(start 377.311412 -416.840162)
		(end 377.311412 -416.139122)
		(stroke
			(width 0.07112)
			(type default)
		)
		(layer "In13.Cu")
	)
	(gr_line
		(start 377.348242 -408.68092)
		(end 377.155964 -408.68092)
		(stroke
			(width 0.07112)
			(type default)
		)
		(layer "In13.Cu")
	)
	(gr_line
		(start 377.375674 -404.708614)
		(end 377.375674 -404.007574)
		(stroke
			(width 0.07112)
			(type default)
		)
		(layer "In13.Cu")
	)
	(gr_line
		(start 377.375674 -403.580854)
		(end 377.375674 -402.879814)
		(stroke
			(width 0.07112)
			(type default)
		)
		(layer "In13.Cu")
	)
	(gr_line
		(start 377.450858 -409.376372)
		(end 376.954796 -408.88031)
		(stroke
			(width 0.07112)
			(type default)
		)
		(layer "In13.Cu")
	)
	(gr_line
		(start 377.594622 -417.966652)
		(end 377.730512 -417.830762)
		(stroke
			(width 0.07112)
			(type default)
		)
		(layer "In13.Cu")
	)
	(gr_line
		(start 377.594622 -416.838892)
		(end 377.730512 -416.703002)
		(stroke
			(width 0.07112)
			(type default)
		)
		(layer "In13.Cu")
	)
	(gr_line
		(start 377.650248 -409.175204)
		(end 377.650248 -408.982926)
		(stroke
			(width 0.07112)
			(type default)
		)
		(layer "In13.Cu")
	)
	(gr_line
		(start 377.650248 -408.982926)
		(end 377.348242 -408.68092)
		(stroke
			(width 0.07112)
			(type default)
		)
		(layer "In13.Cu")
	)
	(gr_line
		(start 377.658884 -404.707344)
		(end 377.794774 -404.571454)
		(stroke
			(width 0.07112)
			(type default)
		)
		(layer "In13.Cu")
	)
	(gr_line
		(start 377.658884 -403.579584)
		(end 377.794774 -403.443694)
		(stroke
			(width 0.07112)
			(type default)
		)
		(layer "In13.Cu")
	)
	(gr_line
		(start 377.730512 -417.830762)
		(end 377.730512 -417.404042)
		(stroke
			(width 0.07112)
			(type default)
		)
		(layer "In13.Cu")
	)
	(gr_line
		(start 377.730512 -417.404042)
		(end 377.594622 -417.268152)
		(stroke
			(width 0.07112)
			(type default)
		)
		(layer "In13.Cu")
	)
	(gr_line
		(start 377.730512 -416.703002)
		(end 377.730512 -416.276282)
		(stroke
			(width 0.07112)
			(type default)
		)
		(layer "In13.Cu")
	)
	(gr_line
		(start 377.730512 -416.276282)
		(end 377.594622 -416.140392)
		(stroke
			(width 0.07112)
			(type default)
		)
		(layer "In13.Cu")
	)
	(gr_line
		(start 377.750578 -407.453338)
		(end 377.5583 -407.453338)
		(stroke
			(width 0.07112)
			(type default)
		)
		(layer "In13.Cu")
	)
	(gr_line
		(start 377.794774 -404.571454)
		(end 377.794774 -404.144734)
		(stroke
			(width 0.07112)
			(type default)
		)
		(layer "In13.Cu")
	)
	(gr_line
		(start 377.794774 -404.144734)
		(end 377.658884 -404.008844)
		(stroke
			(width 0.07112)
			(type default)
		)
		(layer "In13.Cu")
	)
	(gr_line
		(start 377.794774 -403.443694)
		(end 377.794774 -403.016974)
		(stroke
			(width 0.07112)
			(type default)
		)
		(layer "In13.Cu")
	)
	(gr_line
		(start 377.794774 -403.016974)
		(end 377.658884 -402.881084)
		(stroke
			(width 0.07112)
			(type default)
		)
		(layer "In13.Cu")
	)
	(gr_line
		(start 377.853194 -408.14879)
		(end 377.357132 -407.652728)
		(stroke
			(width 0.07112)
			(type default)
		)
		(layer "In13.Cu")
	)
	(gr_line
		(start 377.977146 -401.089622)
		(end 377.989592 -401.089622)
		(stroke
			(width 0.07112)
			(type default)
		)
		(layer "In13.Cu")
	)
	(gr_line
		(start 377.978416 -401.372832)
		(end 378.116592 -401.511008)
		(stroke
			(width 0.07112)
			(type default)
		)
		(layer "In13.Cu")
	)
	(gr_line
		(start 377.989592 -401.089622)
		(end 378.116592 -400.962622)
		(stroke
			(width 0.07112)
			(type default)
		)
		(layer "In13.Cu")
	)
	(gr_line
		(start 378.052584 -407.947622)
		(end 378.052584 -407.755344)
		(stroke
			(width 0.07112)
			(type default)
		)
		(layer "In13.Cu")
	)
	(gr_line
		(start 378.052584 -407.755344)
		(end 377.750578 -407.453338)
		(stroke
			(width 0.07112)
			(type default)
		)
		(layer "In13.Cu")
	)
	(gr_line
		(start 378.116592 -401.511008)
		(end 378.116592 -401.674838)
		(stroke
			(width 0.07112)
			(type default)
		)
		(layer "In13.Cu")
	)
	(gr_line
		(start 378.116592 -400.962622)
		(end 378.116592 -400.811238)
		(stroke
			(width 0.07112)
			(type default)
		)
		(layer "In13.Cu")
	)
	(gr_line
		(start 378.153168 -406.161748)
		(end 377.96089 -406.161748)
		(stroke
			(width 0.07112)
			(type default)
		)
		(layer "In13.Cu")
	)
	(gr_line
		(start 378.191268 -409.523946)
		(end 377.99899 -409.523946)
		(stroke
			(width 0.07112)
			(type default)
		)
		(layer "In13.Cu")
	)
	(gr_line
		(start 378.255784 -406.8572)
		(end 377.759722 -406.361138)
		(stroke
			(width 0.07112)
			(type default)
		)
		(layer "In13.Cu")
	)
	(gr_line
		(start 378.293884 -410.219398)
		(end 377.797822 -409.723336)
		(stroke
			(width 0.07112)
			(type default)
		)
		(layer "In13.Cu")
	)
	(gr_line
		(start 378.455174 -406.656032)
		(end 378.455174 -406.463754)
		(stroke
			(width 0.07112)
			(type default)
		)
		(layer "In13.Cu")
	)
	(gr_line
		(start 378.455174 -406.463754)
		(end 378.153168 -406.161748)
		(stroke
			(width 0.07112)
			(type default)
		)
		(layer "In13.Cu")
	)
	(gr_line
		(start 378.493274 -410.01823)
		(end 378.493274 -409.825952)
		(stroke
			(width 0.07112)
			(type default)
		)
		(layer "In13.Cu")
	)
	(gr_line
		(start 378.493274 -409.825952)
		(end 378.191268 -409.523946)
		(stroke
			(width 0.07112)
			(type default)
		)
		(layer "In13.Cu")
	)
	(gr_line
		(start 378.548138 -408.250898)
		(end 378.35586 -408.250898)
		(stroke
			(width 0.07112)
			(type default)
		)
		(layer "In13.Cu")
	)
	(gr_line
		(start 378.57557 -404.661624)
		(end 378.57557 -403.960584)
		(stroke
			(width 0.07112)
			(type default)
		)
		(layer "In13.Cu")
	)
	(gr_line
		(start 378.57557 -403.533864)
		(end 378.57557 -402.832824)
		(stroke
			(width 0.07112)
			(type default)
		)
		(layer "In13.Cu")
	)
	(gr_line
		(start 378.62891 -422.74871)
		(end 378.459238 -422.839388)
		(stroke
			(width 0.07112)
			(type default)
		)
		(layer "In13.Cu")
	)
	(gr_line
		(start 378.650754 -408.94635)
		(end 378.154692 -408.450288)
		(stroke
			(width 0.07112)
			(type default)
		)
		(layer "In13.Cu")
	)
	(gr_line
		(start 378.850144 -408.745182)
		(end 378.850144 -408.552904)
		(stroke
			(width 0.07112)
			(type default)
		)
		(layer "In13.Cu")
	)
	(gr_line
		(start 378.850144 -408.552904)
		(end 378.548138 -408.250898)
		(stroke
			(width 0.07112)
			(type default)
		)
		(layer "In13.Cu")
	)
	(gr_line
		(start 378.85878 -404.660354)
		(end 378.99467 -404.524464)
		(stroke
			(width 0.07112)
			(type default)
		)
		(layer "In13.Cu")
	)
	(gr_line
		(start 378.85878 -403.532594)
		(end 378.99467 -403.396704)
		(stroke
			(width 0.07112)
			(type default)
		)
		(layer "In13.Cu")
	)
	(gr_line
		(start 378.950728 -406.959308)
		(end 378.75845 -406.959308)
		(stroke
			(width 0.07112)
			(type default)
		)
		(layer "In13.Cu")
	)
	(gr_line
		(start 378.988828 -410.321506)
		(end 378.79655 -410.321506)
		(stroke
			(width 0.07112)
			(type default)
		)
		(layer "In13.Cu")
	)
	(gr_line
		(start 378.99467 -404.524464)
		(end 378.99467 -404.097744)
		(stroke
			(width 0.07112)
			(type default)
		)
		(layer "In13.Cu")
	)
	(gr_line
		(start 378.99467 -404.097744)
		(end 378.85878 -403.961854)
		(stroke
			(width 0.07112)
			(type default)
		)
		(layer "In13.Cu")
	)
	(gr_line
		(start 378.99467 -403.396704)
		(end 378.99467 -402.969984)
		(stroke
			(width 0.07112)
			(type default)
		)
		(layer "In13.Cu")
	)
	(gr_line
		(start 378.99467 -402.969984)
		(end 378.85878 -402.834094)
		(stroke
			(width 0.07112)
			(type default)
		)
		(layer "In13.Cu")
	)
	(gr_line
		(start 379.037596 -422.872408)
		(end 378.62891 -422.74871)
		(stroke
			(width 0.07112)
			(type default)
		)
		(layer "In13.Cu")
	)
	(gr_line
		(start 379.047248 -423.313606)
		(end 378.37618 -423.110152)
		(stroke
			(width 0.07112)
			(type default)
		)
		(layer "In13.Cu")
	)
	(gr_line
		(start 379.053344 -407.65476)
		(end 378.557282 -407.158698)
		(stroke
			(width 0.07112)
			(type default)
		)
		(layer "In13.Cu")
	)
	(gr_line
		(start 379.091444 -411.016958)
		(end 378.595382 -410.520896)
		(stroke
			(width 0.07112)
			(type default)
		)
		(layer "In13.Cu")
	)
	(gr_line
		(start 379.128274 -423.042334)
		(end 379.037596 -422.872408)
		(stroke
			(width 0.07112)
			(type default)
		)
		(layer "In13.Cu")
	)
	(gr_line
		(start 379.177042 -401.089622)
		(end 379.189488 -401.089622)
		(stroke
			(width 0.07112)
			(type default)
		)
		(layer "In13.Cu")
	)
	(gr_line
		(start 379.178312 -401.372832)
		(end 379.316488 -401.511008)
		(stroke
			(width 0.07112)
			(type default)
		)
		(layer "In13.Cu")
	)
	(gr_line
		(start 379.189488 -401.089622)
		(end 379.316488 -400.962622)
		(stroke
			(width 0.07112)
			(type default)
		)
		(layer "In13.Cu")
	)
	(gr_line
		(start 379.252734 -407.453846)
		(end 379.252734 -407.261314)
		(stroke
			(width 0.07112)
			(type default)
		)
		(layer "In13.Cu")
	)
	(gr_line
		(start 379.252734 -407.261314)
		(end 378.950728 -406.959308)
		(stroke
			(width 0.07112)
			(type default)
		)
		(layer "In13.Cu")
	)
	(gr_line
		(start 379.290834 -410.81579)
		(end 379.290834 -410.623512)
		(stroke
			(width 0.07112)
			(type default)
		)
		(layer "In13.Cu")
	)
	(gr_line
		(start 379.290834 -410.623512)
		(end 378.988828 -410.321506)
		(stroke
			(width 0.07112)
			(type default)
		)
		(layer "In13.Cu")
	)
	(gr_line
		(start 379.316488 -401.511008)
		(end 379.316488 -401.674838)
		(stroke
			(width 0.07112)
			(type default)
		)
		(layer "In13.Cu")
	)
	(gr_line
		(start 379.316488 -400.962622)
		(end 379.316488 -400.811238)
		(stroke
			(width 0.07112)
			(type default)
		)
		(layer "In13.Cu")
	)
	(gr_line
		(start 379.345698 -409.048458)
		(end 379.15342 -409.048458)
		(stroke
			(width 0.07112)
			(type default)
		)
		(layer "In13.Cu")
	)
	(gr_line
		(start 379.353064 -405.77008)
		(end 379.160786 -405.77008)
		(stroke
			(width 0.07112)
			(type default)
		)
		(layer "In13.Cu")
	)
	(gr_line
		(start 379.448314 -409.74391)
		(end 378.952252 -409.247848)
		(stroke
			(width 0.07112)
			(type default)
		)
		(layer "In13.Cu")
	)
	(gr_line
		(start 379.45568 -406.465532)
		(end 378.959618 -405.96947)
		(stroke
			(width 0.07112)
			(type default)
		)
		(layer "In13.Cu")
	)
	(gr_line
		(start 379.647704 -409.542742)
		(end 379.647704 -409.350464)
		(stroke
			(width 0.07112)
			(type default)
		)
		(layer "In13.Cu")
	)
	(gr_line
		(start 379.647704 -409.350464)
		(end 379.345698 -409.048458)
		(stroke
			(width 0.07112)
			(type default)
		)
		(layer "In13.Cu")
	)
	(gr_line
		(start 379.65507 -406.264364)
		(end 379.65507 -406.072086)
		(stroke
			(width 0.07112)
			(type default)
		)
		(layer "In13.Cu")
	)
	(gr_line
		(start 379.65507 -406.072086)
		(end 379.353064 -405.77008)
		(stroke
			(width 0.07112)
			(type default)
		)
		(layer "In13.Cu")
	)
	(gr_line
		(start 379.748288 -407.756868)
		(end 379.555756 -407.756868)
		(stroke
			(width 0.07112)
			(type default)
		)
		(layer "In13.Cu")
	)
	(gr_line
		(start 379.77572 -404.681944)
		(end 379.77572 -403.980904)
		(stroke
			(width 0.07112)
			(type default)
		)
		(layer "In13.Cu")
	)
	(gr_line
		(start 379.77572 -403.554184)
		(end 379.77572 -402.853144)
		(stroke
			(width 0.07112)
			(type default)
		)
		(layer "In13.Cu")
	)
	(gr_line
		(start 379.850904 -408.45232)
		(end 379.354842 -407.956258)
		(stroke
			(width 0.07112)
			(type default)
		)
		(layer "In13.Cu")
	)
	(gr_line
		(start 380.050294 -408.251406)
		(end 380.050294 -408.058874)
		(stroke
			(width 0.07112)
			(type default)
		)
		(layer "In13.Cu")
	)
	(gr_line
		(start 380.050294 -408.058874)
		(end 379.748288 -407.756868)
		(stroke
			(width 0.07112)
			(type default)
		)
		(layer "In13.Cu")
	)
	(gr_line
		(start 380.05893 -404.680674)
		(end 380.19482 -404.544784)
		(stroke
			(width 0.07112)
			(type default)
		)
		(layer "In13.Cu")
	)
	(gr_line
		(start 380.05893 -403.552914)
		(end 380.19482 -403.417024)
		(stroke
			(width 0.07112)
			(type default)
		)
		(layer "In13.Cu")
	)
	(gr_line
		(start 380.150624 -406.56764)
		(end 379.958346 -406.56764)
		(stroke
			(width 0.07112)
			(type default)
		)
		(layer "In13.Cu")
	)
	(gr_line
		(start 380.19482 -404.544784)
		(end 380.19482 -404.118064)
		(stroke
			(width 0.07112)
			(type default)
		)
		(layer "In13.Cu")
	)
	(gr_line
		(start 380.19482 -404.118064)
		(end 380.05893 -403.982174)
		(stroke
			(width 0.07112)
			(type default)
		)
		(layer "In13.Cu")
	)
	(gr_line
		(start 380.19482 -403.417024)
		(end 380.19482 -402.990304)
		(stroke
			(width 0.07112)
			(type default)
		)
		(layer "In13.Cu")
	)
	(gr_line
		(start 380.19482 -402.990304)
		(end 380.05893 -402.854414)
		(stroke
			(width 0.07112)
			(type default)
		)
		(layer "In13.Cu")
	)
	(gr_line
		(start 380.25324 -407.263092)
		(end 379.757432 -406.767284)
		(stroke
			(width 0.07112)
			(type default)
		)
		(layer "In13.Cu")
	)
	(gr_line
		(start 380.374652 -417.909502)
		(end 380.374652 -417.208462)
		(stroke
			(width 0.07112)
			(type default)
		)
		(layer "In13.Cu")
	)
	(gr_line
		(start 380.374652 -416.781742)
		(end 380.374652 -416.080702)
		(stroke
			(width 0.07112)
			(type default)
		)
		(layer "In13.Cu")
	)
	(gr_line
		(start 380.377192 -401.089622)
		(end 380.389638 -401.089622)
		(stroke
			(width 0.07112)
			(type default)
		)
		(layer "In13.Cu")
	)
	(gr_line
		(start 380.378462 -401.372832)
		(end 380.516638 -401.511008)
		(stroke
			(width 0.07112)
			(type default)
		)
		(layer "In13.Cu")
	)
	(gr_line
		(start 380.389638 -401.089622)
		(end 380.516638 -400.962622)
		(stroke
			(width 0.07112)
			(type default)
		)
		(layer "In13.Cu")
	)
	(gr_line
		(start 380.45263 -407.061924)
		(end 380.45263 -406.869646)
		(stroke
			(width 0.07112)
			(type default)
		)
		(layer "In13.Cu")
	)
	(gr_line
		(start 380.45263 -406.869646)
		(end 380.150624 -406.56764)
		(stroke
			(width 0.07112)
			(type default)
		)
		(layer "In13.Cu")
	)
	(gr_line
		(start 380.516638 -401.511008)
		(end 380.516638 -401.674838)
		(stroke
			(width 0.07112)
			(type default)
		)
		(layer "In13.Cu")
	)
	(gr_line
		(start 380.516638 -400.962622)
		(end 380.516638 -400.811238)
		(stroke
			(width 0.07112)
			(type default)
		)
		(layer "In13.Cu")
	)
	(gr_line
		(start 380.553214 -405.410162)
		(end 380.360936 -405.410162)
		(stroke
			(width 0.07112)
			(type default)
		)
		(layer "In13.Cu")
	)
	(gr_line
		(start 380.625858 -408.634438)
		(end 380.433326 -408.634438)
		(stroke
			(width 0.07112)
			(type default)
		)
		(layer "In13.Cu")
	)
	(gr_line
		(start 380.64567 -409.24734)
		(end 380.232412 -408.833828)
		(stroke
			(width 0.07112)
			(type default)
		)
		(layer "In13.Cu")
	)
	(gr_line
		(start 380.64567 -409.24734)
		(end 380.645924 -409.24734)
		(stroke
			(width 0.07112)
			(type default)
		)
		(layer "In13.Cu")
	)
	(gr_line
		(start 380.65583 -406.105614)
		(end 380.159768 -405.609552)
		(stroke
			(width 0.07112)
			(type default)
		)
		(layer "In13.Cu")
	)
	(gr_line
		(start 380.657862 -417.908232)
		(end 380.793752 -417.772342)
		(stroke
			(width 0.07112)
			(type default)
		)
		(layer "In13.Cu")
	)
	(gr_line
		(start 380.657862 -416.780472)
		(end 380.793752 -416.644582)
		(stroke
			(width 0.07112)
			(type default)
		)
		(layer "In13.Cu")
	)
	(gr_line
		(start 380.728474 -409.32989)
		(end 380.645924 -409.24734)
		(stroke
			(width 0.07112)
			(type default)
		)
		(layer "In13.Cu")
	)
	(gr_line
		(start 380.745492 -422.299384)
		(end 380.57582 -422.390062)
		(stroke
			(width 0.07112)
			(type default)
		)
		(layer "In13.Cu")
	)
	(gr_line
		(start 380.793752 -417.772342)
		(end 380.793752 -417.345622)
		(stroke
			(width 0.07112)
			(type default)
		)
		(layer "In13.Cu")
	)
	(gr_line
		(start 380.793752 -417.345622)
		(end 380.657862 -417.209732)
		(stroke
			(width 0.07112)
			(type default)
		)
		(layer "In13.Cu")
	)
	(gr_line
		(start 380.793752 -416.644582)
		(end 380.793752 -416.217862)
		(stroke
			(width 0.07112)
			(type default)
		)
		(layer "In13.Cu")
	)
	(gr_line
		(start 380.793752 -416.217862)
		(end 380.657862 -416.081972)
		(stroke
			(width 0.07112)
			(type default)
		)
		(layer "In13.Cu")
	)
	(gr_line
		(start 380.85522 -405.904446)
		(end 380.85522 -405.712168)
		(stroke
			(width 0.07112)
			(type default)
		)
		(layer "In13.Cu")
	)
	(gr_line
		(start 380.85522 -405.712168)
		(end 380.553214 -405.410162)
		(stroke
			(width 0.07112)
			(type default)
		)
		(layer "In13.Cu")
	)
	(gr_line
		(start 380.927864 -409.128722)
		(end 380.927864 -408.936444)
		(stroke
			(width 0.07112)
			(type default)
		)
		(layer "In13.Cu")
	)
	(gr_line
		(start 380.927864 -408.936444)
		(end 380.625858 -408.634438)
		(stroke
			(width 0.07112)
			(type default)
		)
		(layer "In13.Cu")
	)
	(gr_line
		(start 380.948184 -407.3652)
		(end 380.755906 -407.3652)
		(stroke
			(width 0.07112)
			(type default)
		)
		(layer "In13.Cu")
	)
	(gr_line
		(start 380.975616 -404.236428)
		(end 380.975616 -403.535388)
		(stroke
			(width 0.07112)
			(type default)
		)
		(layer "In13.Cu")
	)
	(gr_line
		(start 381.0508 -408.060652)
		(end 380.554992 -407.564844)
		(stroke
			(width 0.07112)
			(type default)
		)
		(layer "In13.Cu")
	)
	(gr_line
		(start 381.154178 -422.423082)
		(end 380.745492 -422.299384)
		(stroke
			(width 0.07112)
			(type default)
		)
		(layer "In13.Cu")
	)
	(gr_line
		(start 381.164338 -422.864026)
		(end 380.492762 -422.66108)
		(stroke
			(width 0.07112)
			(type default)
		)
		(layer "In13.Cu")
	)
	(gr_line
		(start 381.170942 -422.866058)
		(end 381.164338 -422.864026)
		(stroke
			(width 0.07112)
			(type default)
		)
		(layer "In13.Cu")
	)
	(gr_line
		(start 381.24511 -422.592754)
		(end 381.154178 -422.423082)
		(stroke
			(width 0.07112)
			(type default)
		)
		(layer "In13.Cu")
	)
	(gr_line
		(start 381.25019 -407.859484)
		(end 381.25019 -407.667206)
		(stroke
			(width 0.07112)
			(type default)
		)
		(layer "In13.Cu")
	)
	(gr_line
		(start 381.25019 -407.667206)
		(end 380.948184 -407.3652)
		(stroke
			(width 0.07112)
			(type default)
		)
		(layer "In13.Cu")
	)
	(gr_line
		(start 381.252476 -422.59631)
		(end 381.245872 -422.594278)
		(stroke
			(width 0.07112)
			(type default)
		)
		(layer "In13.Cu")
	)
	(gr_line
		(start 381.258826 -404.235158)
		(end 381.394716 -404.099268)
		(stroke
			(width 0.07112)
			(type default)
		)
		(layer "In13.Cu")
	)
	(gr_line
		(start 381.350774 -406.207722)
		(end 381.158496 -406.207722)
		(stroke
			(width 0.07112)
			(type default)
		)
		(layer "In13.Cu")
	)
	(gr_line
		(start 381.394716 -404.099268)
		(end 381.394716 -403.672548)
		(stroke
			(width 0.07112)
			(type default)
		)
		(layer "In13.Cu")
	)
	(gr_line
		(start 381.394716 -403.672548)
		(end 381.258826 -403.536658)
		(stroke
			(width 0.07112)
			(type default)
		)
		(layer "In13.Cu")
	)
	(gr_line
		(start 381.45339 -406.903174)
		(end 380.957582 -406.407366)
		(stroke
			(width 0.07112)
			(type default)
		)
		(layer "In13.Cu")
	)
	(gr_line
		(start 381.56769 -401.393406)
		(end 381.589534 -401.393406)
		(stroke
			(width 0.07112)
			(type default)
		)
		(layer "In13.Cu")
	)
	(gr_line
		(start 381.56896 -401.110196)
		(end 381.716534 -400.962622)
		(stroke
			(width 0.07112)
			(type default)
		)
		(layer "In13.Cu")
	)
	(gr_line
		(start 381.589534 -401.393406)
		(end 381.716534 -401.520406)
		(stroke
			(width 0.07112)
			(type default)
		)
		(layer "In13.Cu")
	)
	(gr_line
		(start 381.65278 -406.702006)
		(end 381.65278 -406.509728)
		(stroke
			(width 0.07112)
			(type default)
		)
		(layer "In13.Cu")
	)
	(gr_line
		(start 381.65278 -406.509728)
		(end 381.350774 -406.207722)
		(stroke
			(width 0.07112)
			(type default)
		)
		(layer "In13.Cu")
	)
	(gr_line
		(start 381.716534 -401.520406)
		(end 381.716534 -401.674838)
		(stroke
			(width 0.07112)
			(type default)
		)
		(layer "In13.Cu")
	)
	(gr_line
		(start 381.716534 -400.962622)
		(end 381.716534 -400.811238)
		(stroke
			(width 0.07112)
			(type default)
		)
		(layer "In13.Cu")
	)
	(gr_line
		(start 381.749808 -434.48986)
		(end 381.749808 -434.157882)
		(stroke
			(width 0.07112)
			(type default)
		)
		(layer "In13.Cu")
	)
	(gr_line
		(start 381.749808 -434.157882)
		(end 381.622808 -434.030882)
		(stroke
			(width 0.07112)
			(type default)
		)
		(layer "In13.Cu")
	)
	(gr_line
		(start 381.749808 -433.621942)
		(end 381.622808 -433.748942)
		(stroke
			(width 0.07112)
			(type default)
		)
		(layer "In13.Cu")
	)
	(gr_line
		(start 381.749808 -433.289964)
		(end 381.749808 -433.621942)
		(stroke
			(width 0.07112)
			(type default)
		)
		(layer "In13.Cu")
	)
	(gr_line
		(start 381.75311 -404.964646)
		(end 381.560832 -404.964646)
		(stroke
			(width 0.07112)
			(type default)
		)
		(layer "In13.Cu")
	)
	(gr_line
		(start 381.855726 -405.660098)
		(end 381.359664 -405.164036)
		(stroke
			(width 0.07112)
			(type default)
		)
		(layer "In13.Cu")
	)
	(gr_line
		(start 381.895858 -374.233948)
		(end 381.895858 -374.041924)
		(stroke
			(width 0.07112)
			(type default)
		)
		(layer "In13.Cu")
	)
	(gr_line
		(start 381.895858 -374.041924)
		(end 382.197864 -373.739918)
		(stroke
			(width 0.07112)
			(type default)
		)
		(layer "In13.Cu")
	)
	(gr_line
		(start 382.055116 -405.459184)
		(end 382.055116 -405.266652)
		(stroke
			(width 0.07112)
			(type default)
		)
		(layer "In13.Cu")
	)
	(gr_line
		(start 382.055116 -405.266652)
		(end 381.75311 -404.964646)
		(stroke
			(width 0.07112)
			(type default)
		)
		(layer "In13.Cu")
	)
	(gr_line
		(start 382.095248 -374.435116)
		(end 382.591056 -373.939308)
		(stroke
			(width 0.07112)
			(type default)
		)
		(layer "In13.Cu")
	)
	(gr_line
		(start 382.148334 -407.005282)
		(end 381.956056 -407.005282)
		(stroke
			(width 0.07112)
			(type default)
		)
		(layer "In13.Cu")
	)
	(gr_line
		(start 382.168146 -407.61793)
		(end 381.755142 -407.204926)
		(stroke
			(width 0.07112)
			(type default)
		)
		(layer "In13.Cu")
	)
	(gr_line
		(start 382.1684 -407.61793)
		(end 382.168146 -407.61793)
		(stroke
			(width 0.07112)
			(type default)
		)
		(layer "In13.Cu")
	)
	(gr_line
		(start 382.175766 -403.721062)
		(end 382.175766 -403.020022)
		(stroke
			(width 0.07112)
			(type default)
		)
		(layer "In13.Cu")
	)
	(gr_line
		(start 382.197864 -373.739918)
		(end 382.389888 -373.739918)
		(stroke
			(width 0.07112)
			(type default)
		)
		(layer "In13.Cu")
	)
	(gr_line
		(start 382.25095 -407.70048)
		(end 382.1684 -407.61793)
		(stroke
			(width 0.07112)
			(type default)
		)
		(layer "In13.Cu")
	)
	(gr_line
		(start 382.45034 -407.499312)
		(end 382.45034 -407.307288)
		(stroke
			(width 0.07112)
			(type default)
		)
		(layer "In13.Cu")
	)
	(gr_line
		(start 382.45034 -407.307288)
		(end 382.148334 -407.005282)
		(stroke
			(width 0.07112)
			(type default)
		)
		(layer "In13.Cu")
	)
	(gr_line
		(start 382.458976 -403.719792)
		(end 382.594866 -403.583902)
		(stroke
			(width 0.07112)
			(type default)
		)
		(layer "In13.Cu")
	)
	(gr_line
		(start 382.55067 -405.762206)
		(end 382.358138 -405.762206)
		(stroke
			(width 0.07112)
			(type default)
		)
		(layer "In13.Cu")
	)
	(gr_line
		(start 382.570482 -406.375108)
		(end 382.157224 -405.961596)
		(stroke
			(width 0.07112)
			(type default)
		)
		(layer "In13.Cu")
	)
	(gr_line
		(start 382.570736 -406.375108)
		(end 382.570482 -406.375108)
		(stroke
			(width 0.07112)
			(type default)
		)
		(layer "In13.Cu")
	)
	(gr_line
		(start 382.594866 -403.583902)
		(end 382.594866 -403.157182)
		(stroke
			(width 0.07112)
			(type default)
		)
		(layer "In13.Cu")
	)
	(gr_line
		(start 382.594866 -403.157182)
		(end 382.458976 -403.021292)
		(stroke
			(width 0.07112)
			(type default)
		)
		(layer "In13.Cu")
	)
	(gr_line
		(start 382.653286 -406.457658)
		(end 382.570736 -406.375108)
		(stroke
			(width 0.07112)
			(type default)
		)
		(layer "In13.Cu")
	)
	(gr_line
		(start 382.693164 -373.436642)
		(end 382.693164 -373.244364)
		(stroke
			(width 0.07112)
			(type default)
		)
		(layer "In13.Cu")
	)
	(gr_line
		(start 382.693164 -373.244364)
		(end 382.99517 -372.942358)
		(stroke
			(width 0.07112)
			(type default)
		)
		(layer "In13.Cu")
	)
	(gr_line
		(start 382.777238 -401.089622)
		(end 382.789684 -401.089622)
		(stroke
			(width 0.07112)
			(type default)
		)
		(layer "In13.Cu")
	)
	(gr_line
		(start 382.778508 -401.372832)
		(end 382.916684 -401.511008)
		(stroke
			(width 0.07112)
			(type default)
		)
		(layer "In13.Cu")
	)
	(gr_line
		(start 382.789684 -401.089622)
		(end 382.916684 -400.962622)
		(stroke
			(width 0.07112)
			(type default)
		)
		(layer "In13.Cu")
	)
	(gr_line
		(start 382.852676 -406.25649)
		(end 382.852676 -406.064212)
		(stroke
			(width 0.07112)
			(type default)
		)
		(layer "In13.Cu")
	)
	(gr_line
		(start 382.852676 -406.064212)
		(end 382.55067 -405.762206)
		(stroke
			(width 0.07112)
			(type default)
		)
		(layer "In13.Cu")
	)
	(gr_line
		(start 382.892554 -373.63781)
		(end 383.388616 -373.141748)
		(stroke
			(width 0.07112)
			(type default)
		)
		(layer "In13.Cu")
	)
	(gr_line
		(start 382.916684 -401.511008)
		(end 382.916684 -401.674838)
		(stroke
			(width 0.07112)
			(type default)
		)
		(layer "In13.Cu")
	)
	(gr_line
		(start 382.916684 -400.962622)
		(end 382.916684 -400.811238)
		(stroke
			(width 0.07112)
			(type default)
		)
		(layer "In13.Cu")
	)
	(gr_line
		(start 382.99517 -372.942358)
		(end 383.187448 -372.942358)
		(stroke
			(width 0.07112)
			(type default)
		)
		(layer "In13.Cu")
	)
	(gr_line
		(start 383.34823 -406.559766)
		(end 383.155952 -406.559766)
		(stroke
			(width 0.07112)
			(type default)
		)
		(layer "In13.Cu")
	)
	(gr_line
		(start 383.375662 -403.582124)
		(end 383.375662 -402.881084)
		(stroke
			(width 0.07112)
			(type default)
		)
		(layer "In13.Cu")
	)
	(gr_line
		(start 383.437892 -417.296854)
		(end 383.437892 -416.595814)
		(stroke
			(width 0.07112)
			(type default)
		)
		(layer "In13.Cu")
	)
	(gr_line
		(start 383.450846 -407.255218)
		(end 382.954784 -406.759156)
		(stroke
			(width 0.07112)
			(type default)
		)
		(layer "In13.Cu")
	)
	(gr_line
		(start 383.494788 -372.635018)
		(end 383.494788 -372.442994)
		(stroke
			(width 0.07112)
			(type default)
		)
		(layer "In13.Cu")
	)
	(gr_line
		(start 383.494788 -372.442994)
		(end 383.796794 -372.140988)
		(stroke
			(width 0.07112)
			(type default)
		)
		(layer "In13.Cu")
	)
	(gr_line
		(start 383.595118 -434.74894)
		(end 383.58445 -434.74894)
		(stroke
			(width 0.07112)
			(type default)
		)
		(layer "In13.Cu")
	)
	(gr_line
		(start 383.650236 -407.05405)
		(end 383.650236 -406.861772)
		(stroke
			(width 0.07112)
			(type default)
		)
		(layer "In13.Cu")
	)
	(gr_line
		(start 383.650236 -406.861772)
		(end 383.34823 -406.559766)
		(stroke
			(width 0.07112)
			(type default)
		)
		(layer "In13.Cu")
	)
	(gr_line
		(start 383.658872 -403.580854)
		(end 383.794762 -403.444964)
		(stroke
			(width 0.07112)
			(type default)
		)
		(layer "In13.Cu")
	)
	(gr_line
		(start 383.694178 -372.836186)
		(end 384.189986 -372.340378)
		(stroke
			(width 0.07112)
			(type default)
		)
		(layer "In13.Cu")
	)
	(gr_line
		(start 383.721102 -417.295584)
		(end 383.856992 -417.159694)
		(stroke
			(width 0.07112)
			(type default)
		)
		(layer "In13.Cu")
	)
	(gr_line
		(start 383.749804 -435.489858)
		(end 383.749804 -435.196234)
		(stroke
			(width 0.07112)
			(type default)
		)
		(layer "In13.Cu")
	)
	(gr_line
		(start 383.749804 -435.196234)
		(end 383.58572 -435.03215)
		(stroke
			(width 0.07112)
			(type default)
		)
		(layer "In13.Cu")
	)
	(gr_line
		(start 383.749804 -434.594254)
		(end 383.595118 -434.74894)
		(stroke
			(width 0.07112)
			(type default)
		)
		(layer "In13.Cu")
	)
	(gr_line
		(start 383.749804 -434.289962)
		(end 383.749804 -434.594254)
		(stroke
			(width 0.07112)
			(type default)
		)
		(layer "In13.Cu")
	)
	(gr_line
		(start 383.794762 -403.444964)
		(end 383.794762 -403.018244)
		(stroke
			(width 0.07112)
			(type default)
		)
		(layer "In13.Cu")
	)
	(gr_line
		(start 383.794762 -403.018244)
		(end 383.658872 -402.882354)
		(stroke
			(width 0.07112)
			(type default)
		)
		(layer "In13.Cu")
	)
	(gr_line
		(start 383.796794 -372.140988)
		(end 383.988818 -372.140988)
		(stroke
			(width 0.07112)
			(type default)
		)
		(layer "In13.Cu")
	)
	(gr_line
		(start 383.856992 -417.159694)
		(end 383.856992 -416.732974)
		(stroke
			(width 0.07112)
			(type default)
		)
		(layer "In13.Cu")
	)
	(gr_line
		(start 383.856992 -416.732974)
		(end 383.721102 -416.597084)
		(stroke
			(width 0.07112)
			(type default)
		)
		(layer "In13.Cu")
	)
	(gr_line
		(start 383.977134 -401.089622)
		(end 383.98958 -401.089622)
		(stroke
			(width 0.07112)
			(type default)
		)
		(layer "In13.Cu")
	)
	(gr_line
		(start 383.978404 -401.372832)
		(end 384.11658 -401.511008)
		(stroke
			(width 0.07112)
			(type default)
		)
		(layer "In13.Cu")
	)
	(gr_line
		(start 383.98958 -401.089622)
		(end 384.11658 -400.962622)
		(stroke
			(width 0.07112)
			(type default)
		)
		(layer "In13.Cu")
	)
	(gr_line
		(start 384.11658 -401.511008)
		(end 384.11658 -401.674838)
		(stroke
			(width 0.07112)
			(type default)
		)
		(layer "In13.Cu")
	)
	(gr_line
		(start 384.11658 -400.962622)
		(end 384.11658 -400.811238)
		(stroke
			(width 0.07112)
			(type default)
		)
		(layer "In13.Cu")
	)
	(gr_line
		(start 384.567684 -406.35936)
		(end 384.567176 -406.358852)
		(stroke
			(width 0.07112)
			(type default)
		)
		(layer "In13.Cu")
	)
	(gr_line
		(start 384.575558 -403.33041)
		(end 384.575558 -402.682202)
		(stroke
			(width 0.07112)
			(type default)
		)
		(layer "In13.Cu")
	)
	(gr_line
		(start 384.607562 -422.914064)
		(end 384.423158 -422.96969)
		(stroke
			(width 0.07112)
			(type default)
		)
		(layer "In13.Cu")
	)
	(gr_line
		(start 384.858768 -403.32914)
		(end 384.968242 -403.219666)
		(stroke
			(width 0.07112)
			(type default)
		)
		(layer "In13.Cu")
	)
	(gr_line
		(start 384.907536 -423.549826)
		(end 384.288792 -423.219118)
		(stroke
			(width 0.07112)
			(type default)
		)
		(layer "In13.Cu")
	)
	(gr_line
		(start 384.968242 -403.219666)
		(end 384.968242 -402.792946)
		(stroke
			(width 0.07112)
			(type default)
		)
		(layer "In13.Cu")
	)
	(gr_line
		(start 384.968242 -402.792946)
		(end 384.858768 -402.683472)
		(stroke
			(width 0.07112)
			(type default)
		)
		(layer "In13.Cu")
	)
	(gr_line
		(start 384.984244 -423.115232)
		(end 384.607562 -422.914064)
		(stroke
			(width 0.07112)
			(type default)
		)
		(layer "In13.Cu")
	)
	(gr_line
		(start 385.040124 -423.299636)
		(end 384.984244 -423.115232)
		(stroke
			(width 0.07112)
			(type default)
		)
		(layer "In13.Cu")
	)
	(gr_line
		(start 385.17703 -401.089622)
		(end 385.189476 -401.089622)
		(stroke
			(width 0.07112)
			(type default)
		)
		(layer "In13.Cu")
	)
	(gr_line
		(start 385.1783 -401.372832)
		(end 385.316476 -401.511008)
		(stroke
			(width 0.07112)
			(type default)
		)
		(layer "In13.Cu")
	)
	(gr_line
		(start 385.189476 -401.089622)
		(end 385.316476 -400.962622)
		(stroke
			(width 0.07112)
			(type default)
		)
		(layer "In13.Cu")
	)
	(gr_line
		(start 385.316476 -401.511008)
		(end 385.316476 -401.674838)
		(stroke
			(width 0.07112)
			(type default)
		)
		(layer "In13.Cu")
	)
	(gr_line
		(start 385.316476 -400.962622)
		(end 385.316476 -400.811238)
		(stroke
			(width 0.07112)
			(type default)
		)
		(layer "In13.Cu")
	)
	(gr_arc
		(start 385.71932 -378.963936)
		(mid 385.719447 -378.963809)
		(end 385.719574 -378.963682)
		(stroke
			(width 0.07112)
			(type default)
		)
		(layer "In13.Cu")
	)
	(gr_line
		(start 385.7498 -434.48986)
		(end 385.7498 -434.157882)
		(stroke
			(width 0.07112)
			(type default)
		)
		(layer "In13.Cu")
	)
	(gr_line
		(start 385.7498 -434.157882)
		(end 385.6228 -434.030882)
		(stroke
			(width 0.07112)
			(type default)
		)
		(layer "In13.Cu")
	)
	(gr_line
		(start 385.7498 -433.621942)
		(end 385.6228 -433.748942)
		(stroke
			(width 0.07112)
			(type default)
		)
		(layer "In13.Cu")
	)
	(gr_line
		(start 385.7498 -433.289964)
		(end 385.7498 -433.621942)
		(stroke
			(width 0.07112)
			(type default)
		)
		(layer "In13.Cu")
	)
	(gr_line
		(start 386.389372 -401.371562)
		(end 386.516372 -401.498562)
		(stroke
			(width 0.07112)
			(type default)
		)
		(layer "In13.Cu")
	)
	(gr_line
		(start 386.389372 -401.089622)
		(end 386.516372 -400.962622)
		(stroke
			(width 0.07112)
			(type default)
		)
		(layer "In13.Cu")
	)
	(gr_line
		(start 386.501132 -418.175186)
		(end 386.501132 -417.474146)
		(stroke
			(width 0.07112)
			(type default)
		)
		(layer "In13.Cu")
	)
	(gr_line
		(start 386.501132 -417.047426)
		(end 386.501132 -416.346386)
		(stroke
			(width 0.07112)
			(type default)
		)
		(layer "In13.Cu")
	)
	(gr_line
		(start 386.516372 -401.498562)
		(end 386.516372 -401.674838)
		(stroke
			(width 0.07112)
			(type default)
		)
		(layer "In13.Cu")
	)
	(gr_line
		(start 386.516372 -400.962622)
		(end 386.516372 -400.811238)
		(stroke
			(width 0.07112)
			(type default)
		)
		(layer "In13.Cu")
	)
	(gr_line
		(start 386.536438 -422.602914)
		(end 386.350764 -422.639998)
		(stroke
			(width 0.07112)
			(type default)
		)
		(layer "In13.Cu")
	)
	(gr_line
		(start 386.694934 -385.902708)
		(end 386.694934 -385.475988)
		(stroke
			(width 0.07112)
			(type default)
		)
		(layer "In13.Cu")
	)
	(gr_line
		(start 386.694934 -385.475988)
		(end 386.830824 -385.340098)
		(stroke
			(width 0.07112)
			(type default)
		)
		(layer "In13.Cu")
	)
	(gr_line
		(start 386.694934 -384.774948)
		(end 386.694934 -384.348228)
		(stroke
			(width 0.07112)
			(type default)
		)
		(layer "In13.Cu")
	)
	(gr_line
		(start 386.694934 -384.348228)
		(end 386.78485 -384.258312)
		(stroke
			(width 0.07112)
			(type default)
		)
		(layer "In13.Cu")
	)
	(gr_line
		(start 386.77215 -423.26179)
		(end 386.19303 -422.875456)
		(stroke
			(width 0.07112)
			(type default)
		)
		(layer "In13.Cu")
	)
	(gr_line
		(start 386.784342 -418.173916)
		(end 386.920232 -418.038026)
		(stroke
			(width 0.07112)
			(type default)
		)
		(layer "In13.Cu")
	)
	(gr_line
		(start 386.784342 -417.046156)
		(end 386.920232 -416.910266)
		(stroke
			(width 0.07112)
			(type default)
		)
		(layer "In13.Cu")
	)
	(gr_arc
		(start 386.78485 -384.258312)
		(mid 386.815647 -384.215278)
		(end 386.830824 -384.164586)
		(stroke
			(width 0.07112)
			(type default)
		)
		(layer "In13.Cu")
	)
	(gr_line
		(start 386.830824 -386.038598)
		(end 386.694934 -385.902708)
		(stroke
			(width 0.07112)
			(type default)
		)
		(layer "In13.Cu")
	)
	(gr_line
		(start 386.830824 -384.910838)
		(end 386.694934 -384.774948)
		(stroke
			(width 0.07112)
			(type default)
		)
		(layer "In13.Cu")
	)
	(gr_line
		(start 386.891784 -422.839896)
		(end 386.536438 -422.602914)
		(stroke
			(width 0.07112)
			(type default)
		)
		(layer "In13.Cu")
	)
	(gr_line
		(start 386.920232 -418.038026)
		(end 386.920232 -417.611306)
		(stroke
			(width 0.07112)
			(type default)
		)
		(layer "In13.Cu")
	)
	(gr_line
		(start 386.920232 -417.611306)
		(end 386.784342 -417.475416)
		(stroke
			(width 0.07112)
			(type default)
		)
		(layer "In13.Cu")
	)
	(gr_line
		(start 386.920232 -416.910266)
		(end 386.920232 -416.483546)
		(stroke
			(width 0.07112)
			(type default)
		)
		(layer "In13.Cu")
	)
	(gr_line
		(start 386.920232 -416.483546)
		(end 386.784342 -416.347656)
		(stroke
			(width 0.07112)
			(type default)
		)
		(layer "In13.Cu")
	)
	(gr_line
		(start 386.929376 -423.026078)
		(end 386.891784 -422.839896)
		(stroke
			(width 0.07112)
			(type default)
		)
		(layer "In13.Cu")
	)
	(gr_line
		(start 387.114034 -386.039868)
		(end 387.114034 -385.338828)
		(stroke
			(width 0.07112)
			(type default)
		)
		(layer "In13.Cu")
	)
	(gr_line
		(start 387.114034 -384.912108)
		(end 387.114034 -384.177794)
		(stroke
			(width 0.07112)
			(type default)
		)
		(layer "In13.Cu")
	)
	(gr_line
		(start 387.577076 -401.089622)
		(end 387.589522 -401.089622)
		(stroke
			(width 0.07112)
			(type default)
		)
		(layer "In13.Cu")
	)
	(gr_line
		(start 387.578346 -401.372832)
		(end 387.716522 -401.511008)
		(stroke
			(width 0.07112)
			(type default)
		)
		(layer "In13.Cu")
	)
	(gr_line
		(start 387.589522 -401.089622)
		(end 387.716522 -400.962622)
		(stroke
			(width 0.07112)
			(type default)
		)
		(layer "In13.Cu")
	)
	(gr_line
		(start 387.60527 -423.313098)
		(end 387.415786 -423.35069)
		(stroke
			(width 0.07112)
			(type default)
		)
		(layer "In13.Cu")
	)
	(gr_line
		(start 387.716522 -401.511008)
		(end 387.716522 -401.674838)
		(stroke
			(width 0.07112)
			(type default)
		)
		(layer "In13.Cu")
	)
	(gr_line
		(start 387.716522 -400.962622)
		(end 387.716522 -400.811238)
		(stroke
			(width 0.07112)
			(type default)
		)
		(layer "In13.Cu")
	)
	(gr_line
		(start 387.749796 -435.489858)
		(end 387.749796 -435.15788)
		(stroke
			(width 0.07112)
			(type default)
		)
		(layer "In13.Cu")
	)
	(gr_line
		(start 387.749796 -435.15788)
		(end 387.622796 -435.03088)
		(stroke
			(width 0.07112)
			(type default)
		)
		(layer "In13.Cu")
	)
	(gr_line
		(start 387.749796 -434.62194)
		(end 387.622796 -434.74894)
		(stroke
			(width 0.07112)
			(type default)
		)
		(layer "In13.Cu")
	)
	(gr_line
		(start 387.749796 -434.289962)
		(end 387.749796 -434.62194)
		(stroke
			(width 0.07112)
			(type default)
		)
		(layer "In13.Cu")
	)
	(gr_line
		(start 387.84149 -423.975276)
		(end 387.258052 -423.585894)
		(stroke
			(width 0.07112)
			(type default)
		)
		(layer "In13.Cu")
	)
	(gr_line
		(start 387.960362 -423.550334)
		(end 387.60527 -423.313098)
		(stroke
			(width 0.07112)
			(type default)
		)
		(layer "In13.Cu")
	)
	(gr_line
		(start 387.997954 -423.73931)
		(end 387.960362 -423.550334)
		(stroke
			(width 0.07112)
			(type default)
		)
		(layer "In13.Cu")
	)
	(gr_line
		(start 388.524242 -403.786086)
		(end 388.52348 -403.785832)
		(stroke
			(width 0.07112)
			(type default)
		)
		(layer "In13.Cu")
	)
	(gr_line
		(start 388.776972 -401.089622)
		(end 388.789418 -401.089622)
		(stroke
			(width 0.07112)
			(type default)
		)
		(layer "In13.Cu")
	)
	(gr_line
		(start 388.778242 -401.372832)
		(end 388.916418 -401.511008)
		(stroke
			(width 0.07112)
			(type default)
		)
		(layer "In13.Cu")
	)
	(gr_line
		(start 388.789418 -401.089622)
		(end 388.916418 -400.962622)
		(stroke
			(width 0.07112)
			(type default)
		)
		(layer "In13.Cu")
	)
	(gr_line
		(start 388.847838 -411.21965)
		(end 388.848092 -411.21965)
		(stroke
			(width 0.07112)
			(type default)
		)
		(layer "In13.Cu")
	)
	(gr_line
		(start 388.916418 -401.511008)
		(end 388.916418 -401.674838)
		(stroke
			(width 0.07112)
			(type default)
		)
		(layer "In13.Cu")
	)
	(gr_line
		(start 388.916418 -400.962622)
		(end 388.916418 -400.811238)
		(stroke
			(width 0.07112)
			(type default)
		)
		(layer "In13.Cu")
	)
	(gr_line
		(start 389.134858 -410.884624)
		(end 388.957312 -410.958538)
		(stroke
			(width 0.07112)
			(type default)
		)
		(layer "In13.Cu")
	)
	(gr_line
		(start 389.398256 -423.258996)
		(end 388.980426 -422.695878)
		(stroke
			(width 0.07112)
			(type default)
		)
		(layer "In13.Cu")
	)
	(gr_line
		(start 389.398764 -422.556178)
		(end 389.208518 -422.527984)
		(stroke
			(width 0.07112)
			(type default)
		)
		(layer "In13.Cu")
	)
	(gr_line
		(start 389.454644 -374.602502)
		(end 389.454644 -374.175782)
		(stroke
			(width 0.07112)
			(type default)
		)
		(layer "In13.Cu")
	)
	(gr_line
		(start 389.454644 -374.175782)
		(end 389.590534 -374.039892)
		(stroke
			(width 0.07112)
			(type default)
		)
		(layer "In13.Cu")
	)
	(gr_line
		(start 389.495538 -411.48762)
		(end 388.847838 -411.21965)
		(stroke
			(width 0.07112)
			(type default)
		)
		(layer "In13.Cu")
	)
	(gr_line
		(start 389.529574 -411.047946)
		(end 389.134858 -410.884624)
		(stroke
			(width 0.07112)
			(type default)
		)
		(layer "In13.Cu")
	)
	(gr_line
		(start 389.564372 -417.7538)
		(end 389.564372 -417.05276)
		(stroke
			(width 0.07112)
			(type default)
		)
		(layer "In13.Cu")
	)
	(gr_line
		(start 389.564372 -416.62604)
		(end 389.564372 -415.925)
		(stroke
			(width 0.07112)
			(type default)
		)
		(layer "In13.Cu")
	)
	(gr_line
		(start 389.590534 -374.738392)
		(end 389.454644 -374.602502)
		(stroke
			(width 0.07112)
			(type default)
		)
		(layer "In13.Cu")
	)
	(gr_line
		(start 389.60298 -411.225746)
		(end 389.529574 -411.047946)
		(stroke
			(width 0.07112)
			(type default)
		)
		(layer "In13.Cu")
	)
	(gr_line
		(start 389.603742 -411.227016)
		(end 389.603742 -411.22727)
		(stroke
			(width 0.07112)
			(type default)
		)
		(layer "In13.Cu")
	)
	(gr_line
		(start 389.625078 -423.089578)
		(end 389.653272 -422.899078)
		(stroke
			(width 0.07112)
			(type default)
		)
		(layer "In13.Cu")
	)
	(gr_line
		(start 389.653272 -422.899078)
		(end 389.398764 -422.556178)
		(stroke
			(width 0.07112)
			(type default)
		)
		(layer "In13.Cu")
	)
	(gr_line
		(start 389.749792 -434.48986)
		(end 389.749792 -434.157882)
		(stroke
			(width 0.07112)
			(type default)
		)
		(layer "In13.Cu")
	)
	(gr_line
		(start 389.749792 -434.157882)
		(end 389.622792 -434.030882)
		(stroke
			(width 0.07112)
			(type default)
		)
		(layer "In13.Cu")
	)
	(gr_line
		(start 389.749792 -433.621942)
		(end 389.622792 -433.748942)
		(stroke
			(width 0.07112)
			(type default)
		)
		(layer "In13.Cu")
	)
	(gr_line
		(start 389.749792 -433.289964)
		(end 389.749792 -433.621942)
		(stroke
			(width 0.07112)
			(type default)
		)
		(layer "In13.Cu")
	)
	(gr_line
		(start 389.847582 -417.75253)
		(end 389.983472 -417.61664)
		(stroke
			(width 0.07112)
			(type default)
		)
		(layer "In13.Cu")
	)
	(gr_line
		(start 389.847582 -416.62477)
		(end 389.983472 -416.48888)
		(stroke
			(width 0.07112)
			(type default)
		)
		(layer "In13.Cu")
	)
	(gr_line
		(start 389.873744 -374.739662)
		(end 389.873744 -374.038622)
		(stroke
			(width 0.07112)
			(type default)
		)
		(layer "In13.Cu")
	)
	(gr_line
		(start 389.983472 -417.61664)
		(end 389.983472 -417.18992)
		(stroke
			(width 0.07112)
			(type default)
		)
		(layer "In13.Cu")
	)
	(gr_line
		(start 389.983472 -417.18992)
		(end 389.847582 -417.05403)
		(stroke
			(width 0.07112)
			(type default)
		)
		(layer "In13.Cu")
	)
	(gr_line
		(start 389.983472 -416.48888)
		(end 389.983472 -416.06216)
		(stroke
			(width 0.07112)
			(type default)
		)
		(layer "In13.Cu")
	)
	(gr_line
		(start 389.983472 -416.06216)
		(end 389.847582 -415.92627)
		(stroke
			(width 0.07112)
			(type default)
		)
		(layer "In13.Cu")
	)
	(gr_line
		(start 390.07034 -424.16476)
		(end 389.65251 -423.601642)
		(stroke
			(width 0.07112)
			(type default)
		)
		(layer "In13.Cu")
	)
	(gr_line
		(start 390.070848 -423.461942)
		(end 389.880348 -423.433748)
		(stroke
			(width 0.07112)
			(type default)
		)
		(layer "In13.Cu")
	)
	(gr_line
		(start 390.297162 -423.995342)
		(end 390.325356 -423.804842)
		(stroke
			(width 0.07112)
			(type default)
		)
		(layer "In13.Cu")
	)
	(gr_line
		(start 390.325356 -423.804842)
		(end 390.070848 -423.461942)
		(stroke
			(width 0.07112)
			(type default)
		)
		(layer "In13.Cu")
	)
	(gr_line
		(start 390.760204 -410.387292)
		(end 390.608566 -410.431742)
		(stroke
			(width 0.07112)
			(type default)
		)
		(layer "In13.Cu")
	)
	(gr_line
		(start 391.088626 -411.015434)
		(end 390.472422 -410.680154)
		(stroke
			(width 0.07112)
			(type default)
		)
		(layer "In13.Cu")
	)
	(gr_line
		(start 391.178288 -410.614622)
		(end 390.760204 -410.387292)
		(stroke
			(width 0.07112)
			(type default)
		)
		(layer "In13.Cu")
	)
	(gr_line
		(start 391.222992 -410.76626)
		(end 391.178288 -410.614622)
		(stroke
			(width 0.07112)
			(type default)
		)
		(layer "In13.Cu")
	)
	(gr_line
		(start 391.749788 -435.489858)
		(end 391.749788 -435.15788)
		(stroke
			(width 0.07112)
			(type default)
		)
		(layer "In13.Cu")
	)
	(gr_line
		(start 391.749788 -435.15788)
		(end 391.622788 -435.03088)
		(stroke
			(width 0.07112)
			(type default)
		)
		(layer "In13.Cu")
	)
	(gr_line
		(start 391.749788 -434.62194)
		(end 391.622788 -434.74894)
		(stroke
			(width 0.07112)
			(type default)
		)
		(layer "In13.Cu")
	)
	(gr_line
		(start 391.749788 -434.289962)
		(end 391.749788 -434.62194)
		(stroke
			(width 0.07112)
			(type default)
		)
		(layer "In13.Cu")
	)
	(gr_line
		(start 391.907014 -410.311854)
		(end 391.906506 -410.3116)
		(stroke
			(width 0.07112)
			(type default)
		)
		(layer "In13.Cu")
	)
	(gr_line
		(start 391.907522 -410.312108)
		(end 391.907522 -410.311854)
		(stroke
			(width 0.07112)
			(type default)
		)
		(layer "In13.Cu")
	)
	(gr_line
		(start 392.007852 -423.40276)
		(end 391.710164 -422.773348)
		(stroke
			(width 0.07112)
			(type default)
		)
		(layer "In13.Cu")
	)
	(gr_line
		(start 392.144504 -422.716706)
		(end 391.966704 -422.653206)
		(stroke
			(width 0.07112)
			(type default)
		)
		(layer "In13.Cu")
	)
	(gr_line
		(start 392.245342 -406.004014)
		(end 392.245088 -406.00376)
		(stroke
			(width 0.07112)
			(type default)
		)
		(layer "In13.Cu")
	)
	(gr_line
		(start 392.263376 -423.280586)
		(end 392.32713 -423.102786)
		(stroke
			(width 0.07112)
			(type default)
		)
		(layer "In13.Cu")
	)
	(gr_line
		(start 392.32713 -423.102786)
		(end 392.144504 -422.716706)
		(stroke
			(width 0.07112)
			(type default)
		)
		(layer "In13.Cu")
	)
	(gr_line
		(start 392.471148 -405.624792)
		(end 392.308334 -405.727916)
		(stroke
			(width 0.07112)
			(type default)
		)
		(layer "In13.Cu")
	)
	(gr_line
		(start 392.487912 -424.417744)
		(end 392.190224 -423.788332)
		(stroke
			(width 0.07112)
			(type default)
		)
		(layer "In13.Cu")
	)
	(gr_line
		(start 392.624818 -423.731944)
		(end 392.446764 -423.66819)
		(stroke
			(width 0.07112)
			(type default)
		)
		(layer "In13.Cu")
	)
	(gr_line
		(start 392.627612 -417.858702)
		(end 392.627612 -417.157662)
		(stroke
			(width 0.07112)
			(type default)
		)
		(layer "In13.Cu")
	)
	(gr_line
		(start 392.627612 -416.730942)
		(end 392.627612 -416.029902)
		(stroke
			(width 0.07112)
			(type default)
		)
		(layer "In13.Cu")
	)
	(gr_line
		(start 392.743436 -424.29557)
		(end 392.80719 -424.11777)
		(stroke
			(width 0.07112)
			(type default)
		)
		(layer "In13.Cu")
	)
	(gr_line
		(start 392.80719 -424.11777)
		(end 392.624818 -423.731944)
		(stroke
			(width 0.07112)
			(type default)
		)
		(layer "In13.Cu")
	)
	(gr_line
		(start 392.85672 -409.073096)
		(end 392.686286 -409.164028)
		(stroke
			(width 0.07112)
			(type default)
		)
		(layer "In13.Cu")
	)
	(gr_line
		(start 392.887708 -405.718518)
		(end 392.471148 -405.624792)
		(stroke
			(width 0.07112)
			(type default)
		)
		(layer "In13.Cu")
	)
	(gr_line
		(start 392.910822 -417.857432)
		(end 393.046712 -417.721542)
		(stroke
			(width 0.07112)
			(type default)
		)
		(layer "In13.Cu")
	)
	(gr_line
		(start 392.910822 -416.729672)
		(end 393.046712 -416.593782)
		(stroke
			(width 0.07112)
			(type default)
		)
		(layer "In13.Cu")
	)
	(gr_line
		(start 392.929618 -406.157684)
		(end 392.245342 -406.004014)
		(stroke
			(width 0.07112)
			(type default)
		)
		(layer "In13.Cu")
	)
	(gr_line
		(start 392.990324 -405.881078)
		(end 392.887708 -405.718518)
		(stroke
			(width 0.07112)
			(type default)
		)
		(layer "In13.Cu")
	)
	(gr_line
		(start 393.046712 -417.721542)
		(end 393.046712 -417.294822)
		(stroke
			(width 0.07112)
			(type default)
		)
		(layer "In13.Cu")
	)
	(gr_line
		(start 393.046712 -417.294822)
		(end 392.910822 -417.158932)
		(stroke
			(width 0.07112)
			(type default)
		)
		(layer "In13.Cu")
	)
	(gr_line
		(start 393.046712 -416.593782)
		(end 393.046712 -416.167062)
		(stroke
			(width 0.07112)
			(type default)
		)
		(layer "In13.Cu")
	)
	(gr_line
		(start 393.046712 -416.167062)
		(end 392.910822 -416.031172)
		(stroke
			(width 0.07112)
			(type default)
		)
		(layer "In13.Cu")
	)
	(gr_line
		(start 393.192254 -406.216612)
		(end 392.929618 -406.157684)
		(stroke
			(width 0.07112)
			(type default)
		)
		(layer "In13.Cu")
	)
	(gr_line
		(start 393.253976 -405.94153)
		(end 392.99134 -405.882602)
		(stroke
			(width 0.07112)
			(type default)
		)
		(layer "In13.Cu")
	)
	(gr_line
		(start 393.265152 -409.197048)
		(end 392.85672 -409.073096)
		(stroke
			(width 0.07112)
			(type default)
		)
		(layer "In13.Cu")
	)
	(gr_line
		(start 393.27455 -409.6385)
		(end 392.603482 -409.435046)
		(stroke
			(width 0.07112)
			(type default)
		)
		(layer "In13.Cu")
	)
	(gr_line
		(start 393.356084 -409.367228)
		(end 393.265152 -409.197048)
		(stroke
			(width 0.07112)
			(type default)
		)
		(layer "In13.Cu")
	)
	(gr_line
		(start 393.629388 -410.439108)
		(end 393.510516 -410.502608)
		(stroke
			(width 0.07112)
			(type default)
		)
		(layer "In13.Cu")
	)
	(gr_line
		(start 393.749784 -434.48986)
		(end 393.749784 -434.157882)
		(stroke
			(width 0.07112)
			(type default)
		)
		(layer "In13.Cu")
	)
	(gr_line
		(start 393.749784 -434.157882)
		(end 393.622784 -434.030882)
		(stroke
			(width 0.07112)
			(type default)
		)
		(layer "In13.Cu")
	)
	(gr_line
		(start 393.749784 -433.621942)
		(end 393.622784 -433.748942)
		(stroke
			(width 0.07112)
			(type default)
		)
		(layer "In13.Cu")
	)
	(gr_line
		(start 393.749784 -433.289964)
		(end 393.749784 -433.621942)
		(stroke
			(width 0.07112)
			(type default)
		)
		(layer "In13.Cu")
	)
	(gr_line
		(start 393.935966 -409.400502)
		(end 393.765532 -409.491434)
		(stroke
			(width 0.07112)
			(type default)
		)
		(layer "In13.Cu")
	)
	(gr_line
		(start 394.098272 -410.97708)
		(end 393.427204 -410.773372)
		(stroke
			(width 0.07112)
			(type default)
		)
		(layer "In13.Cu")
	)
	(gr_line
		(start 394.116052 -410.586936)
		(end 393.629388 -410.439108)
		(stroke
			(width 0.07112)
			(type default)
		)
		(layer "In13.Cu")
	)
	(gr_line
		(start 394.179552 -410.705808)
		(end 394.116052 -410.586936)
		(stroke
			(width 0.07112)
			(type default)
		)
		(layer "In13.Cu")
	)
	(gr_line
		(start 394.344398 -409.524454)
		(end 393.935966 -409.400502)
		(stroke
			(width 0.07112)
			(type default)
		)
		(layer "In13.Cu")
	)
	(gr_line
		(start 394.35405 -409.965906)
		(end 393.682728 -409.762452)
		(stroke
			(width 0.07112)
			(type default)
		)
		(layer "In13.Cu")
	)
	(gr_line
		(start 394.428218 -423.364406)
		(end 394.292582 -422.681908)
		(stroke
			(width 0.07112)
			(type default)
		)
		(layer "In13.Cu")
	)
	(gr_line
		(start 394.43533 -409.694634)
		(end 394.344398 -409.524454)
		(stroke
			(width 0.07112)
			(type default)
		)
		(layer "In13.Cu")
	)
	(gr_line
		(start 394.542772 -406.09012)
		(end 394.380212 -406.193244)
		(stroke
			(width 0.07112)
			(type default)
		)
		(layer "In13.Cu")
	)
	(gr_arc
		(start 394.56487 -404.89251)
		(mid 394.581413 -404.884172)
		(end 394.596874 -404.873968)
		(stroke
			(width 0.07112)
			(type default)
		)
		(layer "In13.Cu")
	)
	(gr_line
		(start 394.648182 -424.47083)
		(end 394.51153 -423.782744)
		(stroke
			(width 0.07112)
			(type default)
		)
		(layer "In13.Cu")
	)
	(gr_line
		(start 394.698982 -404.798276)
		(end 394.596874 -404.873968)
		(stroke
			(width 0.07112)
			(type default)
		)
		(layer "In13.Cu")
	)
	(gr_line
		(start 394.70584 -423.308272)
		(end 394.810742 -423.151046)
		(stroke
			(width 0.07112)
			(type default)
		)
		(layer "In13.Cu")
	)
	(gr_line
		(start 394.72235 -410.759656)
		(end 394.589762 -410.830268)
		(stroke
			(width 0.07112)
			(type default)
		)
		(layer "In13.Cu")
	)
	(gr_line
		(start 394.727684 -422.732454)
		(end 394.570712 -422.627806)
		(stroke
			(width 0.07112)
			(type default)
		)
		(layer "In13.Cu")
	)
	(gr_line
		(start 394.810742 -423.151046)
		(end 394.727684 -422.732454)
		(stroke
			(width 0.07112)
			(type default)
		)
		(layer "In13.Cu")
	)
	(gr_line
		(start 394.925804 -424.414696)
		(end 395.032992 -424.254422)
		(stroke
			(width 0.07112)
			(type default)
		)
		(layer "In13.Cu")
	)
	(gr_line
		(start 394.94968 -423.83583)
		(end 394.78966 -423.728896)
		(stroke
			(width 0.07112)
			(type default)
		)
		(layer "In13.Cu")
	)
	(gr_arc
		(start 394.952982 -405.185626)
		(mid 394.80638 -405.147669)
		(end 394.655548 -405.161242)
		(stroke
			(width 0.07112)
			(type default)
		)
		(layer "In13.Cu")
	)
	(gr_line
		(start 394.959332 -406.183592)
		(end 394.542772 -406.09012)
		(stroke
			(width 0.07112)
			(type default)
		)
		(layer "In13.Cu")
	)
	(gr_line
		(start 394.964412 -407.366724)
		(end 394.793724 -407.455624)
		(stroke
			(width 0.07112)
			(type default)
		)
		(layer "In13.Cu")
	)
	(gr_line
		(start 395.001496 -406.623012)
		(end 394.31722 -406.469342)
		(stroke
			(width 0.07112)
			(type default)
		)
		(layer "In13.Cu")
	)
	(gr_line
		(start 395.015212 -409.727908)
		(end 394.845032 -409.81884)
		(stroke
			(width 0.07112)
			(type default)
		)
		(layer "In13.Cu")
	)
	(gr_line
		(start 395.032992 -424.254422)
		(end 394.94968 -423.83583)
		(stroke
			(width 0.07112)
			(type default)
		)
		(layer "In13.Cu")
	)
	(gr_line
		(start 395.062456 -406.346406)
		(end 394.959332 -406.183592)
		(stroke
			(width 0.07112)
			(type default)
		)
		(layer "In13.Cu")
	)
	(gr_line
		(start 395.121384 -404.86076)
		(end 394.698982 -404.798276)
		(stroke
			(width 0.07112)
			(type default)
		)
		(layer "In13.Cu")
	)
	(gr_line
		(start 395.13764 -405.269446)
		(end 394.952982 -405.185626)
		(stroke
			(width 0.07112)
			(type default)
		)
		(layer "In13.Cu")
	)
	(gr_line
		(start 395.177772 -411.30474)
		(end 394.50645 -411.101032)
		(stroke
			(width 0.07112)
			(type default)
		)
		(layer "In13.Cu")
	)
	(gr_line
		(start 395.187932 -410.90088)
		(end 394.72235 -410.759656)
		(stroke
			(width 0.07112)
			(type default)
		)
		(layer "In13.Cu")
	)
	(gr_line
		(start 395.198092 -405.27859)
		(end 395.13764 -405.269446)
		(stroke
			(width 0.07112)
			(type default)
		)
		(layer "In13.Cu")
	)
	(gr_line
		(start 395.221206 -404.995634)
		(end 395.121384 -404.86076)
		(stroke
			(width 0.07112)
			(type default)
		)
		(layer "In13.Cu")
	)
	(gr_line
		(start 395.236954 -405.01697)
		(end 395.222222 -404.997158)
		(stroke
			(width 0.07112)
			(type default)
		)
		(layer "In13.Cu")
	)
	(gr_line
		(start 395.258798 -411.033468)
		(end 395.187932 -410.90088)
		(stroke
			(width 0.07112)
			(type default)
		)
		(layer "In13.Cu")
	)
	(gr_line
		(start 395.371574 -407.495248)
		(end 394.964412 -407.366724)
		(stroke
			(width 0.07112)
			(type default)
		)
		(layer "In13.Cu")
	)
	(gr_line
		(start 395.376146 -407.936446)
		(end 394.707618 -407.725372)
		(stroke
			(width 0.07112)
			(type default)
		)
		(layer "In13.Cu")
	)
	(gr_line
		(start 395.381226 -404.047198)
		(end 395.38148 -404.04669)
		(stroke
			(width 0.07112)
			(type default)
		)
		(layer "In13.Cu")
	)
	(gr_line
		(start 395.423644 -409.85186)
		(end 395.015212 -409.727908)
		(stroke
			(width 0.07112)
			(type default)
		)
		(layer "In13.Cu")
	)
	(gr_line
		(start 395.433296 -410.293312)
		(end 394.761974 -410.089604)
		(stroke
			(width 0.07112)
			(type default)
		)
		(layer "In13.Cu")
	)
	(gr_line
		(start 395.46022 -407.665936)
		(end 395.371574 -407.495248)
		(stroke
			(width 0.07112)
			(type default)
		)
		(layer "In13.Cu")
	)
	(gr_line
		(start 395.514576 -410.021786)
		(end 395.423644 -409.85186)
		(stroke
			(width 0.07112)
			(type default)
		)
		(layer "In13.Cu")
	)
	(gr_line
		(start 395.558772 -403.64283)
		(end 395.409674 -403.765512)
		(stroke
			(width 0.07112)
			(type default)
		)
		(layer "In13.Cu")
	)
	(gr_line
		(start 395.624812 -382.678178)
		(end 395.624812 -383.379218)
		(stroke
			(width 0.07112)
			(type default)
		)
		(layer "In13.Cu")
	)
	(gr_line
		(start 395.624812 -381.550418)
		(end 395.624812 -382.251458)
		(stroke
			(width 0.07112)
			(type default)
		)
		(layer "In13.Cu")
	)
	(gr_line
		(start 395.624812 -380.422658)
		(end 395.624812 -381.123698)
		(stroke
			(width 0.07112)
			(type default)
		)
		(layer "In13.Cu")
	)
	(gr_line
		(start 395.624812 -379.294898)
		(end 395.624812 -379.995938)
		(stroke
			(width 0.07112)
			(type default)
		)
		(layer "In13.Cu")
	)
	(gr_line
		(start 395.690852 -417.983416)
		(end 395.690852 -417.282376)
		(stroke
			(width 0.07112)
			(type default)
		)
		(layer "In13.Cu")
	)
	(gr_line
		(start 395.690852 -416.855656)
		(end 395.690852 -416.154616)
		(stroke
			(width 0.07112)
			(type default)
		)
		(layer "In13.Cu")
	)
	(gr_line
		(start 395.73454 -408.04973)
		(end 395.376146 -407.936446)
		(stroke
			(width 0.07112)
			(type default)
		)
		(layer "In13.Cu")
	)
	(gr_line
		(start 395.74978 -435.489858)
		(end 395.74978 -435.15788)
		(stroke
			(width 0.07112)
			(type default)
		)
		(layer "In13.Cu")
	)
	(gr_line
		(start 395.74978 -435.15788)
		(end 395.62278 -435.03088)
		(stroke
			(width 0.07112)
			(type default)
		)
		(layer "In13.Cu")
	)
	(gr_line
		(start 395.74978 -434.62194)
		(end 395.62278 -434.74894)
		(stroke
			(width 0.07112)
			(type default)
		)
		(layer "In13.Cu")
	)
	(gr_line
		(start 395.74978 -434.289962)
		(end 395.74978 -434.62194)
		(stroke
			(width 0.07112)
			(type default)
		)
		(layer "In13.Cu")
	)
	(gr_line
		(start 395.804136 -411.085792)
		(end 395.669008 -411.157928)
		(stroke
			(width 0.07112)
			(type default)
		)
		(layer "In13.Cu")
	)
	(gr_line
		(start 395.806676 -408.7495)
		(end 395.642846 -408.853386)
		(stroke
			(width 0.07112)
			(type default)
		)
		(layer "In13.Cu")
	)
	(gr_line
		(start 395.908022 -382.679448)
		(end 396.043912 -382.815338)
		(stroke
			(width 0.07112)
			(type default)
		)
		(layer "In13.Cu")
	)
	(gr_line
		(start 395.908022 -381.551688)
		(end 396.043912 -381.687578)
		(stroke
			(width 0.07112)
			(type default)
		)
		(layer "In13.Cu")
	)
	(gr_line
		(start 395.908022 -380.423928)
		(end 396.043912 -380.559818)
		(stroke
			(width 0.07112)
			(type default)
		)
		(layer "In13.Cu")
	)
	(gr_line
		(start 395.908022 -379.296168)
		(end 396.043912 -379.432058)
		(stroke
			(width 0.07112)
			(type default)
		)
		(layer "In13.Cu")
	)
	(gr_line
		(start 395.974062 -417.982146)
		(end 396.109952 -417.846256)
		(stroke
			(width 0.07112)
			(type default)
		)
		(layer "In13.Cu")
	)
	(gr_line
		(start 395.974062 -416.854386)
		(end 396.109952 -416.718496)
		(stroke
			(width 0.07112)
			(type default)
		)
		(layer "In13.Cu")
	)
	(gr_line
		(start 395.983714 -403.68474)
		(end 395.558772 -403.64283)
		(stroke
			(width 0.07112)
			(type default)
		)
		(layer "In13.Cu")
	)
	(gr_line
		(start 396.043912 -383.242058)
		(end 395.908022 -383.377948)
		(stroke
			(width 0.07112)
			(type default)
		)
		(layer "In13.Cu")
	)
	(gr_line
		(start 396.043912 -382.815338)
		(end 396.043912 -383.242058)
		(stroke
			(width 0.07112)
			(type default)
		)
		(layer "In13.Cu")
	)
	(gr_line
		(start 396.043912 -382.114298)
		(end 395.908022 -382.250188)
		(stroke
			(width 0.07112)
			(type default)
		)
		(layer "In13.Cu")
	)
	(gr_line
		(start 396.043912 -381.687578)
		(end 396.043912 -382.114298)
		(stroke
			(width 0.07112)
			(type default)
		)
		(layer "In13.Cu")
	)
	(gr_line
		(start 396.043912 -380.986538)
		(end 395.908022 -381.122428)
		(stroke
			(width 0.07112)
			(type default)
		)
		(layer "In13.Cu")
	)
	(gr_line
		(start 396.043912 -380.559818)
		(end 396.043912 -380.986538)
		(stroke
			(width 0.07112)
			(type default)
		)
		(layer "In13.Cu")
	)
	(gr_line
		(start 396.043912 -379.858778)
		(end 395.908022 -379.994668)
		(stroke
			(width 0.07112)
			(type default)
		)
		(layer "In13.Cu")
	)
	(gr_line
		(start 396.043912 -379.432058)
		(end 396.043912 -379.858778)
		(stroke
			(width 0.07112)
			(type default)
		)
		(layer "In13.Cu")
	)
	(gr_line
		(start 396.079218 -404.116032)
		(end 395.381226 -404.047198)
		(stroke
			(width 0.07112)
			(type default)
		)
		(layer "In13.Cu")
	)
	(gr_line
		(start 396.094458 -410.055314)
		(end 395.924278 -410.146246)
		(stroke
			(width 0.07112)
			(type default)
		)
		(layer "In13.Cu")
	)
	(gr_line
		(start 396.106142 -403.834092)
		(end 395.983714 -403.68474)
		(stroke
			(width 0.07112)
			(type default)
		)
		(layer "In13.Cu")
	)
	(gr_line
		(start 396.10792 -405.415496)
		(end 395.198092 -405.27859)
		(stroke
			(width 0.07112)
			(type default)
		)
		(layer "In13.Cu")
	)
	(gr_line
		(start 396.109952 -417.846256)
		(end 396.109952 -417.419536)
		(stroke
			(width 0.07112)
			(type default)
		)
		(layer "In13.Cu")
	)
	(gr_line
		(start 396.109952 -417.419536)
		(end 395.974062 -417.283646)
		(stroke
			(width 0.07112)
			(type default)
		)
		(layer "In13.Cu")
	)
	(gr_line
		(start 396.109952 -416.718496)
		(end 396.109952 -416.291776)
		(stroke
			(width 0.07112)
			(type default)
		)
		(layer "In13.Cu")
	)
	(gr_line
		(start 396.109952 -416.291776)
		(end 395.974062 -416.155886)
		(stroke
			(width 0.07112)
			(type default)
		)
		(layer "In13.Cu")
	)
	(gr_line
		(start 396.147036 -405.151844)
		(end 395.236954 -405.01697)
		(stroke
			(width 0.07112)
			(type default)
		)
		(layer "In13.Cu")
	)
	(gr_line
		(start 396.164562 -405.13889)
		(end 396.147036 -405.151844)
		(stroke
			(width 0.07112)
			(type default)
		)
		(layer "In13.Cu")
	)
	(gr_line
		(start 396.223236 -408.842972)
		(end 395.806676 -408.7495)
		(stroke
			(width 0.07112)
			(type default)
		)
		(layer "In13.Cu")
	)
	(gr_line
		(start 396.256764 -411.6324)
		(end 395.58595 -411.428692)
		(stroke
			(width 0.07112)
			(type default)
		)
		(layer "In13.Cu")
	)
	(gr_line
		(start 396.265146 -409.283154)
		(end 395.58087 -409.129484)
		(stroke
			(width 0.07112)
			(type default)
		)
		(layer "In13.Cu")
	)
	(gr_line
		(start 396.265908 -411.226)
		(end 395.804136 -411.085792)
		(stroke
			(width 0.07112)
			(type default)
		)
		(layer "In13.Cu")
	)
	(gr_line
		(start 396.302738 -405.036274)
		(end 396.165832 -405.137874)
		(stroke
			(width 0.07112)
			(type default)
		)
		(layer "In13.Cu")
	)
	(gr_line
		(start 396.326868 -409.006802)
		(end 396.223236 -408.842972)
		(stroke
			(width 0.07112)
			(type default)
		)
		(layer "In13.Cu")
	)
	(gr_line
		(start 396.338044 -411.361128)
		(end 396.265908 -411.226)
		(stroke
			(width 0.07112)
			(type default)
		)
		(layer "In13.Cu")
	)
	(gr_line
		(start 396.50289 -410.179266)
		(end 396.094458 -410.055314)
		(stroke
			(width 0.07112)
			(type default)
		)
		(layer "In13.Cu")
	)
	(gr_line
		(start 396.512542 -410.620464)
		(end 395.841474 -410.41701)
		(stroke
			(width 0.07112)
			(type default)
		)
		(layer "In13.Cu")
	)
	(gr_line
		(start 396.593568 -410.349192)
		(end 396.50289 -410.179266)
		(stroke
			(width 0.07112)
			(type default)
		)
		(layer "In13.Cu")
	)
	(gr_line
		(start 396.628874 -408.247596)
		(end 396.628874 -408.247342)
		(stroke
			(width 0.07112)
			(type default)
		)
		(layer "In13.Cu")
	)
	(gr_line
		(start 396.681198 -403.75332)
		(end 396.5321 -403.876002)
		(stroke
			(width 0.07112)
			(type default)
		)
		(layer "In13.Cu")
	)
	(gr_line
		(start 396.72514 -405.099012)
		(end 396.302738 -405.036274)
		(stroke
			(width 0.07112)
			(type default)
		)
		(layer "In13.Cu")
	)
	(gr_line
		(start 396.767558 -390.46023)
		(end 397.058388 -390.75106)
		(stroke
			(width 0.07112)
			(type default)
		)
		(layer "In13.Cu")
	)
	(gr_line
		(start 396.767558 -390.17829)
		(end 397.058388 -389.88746)
		(stroke
			(width 0.07112)
			(type default)
		)
		(layer "In13.Cu")
	)
	(gr_line
		(start 396.80134 -405.51989)
		(end 396.10792 -405.415496)
		(stroke
			(width 0.07112)
			(type default)
		)
		(layer "In13.Cu")
	)
	(gr_line
		(start 396.827756 -405.237442)
		(end 396.72514 -405.099012)
		(stroke
			(width 0.07112)
			(type default)
		)
		(layer "In13.Cu")
	)
	(gr_line
		(start 396.84071 -405.254968)
		(end 396.828772 -405.238966)
		(stroke
			(width 0.07112)
			(type default)
		)
		(layer "In13.Cu")
	)
	(gr_line
		(start 396.845282 -407.862786)
		(end 396.685008 -407.969974)
		(stroke
			(width 0.07112)
			(type default)
		)
		(layer "In13.Cu")
	)
	(gr_line
		(start 396.907258 -408.996896)
		(end 396.743936 -409.100528)
		(stroke
			(width 0.07112)
			(type default)
		)
		(layer "In13.Cu")
	)
	(gr_line
		(start 396.986252 -381.710184)
		(end 397.122142 -381.846074)
		(stroke
			(width 0.07112)
			(type default)
		)
		(layer "In13.Cu")
	)
	(gr_line
		(start 396.986252 -381.283464)
		(end 396.986252 -381.710184)
		(stroke
			(width 0.07112)
			(type default)
		)
		(layer "In13.Cu")
	)
	(gr_line
		(start 396.986252 -380.582424)
		(end 397.122142 -380.718314)
		(stroke
			(width 0.07112)
			(type default)
		)
		(layer "In13.Cu")
	)
	(gr_line
		(start 396.986252 -380.155704)
		(end 396.986252 -380.582424)
		(stroke
			(width 0.07112)
			(type default)
		)
		(layer "In13.Cu")
	)
	(gr_line
		(start 396.986252 -379.454664)
		(end 397.122142 -379.590554)
		(stroke
			(width 0.07112)
			(type default)
		)
		(layer "In13.Cu")
	)
	(gr_line
		(start 396.986252 -379.027944)
		(end 396.986252 -379.454664)
		(stroke
			(width 0.07112)
			(type default)
		)
		(layer "In13.Cu")
	)
	(gr_line
		(start 396.986252 -378.265436)
		(end 397.122142 -378.401326)
		(stroke
			(width 0.07112)
			(type default)
		)
		(layer "In13.Cu")
	)
	(gr_line
		(start 396.986252 -377.838716)
		(end 396.986252 -378.265436)
		(stroke
			(width 0.07112)
			(type default)
		)
		(layer "In13.Cu")
	)
	(gr_line
		(start 397.10614 -403.79523)
		(end 396.681198 -403.75332)
		(stroke
			(width 0.07112)
			(type default)
		)
		(layer "In13.Cu")
	)
	(gr_line
		(start 397.122142 -381.147574)
		(end 396.986252 -381.283464)
		(stroke
			(width 0.07112)
			(type default)
		)
		(layer "In13.Cu")
	)
	(gr_line
		(start 397.122142 -380.019814)
		(end 396.986252 -380.155704)
		(stroke
			(width 0.07112)
			(type default)
		)
		(layer "In13.Cu")
	)
	(gr_line
		(start 397.122142 -378.892054)
		(end 396.986252 -379.027944)
		(stroke
			(width 0.07112)
			(type default)
		)
		(layer "In13.Cu")
	)
	(gr_line
		(start 397.122142 -377.702826)
		(end 396.986252 -377.838716)
		(stroke
			(width 0.07112)
			(type default)
		)
		(layer "In13.Cu")
	)
	(gr_line
		(start 397.173704 -410.38272)
		(end 397.003524 -410.473652)
		(stroke
			(width 0.07112)
			(type default)
		)
		(layer "In13.Cu")
	)
	(gr_line
		(start 397.201644 -404.226522)
		(end 396.503652 -404.157688)
		(stroke
			(width 0.07112)
			(type default)
		)
		(layer "In13.Cu")
	)
	(gr_line
		(start 397.222472 -421.998902)
		(end 397.222472 -421.320214)
		(stroke
			(width 0.07112)
			(type default)
		)
		(layer "In13.Cu")
	)
	(gr_line
		(start 397.228568 -403.944582)
		(end 397.10614 -403.79523)
		(stroke
			(width 0.07112)
			(type default)
		)
		(layer "In13.Cu")
	)
	(gr_line
		(start 397.263874 -407.946098)
		(end 396.845282 -407.862786)
		(stroke
			(width 0.07112)
			(type default)
		)
		(layer "In13.Cu")
	)
	(gr_line
		(start 397.31696 -408.384502)
		(end 396.628874 -408.247596)
		(stroke
			(width 0.07112)
			(type default)
		)
		(layer "In13.Cu")
	)
	(gr_line
		(start 397.323818 -409.090368)
		(end 396.907258 -408.996896)
		(stroke
			(width 0.07112)
			(type default)
		)
		(layer "In13.Cu")
	)
	(gr_line
		(start 397.349218 -384.92303)
		(end 397.058388 -385.21386)
		(stroke
			(width 0.07112)
			(type default)
		)
		(layer "In13.Cu")
	)
	(gr_line
		(start 397.349218 -384.64109)
		(end 397.058388 -384.35026)
		(stroke
			(width 0.07112)
			(type default)
		)
		(layer "In13.Cu")
	)
	(gr_line
		(start 397.365728 -409.530296)
		(end 396.681452 -409.376626)
		(stroke
			(width 0.07112)
			(type default)
		)
		(layer "In13.Cu")
	)
	(gr_line
		(start 397.371062 -408.106626)
		(end 397.263874 -407.946098)
		(stroke
			(width 0.07112)
			(type default)
		)
		(layer "In13.Cu")
	)
	(gr_line
		(start 397.405352 -381.146304)
		(end 397.405352 -381.847344)
		(stroke
			(width 0.07112)
			(type default)
		)
		(layer "In13.Cu")
	)
	(gr_line
		(start 397.405352 -380.018544)
		(end 397.405352 -380.719584)
		(stroke
			(width 0.07112)
			(type default)
		)
		(layer "In13.Cu")
	)
	(gr_line
		(start 397.405352 -378.890784)
		(end 397.405352 -379.591824)
		(stroke
			(width 0.07112)
			(type default)
		)
		(layer "In13.Cu")
	)
	(gr_line
		(start 397.405352 -377.701556)
		(end 397.405352 -378.402596)
		(stroke
			(width 0.07112)
			(type default)
		)
		(layer "In13.Cu")
	)
	(gr_line
		(start 397.42745 -409.253944)
		(end 397.323818 -409.090368)
		(stroke
			(width 0.07112)
			(type default)
		)
		(layer "In13.Cu")
	)
	(gr_line
		(start 397.44777 -423.515536)
		(end 397.310864 -422.82745)
		(stroke
			(width 0.07112)
			(type default)
		)
		(layer "In13.Cu")
	)
	(gr_line
		(start 397.47952 -410.913834)
		(end 396.92072 -410.744416)
		(stroke
			(width 0.07112)
			(type default)
		)
		(layer "In13.Cu")
	)
	(gr_line
		(start 397.479774 -410.914088)
		(end 397.47952 -410.913834)
		(stroke
			(width 0.07112)
			(type default)
		)
		(layer "In13.Cu")
	)
	(gr_line
		(start 397.505682 -421.997632)
		(end 397.630396 -421.872918)
		(stroke
			(width 0.07112)
			(type default)
		)
		(layer "In13.Cu")
	)
	(gr_line
		(start 397.582136 -410.506672)
		(end 397.173704 -410.38272)
		(stroke
			(width 0.07112)
			(type default)
		)
		(layer "In13.Cu")
	)
	(gr_line
		(start 397.591788 -410.948124)
		(end 397.479774 -410.914088)
		(stroke
			(width 0.07112)
			(type default)
		)
		(layer "In13.Cu")
	)
	(gr_line
		(start 397.630396 -421.872918)
		(end 397.630396 -421.446198)
		(stroke
			(width 0.07112)
			(type default)
		)
		(layer "In13.Cu")
	)
	(gr_line
		(start 397.630396 -421.446198)
		(end 397.505682 -421.321484)
		(stroke
			(width 0.07112)
			(type default)
		)
		(layer "In13.Cu")
	)
	(gr_line
		(start 397.667734 -424.621706)
		(end 397.530828 -423.93362)
		(stroke
			(width 0.07112)
			(type default)
		)
		(layer "In13.Cu")
	)
	(gr_line
		(start 397.673068 -410.676598)
		(end 397.582136 -410.506672)
		(stroke
			(width 0.07112)
			(type default)
		)
		(layer "In13.Cu")
	)
	(gr_line
		(start 397.697452 -406.740614)
		(end 397.542766 -406.855422)
		(stroke
			(width 0.07112)
			(type default)
		)
		(layer "In13.Cu")
	)
	(gr_line
		(start 397.725392 -423.459402)
		(end 397.832326 -423.299128)
		(stroke
			(width 0.07112)
			(type default)
		)
		(layer "In13.Cu")
	)
	(gr_line
		(start 397.749014 -422.880282)
		(end 397.58874 -422.773602)
		(stroke
			(width 0.07112)
			(type default)
		)
		(layer "In13.Cu")
	)
	(gr_line
		(start 397.832326 -423.299128)
		(end 397.749014 -422.880282)
		(stroke
			(width 0.07112)
			(type default)
		)
		(layer "In13.Cu")
	)
	(gr_line
		(start 397.909034 -403.874478)
		(end 397.759936 -403.996906)
		(stroke
			(width 0.07112)
			(type default)
		)
		(layer "In13.Cu")
	)
	(gr_line
		(start 397.945356 -424.565572)
		(end 398.052544 -424.405298)
		(stroke
			(width 0.07112)
			(type default)
		)
		(layer "In13.Cu")
	)
	(gr_line
		(start 397.951452 -408.08275)
		(end 397.790924 -408.190192)
		(stroke
			(width 0.07112)
			(type default)
		)
		(layer "In13.Cu")
	)
	(gr_line
		(start 397.969232 -423.986706)
		(end 397.808958 -423.879518)
		(stroke
			(width 0.07112)
			(type default)
		)
		(layer "In13.Cu")
	)
	(gr_line
		(start 398.00784 -409.244038)
		(end 397.84401 -409.347924)
		(stroke
			(width 0.07112)
			(type default)
		)
		(layer "In13.Cu")
	)
	(gr_line
		(start 398.052544 -424.405298)
		(end 397.969232 -423.986706)
		(stroke
			(width 0.07112)
			(type default)
		)
		(layer "In13.Cu")
	)
	(gr_line
		(start 398.119854 -406.803352)
		(end 397.697452 -406.740614)
		(stroke
			(width 0.07112)
			(type default)
		)
		(layer "In13.Cu")
	)
	(gr_line
		(start 398.144492 -405.722074)
		(end 396.80134 -405.51989)
		(stroke
			(width 0.07112)
			(type default)
		)
		(layer "In13.Cu")
	)
	(gr_line
		(start 398.184116 -405.454358)
		(end 396.84071 -405.254968)
		(stroke
			(width 0.07112)
			(type default)
		)
		(layer "In13.Cu")
	)
	(gr_line
		(start 398.194022 -407.2382)
		(end 397.500348 -407.135584)
		(stroke
			(width 0.07112)
			(type default)
		)
		(layer "In13.Cu")
	)
	(gr_line
		(start 398.19707 -405.44496)
		(end 398.184116 -405.454358)
		(stroke
			(width 0.07112)
			(type default)
		)
		(layer "In13.Cu")
	)
	(gr_line
		(start 398.234408 -406.958038)
		(end 398.119854 -406.803352)
		(stroke
			(width 0.07112)
			(type default)
		)
		(layer "In13.Cu")
	)
	(gr_line
		(start 398.308322 -408.58186)
		(end 397.735044 -408.467814)
		(stroke
			(width 0.07112)
			(type default)
		)
		(layer "In13.Cu")
	)
	(gr_line
		(start 398.308322 -408.581606)
		(end 398.308322 -408.58186)
		(stroke
			(width 0.07112)
			(type default)
		)
		(layer "In13.Cu")
	)
	(gr_line
		(start 398.333976 -403.916388)
		(end 397.909034 -403.874478)
		(stroke
			(width 0.07112)
			(type default)
		)
		(layer "In13.Cu")
	)
	(gr_line
		(start 398.340072 -405.338788)
		(end 398.19834 -405.44369)
		(stroke
			(width 0.07112)
			(type default)
		)
		(layer "In13.Cu")
	)
	(gr_line
		(start 398.370044 -408.166062)
		(end 397.951452 -408.08275)
		(stroke
			(width 0.07112)
			(type default)
		)
		(layer "In13.Cu")
	)
	(gr_line
		(start 398.422876 -408.604466)
		(end 398.308322 -408.581606)
		(stroke
			(width 0.07112)
			(type default)
		)
		(layer "In13.Cu")
	)
	(gr_line
		(start 398.4244 -409.33751)
		(end 398.00784 -409.244038)
		(stroke
			(width 0.07112)
			(type default)
		)
		(layer "In13.Cu")
	)
	(gr_line
		(start 398.42948 -404.347426)
		(end 397.731488 -404.278592)
		(stroke
			(width 0.07112)
			(type default)
		)
		(layer "In13.Cu")
	)
	(gr_line
		(start 398.456404 -404.065486)
		(end 398.333976 -403.916388)
		(stroke
			(width 0.07112)
			(type default)
		)
		(layer "In13.Cu")
	)
	(gr_line
		(start 398.46631 -409.777692)
		(end 397.782034 -409.624022)
		(stroke
			(width 0.07112)
			(type default)
		)
		(layer "In13.Cu")
	)
	(gr_line
		(start 398.477232 -408.326336)
		(end 398.370044 -408.166062)
		(stroke
			(width 0.07112)
			(type default)
		)
		(layer "In13.Cu")
	)
	(gr_line
		(start 398.527778 -409.501086)
		(end 398.4244 -409.33751)
		(stroke
			(width 0.07112)
			(type default)
		)
		(layer "In13.Cu")
	)
	(gr_line
		(start 398.750028 -434.48986)
		(end 398.750028 -434.157882)
		(stroke
			(width 0.07112)
			(type default)
		)
		(layer "In13.Cu")
	)
	(gr_line
		(start 398.750028 -434.157882)
		(end 398.623028 -434.030882)
		(stroke
			(width 0.07112)
			(type default)
		)
		(layer "In13.Cu")
	)
	(gr_line
		(start 398.750028 -433.621942)
		(end 398.623028 -433.748942)
		(stroke
			(width 0.07112)
			(type default)
		)
		(layer "In13.Cu")
	)
	(gr_line
		(start 398.750028 -433.289964)
		(end 398.750028 -433.621942)
		(stroke
			(width 0.07112)
			(type default)
		)
		(layer "In13.Cu")
	)
	(gr_line
		(start 398.754092 -417.60902)
		(end 398.754092 -416.90798)
		(stroke
			(width 0.07112)
			(type default)
		)
		(layer "In13.Cu")
	)
	(gr_line
		(start 398.754092 -416.48126)
		(end 398.754092 -415.78022)
		(stroke
			(width 0.07112)
			(type default)
		)
		(layer "In13.Cu")
	)
	(gr_line
		(start 398.76222 -405.401526)
		(end 398.340072 -405.338788)
		(stroke
			(width 0.07112)
			(type default)
		)
		(layer "In13.Cu")
	)
	(gr_line
		(start 398.837912 -405.826468)
		(end 398.144492 -405.722074)
		(stroke
			(width 0.07112)
			(type default)
		)
		(layer "In13.Cu")
	)
	(gr_line
		(start 398.868138 -405.544528)
		(end 398.76222 -405.401526)
		(stroke
			(width 0.07112)
			(type default)
		)
		(layer "In13.Cu")
	)
	(gr_line
		(start 398.87779 -405.557482)
		(end 398.869408 -405.546052)
		(stroke
			(width 0.07112)
			(type default)
		)
		(layer "In13.Cu")
	)
	(gr_line
		(start 398.93367 -379.5903)
		(end 398.64284 -379.88113)
		(stroke
			(width 0.07112)
			(type default)
		)
		(layer "In13.Cu")
	)
	(gr_line
		(start 399.031714 -403.985222)
		(end 398.882362 -404.107396)
		(stroke
			(width 0.07112)
			(type default)
		)
		(layer "In13.Cu")
	)
	(gr_line
		(start 399.037302 -417.60775)
		(end 399.173192 -417.47186)
		(stroke
			(width 0.07112)
			(type default)
		)
		(layer "In13.Cu")
	)
	(gr_line
		(start 399.037302 -416.47999)
		(end 399.173192 -416.3441)
		(stroke
			(width 0.07112)
			(type default)
		)
		(layer "In13.Cu")
	)
	(gr_line
		(start 399.108422 -409.491434)
		(end 398.9451 -409.594812)
		(stroke
			(width 0.07112)
			(type default)
		)
		(layer "In13.Cu")
	)
	(gr_line
		(start 399.173192 -417.47186)
		(end 399.173192 -417.04514)
		(stroke
			(width 0.07112)
			(type default)
		)
		(layer "In13.Cu")
	)
	(gr_line
		(start 399.173192 -417.04514)
		(end 399.037302 -416.90925)
		(stroke
			(width 0.07112)
			(type default)
		)
		(layer "In13.Cu")
	)
	(gr_line
		(start 399.173192 -416.3441)
		(end 399.173192 -415.91738)
		(stroke
			(width 0.07112)
			(type default)
		)
		(layer "In13.Cu")
	)
	(gr_line
		(start 399.173192 -415.91738)
		(end 399.037302 -415.78149)
		(stroke
			(width 0.07112)
			(type default)
		)
		(layer "In13.Cu")
	)
	(gr_line
		(start 399.21561 -379.5903)
		(end 399.50644 -379.88113)
		(stroke
			(width 0.07112)
			(type default)
		)
		(layer "In13.Cu")
	)
	(gr_line
		(start 399.456656 -404.027132)
		(end 399.031714 -403.985222)
		(stroke
			(width 0.07112)
			(type default)
		)
		(layer "In13.Cu")
	)
	(gr_line
		(start 399.461482 -407.426668)
		(end 399.461482 -407.42616)
		(stroke
			(width 0.07112)
			(type default)
		)
		(layer "In13.Cu")
	)
	(gr_line
		(start 399.524982 -409.584906)
		(end 399.108422 -409.491434)
		(stroke
			(width 0.07112)
			(type default)
		)
		(layer "In13.Cu")
	)
	(gr_line
		(start 399.551906 -404.457916)
		(end 398.853914 -404.389336)
		(stroke
			(width 0.07112)
			(type default)
		)
		(layer "In13.Cu")
	)
	(gr_line
		(start 399.5674 -410.025088)
		(end 398.882616 -409.871164)
		(stroke
			(width 0.07112)
			(type default)
		)
		(layer "In13.Cu")
	)
	(gr_line
		(start 399.578576 -404.175976)
		(end 399.456656 -404.027132)
		(stroke
			(width 0.07112)
			(type default)
		)
		(layer "In13.Cu")
	)
	(gr_line
		(start 399.628614 -409.748482)
		(end 399.524982 -409.584906)
		(stroke
			(width 0.07112)
			(type default)
		)
		(layer "In13.Cu")
	)
	(gr_line
		(start 399.658586 -407.031698)
		(end 399.503646 -407.146506)
		(stroke
			(width 0.07112)
			(type default)
		)
		(layer "In13.Cu")
	)
	(gr_line
		(start 399.864834 -424.206924)
		(end 399.99793 -423.53738)
		(stroke
			(width 0.07112)
			(type default)
		)
		(layer "In13.Cu")
	)
	(gr_line
		(start 400.078448 -422.998646)
		(end 400.180556 -422.309798)
		(stroke
			(width 0.07112)
			(type default)
		)
		(layer "In13.Cu")
	)
	(gr_line
		(start 400.080988 -407.094436)
		(end 399.658586 -407.031698)
		(stroke
			(width 0.07112)
			(type default)
		)
		(layer "In13.Cu")
	)
	(gr_line
		(start 400.138138 -424.278552)
		(end 400.14144 -424.261788)
		(stroke
			(width 0.07112)
			(type default)
		)
		(layer "In13.Cu")
	)
	(gr_line
		(start 400.142964 -424.260772)
		(end 400.299936 -424.15587)
		(stroke
			(width 0.07112)
			(type default)
		)
		(layer "In13.Cu")
	)
	(gr_line
		(start 400.155156 -407.529538)
		(end 399.461482 -407.426668)
		(stroke
			(width 0.07112)
			(type default)
		)
		(layer "In13.Cu")
	)
	(gr_line
		(start 400.163792 -408.522932)
		(end 400.003518 -408.629866)
		(stroke
			(width 0.07112)
			(type default)
		)
		(layer "In13.Cu")
	)
	(gr_line
		(start 400.195796 -407.249122)
		(end 400.080988 -407.094436)
		(stroke
			(width 0.07112)
			(type default)
		)
		(layer "In13.Cu")
	)
	(gr_line
		(start 400.277584 -423.578782)
		(end 400.279108 -423.568368)
		(stroke
			(width 0.07112)
			(type default)
		)
		(layer "In13.Cu")
	)
	(gr_line
		(start 400.299936 -424.15587)
		(end 400.383248 -423.737278)
		(stroke
			(width 0.07112)
			(type default)
		)
		(layer "In13.Cu")
	)
	(gr_line
		(start 400.35861 -423.039032)
		(end 400.510502 -422.92651)
		(stroke
			(width 0.07112)
			(type default)
		)
		(layer "In13.Cu")
	)
	(gr_line
		(start 400.383248 -423.737278)
		(end 400.277584 -423.578782)
		(stroke
			(width 0.07112)
			(type default)
		)
		(layer "In13.Cu")
	)
	(gr_line
		(start 400.510502 -422.92651)
		(end 400.57324 -422.504108)
		(stroke
			(width 0.07112)
			(type default)
		)
		(layer "In13.Cu")
	)
	(gr_line
		(start 400.57324 -422.504108)
		(end 400.460718 -422.35247)
		(stroke
			(width 0.07112)
			(type default)
		)
		(layer "In13.Cu")
	)
	(gr_line
		(start 400.576034 -406.088088)
		(end 398.837912 -405.826468)
		(stroke
			(width 0.07112)
			(type default)
		)
		(layer "In13.Cu")
	)
	(gr_line
		(start 400.582384 -408.606244)
		(end 400.163792 -408.522932)
		(stroke
			(width 0.07112)
			(type default)
		)
		(layer "In13.Cu")
	)
	(gr_line
		(start 400.595338 -434.74894)
		(end 400.58467 -434.74894)
		(stroke
			(width 0.07112)
			(type default)
		)
		(layer "In13.Cu")
	)
	(gr_line
		(start 400.61642 -405.815546)
		(end 398.87779 -405.557482)
		(stroke
			(width 0.07112)
			(type default)
		)
		(layer "In13.Cu")
	)
	(gr_line
		(start 400.623786 -405.810212)
		(end 400.61642 -405.815546)
		(stroke
			(width 0.07112)
			(type default)
		)
		(layer "In13.Cu")
	)
	(gr_line
		(start 400.63547 -409.044394)
		(end 399.947384 -408.907488)
		(stroke
			(width 0.07112)
			(type default)
		)
		(layer "In13.Cu")
	)
	(gr_line
		(start 400.63547 -377.1265)
		(end 400.34464 -377.41733)
		(stroke
			(width 0.07112)
			(type default)
		)
		(layer "In13.Cu")
	)
	(gr_line
		(start 400.689318 -408.766264)
		(end 400.582384 -408.606244)
		(stroke
			(width 0.07112)
			(type default)
		)
		(layer "In13.Cu")
	)
	(gr_line
		(start 400.750024 -435.489858)
		(end 400.750024 -435.196234)
		(stroke
			(width 0.07112)
			(type default)
		)
		(layer "In13.Cu")
	)
	(gr_line
		(start 400.750024 -435.196234)
		(end 400.58594 -435.03215)
		(stroke
			(width 0.07112)
			(type default)
		)
		(layer "In13.Cu")
	)
	(gr_line
		(start 400.750024 -434.594254)
		(end 400.595338 -434.74894)
		(stroke
			(width 0.07112)
			(type default)
		)
		(layer "In13.Cu")
	)
	(gr_line
		(start 400.750024 -434.289962)
		(end 400.750024 -434.594254)
		(stroke
			(width 0.07112)
			(type default)
		)
		(layer "In13.Cu")
	)
	(gr_line
		(start 400.772122 -405.699976)
		(end 400.625056 -405.809196)
		(stroke
			(width 0.07112)
			(type default)
		)
		(layer "In13.Cu")
	)
	(gr_line
		(start 400.774154 -407.197306)
		(end 400.619468 -407.312114)
		(stroke
			(width 0.07112)
			(type default)
		)
		(layer "In13.Cu")
	)
	(gr_line
		(start 400.91741 -377.1265)
		(end 401.20824 -377.41733)
		(stroke
			(width 0.07112)
			(type default)
		)
		(layer "In13.Cu")
	)
	(gr_line
		(start 401.194524 -405.76246)
		(end 400.772122 -405.699976)
		(stroke
			(width 0.07112)
			(type default)
		)
		(layer "In13.Cu")
	)
	(gr_line
		(start 401.196556 -407.260044)
		(end 400.774154 -407.197306)
		(stroke
			(width 0.07112)
			(type default)
		)
		(layer "In13.Cu")
	)
	(gr_line
		(start 401.269454 -406.192482)
		(end 400.576034 -406.088088)
		(stroke
			(width 0.07112)
			(type default)
		)
		(layer "In13.Cu")
	)
	(gr_line
		(start 401.269962 -408.74315)
		(end 401.109942 -408.850084)
		(stroke
			(width 0.07112)
			(type default)
		)
		(layer "In13.Cu")
	)
	(gr_line
		(start 401.270724 -407.694892)
		(end 400.57705 -407.592022)
		(stroke
			(width 0.07112)
			(type default)
		)
		(layer "In13.Cu")
	)
	(gr_line
		(start 401.30476 -405.911304)
		(end 401.194524 -405.76246)
		(stroke
			(width 0.07112)
			(type default)
		)
		(layer "In13.Cu")
	)
	(gr_line
		(start 401.310094 -405.91867)
		(end 401.305776 -405.912828)
		(stroke
			(width 0.07112)
			(type default)
		)
		(layer "In13.Cu")
	)
	(gr_line
		(start 401.31111 -407.41473)
		(end 401.196556 -407.260044)
		(stroke
			(width 0.07112)
			(type default)
		)
		(layer "In13.Cu")
	)
	(gr_line
		(start 401.688808 -408.826462)
		(end 401.269962 -408.74315)
		(stroke
			(width 0.07112)
			(type default)
		)
		(layer "In13.Cu")
	)
	(gr_line
		(start 401.741386 -409.264358)
		(end 401.053808 -409.127706)
		(stroke
			(width 0.07112)
			(type default)
		)
		(layer "In13.Cu")
	)
	(gr_line
		(start 401.795488 -408.986482)
		(end 401.688808 -408.826462)
		(stroke
			(width 0.07112)
			(type default)
		)
		(layer "In13.Cu")
	)
	(gr_line
		(start 401.817332 -417.783264)
		(end 401.817332 -417.082224)
		(stroke
			(width 0.07112)
			(type default)
		)
		(layer "In13.Cu")
	)
	(gr_line
		(start 401.817332 -416.655504)
		(end 401.817332 -415.954464)
		(stroke
			(width 0.07112)
			(type default)
		)
		(layer "In13.Cu")
	)
	(gr_line
		(start 402.100542 -417.781994)
		(end 402.236432 -417.646104)
		(stroke
			(width 0.07112)
			(type default)
		)
		(layer "In13.Cu")
	)
	(gr_line
		(start 402.100542 -416.654234)
		(end 402.236432 -416.518344)
		(stroke
			(width 0.07112)
			(type default)
		)
		(layer "In13.Cu")
	)
	(gr_line
		(start 402.143214 -423.864278)
		(end 402.53285 -423.281094)
		(stroke
			(width 0.07112)
			(type default)
		)
		(layer "In13.Cu")
	)
	(gr_line
		(start 402.14804 -410.759402)
		(end 401.959064 -410.794454)
		(stroke
			(width 0.07112)
			(type default)
		)
		(layer "In13.Cu")
	)
	(gr_line
		(start 402.236432 -417.646104)
		(end 402.236432 -417.219384)
		(stroke
			(width 0.07112)
			(type default)
		)
		(layer "In13.Cu")
	)
	(gr_line
		(start 402.236432 -417.219384)
		(end 402.100542 -417.083494)
		(stroke
			(width 0.07112)
			(type default)
		)
		(layer "In13.Cu")
	)
	(gr_line
		(start 402.236432 -416.518344)
		(end 402.236432 -416.091624)
		(stroke
			(width 0.07112)
			(type default)
		)
		(layer "In13.Cu")
	)
	(gr_line
		(start 402.236432 -416.091624)
		(end 402.100542 -415.955734)
		(stroke
			(width 0.07112)
			(type default)
		)
		(layer "In13.Cu")
	)
	(gr_line
		(start 402.311362 -406.3492)
		(end 401.269454 -406.192482)
		(stroke
			(width 0.07112)
			(type default)
		)
		(layer "In13.Cu")
	)
	(gr_line
		(start 402.352256 -406.073102)
		(end 401.310094 -405.91867)
		(stroke
			(width 0.07112)
			(type default)
		)
		(layer "In13.Cu")
	)
	(gr_line
		(start 402.355304 -406.070816)
		(end 402.352256 -406.073102)
		(stroke
			(width 0.07112)
			(type default)
		)
		(layer "In13.Cu")
	)
	(gr_line
		(start 402.376132 -411.42412)
		(end 401.798028 -411.027372)
		(stroke
			(width 0.07112)
			(type default)
		)
		(layer "In13.Cu")
	)
	(gr_line
		(start 402.379434 -424.020742)
		(end 402.567902 -423.98315)
		(stroke
			(width 0.07112)
			(type default)
		)
		(layer "In13.Cu")
	)
	(gr_line
		(start 402.500338 -411.00121)
		(end 402.14804 -410.759402)
		(stroke
			(width 0.07112)
			(type default)
		)
		(layer "In13.Cu")
	)
	(gr_line
		(start 402.508212 -405.957532)
		(end 402.356828 -406.0698)
		(stroke
			(width 0.07112)
			(type default)
		)
		(layer "In13.Cu")
	)
	(gr_line
		(start 402.53539 -411.189932)
		(end 402.500338 -411.00121)
		(stroke
			(width 0.07112)
			(type default)
		)
		(layer "In13.Cu")
	)
	(gr_line
		(start 402.567902 -423.98315)
		(end 402.805138 -423.628058)
		(stroke
			(width 0.07112)
			(type default)
		)
		(layer "In13.Cu")
	)
	(gr_line
		(start 402.75002 -434.48986)
		(end 402.75002 -434.157882)
		(stroke
			(width 0.07112)
			(type default)
		)
		(layer "In13.Cu")
	)
	(gr_line
		(start 402.75002 -434.157882)
		(end 402.62302 -434.030882)
		(stroke
			(width 0.07112)
			(type default)
		)
		(layer "In13.Cu")
	)
	(gr_line
		(start 402.75002 -433.621942)
		(end 402.62302 -433.748942)
		(stroke
			(width 0.07112)
			(type default)
		)
		(layer "In13.Cu")
	)
	(gr_line
		(start 402.75002 -433.289964)
		(end 402.75002 -433.621942)
		(stroke
			(width 0.07112)
			(type default)
		)
		(layer "In13.Cu")
	)
	(gr_line
		(start 402.769832 -422.92651)
		(end 403.159468 -422.343326)
		(stroke
			(width 0.07112)
			(type default)
		)
		(layer "In13.Cu")
	)
	(gr_line
		(start 402.805138 -423.628058)
		(end 402.767546 -423.43959)
		(stroke
			(width 0.07112)
			(type default)
		)
		(layer "In13.Cu")
	)
	(gr_line
		(start 402.93036 -406.02027)
		(end 402.508212 -405.957532)
		(stroke
			(width 0.07112)
			(type default)
		)
		(layer "In13.Cu")
	)
	(gr_line
		(start 403.004782 -406.453594)
		(end 402.311362 -406.3492)
		(stroke
			(width 0.07112)
			(type default)
		)
		(layer "In13.Cu")
	)
	(gr_line
		(start 403.006052 -423.082974)
		(end 403.19452 -423.045382)
		(stroke
			(width 0.07112)
			(type default)
		)
		(layer "In13.Cu")
	)
	(gr_line
		(start 403.043644 -406.173178)
		(end 402.93036 -406.02027)
		(stroke
			(width 0.07112)
			(type default)
		)
		(layer "In13.Cu")
	)
	(gr_line
		(start 403.04593 -406.176226)
		(end 403.04466 -406.174702)
		(stroke
			(width 0.07112)
			(type default)
		)
		(layer "In13.Cu")
	)
	(gr_line
		(start 403.19452 -423.045382)
		(end 403.431756 -422.69029)
		(stroke
			(width 0.07112)
			(type default)
		)
		(layer "In13.Cu")
	)
	(gr_line
		(start 403.431756 -422.69029)
		(end 403.394164 -422.501822)
		(stroke
			(width 0.07112)
			(type default)
		)
		(layer "In13.Cu")
	)
	(gr_line
		(start 403.461728 -407.942034)
		(end 403.281642 -408.009344)
		(stroke
			(width 0.07112)
			(type default)
		)
		(layer "In13.Cu")
	)
	(gr_line
		(start 403.659086 -406.552146)
		(end 403.004782 -406.453594)
		(stroke
			(width 0.07112)
			(type default)
		)
		(layer "In13.Cu")
	)
	(gr_line
		(start 403.700742 -406.273254)
		(end 403.04593 -406.176226)
		(stroke
			(width 0.07112)
			(type default)
		)
		(layer "In13.Cu")
	)
	(gr_line
		(start 403.751542 -409.600908)
		(end 403.563074 -409.6385)
		(stroke
			(width 0.07112)
			(type default)
		)
		(layer "In13.Cu")
	)
	(gr_line
		(start 403.80031 -408.558238)
		(end 403.16277 -408.266138)
		(stroke
			(width 0.07112)
			(type default)
		)
		(layer "In13.Cu")
	)
	(gr_line
		(start 403.850094 -408.119834)
		(end 403.461728 -407.942034)
		(stroke
			(width 0.07112)
			(type default)
		)
		(layer "In13.Cu")
	)
	(gr_line
		(start 403.91715 -408.300428)
		(end 403.850094 -408.119834)
		(stroke
			(width 0.07112)
			(type default)
		)
		(layer "In13.Cu")
	)
	(gr_line
		(start 403.987762 -410.262832)
		(end 403.404578 -409.873196)
		(stroke
			(width 0.07112)
			(type default)
		)
		(layer "In13.Cu")
	)
	(gr_line
		(start 404.03907 -382.0541)
		(end 403.74824 -382.34493)
		(stroke
			(width 0.07112)
			(type default)
		)
		(layer "In13.Cu")
	)
	(gr_line
		(start 404.106634 -409.838144)
		(end 403.751542 -409.600908)
		(stroke
			(width 0.07112)
			(type default)
		)
		(layer "In13.Cu")
	)
	(gr_line
		(start 404.144226 -410.026612)
		(end 404.106634 -409.838144)
		(stroke
			(width 0.07112)
			(type default)
		)
		(layer "In13.Cu")
	)
	(gr_line
		(start 404.32101 -382.0541)
		(end 404.61184 -382.34493)
		(stroke
			(width 0.07112)
			(type default)
		)
		(layer "In13.Cu")
	)
	(gr_line
		(start 404.68931 -410.227526)
		(end 404.500842 -410.265118)
		(stroke
			(width 0.07112)
			(type default)
		)
		(layer "In13.Cu")
	)
	(gr_line
		(start 404.69693 -408.507692)
		(end 404.51659 -408.575002)
		(stroke
			(width 0.07112)
			(type default)
		)
		(layer "In13.Cu")
	)
	(gr_line
		(start 404.750016 -435.489858)
		(end 404.750016 -435.15788)
		(stroke
			(width 0.07112)
			(type default)
		)
		(layer "In13.Cu")
	)
	(gr_line
		(start 404.750016 -435.15788)
		(end 404.623016 -435.03088)
		(stroke
			(width 0.07112)
			(type default)
		)
		(layer "In13.Cu")
	)
	(gr_line
		(start 404.750016 -434.62194)
		(end 404.623016 -434.74894)
		(stroke
			(width 0.07112)
			(type default)
		)
		(layer "In13.Cu")
	)
	(gr_line
		(start 404.750016 -434.289962)
		(end 404.750016 -434.62194)
		(stroke
			(width 0.07112)
			(type default)
		)
		(layer "In13.Cu")
	)
	(gr_line
		(start 404.770844 -423.147998)
		(end 405.266906 -422.651936)
		(stroke
			(width 0.07112)
			(type default)
		)
		(layer "In13.Cu")
	)
	(gr_line
		(start 404.880572 -417.764976)
		(end 404.880572 -417.063936)
		(stroke
			(width 0.07112)
			(type default)
		)
		(layer "In13.Cu")
	)
	(gr_line
		(start 404.880572 -416.637216)
		(end 404.880572 -415.936176)
		(stroke
			(width 0.07112)
			(type default)
		)
		(layer "In13.Cu")
	)
	(gr_line
		(start 404.92553 -410.88945)
		(end 404.342346 -410.499814)
		(stroke
			(width 0.07112)
			(type default)
		)
		(layer "In13.Cu")
	)
	(gr_line
		(start 404.972012 -423.347388)
		(end 405.16429 -423.347388)
		(stroke
			(width 0.07112)
			(type default)
		)
		(layer "In13.Cu")
	)
	(gr_line
		(start 405.035258 -409.12415)
		(end 404.397718 -408.83205)
		(stroke
			(width 0.07112)
			(type default)
		)
		(layer "In13.Cu")
	)
	(gr_line
		(start 405.044402 -410.464762)
		(end 404.68931 -410.227526)
		(stroke
			(width 0.07112)
			(type default)
		)
		(layer "In13.Cu")
	)
	(gr_line
		(start 405.081994 -410.65323)
		(end 405.044402 -410.464762)
		(stroke
			(width 0.07112)
			(type default)
		)
		(layer "In13.Cu")
	)
	(gr_line
		(start 405.085042 -408.685492)
		(end 404.69693 -408.507692)
		(stroke
			(width 0.07112)
			(type default)
		)
		(layer "In13.Cu")
	)
	(gr_line
		(start 405.152098 -408.866086)
		(end 405.085042 -408.685492)
		(stroke
			(width 0.07112)
			(type default)
		)
		(layer "In13.Cu")
	)
	(gr_line
		(start 405.163782 -417.763706)
		(end 405.299672 -417.627816)
		(stroke
			(width 0.07112)
			(type default)
		)
		(layer "In13.Cu")
	)
	(gr_line
		(start 405.163782 -416.635946)
		(end 405.299672 -416.500056)
		(stroke
			(width 0.07112)
			(type default)
		)
		(layer "In13.Cu")
	)
	(gr_line
		(start 405.16429 -423.347388)
		(end 405.466296 -423.045382)
		(stroke
			(width 0.07112)
			(type default)
		)
		(layer "In13.Cu")
	)
	(gr_line
		(start 405.299672 -417.627816)
		(end 405.299672 -417.201096)
		(stroke
			(width 0.07112)
			(type default)
		)
		(layer "In13.Cu")
	)
	(gr_line
		(start 405.299672 -417.201096)
		(end 405.163782 -417.065206)
		(stroke
			(width 0.07112)
			(type default)
		)
		(layer "In13.Cu")
	)
	(gr_line
		(start 405.299672 -416.500056)
		(end 405.299672 -416.073336)
		(stroke
			(width 0.07112)
			(type default)
		)
		(layer "In13.Cu")
	)
	(gr_line
		(start 405.299672 -416.073336)
		(end 405.163782 -415.937446)
		(stroke
			(width 0.07112)
			(type default)
		)
		(layer "In13.Cu")
	)
	(gr_line
		(start 405.363172 -406.772872)
		(end 405.184864 -406.845516)
		(stroke
			(width 0.07112)
			(type default)
		)
		(layer "In13.Cu")
	)
	(gr_line
		(start 405.466296 -423.045382)
		(end 405.466296 -422.853104)
		(stroke
			(width 0.07112)
			(type default)
		)
		(layer "In13.Cu")
	)
	(gr_line
		(start 405.568404 -422.350438)
		(end 406.064466 -421.854376)
		(stroke
			(width 0.07112)
			(type default)
		)
		(layer "In13.Cu")
	)
	(gr_line
		(start 405.720296 -407.378408)
		(end 405.07412 -407.10612)
		(stroke
			(width 0.07112)
			(type default)
		)
		(layer "In13.Cu")
	)
	(gr_line
		(start 405.74087 -379.5903)
		(end 405.45004 -379.88113)
		(stroke
			(width 0.07112)
			(type default)
		)
		(layer "In13.Cu")
	)
	(gr_line
		(start 405.756618 -406.93848)
		(end 405.363172 -406.772872)
		(stroke
			(width 0.07112)
			(type default)
		)
		(layer "In13.Cu")
	)
	(gr_line
		(start 405.769572 -422.549828)
		(end 405.96185 -422.549828)
		(stroke
			(width 0.07112)
			(type default)
		)
		(layer "In13.Cu")
	)
	(gr_line
		(start 405.829008 -407.117042)
		(end 405.756618 -406.93848)
		(stroke
			(width 0.07112)
			(type default)
		)
		(layer "In13.Cu")
	)
	(gr_line
		(start 405.96185 -422.549828)
		(end 406.263856 -422.247822)
		(stroke
			(width 0.07112)
			(type default)
		)
		(layer "In13.Cu")
	)
	(gr_line
		(start 406.02281 -379.5903)
		(end 406.31364 -379.88113)
		(stroke
			(width 0.07112)
			(type default)
		)
		(layer "In13.Cu")
	)
	(gr_line
		(start 406.263856 -422.247822)
		(end 406.263856 -422.055544)
		(stroke
			(width 0.07112)
			(type default)
		)
		(layer "In13.Cu")
	)
	(gr_line
		(start 406.750012 -434.48986)
		(end 406.750012 -434.157882)
		(stroke
			(width 0.07112)
			(type default)
		)
		(layer "In13.Cu")
	)
	(gr_line
		(start 406.750012 -434.157882)
		(end 406.623012 -434.030882)
		(stroke
			(width 0.07112)
			(type default)
		)
		(layer "In13.Cu")
	)
	(gr_line
		(start 406.750012 -433.621942)
		(end 406.623012 -433.748942)
		(stroke
			(width 0.07112)
			(type default)
		)
		(layer "In13.Cu")
	)
	(gr_line
		(start 406.750012 -433.289964)
		(end 406.750012 -433.621942)
		(stroke
			(width 0.07112)
			(type default)
		)
		(layer "In13.Cu")
	)
	(gr_line
		(start 407.40965 -423.095928)
		(end 407.99258 -422.706038)
		(stroke
			(width 0.07112)
			(type default)
		)
		(layer "In13.Cu")
	)
	(gr_line
		(start 407.44267 -377.1265)
		(end 407.15184 -377.41733)
		(stroke
			(width 0.07112)
			(type default)
		)
		(layer "In13.Cu")
	)
	(gr_line
		(start 407.567892 -423.330624)
		(end 407.756614 -423.367962)
		(stroke
			(width 0.07112)
			(type default)
		)
		(layer "In13.Cu")
	)
	(gr_line
		(start 407.72461 -377.1265)
		(end 408.01544 -377.41733)
		(stroke
			(width 0.07112)
			(type default)
		)
		(layer "In13.Cu")
	)
	(gr_line
		(start 407.756614 -423.367962)
		(end 408.111452 -423.130726)
		(stroke
			(width 0.07112)
			(type default)
		)
		(layer "In13.Cu")
	)
	(gr_arc
		(start 407.92908 -375.244106)
		(mid 407.929334 -375.24436)
		(end 407.929588 -375.244614)
		(stroke
			(width 0.07112)
			(type default)
		)
		(layer "In13.Cu")
	)
	(gr_line
		(start 407.943812 -417.858702)
		(end 407.943812 -417.157662)
		(stroke
			(width 0.07112)
			(type default)
		)
		(layer "In13.Cu")
	)
	(gr_line
		(start 407.943812 -416.730942)
		(end 407.943812 -416.029902)
		(stroke
			(width 0.07112)
			(type default)
		)
		(layer "In13.Cu")
	)
	(gr_line
		(start 408.04465 -434.983636)
		(end 408.009344 -434.94833)
		(stroke
			(width 0.07112)
			(type default)
		)
		(layer "In13.Cu")
	)
	(gr_arc
		(start 408.04465 -434.983636)
		(mid 408.096974 -435.018602)
		(end 408.158696 -435.03088)
		(stroke
			(width 0.07112)
			(type default)
		)
		(layer "In13.Cu")
	)
	(gr_line
		(start 408.111452 -423.130726)
		(end 408.149044 -422.942004)
		(stroke
			(width 0.07112)
			(type default)
		)
		(layer "In13.Cu")
	)
	(gr_line
		(start 408.118564 -408.70759)
		(end 408.118564 -408.707336)
		(stroke
			(width 0.07112)
			(type default)
		)
		(layer "In13.Cu")
	)
	(gr_line
		(start 408.208734 -435.03088)
		(end 408.158696 -435.03088)
		(stroke
			(width 0.07112)
			(type default)
		)
		(layer "In13.Cu")
	)
	(gr_line
		(start 408.227022 -417.857432)
		(end 408.362912 -417.721542)
		(stroke
			(width 0.07112)
			(type default)
		)
		(layer "In13.Cu")
	)
	(gr_line
		(start 408.227022 -416.729672)
		(end 408.362912 -416.593782)
		(stroke
			(width 0.07112)
			(type default)
		)
		(layer "In13.Cu")
	)
	(gr_line
		(start 408.362912 -417.721542)
		(end 408.362912 -417.294822)
		(stroke
			(width 0.07112)
			(type default)
		)
		(layer "In13.Cu")
	)
	(gr_line
		(start 408.362912 -417.294822)
		(end 408.227022 -417.158932)
		(stroke
			(width 0.07112)
			(type default)
		)
		(layer "In13.Cu")
	)
	(gr_line
		(start 408.362912 -416.593782)
		(end 408.362912 -416.167062)
		(stroke
			(width 0.07112)
			(type default)
		)
		(layer "In13.Cu")
	)
	(gr_line
		(start 408.362912 -416.167062)
		(end 408.227022 -416.031172)
		(stroke
			(width 0.07112)
			(type default)
		)
		(layer "In13.Cu")
	)
	(gr_line
		(start 408.448002 -408.41422)
		(end 408.262074 -408.463496)
		(stroke
			(width 0.07112)
			(type default)
		)
		(layer "In13.Cu")
	)
	(gr_line
		(start 408.623008 -409.001722)
		(end 408.118564 -408.70759)
		(stroke
			(width 0.07112)
			(type default)
		)
		(layer "In13.Cu")
	)
	(gr_line
		(start 408.623262 -409.001722)
		(end 408.623008 -409.001722)
		(stroke
			(width 0.07112)
			(type default)
		)
		(layer "In13.Cu")
	)
	(gr_line
		(start 408.724354 -409.06065)
		(end 408.623262 -409.001722)
		(stroke
			(width 0.07112)
			(type default)
		)
		(layer "In13.Cu")
	)
	(gr_line
		(start 408.725878 -423.637964)
		(end 409.309316 -423.248328)
		(stroke
			(width 0.07112)
			(type default)
		)
		(layer "In13.Cu")
	)
	(gr_line
		(start 408.750008 -435.489858)
		(end 408.750008 -435.15788)
		(stroke
			(width 0.07112)
			(type default)
		)
		(layer "In13.Cu")
	)
	(gr_line
		(start 408.750008 -435.15788)
		(end 408.623008 -435.03088)
		(stroke
			(width 0.07112)
			(type default)
		)
		(layer "In13.Cu")
	)
	(gr_line
		(start 408.750008 -434.62194)
		(end 408.623008 -434.74894)
		(stroke
			(width 0.07112)
			(type default)
		)
		(layer "In13.Cu")
	)
	(gr_line
		(start 408.750008 -434.289962)
		(end 408.750008 -434.62194)
		(stroke
			(width 0.07112)
			(type default)
		)
		(layer "In13.Cu")
	)
	(gr_line
		(start 408.81681 -408.629104)
		(end 408.448002 -408.41422)
		(stroke
			(width 0.07112)
			(type default)
		)
		(layer "In13.Cu")
	)
	(gr_line
		(start 408.865832 -408.815286)
		(end 408.81681 -408.629104)
		(stroke
			(width 0.07112)
			(type default)
		)
		(layer "In13.Cu")
	)
	(gr_line
		(start 408.884374 -423.87266)
		(end 409.072842 -423.910506)
		(stroke
			(width 0.07112)
			(type default)
		)
		(layer "In13.Cu")
	)
	(gr_line
		(start 409.00731 -407.176224)
		(end 408.818842 -407.213816)
		(stroke
			(width 0.07112)
			(type default)
		)
		(layer "In13.Cu")
	)
	(gr_line
		(start 409.072842 -423.910506)
		(end 409.427934 -423.67327)
		(stroke
			(width 0.07112)
			(type default)
		)
		(layer "In13.Cu")
	)
	(gr_line
		(start 409.24353 -407.838148)
		(end 408.660346 -407.448512)
		(stroke
			(width 0.07112)
			(type default)
		)
		(layer "In13.Cu")
	)
	(gr_line
		(start 409.362402 -407.41346)
		(end 409.00731 -407.176224)
		(stroke
			(width 0.07112)
			(type default)
		)
		(layer "In13.Cu")
	)
	(gr_line
		(start 409.399994 -407.601928)
		(end 409.362402 -407.41346)
		(stroke
			(width 0.07112)
			(type default)
		)
		(layer "In13.Cu")
	)
	(gr_line
		(start 409.427934 -423.67327)
		(end 409.46578 -423.484548)
		(stroke
			(width 0.07112)
			(type default)
		)
		(layer "In13.Cu")
	)
	(gr_line
		(start 410.750004 -434.48986)
		(end 410.750004 -434.157882)
		(stroke
			(width 0.07112)
			(type default)
		)
		(layer "In13.Cu")
	)
	(gr_line
		(start 410.750004 -434.157882)
		(end 410.623004 -434.030882)
		(stroke
			(width 0.07112)
			(type default)
		)
		(layer "In13.Cu")
	)
	(gr_line
		(start 410.750004 -433.621942)
		(end 410.623004 -433.748942)
		(stroke
			(width 0.07112)
			(type default)
		)
		(layer "In13.Cu")
	)
	(gr_line
		(start 410.750004 -433.289964)
		(end 410.750004 -433.621942)
		(stroke
			(width 0.07112)
			(type default)
		)
		(layer "In13.Cu")
	)
	(gr_line
		(start 410.84627 -382.0541)
		(end 410.55544 -382.34493)
		(stroke
			(width 0.07112)
			(type default)
		)
		(layer "In13.Cu")
	)
	(gr_line
		(start 411.007052 -417.4744)
		(end 411.007052 -416.77336)
		(stroke
			(width 0.07112)
			(type default)
		)
		(layer "In13.Cu")
	)
	(gr_line
		(start 411.007052 -416.34664)
		(end 411.007052 -415.6456)
		(stroke
			(width 0.07112)
			(type default)
		)
		(layer "In13.Cu")
	)
	(gr_line
		(start 411.12821 -382.0541)
		(end 411.41904 -382.34493)
		(stroke
			(width 0.07112)
			(type default)
		)
		(layer "In13.Cu")
	)
	(gr_line
		(start 411.207458 -419.214046)
		(end 411.207712 -419.214046)
		(stroke
			(width 0.07112)
			(type default)
		)
		(layer "In13.Cu")
	)
	(gr_line
		(start 411.290262 -417.47313)
		(end 411.426152 -417.33724)
		(stroke
			(width 0.07112)
			(type default)
		)
		(layer "In13.Cu")
	)
	(gr_line
		(start 411.290262 -416.34537)
		(end 411.426152 -416.20948)
		(stroke
			(width 0.07112)
			(type default)
		)
		(layer "In13.Cu")
	)
	(gr_line
		(start 411.426152 -417.33724)
		(end 411.426152 -416.91052)
		(stroke
			(width 0.07112)
			(type default)
		)
		(layer "In13.Cu")
	)
	(gr_line
		(start 411.426152 -416.91052)
		(end 411.290262 -416.77463)
		(stroke
			(width 0.07112)
			(type default)
		)
		(layer "In13.Cu")
	)
	(gr_line
		(start 411.426152 -416.20948)
		(end 411.426152 -415.78276)
		(stroke
			(width 0.07112)
			(type default)
		)
		(layer "In13.Cu")
	)
	(gr_line
		(start 411.426152 -415.78276)
		(end 411.290262 -415.64687)
		(stroke
			(width 0.07112)
			(type default)
		)
		(layer "In13.Cu")
	)
	(gr_line
		(start 412.54807 -379.5903)
		(end 412.25724 -379.88113)
		(stroke
			(width 0.07112)
			(type default)
		)
		(layer "In13.Cu")
	)
	(gr_line
		(start 412.75 -435.489858)
		(end 412.75 -435.15788)
		(stroke
			(width 0.07112)
			(type default)
		)
		(layer "In13.Cu")
	)
	(gr_line
		(start 412.75 -435.15788)
		(end 412.623 -435.03088)
		(stroke
			(width 0.07112)
			(type default)
		)
		(layer "In13.Cu")
	)
	(gr_line
		(start 412.75 -434.62194)
		(end 412.623 -434.74894)
		(stroke
			(width 0.07112)
			(type default)
		)
		(layer "In13.Cu")
	)
	(gr_line
		(start 412.75 -434.289962)
		(end 412.75 -434.62194)
		(stroke
			(width 0.07112)
			(type default)
		)
		(layer "In13.Cu")
	)
	(gr_line
		(start 412.83001 -379.5903)
		(end 413.12084 -379.88113)
		(stroke
			(width 0.07112)
			(type default)
		)
		(layer "In13.Cu")
	)
	(gr_line
		(start 413.109918 -422.644824)
		(end 413.707834 -422.445688)
		(stroke
			(width 0.07112)
			(type default)
		)
		(layer "In13.Cu")
	)
	(gr_line
		(start 413.200088 -422.913302)
		(end 413.327596 -422.977056)
		(stroke
			(width 0.07112)
			(type default)
		)
		(layer "In13.Cu")
	)
	(gr_line
		(start 413.327596 -422.977056)
		(end 413.732726 -422.842182)
		(stroke
			(width 0.07112)
			(type default)
		)
		(layer "In13.Cu")
	)
	(gr_line
		(start 413.732726 -422.842182)
		(end 413.79648 -422.714674)
		(stroke
			(width 0.07112)
			(type default)
		)
		(layer "In13.Cu")
	)
	(gr_line
		(start 413.768794 -423.524426)
		(end 414.439862 -423.320972)
		(stroke
			(width 0.07112)
			(type default)
		)
		(layer "In13.Cu")
	)
	(gr_line
		(start 413.851852 -423.79519)
		(end 414.021778 -423.886122)
		(stroke
			(width 0.07112)
			(type default)
		)
		(layer "In13.Cu")
	)
	(gr_line
		(start 414.021778 -423.886122)
		(end 414.43021 -423.76217)
		(stroke
			(width 0.07112)
			(type default)
		)
		(layer "In13.Cu")
	)
	(gr_line
		(start 414.070292 -417.764976)
		(end 414.070292 -417.063936)
		(stroke
			(width 0.07112)
			(type default)
		)
		(layer "In13.Cu")
	)
	(gr_line
		(start 414.070292 -416.637216)
		(end 414.070292 -415.936176)
		(stroke
			(width 0.07112)
			(type default)
		)
		(layer "In13.Cu")
	)
	(gr_line
		(start 414.112456 -422.310814)
		(end 414.710372 -422.111424)
		(stroke
			(width 0.07112)
			(type default)
		)
		(layer "In13.Cu")
	)
	(gr_line
		(start 414.20288 -422.579038)
		(end 414.330134 -422.642792)
		(stroke
			(width 0.07112)
			(type default)
		)
		(layer "In13.Cu")
	)
	(gr_line
		(start 414.24987 -377.1265)
		(end 413.95904 -377.41733)
		(stroke
			(width 0.07112)
			(type default)
		)
		(layer "In13.Cu")
	)
	(gr_line
		(start 414.330134 -422.642792)
		(end 414.735264 -422.507918)
		(stroke
			(width 0.07112)
			(type default)
		)
		(layer "In13.Cu")
	)
	(gr_line
		(start 414.353502 -417.763706)
		(end 414.489392 -417.627816)
		(stroke
			(width 0.07112)
			(type default)
		)
		(layer "In13.Cu")
	)
	(gr_line
		(start 414.353502 -416.635946)
		(end 414.489392 -416.500056)
		(stroke
			(width 0.07112)
			(type default)
		)
		(layer "In13.Cu")
	)
	(gr_line
		(start 414.43021 -423.76217)
		(end 414.520888 -423.592244)
		(stroke
			(width 0.07112)
			(type default)
		)
		(layer "In13.Cu")
	)
	(gr_line
		(start 414.489392 -417.627816)
		(end 414.489392 -417.201096)
		(stroke
			(width 0.07112)
			(type default)
		)
		(layer "In13.Cu")
	)
	(gr_line
		(start 414.489392 -417.201096)
		(end 414.353502 -417.065206)
		(stroke
			(width 0.07112)
			(type default)
		)
		(layer "In13.Cu")
	)
	(gr_line
		(start 414.489392 -416.500056)
		(end 414.489392 -416.073336)
		(stroke
			(width 0.07112)
			(type default)
		)
		(layer "In13.Cu")
	)
	(gr_line
		(start 414.489392 -416.073336)
		(end 414.353502 -415.937446)
		(stroke
			(width 0.07112)
			(type default)
		)
		(layer "In13.Cu")
	)
	(gr_line
		(start 414.53181 -377.1265)
		(end 414.82264 -377.41733)
		(stroke
			(width 0.07112)
			(type default)
		)
		(layer "In13.Cu")
	)
	(gr_line
		(start 414.735264 -422.507918)
		(end 414.799018 -422.38041)
		(stroke
			(width 0.07112)
			(type default)
		)
		(layer "In13.Cu")
	)
	(gr_line
		(start 414.84804 -423.197274)
		(end 415.519108 -422.993566)
		(stroke
			(width 0.07112)
			(type default)
		)
		(layer "In13.Cu")
	)
	(gr_line
		(start 414.931098 -423.468038)
		(end 415.101024 -423.558716)
		(stroke
			(width 0.07112)
			(type default)
		)
		(layer "In13.Cu")
	)
	(gr_line
		(start 415.101024 -423.558716)
		(end 415.509456 -423.434764)
		(stroke
			(width 0.07112)
			(type default)
		)
		(layer "In13.Cu")
	)
	(gr_line
		(start 415.509456 -423.434764)
		(end 415.600134 -423.265092)
		(stroke
			(width 0.07112)
			(type default)
		)
		(layer "In13.Cu")
	)
	(gr_line
		(start 415.578798 -412.22676)
		(end 415.57829 -412.225744)
		(stroke
			(width 0.07112)
			(type default)
		)
		(layer "In13.Cu")
	)
	(gr_line
		(start 415.844228 -412.130748)
		(end 415.843974 -412.130748)
		(stroke
			(width 0.07112)
			(type default)
		)
		(layer "In13.Cu")
	)
	(gr_arc
		(start 415.85261 -412.15564)
		(mid 415.850731 -412.14979)
		(end 415.8488 -412.143956)
		(stroke
			(width 0.07112)
			(type default)
		)
		(layer "In13.Cu")
	)
	(gr_line
		(start 415.883344 -412.356554)
		(end 415.883598 -412.356554)
		(stroke
			(width 0.07112)
			(type default)
		)
		(layer "In13.Cu")
	)
	(gr_arc
		(start 415.883344 -412.336488)
		(mid 415.883123 -412.329883)
		(end 415.882836 -412.32328)
		(stroke
			(width 0.07112)
			(type default)
		)
		(layer "In13.Cu")
	)
	(gr_line
		(start 415.927286 -422.869868)
		(end 416.598354 -422.666414)
		(stroke
			(width 0.07112)
			(type default)
		)
		(layer "In13.Cu")
	)
	(gr_line
		(start 416.010344 -423.140632)
		(end 416.18027 -423.23131)
		(stroke
			(width 0.07112)
			(type default)
		)
		(layer "In13.Cu")
	)
	(gr_line
		(start 416.18027 -423.23131)
		(end 416.588702 -423.107612)
		(stroke
			(width 0.07112)
			(type default)
		)
		(layer "In13.Cu")
	)
	(gr_line
		(start 416.588702 -423.107612)
		(end 416.67938 -422.937686)
		(stroke
			(width 0.07112)
			(type default)
		)
		(layer "In13.Cu")
	)
	(gr_line
		(start 417.133532 -417.671504)
		(end 417.133532 -416.970464)
		(stroke
			(width 0.07112)
			(type default)
		)
		(layer "In13.Cu")
	)
	(gr_line
		(start 417.133532 -416.543744)
		(end 417.133532 -415.842704)
		(stroke
			(width 0.07112)
			(type default)
		)
		(layer "In13.Cu")
	)
	(gr_line
		(start 417.416742 -417.670234)
		(end 417.552632 -417.534344)
		(stroke
			(width 0.07112)
			(type default)
		)
		(layer "In13.Cu")
	)
	(gr_line
		(start 417.416742 -416.542474)
		(end 417.552632 -416.406584)
		(stroke
			(width 0.07112)
			(type default)
		)
		(layer "In13.Cu")
	)
	(gr_line
		(start 417.552632 -417.534344)
		(end 417.552632 -417.107624)
		(stroke
			(width 0.07112)
			(type default)
		)
		(layer "In13.Cu")
	)
	(gr_line
		(start 417.552632 -417.107624)
		(end 417.416742 -416.971734)
		(stroke
			(width 0.07112)
			(type default)
		)
		(layer "In13.Cu")
	)
	(gr_line
		(start 417.552632 -416.406584)
		(end 417.552632 -415.979864)
		(stroke
			(width 0.07112)
			(type default)
		)
		(layer "In13.Cu")
	)
	(gr_line
		(start 417.552632 -415.979864)
		(end 417.416742 -415.843974)
		(stroke
			(width 0.07112)
			(type default)
		)
		(layer "In13.Cu")
	)
	(gr_line
		(start 417.65347 -382.0541)
		(end 417.36264 -382.34493)
		(stroke
			(width 0.07112)
			(type default)
		)
		(layer "In13.Cu")
	)
	(gr_line
		(start 417.93541 -382.0541)
		(end 418.22624 -382.34493)
		(stroke
			(width 0.07112)
			(type default)
		)
		(layer "In13.Cu")
	)
	(gr_line
		(start 419.35527 -379.5903)
		(end 419.06444 -379.88113)
		(stroke
			(width 0.07112)
			(type default)
		)
		(layer "In13.Cu")
	)
	(gr_line
		(start 419.393624 -371.364002)
		(end 420.094664 -371.364002)
		(stroke
			(width 0.07112)
			(type default)
		)
		(layer "In13.Cu")
	)
	(gr_line
		(start 419.394894 -371.647212)
		(end 419.530784 -371.783102)
		(stroke
			(width 0.07112)
			(type default)
		)
		(layer "In13.Cu")
	)
	(gr_line
		(start 419.530784 -371.783102)
		(end 419.957504 -371.783102)
		(stroke
			(width 0.07112)
			(type default)
		)
		(layer "In13.Cu")
	)
	(gr_line
		(start 419.63721 -379.5903)
		(end 419.92804 -379.88113)
		(stroke
			(width 0.07112)
			(type default)
		)
		(layer "In13.Cu")
	)
	(gr_line
		(start 419.957504 -371.783102)
		(end 420.093394 -371.647212)
		(stroke
			(width 0.07112)
			(type default)
		)
		(layer "In13.Cu")
	)
	(gr_line
		(start 420.521384 -371.364002)
		(end 421.222424 -371.364002)
		(stroke
			(width 0.07112)
			(type default)
		)
		(layer "In13.Cu")
	)
	(gr_line
		(start 420.522654 -371.647212)
		(end 420.658544 -371.783102)
		(stroke
			(width 0.07112)
			(type default)
		)
		(layer "In13.Cu")
	)
	(gr_line
		(start 420.658544 -371.783102)
		(end 421.085264 -371.783102)
		(stroke
			(width 0.07112)
			(type default)
		)
		(layer "In13.Cu")
	)
	(gr_line
		(start 421.05707 -377.1265)
		(end 420.76624 -377.41733)
		(stroke
			(width 0.07112)
			(type default)
		)
		(layer "In13.Cu")
	)
	(gr_line
		(start 421.085264 -371.783102)
		(end 421.221154 -371.647212)
		(stroke
			(width 0.07112)
			(type default)
		)
		(layer "In13.Cu")
	)
	(gr_line
		(start 421.33901 -377.1265)
		(end 421.62984 -377.41733)
		(stroke
			(width 0.07112)
			(type default)
		)
		(layer "In13.Cu")
	)
	(gr_line
		(start 421.649144 -371.364002)
		(end 422.350184 -371.364002)
		(stroke
			(width 0.07112)
			(type default)
		)
		(layer "In13.Cu")
	)
	(gr_line
		(start 421.650414 -371.647212)
		(end 421.786304 -371.783102)
		(stroke
			(width 0.07112)
			(type default)
		)
		(layer "In13.Cu")
	)
	(gr_line
		(start 421.786304 -371.783102)
		(end 422.213024 -371.783102)
		(stroke
			(width 0.07112)
			(type default)
		)
		(layer "In13.Cu")
	)
	(gr_line
		(start 422.213024 -371.783102)
		(end 422.348914 -371.647212)
		(stroke
			(width 0.07112)
			(type default)
		)
		(layer "In13.Cu")
	)
	(gr_line
		(start 422.776904 -371.364002)
		(end 423.477944 -371.364002)
		(stroke
			(width 0.07112)
			(type default)
		)
		(layer "In13.Cu")
	)
	(gr_line
		(start 422.778174 -371.647212)
		(end 422.914064 -371.783102)
		(stroke
			(width 0.07112)
			(type default)
		)
		(layer "In13.Cu")
	)
	(gr_line
		(start 422.914064 -371.783102)
		(end 423.340784 -371.783102)
		(stroke
			(width 0.07112)
			(type default)
		)
		(layer "In13.Cu")
	)
	(gr_line
		(start 423.340784 -371.783102)
		(end 423.476674 -371.647212)
		(stroke
			(width 0.07112)
			(type default)
		)
		(layer "In13.Cu")
	)
	(gr_line
		(start 424.46067 -377.1265)
		(end 424.16984 -377.41733)
		(stroke
			(width 0.07112)
			(type default)
		)
		(layer "In13.Cu")
	)
	(gr_line
		(start 424.74261 -377.1265)
		(end 425.03344 -377.41733)
		(stroke
			(width 0.07112)
			(type default)
		)
		(layer "In13.Cu")
	)
	(gr_line
		(start 424.938444 -374.392444)
		(end 425.24045 -374.69445)
		(stroke
			(width 0.07112)
			(type default)
		)
		(layer "In13.Cu")
	)
	(gr_line
		(start 424.938444 -374.200166)
		(end 424.938444 -374.392444)
		(stroke
			(width 0.07112)
			(type default)
		)
		(layer "In13.Cu")
	)
	(gr_line
		(start 425.137834 -373.998998)
		(end 425.633896 -374.49506)
		(stroke
			(width 0.07112)
			(type default)
		)
		(layer "In13.Cu")
	)
	(gr_line
		(start 425.24045 -374.69445)
		(end 425.432728 -374.69445)
		(stroke
			(width 0.07112)
			(type default)
		)
		(layer "In13.Cu")
	)
	(gr_line
		(start 426.619416 -376.810524)
		(end 426.921422 -377.11253)
		(stroke
			(width 0.07112)
			(type default)
		)
		(layer "In13.Cu")
	)
	(gr_line
		(start 426.619416 -376.6185)
		(end 426.619416 -376.810524)
		(stroke
			(width 0.07112)
			(type default)
		)
		(layer "In13.Cu")
	)
	(gr_line
		(start 426.818806 -376.417332)
		(end 427.314614 -376.91314)
		(stroke
			(width 0.07112)
			(type default)
		)
		(layer "In13.Cu")
	)
	(gr_line
		(start 426.921422 -377.11253)
		(end 427.113446 -377.11253)
		(stroke
			(width 0.07112)
			(type default)
		)
		(layer "In13.Cu")
	)
	(gr_line
		(start 427.19625 -388.451598)
		(end 426.90542 -388.742428)
		(stroke
			(width 0.07112)
			(type default)
		)
		(layer "In13.Cu")
	)
	(gr_line
		(start 427.19625 -388.169658)
		(end 426.90542 -387.878828)
		(stroke
			(width 0.07112)
			(type default)
		)
		(layer "In13.Cu")
	)
	(gr_line
		(start 427.19625 -385.047998)
		(end 426.90542 -385.338828)
		(stroke
			(width 0.07112)
			(type default)
		)
		(layer "In13.Cu")
	)
	(gr_line
		(start 427.19625 -384.766058)
		(end 426.90542 -384.475228)
		(stroke
			(width 0.07112)
			(type default)
		)
		(layer "In13.Cu")
	)
	(gr_line
		(start 427.736 -382.99136)
		(end 427.87189 -383.12725)
		(stroke
			(width 0.07112)
			(type default)
		)
		(layer "In13.Cu")
	)
	(gr_line
		(start 427.736 -382.56464)
		(end 427.736 -382.99136)
		(stroke
			(width 0.07112)
			(type default)
		)
		(layer "In13.Cu")
	)
	(gr_line
		(start 427.736 -381.481838)
		(end 427.87189 -381.617728)
		(stroke
			(width 0.07112)
			(type default)
		)
		(layer "In13.Cu")
	)
	(gr_line
		(start 427.736 -381.055118)
		(end 427.736 -381.481838)
		(stroke
			(width 0.07112)
			(type default)
		)
		(layer "In13.Cu")
	)
	(gr_line
		(start 427.87189 -382.42875)
		(end 427.736 -382.56464)
		(stroke
			(width 0.07112)
			(type default)
		)
		(layer "In13.Cu")
	)
	(gr_line
		(start 427.87189 -380.919228)
		(end 427.736 -381.055118)
		(stroke
			(width 0.07112)
			(type default)
		)
		(layer "In13.Cu")
	)
	(gr_line
		(start 428.1551 -382.42748)
		(end 428.1551 -383.12852)
		(stroke
			(width 0.07112)
			(type default)
		)
		(layer "In13.Cu")
	)
	(gr_line
		(start 428.1551 -380.917958)
		(end 428.1551 -381.618998)
		(stroke
			(width 0.07112)
			(type default)
		)
		(layer "In13.Cu")
	)
	(gr_line
		(start 0 -77.671676)
		(end 0 -13.780008)
		(stroke
			(width 1.016)
			(type default)
		)
		(layer "In14.Cu")
	)
	(gr_arc
		(start 0 -77.671676)
		(mid 0.152237 -78.436936)
		(end 0.585724 -79.085694)
		(stroke
			(width 1.016)
			(type default)
		)
		(layer "In14.Cu")
	)
	(gr_poly
		(pts
			(arc
				(start 279.248108 -392.23696)
				(mid 279.284029 -392.222081)
				(end 279.298908 -392.18616)
			)
			(arc
				(start 279.298908 -383.93116)
				(mid 279.284029 -383.895239)
				(end 279.248108 -383.88036)
			)
			(arc
				(start 275.026374 -383.88036)
				(mid 275.006851 -383.884261)
				(end 274.990306 -383.895346)
			)
			(arc
				(start 274.766278 -384.119374)
				(mid 274.755167 -384.135908)
				(end 274.751292 -384.155442)
			)
			(arc
				(start 274.751292 -392.107928)
				(mid 274.755193 -392.127451)
				(end 274.766278 -392.143996)
			)
			(arc
				(start 274.844256 -392.221974)
				(mid 274.86079 -392.233085)
				(end 274.880324 -392.23696)
			)
		)
		(stroke
			(width 0)
			(type solid)
		)
		(fill yes)
		(layer "In14.Cu")
		(net "P12V_MAIN_R_0")
	)
	(gr_poly
		(pts
			(arc
				(start 273.15541 -393.27836)
				(mid 273.174933 -393.274459)
				(end 273.191478 -393.263374)
			)
			(xy 273.191732 -393.26312) (xy 273.669252 -392.7856)
			(arc
				(start 273.669506 -392.785346)
				(mid 273.680617 -392.768812)
				(end 273.684492 -392.749278)
			)
			(arc
				(start 273.684492 -384.155442)
				(mid 273.680591 -384.135919)
				(end 273.669506 -384.119374)
			)
			(xy 273.669252 -384.11912) (xy 273.447764 -383.897632) (xy 273.447256 -383.897124)
			(arc
				(start 273.445478 -383.895346)
				(mid 273.428944 -383.884235)
				(end 273.40941 -383.88036)
			)
			(arc
				(start 239.542574 -383.88036)
				(mid 239.523051 -383.884261)
				(end 239.506506 -383.895346)
			)
			(xy 239.506252 -383.8956) (xy 239.03051 -384.371342) (xy 239.030256 -384.371596)
			(arc
				(start 239.028478 -384.373374)
				(mid 239.017367 -384.389908)
				(end 239.013492 -384.409442)
			)
			(arc
				(start 239.013492 -393.003278)
				(mid 239.017393 -393.022801)
				(end 239.028478 -393.039346)
			)
			(xy 239.028732 -393.0396) (xy 239.252252 -393.26312)
			(arc
				(start 239.252506 -393.263374)
				(mid 239.26904 -393.274485)
				(end 239.288574 -393.27836)
			)
		)
		(stroke
			(width 0)
			(type solid)
		)
		(fill yes)
		(layer "In14.Cu")
		(net "P12V_MAIN_R")
	)
	(gr_poly
		(pts
			(arc
				(start 228.921818 -436.47868)
				(mid 228.941341 -436.474779)
				(end 228.957886 -436.463694)
			)
			(arc
				(start 229.664514 -435.757066)
				(mid 229.675625 -435.740532)
				(end 229.6795 -435.720998)
			)
			(arc
				(start 229.6795 -422.180766)
				(mid 229.703653 -422.05925)
				(end 229.772464 -421.95623)
			)
			(arc
				(start 234.67314 -417.055554)
				(mid 234.776172 -416.986773)
				(end 234.897676 -416.96259)
			)
			(arc
				(start 272.037556 -416.96259)
				(mid 272.057079 -416.958689)
				(end 272.073624 -416.947604)
			)
			(arc
				(start 280.035254 -408.985974)
				(mid 280.046365 -408.96944)
				(end 280.05024 -408.949906)
			)
			(arc
				(start 280.05024 -394.963396)
				(mid 280.046339 -394.943873)
				(end 280.035254 -394.927328)
			)
			(xy 280.035 -394.927074) (xy 279.65146 -394.543534)
			(arc
				(start 279.651206 -394.54328)
				(mid 279.634672 -394.532169)
				(end 279.615138 -394.528294)
			)
			(arc
				(start 278.051514 -394.528294)
				(mid 278.036928 -394.530433)
				(end 278.023574 -394.536676)
			)
			(arc
				(start 278.023574 -394.536676)
				(mid 277.823537 -394.629726)
				(end 277.605236 -394.661644)
			)
			(arc
				(start 277.605236 -394.661644)
				(mid 277.421236 -394.639047)
				(end 277.248112 -394.572744)
			)
			(arc
				(start 277.248112 -394.572744)
				(mid 277.224236 -394.566797)
				(end 277.20036 -394.572744)
			)
			(arc
				(start 277.20036 -394.572744)
				(mid 277.027244 -394.639078)
				(end 276.843236 -394.661644)
			)
			(arc
				(start 276.843236 -394.661644)
				(mid 276.624932 -394.629737)
				(end 276.424898 -394.536676)
			)
			(arc
				(start 276.424898 -394.536676)
				(mid 276.411542 -394.53044)
				(end 276.396958 -394.528294)
			)
			(arc
				(start 269.04569 -394.528294)
				(mid 269.030398 -394.53065)
				(end 269.01648 -394.537438)
			)
			(arc
				(start 269.01648 -394.537438)
				(mid 268.808203 -394.640414)
				(end 268.578584 -394.675868)
			)
			(arc
				(start 268.578584 -394.675868)
				(mid 268.394584 -394.653271)
				(end 268.22146 -394.586968)
			)
			(arc
				(start 268.22146 -394.586968)
				(mid 268.197584 -394.581021)
				(end 268.173708 -394.586968)
			)
			(arc
				(start 268.173708 -394.586968)
				(mid 268.000592 -394.653302)
				(end 267.816584 -394.675868)
			)
			(arc
				(start 267.816584 -394.675868)
				(mid 267.586971 -394.640395)
				(end 267.378688 -394.537438)
			)
			(arc
				(start 267.378688 -394.537438)
				(mid 267.364793 -394.530577)
				(end 267.349478 -394.528294)
			)
			(arc
				(start 261.01929 -394.528294)
				(mid 261.003998 -394.53065)
				(end 260.99008 -394.537438)
			)
			(arc
				(start 260.99008 -394.537438)
				(mid 260.781803 -394.640414)
				(end 260.552184 -394.675868)
			)
			(arc
				(start 260.552184 -394.675868)
				(mid 260.368184 -394.653271)
				(end 260.19506 -394.586968)
			)
			(arc
				(start 260.19506 -394.586968)
				(mid 260.171184 -394.581021)
				(end 260.147308 -394.586968)
			)
			(arc
				(start 260.147308 -394.586968)
				(mid 259.974192 -394.653302)
				(end 259.790184 -394.675868)
			)
			(arc
				(start 259.790184 -394.675868)
				(mid 259.560571 -394.640395)
				(end 259.352288 -394.537438)
			)
			(arc
				(start 259.352288 -394.537438)
				(mid 259.338393 -394.530577)
				(end 259.323078 -394.528294)
			)
			(arc
				(start 252.99289 -394.528294)
				(mid 252.977598 -394.53065)
				(end 252.96368 -394.537438)
			)
			(arc
				(start 252.96368 -394.537438)
				(mid 252.755403 -394.640414)
				(end 252.525784 -394.675868)
			)
			(arc
				(start 252.525784 -394.675868)
				(mid 252.341784 -394.653271)
				(end 252.16866 -394.586968)
			)
			(arc
				(start 252.16866 -394.586968)
				(mid 252.144784 -394.581021)
				(end 252.120908 -394.586968)
			)
			(arc
				(start 252.120908 -394.586968)
				(mid 251.947792 -394.653302)
				(end 251.763784 -394.675868)
			)
			(arc
				(start 251.763784 -394.675868)
				(mid 251.534171 -394.640395)
				(end 251.325888 -394.537438)
			)
			(arc
				(start 251.325888 -394.537438)
				(mid 251.311993 -394.530577)
				(end 251.296678 -394.528294)
			)
			(arc
				(start 244.9576 -394.528294)
				(mid 244.942576 -394.530567)
				(end 244.928898 -394.537184)
			)
			(arc
				(start 244.928898 -394.537184)
				(mid 244.722849 -394.637373)
				(end 244.496336 -394.671804)
			)
			(arc
				(start 244.496336 -394.671804)
				(mid 244.312336 -394.649207)
				(end 244.139212 -394.582904)
			)
			(arc
				(start 244.139212 -394.582904)
				(mid 244.115336 -394.576957)
				(end 244.09146 -394.582904)
			)
			(arc
				(start 244.09146 -394.582904)
				(mid 243.918344 -394.649238)
				(end 243.734336 -394.671804)
			)
			(arc
				(start 243.734336 -394.671804)
				(mid 243.507823 -394.637371)
				(end 243.301774 -394.537184)
			)
			(arc
				(start 243.301774 -394.537184)
				(mid 243.288095 -394.53057)
				(end 243.273072 -394.528294)
			)
			(arc
				(start 239.250982 -394.528294)
				(mid 239.215061 -394.543173)
				(end 239.200182 -394.579094)
			)
			(arc
				(start 239.200182 -406.149556)
				(mid 239.176029 -406.271072)
				(end 239.107218 -406.374092)
			)
			(arc
				(start 234.94365 -410.53766)
				(mid 234.840618 -410.606441)
				(end 234.719114 -410.630624)
			)
			(arc
				(start 229.695756 -410.630624)
				(mid 229.676233 -410.634525)
				(end 229.659688 -410.64561)
			)
			(arc
				(start 227.153724 -413.151574)
				(mid 227.050692 -413.220355)
				(end 226.929188 -413.244538)
			)
			(arc
				(start 195.948554 -413.244538)
				(mid 195.929031 -413.248439)
				(end 195.912486 -413.259524)
			)
			(arc
				(start 195.239386 -413.932624)
				(mid 195.228275 -413.949158)
				(end 195.2244 -413.968692)
			)
			(arc
				(start 195.2244 -420.7002)
				(mid 195.228301 -420.719723)
				(end 195.239386 -420.736268)
			)
			(xy 195.23964 -420.736522)
			(arc
				(start 205.961996 -431.458878)
				(mid 206.030777 -431.56191)
				(end 206.05496 -431.683414)
			)
			(arc
				(start 206.05496 -435.078378)
				(mid 206.058861 -435.097901)
				(end 206.069946 -435.114446)
			)
			(arc
				(start 207.419194 -436.463694)
				(mid 207.435728 -436.474805)
				(end 207.455262 -436.47868)
			)
		)
		(stroke
			(width 0)
			(type solid)
		)
		(fill yes)
		(layer "In14.Cu")
		(net "P12V_PSU")
	)
	(gr_poly
		(pts
			(xy 531.7998 -462.519268) (xy 531.855569 -462.518759) (xy 531.966796 -462.510424) (xy 532.077089 -462.4938)
			(xy 532.185831 -462.46898) (xy 532.292414 -462.436103) (xy 532.396243 -462.395354) (xy 532.496736 -462.346959)
			(xy 532.593331 -462.291189) (xy 532.685488 -462.228357) (xy 532.772692 -462.158813) (xy 532.854456 -462.082947)
			(xy 532.930321 -462.001183) (xy 532.999864 -461.913979) (xy 533.062695 -461.821821) (xy 533.118464 -461.725225)
			(xy 533.166858 -461.624732) (xy 533.207607 -461.520903) (xy 533.240483 -461.41432) (xy 533.265302 -461.305577)
			(xy 533.281925 -461.195284) (xy 533.29026 -461.084057) (xy 533.29078 -461.028288) (xy 533.29078 -455.0283)
			(xy 533.290259 -454.972531) (xy 533.281923 -454.861305) (xy 533.265299 -454.751013) (xy 533.24048 -454.642271)
			(xy 533.207603 -454.535688) (xy 533.166854 -454.43186) (xy 533.118459 -454.331368) (xy 533.06269 -454.234773)
			(xy 532.999859 -454.142616) (xy 532.930316 -454.055412) (xy 532.854451 -453.973649) (xy 532.772688 -453.897784)
			(xy 532.685484 -453.828241) (xy 532.593327 -453.76541) (xy 532.496732 -453.709641) (xy 532.39624 -453.661246)
			(xy 532.292412 -453.620497) (xy 532.185829 -453.58762) (xy 532.077087 -453.562801) (xy 531.966795 -453.546177)
			(xy 531.855569 -453.537841) (xy 531.7998 -453.53732) (xy 516.019796 -453.53732) (xy 515.949414 -453.536826)
			(xy 515.808871 -453.528933) (xy 515.668991 -453.513172) (xy 515.530216 -453.489593) (xy 515.392981 -453.45827)
			(xy 515.257718 -453.419302) (xy 515.124852 -453.37281) (xy 514.994803 -453.318942) (xy 514.867978 -453.257866)
			(xy 514.744778 -453.189776) (xy 514.625589 -453.114884) (xy 514.510787 -453.033428) (xy 514.400733 -452.945663)
			(xy 514.295773 -452.851865) (xy 514.196238 -452.75233) (xy 514.10244 -452.64737) (xy 514.014674 -452.537316)
			(xy 513.933218 -452.422514) (xy 513.858326 -452.303325) (xy 513.790236 -452.180125) (xy 513.72916 -452.053301)
			(xy 513.675292 -451.923251) (xy 513.6288 -451.790386) (xy 513.589831 -451.655123) (xy 513.558507 -451.517888)
			(xy 513.534928 -451.379113) (xy 513.519167 -451.239233) (xy 513.511274 -451.09869) (xy 513.510784 -451.028308)
			(xy 513.510784 -312.408316) (xy 513.511268 -312.337933) (xy 513.51916 -312.197389) (xy 513.53492 -312.057508)
			(xy 513.558498 -311.918731) (xy 513.589821 -311.781495) (xy 513.628789 -311.646231) (xy 513.67528 -311.513364)
			(xy 513.729148 -311.383313) (xy 513.790224 -311.256488) (xy 513.858314 -311.133286) (xy 513.933205 -311.014096)
			(xy 514.014662 -310.899292) (xy 514.102427 -310.789237) (xy 514.196225 -310.684276) (xy 514.295761 -310.584739)
			(xy 514.400722 -310.49094) (xy 514.510776 -310.403174) (xy 514.625579 -310.321716) (xy 514.744769 -310.246824)
			(xy 514.86797 -310.178733) (xy 514.994795 -310.117656) (xy 515.124845 -310.063787) (xy 515.257712 -310.017295)
			(xy 515.392976 -309.978326) (xy 515.530212 -309.947002) (xy 515.668989 -309.923423) (xy 515.808869 -309.907662)
			(xy 515.949413 -309.899769) (xy 516.019796 -309.899304) (xy 531.7998 -309.899304) (xy 531.855569 -309.898783)
			(xy 531.966796 -309.890447) (xy 532.077089 -309.873823) (xy 532.185831 -309.849004) (xy 532.292415 -309.816128)
			(xy 532.396243 -309.775378) (xy 532.496737 -309.726984) (xy 532.593332 -309.671215) (xy 532.68549 -309.608384)
			(xy 532.772695 -309.538841) (xy 532.854459 -309.462976) (xy 532.930326 -309.381213) (xy 532.99987 -309.294009)
			(xy 533.062703 -309.201852) (xy 533.118473 -309.105258) (xy 533.166869 -309.004765) (xy 533.20762 -308.900937)
			(xy 533.240498 -308.794355) (xy 533.265319 -308.685613) (xy 533.281945 -308.57532) (xy 533.290282 -308.464093)
			(xy 533.29078 -308.408324) (xy 533.29078 10.40003) (xy 533.290257 10.455798) (xy 533.28192 10.567023)
			(xy 533.265294 10.677313) (xy 533.240473 10.786053) (xy 533.207596 10.892634) (xy 533.166845 10.99646)
			(xy 533.11845 11.09695) (xy 533.06268 11.193543) (xy 532.999848 11.285698) (xy 532.930305 11.3729)
			(xy 532.85444 11.454661) (xy 532.772677 11.530525) (xy 532.685474 11.600066) (xy 532.593318 11.662896)
			(xy 532.496724 11.718664) (xy 532.396232 11.767057) (xy 532.292406 11.807806) (xy 532.185824 11.840681)
			(xy 532.077084 11.8655) (xy 531.966793 11.882123) (xy 531.855568 11.890459) (xy 531.7998 11.89101)
			(xy 475.799912 11.89101) (xy 475.744142 11.890489) (xy 475.632915 11.882155) (xy 475.522621 11.865531)
			(xy 475.413878 11.840713) (xy 475.307293 11.807837) (xy 475.203464 11.767088) (xy 475.10297 11.718694)
			(xy 475.006373 11.662926) (xy 474.914214 11.600094) (xy 474.827008 11.530552) (xy 474.745243 11.454687)
			(xy 474.669376 11.372924) (xy 474.599831 11.28572) (xy 474.536997 11.193563) (xy 474.481225 11.096967)
			(xy 474.432829 10.996475) (xy 474.392077 10.892646) (xy 474.359198 10.786063) (xy 474.334376 10.67732)
			(xy 474.31775 10.567027) (xy 474.309413 10.4558) (xy 474.308932 10.40003) (xy 474.308932 7.335466)
			(xy 526.704041 7.335466) (xy 526.704041 7.464606) (xy 526.711991 7.593501) (xy 526.727861 7.721661)
			(xy 526.75159 7.848602) (xy 526.783089 7.973841) (xy 526.822238 8.096904) (xy 526.868889 8.217323)
			(xy 526.922864 8.334642) (xy 526.983959 8.448416) (xy 527.051942 8.558213) (xy 527.126556 8.663616)
			(xy 527.207517 8.764226) (xy 527.294517 8.859661) (xy 527.387228 8.94956) (xy 527.485298 9.033581)
			(xy 527.588353 9.111405) (xy 527.696004 9.182737) (xy 527.807843 9.247307) (xy 527.923444 9.304869)
			(xy 528.042369 9.355206) (xy 528.164168 9.398126) (xy 528.288378 9.433467) (xy 528.414527 9.461094)
			(xy 528.542139 9.480903) (xy 528.670728 9.492819) (xy 528.799806 9.496796) (xy 528.928884 9.492819)
			(xy 529.057473 9.480903) (xy 529.185085 9.461094) (xy 529.311234 9.433467) (xy 529.435444 9.398126)
			(xy 529.557243 9.355206) (xy 529.676168 9.304869) (xy 529.791769 9.247307) (xy 529.903608 9.182737)
			(xy 530.011259 9.111405) (xy 530.114314 9.033581) (xy 530.212384 8.94956) (xy 530.305095 8.859661)
			(xy 530.392095 8.764226) (xy 530.473056 8.663616) (xy 530.54767 8.558213) (xy 530.615653 8.448416)
			(xy 530.676748 8.334642) (xy 530.730723 8.217323) (xy 530.777374 8.096904) (xy 530.816523 7.973841)
			(xy 530.848022 7.848602) (xy 530.871751 7.721661) (xy 530.887621 7.593501) (xy 530.895571 7.464606)
			(xy 530.896068 7.400036) (xy 530.895571 7.335466) (xy 530.887621 7.206571) (xy 530.871751 7.078411)
			(xy 530.848022 6.95147) (xy 530.816523 6.826231) (xy 530.777374 6.703168) (xy 530.730723 6.582749)
			(xy 530.676748 6.46543) (xy 530.615653 6.351656) (xy 530.54767 6.241859) (xy 530.473056 6.136456)
			(xy 530.392095 6.035846) (xy 530.305095 5.940411) (xy 530.212384 5.850512) (xy 530.114314 5.766491)
			(xy 530.011259 5.688667) (xy 529.903608 5.617335) (xy 529.791769 5.552765) (xy 529.676168 5.495203)
			(xy 529.557243 5.444866) (xy 529.435444 5.401946) (xy 529.311234 5.366605) (xy 529.185085 5.338978)
			(xy 529.057473 5.319169) (xy 528.928884 5.307253) (xy 528.799806 5.303277) (xy 528.670728 5.307253)
			(xy 528.542139 5.319169) (xy 528.414527 5.338978) (xy 528.288378 5.366605) (xy 528.164168 5.401946)
			(xy 528.042369 5.444866) (xy 527.923444 5.495203) (xy 527.807843 5.552765) (xy 527.696004 5.617335)
			(xy 527.588353 5.688667) (xy 527.485298 5.766491) (xy 527.387228 5.850512) (xy 527.294517 5.940411)
			(xy 527.207517 6.035846) (xy 527.126556 6.136456) (xy 527.051942 6.241859) (xy 526.983959 6.351656)
			(xy 526.922864 6.46543) (xy 526.868889 6.582749) (xy 526.822238 6.703168) (xy 526.783089 6.826231)
			(xy 526.75159 6.95147) (xy 526.727861 7.078411) (xy 526.711991 7.206571) (xy 526.704041 7.335466)
			(xy 474.308932 7.335466) (xy 474.308932 -12.515904) (xy 476.704141 -12.515904) (xy 476.704141 -12.386764)
			(xy 476.712091 -12.257869) (xy 476.727961 -12.129709) (xy 476.75169 -12.002768) (xy 476.783189 -11.877529)
			(xy 476.822338 -11.754466) (xy 476.868989 -11.634047) (xy 476.922964 -11.516728) (xy 476.984059 -11.402954)
			(xy 477.052042 -11.293157) (xy 477.126656 -11.187754) (xy 477.207617 -11.087144) (xy 477.294617 -10.991709)
			(xy 477.387328 -10.90181) (xy 477.485398 -10.817789) (xy 477.588453 -10.739965) (xy 477.696104 -10.668633)
			(xy 477.807943 -10.604063) (xy 477.923544 -10.546501) (xy 478.042469 -10.496164) (xy 478.164268 -10.453244)
			(xy 478.288478 -10.417903) (xy 478.414627 -10.390276) (xy 478.542239 -10.370467) (xy 478.670828 -10.358551)
			(xy 478.799906 -10.354575) (xy 478.928984 -10.358551) (xy 479.057573 -10.370467) (xy 479.185185 -10.390276)
			(xy 479.311334 -10.417903) (xy 479.435544 -10.453244) (xy 479.557343 -10.496164) (xy 479.676268 -10.546501)
			(xy 479.791869 -10.604063) (xy 479.903708 -10.668633) (xy 480.011359 -10.739965) (xy 480.114414 -10.817789)
			(xy 480.212484 -10.90181) (xy 480.305195 -10.991709) (xy 480.392195 -11.087144) (xy 480.473156 -11.187754)
			(xy 480.54777 -11.293157) (xy 480.615753 -11.402954) (xy 480.676848 -11.516728) (xy 480.730823 -11.634047)
			(xy 480.777474 -11.754466) (xy 480.816623 -11.877529) (xy 480.848122 -12.002768) (xy 480.871851 -12.129709)
			(xy 480.887721 -12.257869) (xy 480.895671 -12.386764) (xy 480.896168 -12.451334) (xy 480.895671 -12.515904)
			(xy 480.887721 -12.644799) (xy 480.871851 -12.772959) (xy 480.848122 -12.8999) (xy 480.816623 -13.025139)
			(xy 480.777474 -13.148202) (xy 480.730823 -13.268621) (xy 480.676848 -13.38594) (xy 480.615753 -13.499714)
			(xy 480.54777 -13.609511) (xy 480.473156 -13.714914) (xy 480.392195 -13.815524) (xy 480.305195 -13.910959)
			(xy 480.212484 -14.000858) (xy 480.114414 -14.084879) (xy 480.011359 -14.162703) (xy 479.903708 -14.234035)
			(xy 479.791869 -14.298605) (xy 479.676268 -14.356167) (xy 479.557343 -14.406504) (xy 479.435544 -14.449424)
			(xy 479.311334 -14.484765) (xy 479.185185 -14.512392) (xy 479.057573 -14.532201) (xy 478.928984 -14.544117)
			(xy 478.799906 -14.548094) (xy 478.670828 -14.544117) (xy 478.542239 -14.532201) (xy 478.414627 -14.512392)
			(xy 478.288478 -14.484765) (xy 478.164268 -14.449424) (xy 478.042469 -14.406504) (xy 477.923544 -14.356167)
			(xy 477.807943 -14.298605) (xy 477.696104 -14.234035) (xy 477.588453 -14.162703) (xy 477.485398 -14.084879)
			(xy 477.387328 -14.000858) (xy 477.294617 -13.910959) (xy 477.207617 -13.815524) (xy 477.126656 -13.714914)
			(xy 477.052042 -13.609511) (xy 476.984059 -13.499714) (xy 476.922964 -13.38594) (xy 476.868989 -13.268621)
			(xy 476.822338 -13.148202) (xy 476.783189 -13.025139) (xy 476.75169 -12.8999) (xy 476.727961 -12.772959)
			(xy 476.712091 -12.644799) (xy 476.704141 -12.515904) (xy 474.308932 -12.515904) (xy 474.308932 -77.67193)
			(xy 474.308458 -77.765117) (xy 474.300759 -77.951331) (xy 474.28537 -78.137067) (xy 474.262318 -78.32201)
			(xy 474.231642 -78.505841) (xy 474.193396 -78.688247) (xy 474.147643 -78.868917) (xy 474.094463 -79.047542)
			(xy 474.033945 -79.223817) (xy 473.966195 -79.397439) (xy 473.891327 -79.568113) (xy 473.809469 -79.735548)
			(xy 473.720761 -79.899456) (xy 473.625355 -80.059558) (xy 473.523414 -80.21558) (xy 473.415112 -80.367256)
			(xy 473.300633 -80.514327) (xy 473.180175 -80.65654) (xy 473.053942 -80.793654) (xy 472.988386 -80.859884)
			(xy 471.245946 -82.602324) (xy 471.208633 -82.640304) (xy 471.138899 -82.72077) (xy 471.07508 -82.806006)
			(xy 471.017504 -82.895576) (xy 470.966464 -82.989025) (xy 470.922218 -83.085876) (xy 470.884993 -83.185636)
			(xy 470.854978 -83.287798) (xy 470.832326 -83.391839) (xy 470.817153 -83.497232) (xy 470.809535 -83.603438)
			(xy 470.809066 -83.656678) (xy 470.809066 -328.137828) (xy 473.204275 -328.137828) (xy 473.204275 -328.008688)
			(xy 473.212225 -327.879793) (xy 473.228095 -327.751633) (xy 473.251824 -327.624692) (xy 473.283323 -327.499453)
			(xy 473.322472 -327.37639) (xy 473.369123 -327.255971) (xy 473.423098 -327.138652) (xy 473.484193 -327.024878)
			(xy 473.552176 -326.915081) (xy 473.62679 -326.809678) (xy 473.707751 -326.709068) (xy 473.794751 -326.613633)
			(xy 473.887462 -326.523734) (xy 473.985532 -326.439713) (xy 474.088587 -326.361889) (xy 474.196238 -326.290557)
			(xy 474.308077 -326.225987) (xy 474.423678 -326.168425) (xy 474.542603 -326.118088) (xy 474.664402 -326.075168)
			(xy 474.788612 -326.039827) (xy 474.914761 -326.0122) (xy 475.042373 -325.992391) (xy 475.170962 -325.980475)
			(xy 475.30004 -325.976499) (xy 475.429118 -325.980475) (xy 475.557707 -325.992391) (xy 475.685319 -326.0122)
			(xy 475.811468 -326.039827) (xy 475.935678 -326.075168) (xy 476.057477 -326.118088) (xy 476.176402 -326.168425)
			(xy 476.292003 -326.225987) (xy 476.403842 -326.290557) (xy 476.511493 -326.361889) (xy 476.614548 -326.439713)
			(xy 476.712618 -326.523734) (xy 476.805329 -326.613633) (xy 476.892329 -326.709068) (xy 476.97329 -326.809678)
			(xy 477.047904 -326.915081) (xy 477.115887 -327.024878) (xy 477.176982 -327.138652) (xy 477.230957 -327.255971)
			(xy 477.277608 -327.37639) (xy 477.316757 -327.499453) (xy 477.348256 -327.624692) (xy 477.371985 -327.751633)
			(xy 477.387855 -327.879793) (xy 477.395805 -328.008688) (xy 477.396302 -328.073258) (xy 477.395805 -328.137828)
			(xy 477.387855 -328.266723) (xy 477.371985 -328.394883) (xy 477.348256 -328.521824) (xy 477.316757 -328.647063)
			(xy 477.277608 -328.770126) (xy 477.230957 -328.890545) (xy 477.176982 -329.007864) (xy 477.115887 -329.121638)
			(xy 477.047904 -329.231435) (xy 476.97329 -329.336838) (xy 476.892329 -329.437448) (xy 476.805329 -329.532883)
			(xy 476.712618 -329.622782) (xy 476.614548 -329.706803) (xy 476.511493 -329.784627) (xy 476.403842 -329.855959)
			(xy 476.292003 -329.920529) (xy 476.176402 -329.978091) (xy 476.057477 -330.028428) (xy 475.935678 -330.071348)
			(xy 475.811468 -330.106689) (xy 475.685319 -330.134316) (xy 475.557707 -330.154125) (xy 475.429118 -330.166041)
			(xy 475.30004 -330.170018) (xy 475.170962 -330.166041) (xy 475.042373 -330.154125) (xy 474.914761 -330.134316)
			(xy 474.788612 -330.106689) (xy 474.664402 -330.071348) (xy 474.542603 -330.028428) (xy 474.423678 -329.978091)
			(xy 474.308077 -329.920529) (xy 474.196238 -329.855959) (xy 474.088587 -329.784627) (xy 473.985532 -329.706803)
			(xy 473.887462 -329.622782) (xy 473.794751 -329.532883) (xy 473.707751 -329.437448) (xy 473.62679 -329.336838)
			(xy 473.552176 -329.231435) (xy 473.484193 -329.121638) (xy 473.423098 -329.007864) (xy 473.369123 -328.890545)
			(xy 473.322472 -328.770126) (xy 473.283323 -328.647063) (xy 473.251824 -328.521824) (xy 473.228095 -328.394883)
			(xy 473.212225 -328.266723) (xy 473.204275 -328.137828) (xy 470.809066 -328.137828) (xy 470.809066 -404.871936)
			(xy 470.808592 -404.965123) (xy 470.800892 -405.151337) (xy 470.785503 -405.337074) (xy 470.762451 -405.522016)
			(xy 470.731776 -405.705847) (xy 470.693529 -405.888254) (xy 470.647776 -406.068924) (xy 470.594596 -406.247549)
			(xy 470.534079 -406.423823) (xy 470.466329 -406.597446) (xy 470.391461 -406.76812) (xy 470.309603 -406.935555)
			(xy 470.220896 -407.099463) (xy 470.12549 -407.259566) (xy 470.02355 -407.415588) (xy 469.915248 -407.567265)
			(xy 469.80077 -407.714335) (xy 469.680312 -407.856549) (xy 469.554079 -407.993664) (xy 469.48852 -408.05989)
			(xy 468.245698 -409.302712) (xy 468.208406 -409.340689) (xy 468.138712 -409.421147) (xy 468.074932 -409.506369)
			(xy 468.017391 -409.595922) (xy 467.966382 -409.68935) (xy 467.922165 -409.786178) (xy 467.884964 -409.885911)
			(xy 467.85497 -409.988044) (xy 467.832334 -410.092055) (xy 467.817172 -410.197416) (xy 467.809562 -410.303589)
			(xy 467.809072 -410.356812) (xy 467.809072 -439.989976) (xy 467.809593 -440.045746) (xy 467.817926 -440.156975)
			(xy 467.834548 -440.26727) (xy 467.859367 -440.376014) (xy 467.892242 -440.4826) (xy 467.93299 -440.586431)
			(xy 467.981383 -440.686926) (xy 468.037152 -440.783525) (xy 468.099983 -440.875685) (xy 468.169525 -440.962893)
			(xy 468.24539 -441.044659) (xy 468.327153 -441.120528) (xy 468.414357 -441.190075) (xy 468.506514 -441.25291)
			(xy 468.60311 -441.308683) (xy 468.703603 -441.357081) (xy 468.807432 -441.397835) (xy 468.914016 -441.430715)
			(xy 469.022759 -441.455538) (xy 469.133053 -441.472166) (xy 469.244282 -441.480505) (xy 469.300052 -441.480956)
			(xy 471.79992 -441.480956) (xy 471.870302 -441.48145) (xy 472.010845 -441.489344) (xy 472.150724 -441.505105)
			(xy 472.2895 -441.528685) (xy 472.426735 -441.560009) (xy 472.561998 -441.598978) (xy 472.694863 -441.64547)
			(xy 472.824912 -441.699339) (xy 472.951736 -441.760414) (xy 473.074936 -441.828505) (xy 473.194125 -441.903396)
			(xy 473.308927 -441.984852) (xy 473.418981 -442.072617) (xy 473.523941 -442.166415) (xy 473.623477 -442.26595)
			(xy 473.717275 -442.37091) (xy 473.80504 -442.480964) (xy 473.886497 -442.595765) (xy 473.961389 -442.714953)
			(xy 474.02948 -442.838153) (xy 474.090556 -442.964977) (xy 474.144426 -443.095026) (xy 474.190918 -443.227891)
			(xy 474.229888 -443.363154) (xy 474.261212 -443.500389) (xy 474.284793 -443.639164) (xy 474.300555 -443.779043)
			(xy 474.308449 -443.919586) (xy 474.308932 -443.989968) (xy 474.308932 -458.092864) (xy 526.704041 -458.092864)
			(xy 526.704041 -457.963724) (xy 526.711991 -457.834829) (xy 526.727861 -457.706669) (xy 526.75159 -457.579728)
			(xy 526.783089 -457.454489) (xy 526.822238 -457.331426) (xy 526.868889 -457.211007) (xy 526.922864 -457.093688)
			(xy 526.983959 -456.979914) (xy 527.051942 -456.870117) (xy 527.126556 -456.764714) (xy 527.207517 -456.664104)
			(xy 527.294517 -456.568669) (xy 527.387228 -456.47877) (xy 527.485298 -456.394749) (xy 527.588353 -456.316925)
			(xy 527.696004 -456.245593) (xy 527.807843 -456.181023) (xy 527.923444 -456.123461) (xy 528.042369 -456.073124)
			(xy 528.164168 -456.030204) (xy 528.288378 -455.994863) (xy 528.414527 -455.967236) (xy 528.542139 -455.947427)
			(xy 528.670728 -455.935511) (xy 528.799806 -455.931535) (xy 528.928884 -455.935511) (xy 529.057473 -455.947427)
			(xy 529.185085 -455.967236) (xy 529.311234 -455.994863) (xy 529.435444 -456.030204) (xy 529.557243 -456.073124)
			(xy 529.676168 -456.123461) (xy 529.791769 -456.181023) (xy 529.903608 -456.245593) (xy 530.011259 -456.316925)
			(xy 530.114314 -456.394749) (xy 530.212384 -456.47877) (xy 530.305095 -456.568669) (xy 530.392095 -456.664104)
			(xy 530.473056 -456.764714) (xy 530.54767 -456.870117) (xy 530.615653 -456.979914) (xy 530.676748 -457.093688)
			(xy 530.730723 -457.211007) (xy 530.777374 -457.331426) (xy 530.816523 -457.454489) (xy 530.848022 -457.579728)
			(xy 530.871751 -457.706669) (xy 530.887621 -457.834829) (xy 530.895571 -457.963724) (xy 530.896068 -458.028294)
			(xy 530.895571 -458.092864) (xy 530.887621 -458.221759) (xy 530.871751 -458.349919) (xy 530.848022 -458.47686)
			(xy 530.816523 -458.602099) (xy 530.777374 -458.725162) (xy 530.730723 -458.845581) (xy 530.676748 -458.9629)
			(xy 530.615653 -459.076674) (xy 530.54767 -459.186471) (xy 530.473056 -459.291874) (xy 530.392095 -459.392484)
			(xy 530.305095 -459.487919) (xy 530.212384 -459.577818) (xy 530.114314 -459.661839) (xy 530.011259 -459.739663)
			(xy 529.903608 -459.810995) (xy 529.791769 -459.875565) (xy 529.676168 -459.933127) (xy 529.557243 -459.983464)
			(xy 529.435444 -460.026384) (xy 529.311234 -460.061725) (xy 529.185085 -460.089352) (xy 529.057473 -460.109161)
			(xy 528.928884 -460.121077) (xy 528.799806 -460.125054) (xy 528.670728 -460.121077) (xy 528.542139 -460.109161)
			(xy 528.414527 -460.089352) (xy 528.288378 -460.061725) (xy 528.164168 -460.026384) (xy 528.042369 -459.983464)
			(xy 527.923444 -459.933127) (xy 527.807843 -459.875565) (xy 527.696004 -459.810995) (xy 527.588353 -459.739663)
			(xy 527.485298 -459.661839) (xy 527.387228 -459.577818) (xy 527.294517 -459.487919) (xy 527.207517 -459.392484)
			(xy 527.126556 -459.291874) (xy 527.051942 -459.186471) (xy 526.983959 -459.076674) (xy 526.922864 -458.9629)
			(xy 526.868889 -458.845581) (xy 526.822238 -458.725162) (xy 526.783089 -458.602099) (xy 526.75159 -458.47686)
			(xy 526.727861 -458.349919) (xy 526.711991 -458.221759) (xy 526.704041 -458.092864) (xy 474.308932 -458.092864)
			(xy 474.308932 -461.028288) (xy 474.30944 -461.084058) (xy 474.317775 -461.195285) (xy 474.334398 -461.305579)
			(xy 474.359217 -461.414322) (xy 474.392093 -461.520906) (xy 474.432843 -461.624735) (xy 474.481238 -461.725228)
			(xy 474.537007 -461.821824) (xy 474.599839 -461.913982) (xy 474.669383 -462.001187) (xy 474.745248 -462.082952)
			(xy 474.827013 -462.158817) (xy 474.914218 -462.228361) (xy 475.006376 -462.291193) (xy 475.102972 -462.346962)
			(xy 475.203465 -462.395357) (xy 475.307294 -462.436107) (xy 475.413878 -462.468983) (xy 475.522621 -462.493802)
			(xy 475.632915 -462.510425) (xy 475.744142 -462.51876) (xy 475.799912 -462.519268)
		)
		(stroke
			(width 0)
			(type solid)
		)
		(fill yes)
		(layer "In14.Cu")
		(net "T1_GND")
	)
	(gr_poly
		(pts
			(xy 255.800098 -33.611058) (xy 255.832245 -33.610555) (xy 255.89599 -33.602163) (xy 255.958093 -33.585522)
			(xy 256.017493 -33.560917) (xy 256.073173 -33.528769) (xy 256.124181 -33.489628) (xy 256.169643 -33.444164)
			(xy 256.208781 -33.393155) (xy 256.240927 -33.337473) (xy 256.265529 -33.278072) (xy 256.282167 -33.215968)
			(xy 256.290557 -33.152223) (xy 256.29108 -33.120076) (xy 256.29108 -11.780012) (xy 256.291564 -11.709629)
			(xy 256.299456 -11.569085) (xy 256.315217 -11.429205) (xy 256.338795 -11.290428) (xy 256.370118 -11.153191)
			(xy 256.409086 -11.017927) (xy 256.455577 -10.885061) (xy 256.509445 -10.75501) (xy 256.570521 -10.628184)
			(xy 256.638611 -10.504983) (xy 256.713502 -10.385793) (xy 256.794959 -10.27099) (xy 256.882724 -10.160934)
			(xy 256.976523 -10.055973) (xy 257.076059 -9.956436) (xy 257.181019 -9.862637) (xy 257.291074 -9.774871)
			(xy 257.405876 -9.693414) (xy 257.525065 -9.618521) (xy 257.648266 -9.55043) (xy 257.775092 -9.489354)
			(xy 257.905142 -9.435484) (xy 258.038008 -9.388992) (xy 258.173272 -9.350023) (xy 258.310508 -9.318699)
			(xy 258.449285 -9.295119) (xy 258.589165 -9.279358) (xy 258.729709 -9.271465) (xy 258.800092 -9.271)
			(xy 383.601976 -9.271) (xy 383.657746 -9.270492) (xy 383.768975 -9.262159) (xy 383.87927 -9.245536)
			(xy 383.988015 -9.220718) (xy 384.094601 -9.187842) (xy 384.198432 -9.147093) (xy 384.298927 -9.098699)
			(xy 384.395525 -9.04293) (xy 384.487685 -8.980099) (xy 384.574892 -8.910555) (xy 384.656659 -8.83469)
			(xy 384.732527 -8.752926) (xy 384.802073 -8.665721) (xy 384.864907 -8.573562) (xy 384.920679 -8.476966)
			(xy 384.969076 -8.376472) (xy 385.009828 -8.272642) (xy 385.042706 -8.166058) (xy 385.067528 -8.057314)
			(xy 385.084154 -7.947019) (xy 385.092491 -7.83579) (xy 385.092956 -7.78002) (xy 385.092956 0.40005)
			(xy 385.093451 0.470432) (xy 385.101346 0.610973) (xy 385.117109 0.750851) (xy 385.14069 0.889625)
			(xy 385.172015 1.026859) (xy 385.210985 1.16212) (xy 385.257478 1.294984) (xy 385.311348 1.425032)
			(xy 385.372424 1.551855) (xy 385.440515 1.675053) (xy 385.515407 1.79424) (xy 385.596863 1.909041)
			(xy 385.684628 2.019094) (xy 385.778426 2.124052) (xy 385.877961 2.223587) (xy 385.98292 2.317383)
			(xy 386.092974 2.405148) (xy 386.207775 2.486603) (xy 386.326962 2.561494) (xy 386.450161 2.629584)
			(xy 386.576985 2.69066) (xy 386.707033 2.744528) (xy 386.839897 2.79102) (xy 386.975158 2.829989)
			(xy 387.112392 2.861313) (xy 387.251166 2.884893) (xy 387.391045 2.900655) (xy 387.531586 2.908549)
			(xy 387.601968 2.909062) (xy 456.202034 2.909062) (xy 456.272416 2.908567) (xy 456.412959 2.900673)
			(xy 456.552838 2.884911) (xy 456.691613 2.861331) (xy 456.828848 2.830006) (xy 456.96411 2.791037)
			(xy 457.096975 2.744544) (xy 457.227024 2.690676) (xy 457.353848 2.6296) (xy 457.477048 2.561509)
			(xy 457.596236 2.486618) (xy 457.711038 2.405161) (xy 457.821092 2.317396) (xy 457.926052 2.223599)
			(xy 458.025588 2.124064) (xy 458.119386 2.019104) (xy 458.207152 1.909051) (xy 458.288609 1.79425)
			(xy 458.363501 1.675062) (xy 458.431592 1.551862) (xy 458.492669 1.425039) (xy 458.546539 1.29499)
			(xy 458.593032 1.162126) (xy 458.632002 1.026863) (xy 458.663327 0.889629) (xy 458.686909 0.750854)
			(xy 458.702672 0.610975) (xy 458.710567 0.470432) (xy 458.711046 0.40005) (xy 458.711046 -4.844596)
			(xy 464.704165 -4.844596) (xy 464.704165 -4.715456) (xy 464.712115 -4.586561) (xy 464.727985 -4.458401)
			(xy 464.751714 -4.33146) (xy 464.783213 -4.206221) (xy 464.822362 -4.083158) (xy 464.869013 -3.962739)
			(xy 464.922988 -3.84542) (xy 464.984083 -3.731646) (xy 465.052066 -3.621849) (xy 465.12668 -3.516446)
			(xy 465.207641 -3.415836) (xy 465.294641 -3.320401) (xy 465.387352 -3.230502) (xy 465.485422 -3.146481)
			(xy 465.588477 -3.068657) (xy 465.696128 -2.997325) (xy 465.807967 -2.932755) (xy 465.923568 -2.875193)
			(xy 466.042493 -2.824856) (xy 466.164292 -2.781936) (xy 466.288502 -2.746595) (xy 466.414651 -2.718968)
			(xy 466.542263 -2.699159) (xy 466.670852 -2.687243) (xy 466.79993 -2.683267) (xy 466.929008 -2.687243)
			(xy 467.057597 -2.699159) (xy 467.185209 -2.718968) (xy 467.311358 -2.746595) (xy 467.435568 -2.781936)
			(xy 467.557367 -2.824856) (xy 467.676292 -2.875193) (xy 467.791893 -2.932755) (xy 467.903732 -2.997325)
			(xy 468.011383 -3.068657) (xy 468.114438 -3.146481) (xy 468.212508 -3.230502) (xy 468.305219 -3.320401)
			(xy 468.392219 -3.415836) (xy 468.47318 -3.516446) (xy 468.547794 -3.621849) (xy 468.615777 -3.731646)
			(xy 468.676872 -3.84542) (xy 468.730847 -3.962739) (xy 468.777498 -4.083158) (xy 468.816647 -4.206221)
			(xy 468.848146 -4.33146) (xy 468.871875 -4.458401) (xy 468.887745 -4.586561) (xy 468.895695 -4.715456)
			(xy 468.896192 -4.780026) (xy 468.895695 -4.844596) (xy 468.887745 -4.973491) (xy 468.871875 -5.101651)
			(xy 468.848146 -5.228592) (xy 468.816647 -5.353831) (xy 468.777498 -5.476894) (xy 468.730847 -5.597313)
			(xy 468.676872 -5.714632) (xy 468.615777 -5.828406) (xy 468.547794 -5.938203) (xy 468.47318 -6.043606)
			(xy 468.392219 -6.144216) (xy 468.305219 -6.239651) (xy 468.212508 -6.32955) (xy 468.114438 -6.413571)
			(xy 468.011383 -6.491395) (xy 467.903732 -6.562727) (xy 467.791893 -6.627297) (xy 467.676292 -6.684859)
			(xy 467.557367 -6.735196) (xy 467.435568 -6.778116) (xy 467.311358 -6.813457) (xy 467.185209 -6.841084)
			(xy 467.057597 -6.860893) (xy 466.929008 -6.872809) (xy 466.79993 -6.876786) (xy 466.670852 -6.872809)
			(xy 466.542263 -6.860893) (xy 466.414651 -6.841084) (xy 466.288502 -6.813457) (xy 466.164292 -6.778116)
			(xy 466.042493 -6.735196) (xy 465.923568 -6.684859) (xy 465.807967 -6.627297) (xy 465.696128 -6.562727)
			(xy 465.588477 -6.491395) (xy 465.485422 -6.413571) (xy 465.387352 -6.32955) (xy 465.294641 -6.239651)
			(xy 465.207641 -6.144216) (xy 465.12668 -6.043606) (xy 465.052066 -5.938203) (xy 464.984083 -5.828406)
			(xy 464.922988 -5.714632) (xy 464.869013 -5.597313) (xy 464.822362 -5.476894) (xy 464.783213 -5.353831)
			(xy 464.751714 -5.228592) (xy 464.727985 -5.101651) (xy 464.712115 -4.973491) (xy 464.704165 -4.844596)
			(xy 458.711046 -4.844596) (xy 458.711046 -7.78002) (xy 458.711555 -7.835789) (xy 458.719892 -7.947014)
			(xy 458.736517 -8.057305) (xy 458.761338 -8.166046) (xy 458.794216 -8.272628) (xy 458.834967 -8.376454)
			(xy 458.883362 -8.476945) (xy 458.939132 -8.573538) (xy 459.001965 -8.665694) (xy 459.071509 -8.752896)
			(xy 459.147375 -8.834658) (xy 459.229138 -8.910521) (xy 459.316343 -8.980062) (xy 459.4085 -9.042892)
			(xy 459.505096 -9.098659) (xy 459.605588 -9.147052) (xy 459.709416 -9.187799) (xy 459.815999 -9.220674)
			(xy 459.92474 -9.245491) (xy 460.035032 -9.262113) (xy 460.146257 -9.270446) (xy 460.202026 -9.271)
			(xy 469.799924 -9.271) (xy 469.855693 -9.270478) (xy 469.966918 -9.262141) (xy 470.07721 -9.245516)
			(xy 470.18595 -9.220695) (xy 470.292532 -9.187817) (xy 470.396359 -9.147067) (xy 470.49685 -9.098672)
			(xy 470.593444 -9.042903) (xy 470.685601 -8.980071) (xy 470.772804 -8.910528) (xy 470.854566 -8.834664)
			(xy 470.930431 -8.752901) (xy 470.999974 -8.665697) (xy 471.062805 -8.573541) (xy 471.118574 -8.476947)
			(xy 471.166969 -8.376455) (xy 471.207719 -8.272628) (xy 471.240596 -8.166046) (xy 471.265416 -8.057306)
			(xy 471.282041 -7.947014) (xy 471.290378 -7.835789) (xy 471.290904 -7.78002) (xy 471.290904 10.40003)
			(xy 471.290381 10.455799) (xy 471.282044 10.567024) (xy 471.265419 10.677315) (xy 471.240598 10.786055)
			(xy 471.20772 10.892637) (xy 471.16697 10.996464) (xy 471.118574 11.096955) (xy 471.062805 11.193548)
			(xy 470.999973 11.285705) (xy 470.930431 11.372908) (xy 470.854566 11.45467) (xy 470.772803 11.530534)
			(xy 470.6856 11.600077) (xy 470.593443 11.662908) (xy 470.49685 11.718677) (xy 470.396358 11.767072)
			(xy 470.292531 11.807822) (xy 470.18595 11.840699) (xy 470.077209 11.86552) (xy 469.966918 11.882145)
			(xy 469.855693 11.890482) (xy 469.799924 11.89101) (xy 1.999996 11.89101) (xy 1.944227 11.890488)
			(xy 1.833001 11.882153) (xy 1.722709 11.865529) (xy 1.613968 11.840709) (xy 1.507385 11.807832) (xy 1.403558 11.767083)
			(xy 1.303066 11.718688) (xy 1.206471 11.662919) (xy 1.114314 11.600087) (xy 1.027111 11.530545) (xy 0.945348 11.454679)
			(xy 0.869483 11.372916) (xy 0.79994 11.285712) (xy 0.737109 11.193555) (xy 0.68134 11.096961) (xy 0.632946 10.996469)
			(xy 0.592196 10.892641) (xy 0.55932 10.786058) (xy 0.534501 10.677317) (xy 0.517877 10.567025) (xy 0.509541 10.455799)
			(xy 0.509016 10.40003) (xy 0.509016 9.916973) (xy 385.651997 9.916973) (xy 385.651997 10.002723)
			(xy 385.659909 10.088106) (xy 385.675665 10.172396) (xy 385.699132 10.254872) (xy 385.730108 10.334831)
			(xy 385.76833 10.411591) (xy 385.813471 10.484497) (xy 385.865147 10.552926) (xy 385.922916 10.616296)
			(xy 385.986286 10.674065) (xy 386.054715 10.725741) (xy 386.127621 10.770882) (xy 386.204381 10.809104)
			(xy 386.28434 10.84008) (xy 386.366816 10.863547) (xy 386.451106 10.879303) (xy 386.536489 10.887215)
			(xy 386.622239 10.887215) (xy 386.707622 10.879303) (xy 386.791912 10.863547) (xy 386.874388 10.84008)
			(xy 386.954347 10.809104) (xy 387.031107 10.770882) (xy 387.104013 10.725741) (xy 387.172442 10.674065)
			(xy 387.235812 10.616296) (xy 387.293581 10.552926) (xy 387.345257 10.484497) (xy 387.390398 10.411591)
			(xy 387.42862 10.334831) (xy 387.459596 10.254872) (xy 387.483063 10.172396) (xy 387.498819 10.088106)
			(xy 387.506731 10.002723) (xy 387.507226 9.959848) (xy 387.506731 9.916973) (xy 392.001997 9.916973)
			(xy 392.001997 10.002723) (xy 392.009909 10.088106) (xy 392.025665 10.172396) (xy 392.049132 10.254872)
			(xy 392.080108 10.334831) (xy 392.11833 10.411591) (xy 392.163471 10.484497) (xy 392.215147 10.552926)
			(xy 392.272916 10.616296) (xy 392.336286 10.674065) (xy 392.404715 10.725741) (xy 392.477621 10.770882)
			(xy 392.554381 10.809104) (xy 392.63434 10.84008) (xy 392.716816 10.863547) (xy 392.801106 10.879303)
			(xy 392.886489 10.887215) (xy 392.972239 10.887215) (xy 393.057622 10.879303) (xy 393.141912 10.863547)
			(xy 393.224388 10.84008) (xy 393.304347 10.809104) (xy 393.381107 10.770882) (xy 393.454013 10.725741)
			(xy 393.522442 10.674065) (xy 393.585812 10.616296) (xy 393.643581 10.552926) (xy 393.695257 10.484497)
			(xy 393.740398 10.411591) (xy 393.77862 10.334831) (xy 393.809596 10.254872) (xy 393.833063 10.172396)
			(xy 393.848819 10.088106) (xy 393.856731 10.002723) (xy 393.857226 9.959848) (xy 393.856731 9.916973)
			(xy 436.390783 9.916973) (xy 436.390783 10.002723) (xy 436.398695 10.088106) (xy 436.414451 10.172396)
			(xy 436.437918 10.254872) (xy 436.468894 10.334831) (xy 436.507116 10.411591) (xy 436.552257 10.484497)
			(xy 436.603933 10.552926) (xy 436.661702 10.616296) (xy 436.725072 10.674065) (xy 436.793501 10.725741)
			(xy 436.866407 10.770882) (xy 436.943167 10.809104) (xy 437.023126 10.84008) (xy 437.105602 10.863547)
			(xy 437.189892 10.879303) (xy 437.275275 10.887215) (xy 437.361025 10.887215) (xy 437.446408 10.879303)
			(xy 437.530698 10.863547) (xy 437.613174 10.84008) (xy 437.693133 10.809104) (xy 437.769893 10.770882)
			(xy 437.842799 10.725741) (xy 437.911228 10.674065) (xy 437.974598 10.616296) (xy 438.032367 10.552926)
			(xy 438.084043 10.484497) (xy 438.129184 10.411591) (xy 438.167406 10.334831) (xy 438.198382 10.254872)
			(xy 438.221849 10.172396) (xy 438.237605 10.088106) (xy 438.245517 10.002723) (xy 438.246012 9.959848)
			(xy 438.245517 9.916973) (xy 442.740783 9.916973) (xy 442.740783 10.002723) (xy 442.748695 10.088106)
			(xy 442.764451 10.172396) (xy 442.787918 10.254872) (xy 442.818894 10.334831) (xy 442.857116 10.411591)
			(xy 442.902257 10.484497) (xy 442.953933 10.552926) (xy 443.011702 10.616296) (xy 443.075072 10.674065)
			(xy 443.143501 10.725741) (xy 443.216407 10.770882) (xy 443.293167 10.809104) (xy 443.373126 10.84008)
			(xy 443.455602 10.863547) (xy 443.539892 10.879303) (xy 443.625275 10.887215) (xy 443.711025 10.887215)
			(xy 443.796408 10.879303) (xy 443.880698 10.863547) (xy 443.963174 10.84008) (xy 444.043133 10.809104)
			(xy 444.119893 10.770882) (xy 444.192799 10.725741) (xy 444.261228 10.674065) (xy 444.324598 10.616296)
			(xy 444.382367 10.552926) (xy 444.434043 10.484497) (xy 444.479184 10.411591) (xy 444.517406 10.334831)
			(xy 444.548382 10.254872) (xy 444.571849 10.172396) (xy 444.587605 10.088106) (xy 444.595517 10.002723)
			(xy 444.596012 9.959848) (xy 444.595517 9.916973) (xy 444.587605 9.83159) (xy 444.571849 9.7473)
			(xy 444.548382 9.664824) (xy 444.517406 9.584865) (xy 444.479184 9.508105) (xy 444.434043 9.435199)
			(xy 444.382367 9.36677) (xy 444.324598 9.3034) (xy 444.261228 9.245631) (xy 444.192799 9.193955)
			(xy 444.119893 9.148814) (xy 444.043133 9.110592) (xy 443.963174 9.079616) (xy 443.880698 9.056149)
			(xy 443.796408 9.040393) (xy 443.711025 9.032481) (xy 443.625275 9.032481) (xy 443.539892 9.040393)
			(xy 443.455602 9.056149) (xy 443.373126 9.079616) (xy 443.293167 9.110592) (xy 443.216407 9.148814)
			(xy 443.143501 9.193955) (xy 443.075072 9.245631) (xy 443.011702 9.3034) (xy 442.953933 9.36677)
			(xy 442.902257 9.435199) (xy 442.857116 9.508105) (xy 442.818894 9.584865) (xy 442.787918 9.664824)
			(xy 442.764451 9.7473) (xy 442.748695 9.83159) (xy 442.740783 9.916973) (xy 438.245517 9.916973)
			(xy 438.237605 9.83159) (xy 438.221849 9.7473) (xy 438.198382 9.664824) (xy 438.167406 9.584865)
			(xy 438.129184 9.508105) (xy 438.084043 9.435199) (xy 438.032367 9.36677) (xy 437.974598 9.3034)
			(xy 437.911228 9.245631) (xy 437.842799 9.193955) (xy 437.769893 9.148814) (xy 437.693133 9.110592)
			(xy 437.613174 9.079616) (xy 437.530698 9.056149) (xy 437.446408 9.040393) (xy 437.361025 9.032481)
			(xy 437.275275 9.032481) (xy 437.189892 9.040393) (xy 437.105602 9.056149) (xy 437.023126 9.079616)
			(xy 436.943167 9.110592) (xy 436.866407 9.148814) (xy 436.793501 9.193955) (xy 436.725072 9.245631)
			(xy 436.661702 9.3034) (xy 436.603933 9.36677) (xy 436.552257 9.435199) (xy 436.507116 9.508105)
			(xy 436.468894 9.584865) (xy 436.437918 9.664824) (xy 436.414451 9.7473) (xy 436.398695 9.83159)
			(xy 436.390783 9.916973) (xy 393.856731 9.916973) (xy 393.848819 9.83159) (xy 393.833063 9.7473)
			(xy 393.809596 9.664824) (xy 393.77862 9.584865) (xy 393.740398 9.508105) (xy 393.695257 9.435199)
			(xy 393.643581 9.36677) (xy 393.585812 9.3034) (xy 393.522442 9.245631) (xy 393.454013 9.193955)
			(xy 393.381107 9.148814) (xy 393.304347 9.110592) (xy 393.224388 9.079616) (xy 393.141912 9.056149)
			(xy 393.057622 9.040393) (xy 392.972239 9.032481) (xy 392.886489 9.032481) (xy 392.801106 9.040393)
			(xy 392.716816 9.056149) (xy 392.63434 9.079616) (xy 392.554381 9.110592) (xy 392.477621 9.148814)
			(xy 392.404715 9.193955) (xy 392.336286 9.245631) (xy 392.272916 9.3034) (xy 392.215147 9.36677)
			(xy 392.163471 9.435199) (xy 392.11833 9.508105) (xy 392.080108 9.584865) (xy 392.049132 9.664824)
			(xy 392.025665 9.7473) (xy 392.009909 9.83159) (xy 392.001997 9.916973) (xy 387.506731 9.916973)
			(xy 387.498819 9.83159) (xy 387.483063 9.7473) (xy 387.459596 9.664824) (xy 387.42862 9.584865) (xy 387.390398 9.508105)
			(xy 387.345257 9.435199) (xy 387.293581 9.36677) (xy 387.235812 9.3034) (xy 387.172442 9.245631)
			(xy 387.104013 9.193955) (xy 387.031107 9.148814) (xy 386.954347 9.110592) (xy 386.874388 9.079616)
			(xy 386.791912 9.056149) (xy 386.707622 9.040393) (xy 386.622239 9.032481) (xy 386.536489 9.032481)
			(xy 386.451106 9.040393) (xy 386.366816 9.056149) (xy 386.28434 9.079616) (xy 386.204381 9.110592)
			(xy 386.127621 9.148814) (xy 386.054715 9.193955) (xy 385.986286 9.245631) (xy 385.922916 9.3034)
			(xy 385.865147 9.36677) (xy 385.813471 9.435199) (xy 385.76833 9.508105) (xy 385.730108 9.584865)
			(xy 385.699132 9.664824) (xy 385.675665 9.7473) (xy 385.659909 9.83159) (xy 385.651997 9.916973)
			(xy 0.509016 9.916973) (xy 0.509016 7.335466) (xy 2.904225 7.335466) (xy 2.904225 7.464606) (xy 2.912175 7.593501)
			(xy 2.928045 7.721661) (xy 2.951774 7.848602) (xy 2.983273 7.973841) (xy 3.022422 8.096904) (xy 3.069073 8.217323)
			(xy 3.123048 8.334642) (xy 3.184143 8.448416) (xy 3.252126 8.558213) (xy 3.32674 8.663616) (xy 3.407701 8.764226)
			(xy 3.494701 8.859661) (xy 3.587412 8.94956) (xy 3.685482 9.033581) (xy 3.788537 9.111405) (xy 3.896188 9.182737)
			(xy 4.008027 9.247307) (xy 4.123628 9.304869) (xy 4.242553 9.355206) (xy 4.364352 9.398126) (xy 4.488562 9.433467)
			(xy 4.614711 9.461094) (xy 4.742323 9.480903) (xy 4.870912 9.492819) (xy 4.99999 9.496796) (xy 5.129068 9.492819)
			(xy 5.257657 9.480903) (xy 5.385269 9.461094) (xy 5.511418 9.433467) (xy 5.635628 9.398126) (xy 5.757427 9.355206)
			(xy 5.876352 9.304869) (xy 5.991953 9.247307) (xy 6.103792 9.182737) (xy 6.211443 9.111405) (xy 6.314498 9.033581)
			(xy 6.412568 8.94956) (xy 6.505279 8.859661) (xy 6.51416 8.849919) (xy 208.661241 8.849919) (xy 208.661241 8.935669)
			(xy 208.669153 9.021052) (xy 208.684909 9.105342) (xy 208.708376 9.187818) (xy 208.739352 9.267777)
			(xy 208.777574 9.344537) (xy 208.822715 9.417443) (xy 208.874391 9.485872) (xy 208.93216 9.549242)
			(xy 208.99553 9.607011) (xy 209.063959 9.658687) (xy 209.136865 9.703828) (xy 209.213625 9.74205)
			(xy 209.293584 9.773026) (xy 209.37606 9.796493) (xy 209.46035 9.812249) (xy 209.545733 9.820161)
			(xy 209.631483 9.820161) (xy 209.716866 9.812249) (xy 209.801156 9.796493) (xy 209.883632 9.773026)
			(xy 209.963591 9.74205) (xy 210.040351 9.703828) (xy 210.113257 9.658687) (xy 210.181686 9.607011)
			(xy 210.245056 9.549242) (xy 210.302825 9.485872) (xy 210.354501 9.417443) (xy 210.399642 9.344537)
			(xy 210.437864 9.267777) (xy 210.46884 9.187818) (xy 210.492307 9.105342) (xy 210.508063 9.021052)
			(xy 210.515975 8.935669) (xy 210.51647 8.892794) (xy 210.515975 8.849919) (xy 215.011241 8.849919)
			(xy 215.011241 8.935669) (xy 215.019153 9.021052) (xy 215.034909 9.105342) (xy 215.058376 9.187818)
			(xy 215.089352 9.267777) (xy 215.127574 9.344537) (xy 215.172715 9.417443) (xy 215.224391 9.485872)
			(xy 215.28216 9.549242) (xy 215.34553 9.607011) (xy 215.413959 9.658687) (xy 215.486865 9.703828)
			(xy 215.563625 9.74205) (xy 215.643584 9.773026) (xy 215.72606 9.796493) (xy 215.81035 9.812249)
			(xy 215.895733 9.820161) (xy 215.981483 9.820161) (xy 216.066866 9.812249) (xy 216.151156 9.796493)
			(xy 216.233632 9.773026) (xy 216.313591 9.74205) (xy 216.390351 9.703828) (xy 216.463257 9.658687)
			(xy 216.531686 9.607011) (xy 216.595056 9.549242) (xy 216.652825 9.485872) (xy 216.704501 9.417443)
			(xy 216.749642 9.344537) (xy 216.787864 9.267777) (xy 216.81884 9.187818) (xy 216.842307 9.105342)
			(xy 216.858063 9.021052) (xy 216.865975 8.935669) (xy 216.86647 8.892794) (xy 216.865975 8.849919)
			(xy 296.143921 8.849919) (xy 296.143921 8.935669) (xy 296.151833 9.021052) (xy 296.167589 9.105342)
			(xy 296.191056 9.187818) (xy 296.222032 9.267777) (xy 296.260254 9.344537) (xy 296.305395 9.417443)
			(xy 296.357071 9.485872) (xy 296.41484 9.549242) (xy 296.47821 9.607011) (xy 296.546639 9.658687)
			(xy 296.619545 9.703828) (xy 296.696305 9.74205) (xy 296.776264 9.773026) (xy 296.85874 9.796493)
			(xy 296.94303 9.812249) (xy 297.028413 9.820161) (xy 297.114163 9.820161) (xy 297.199546 9.812249)
			(xy 297.283836 9.796493) (xy 297.366312 9.773026) (xy 297.446271 9.74205) (xy 297.523031 9.703828)
			(xy 297.595937 9.658687) (xy 297.664366 9.607011) (xy 297.727736 9.549242) (xy 297.785505 9.485872)
			(xy 297.837181 9.417443) (xy 297.882322 9.344537) (xy 297.920544 9.267777) (xy 297.95152 9.187818)
			(xy 297.974987 9.105342) (xy 297.990743 9.021052) (xy 297.998655 8.935669) (xy 297.99915 8.892794)
			(xy 297.998655 8.849919) (xy 302.493921 8.849919) (xy 302.493921 8.935669) (xy 302.501833 9.021052)
			(xy 302.517589 9.105342) (xy 302.541056 9.187818) (xy 302.572032 9.267777) (xy 302.610254 9.344537)
			(xy 302.655395 9.417443) (xy 302.707071 9.485872) (xy 302.76484 9.549242) (xy 302.82821 9.607011)
			(xy 302.896639 9.658687) (xy 302.969545 9.703828) (xy 303.046305 9.74205) (xy 303.126264 9.773026)
			(xy 303.20874 9.796493) (xy 303.29303 9.812249) (xy 303.378413 9.820161) (xy 303.464163 9.820161)
			(xy 303.549546 9.812249) (xy 303.633836 9.796493) (xy 303.716312 9.773026) (xy 303.796271 9.74205)
			(xy 303.873031 9.703828) (xy 303.945937 9.658687) (xy 304.014366 9.607011) (xy 304.077736 9.549242)
			(xy 304.135505 9.485872) (xy 304.187181 9.417443) (xy 304.232322 9.344537) (xy 304.270544 9.267777)
			(xy 304.30152 9.187818) (xy 304.324987 9.105342) (xy 304.340743 9.021052) (xy 304.348655 8.935669)
			(xy 304.34915 8.892794) (xy 304.348655 8.849919) (xy 311.155321 8.849919) (xy 311.155321 8.935669)
			(xy 311.163233 9.021052) (xy 311.178989 9.105342) (xy 311.202456 9.187818) (xy 311.233432 9.267777)
			(xy 311.271654 9.344537) (xy 311.316795 9.417443) (xy 311.368471 9.485872) (xy 311.42624 9.549242)
			(xy 311.48961 9.607011) (xy 311.558039 9.658687) (xy 311.630945 9.703828) (xy 311.707705 9.74205)
			(xy 311.787664 9.773026) (xy 311.87014 9.796493) (xy 311.95443 9.812249) (xy 312.039813 9.820161)
			(xy 312.125563 9.820161) (xy 312.210946 9.812249) (xy 312.295236 9.796493) (xy 312.377712 9.773026)
			(xy 312.457671 9.74205) (xy 312.534431 9.703828) (xy 312.607337 9.658687) (xy 312.675766 9.607011)
			(xy 312.739136 9.549242) (xy 312.796905 9.485872) (xy 312.848581 9.417443) (xy 312.893722 9.344537)
			(xy 312.931944 9.267777) (xy 312.96292 9.187818) (xy 312.986387 9.105342) (xy 313.002143 9.021052)
			(xy 313.010055 8.935669) (xy 313.01055 8.892794) (xy 313.010055 8.849919) (xy 317.505321 8.849919)
			(xy 317.505321 8.935669) (xy 317.513233 9.021052) (xy 317.528989 9.105342) (xy 317.552456 9.187818)
			(xy 317.583432 9.267777) (xy 317.621654 9.344537) (xy 317.666795 9.417443) (xy 317.718471 9.485872)
			(xy 317.77624 9.549242) (xy 317.83961 9.607011) (xy 317.908039 9.658687) (xy 317.980945 9.703828)
			(xy 318.057705 9.74205) (xy 318.137664 9.773026) (xy 318.22014 9.796493) (xy 318.30443 9.812249)
			(xy 318.389813 9.820161) (xy 318.475563 9.820161) (xy 318.560946 9.812249) (xy 318.645236 9.796493)
			(xy 318.727712 9.773026) (xy 318.807671 9.74205) (xy 318.884431 9.703828) (xy 318.957337 9.658687)
			(xy 319.025766 9.607011) (xy 319.089136 9.549242) (xy 319.146905 9.485872) (xy 319.198581 9.417443)
			(xy 319.243722 9.344537) (xy 319.281944 9.267777) (xy 319.31292 9.187818) (xy 319.336387 9.105342)
			(xy 319.352143 9.021052) (xy 319.360055 8.935669) (xy 319.36055 8.892794) (xy 319.360055 8.849919)
			(xy 361.894107 8.849919) (xy 361.894107 8.935669) (xy 361.902019 9.021052) (xy 361.917775 9.105342)
			(xy 361.941242 9.187818) (xy 361.972218 9.267777) (xy 362.01044 9.344537) (xy 362.055581 9.417443)
			(xy 362.107257 9.485872) (xy 362.165026 9.549242) (xy 362.228396 9.607011) (xy 362.296825 9.658687)
			(xy 362.369731 9.703828) (xy 362.446491 9.74205) (xy 362.52645 9.773026) (xy 362.608926 9.796493)
			(xy 362.693216 9.812249) (xy 362.778599 9.820161) (xy 362.864349 9.820161) (xy 362.949732 9.812249)
			(xy 363.034022 9.796493) (xy 363.116498 9.773026) (xy 363.196457 9.74205) (xy 363.273217 9.703828)
			(xy 363.346123 9.658687) (xy 363.414552 9.607011) (xy 363.477922 9.549242) (xy 363.535691 9.485872)
			(xy 363.587367 9.417443) (xy 363.632508 9.344537) (xy 363.67073 9.267777) (xy 363.701706 9.187818)
			(xy 363.725173 9.105342) (xy 363.740929 9.021052) (xy 363.748841 8.935669) (xy 363.749336 8.892794)
			(xy 363.748841 8.849919) (xy 368.244107 8.849919) (xy 368.244107 8.935669) (xy 368.252019 9.021052)
			(xy 368.267775 9.105342) (xy 368.291242 9.187818) (xy 368.322218 9.267777) (xy 368.36044 9.344537)
			(xy 368.405581 9.417443) (xy 368.457257 9.485872) (xy 368.515026 9.549242) (xy 368.578396 9.607011)
			(xy 368.646825 9.658687) (xy 368.719731 9.703828) (xy 368.796491 9.74205) (xy 368.87645 9.773026)
			(xy 368.958926 9.796493) (xy 369.043216 9.812249) (xy 369.128599 9.820161) (xy 369.214349 9.820161)
			(xy 369.299732 9.812249) (xy 369.384022 9.796493) (xy 369.466498 9.773026) (xy 369.546457 9.74205)
			(xy 369.623217 9.703828) (xy 369.696123 9.658687) (xy 369.764552 9.607011) (xy 369.827922 9.549242)
			(xy 369.885691 9.485872) (xy 369.937367 9.417443) (xy 369.982508 9.344537) (xy 370.02073 9.267777)
			(xy 370.051706 9.187818) (xy 370.075173 9.105342) (xy 370.090929 9.021052) (xy 370.098841 8.935669)
			(xy 370.099336 8.892794) (xy 370.098841 8.849919) (xy 370.090929 8.764536) (xy 370.075173 8.680246)
			(xy 370.051706 8.59777) (xy 370.02073 8.517811) (xy 369.982508 8.441051) (xy 369.937367 8.368145)
			(xy 369.885691 8.299716) (xy 369.827922 8.236346) (xy 369.764552 8.178577) (xy 369.696123 8.126901)
			(xy 369.623217 8.08176) (xy 369.546457 8.043538) (xy 369.466498 8.012562) (xy 369.384022 7.989095)
			(xy 369.299732 7.973339) (xy 369.214349 7.965427) (xy 369.128599 7.965427) (xy 369.043216 7.973339)
			(xy 368.958926 7.989095) (xy 368.87645 8.012562) (xy 368.796491 8.043538) (xy 368.719731 8.08176)
			(xy 368.646825 8.126901) (xy 368.578396 8.178577) (xy 368.515026 8.236346) (xy 368.457257 8.299716)
			(xy 368.405581 8.368145) (xy 368.36044 8.441051) (xy 368.322218 8.517811) (xy 368.291242 8.59777)
			(xy 368.267775 8.680246) (xy 368.252019 8.764536) (xy 368.244107 8.849919) (xy 363.748841 8.849919)
			(xy 363.740929 8.764536) (xy 363.725173 8.680246) (xy 363.701706 8.59777) (xy 363.67073 8.517811)
			(xy 363.632508 8.441051) (xy 363.587367 8.368145) (xy 363.535691 8.299716) (xy 363.477922 8.236346)
			(xy 363.414552 8.178577) (xy 363.346123 8.126901) (xy 363.273217 8.08176) (xy 363.196457 8.043538)
			(xy 363.116498 8.012562) (xy 363.034022 7.989095) (xy 362.949732 7.973339) (xy 362.864349 7.965427)
			(xy 362.778599 7.965427) (xy 362.693216 7.973339) (xy 362.608926 7.989095) (xy 362.52645 8.012562)
			(xy 362.446491 8.043538) (xy 362.369731 8.08176) (xy 362.296825 8.126901) (xy 362.228396 8.178577)
			(xy 362.165026 8.236346) (xy 362.107257 8.299716) (xy 362.055581 8.368145) (xy 362.01044 8.441051)
			(xy 361.972218 8.517811) (xy 361.941242 8.59777) (xy 361.917775 8.680246) (xy 361.902019 8.764536)
			(xy 361.894107 8.849919) (xy 319.360055 8.849919) (xy 319.352143 8.764536) (xy 319.336387 8.680246)
			(xy 319.31292 8.59777) (xy 319.281944 8.517811) (xy 319.243722 8.441051) (xy 319.198581 8.368145)
			(xy 319.146905 8.299716) (xy 319.089136 8.236346) (xy 319.025766 8.178577) (xy 318.957337 8.126901)
			(xy 318.884431 8.08176) (xy 318.807671 8.043538) (xy 318.727712 8.012562) (xy 318.645236 7.989095)
			(xy 318.560946 7.973339) (xy 318.475563 7.965427) (xy 318.389813 7.965427) (xy 318.30443 7.973339)
			(xy 318.22014 7.989095) (xy 318.137664 8.012562) (xy 318.057705 8.043538) (xy 317.980945 8.08176)
			(xy 317.908039 8.126901) (xy 317.83961 8.178577) (xy 317.77624 8.236346) (xy 317.718471 8.299716)
			(xy 317.666795 8.368145) (xy 317.621654 8.441051) (xy 317.583432 8.517811) (xy 317.552456 8.59777)
			(xy 317.528989 8.680246) (xy 317.513233 8.764536) (xy 317.505321 8.849919) (xy 313.010055 8.849919)
			(xy 313.002143 8.764536) (xy 312.986387 8.680246) (xy 312.96292 8.59777) (xy 312.931944 8.517811)
			(xy 312.893722 8.441051) (xy 312.848581 8.368145) (xy 312.796905 8.299716) (xy 312.739136 8.236346)
			(xy 312.675766 8.178577) (xy 312.607337 8.126901) (xy 312.534431 8.08176) (xy 312.457671 8.043538)
			(xy 312.377712 8.012562) (xy 312.295236 7.989095) (xy 312.210946 7.973339) (xy 312.125563 7.965427)
			(xy 312.039813 7.965427) (xy 311.95443 7.973339) (xy 311.87014 7.989095) (xy 311.787664 8.012562)
			(xy 311.707705 8.043538) (xy 311.630945 8.08176) (xy 311.558039 8.126901) (xy 311.48961 8.178577)
			(xy 311.42624 8.236346) (xy 311.368471 8.299716) (xy 311.316795 8.368145) (xy 311.271654 8.441051)
			(xy 311.233432 8.517811) (xy 311.202456 8.59777) (xy 311.178989 8.680246) (xy 311.163233 8.764536)
			(xy 311.155321 8.849919) (xy 304.348655 8.849919) (xy 304.340743 8.764536) (xy 304.324987 8.680246)
			(xy 304.30152 8.59777) (xy 304.270544 8.517811) (xy 304.232322 8.441051) (xy 304.187181 8.368145)
			(xy 304.135505 8.299716) (xy 304.077736 8.236346) (xy 304.014366 8.178577) (xy 303.945937 8.126901)
			(xy 303.873031 8.08176) (xy 303.796271 8.043538) (xy 303.716312 8.012562) (xy 303.633836 7.989095)
			(xy 303.549546 7.973339) (xy 303.464163 7.965427) (xy 303.378413 7.965427) (xy 303.29303 7.973339)
			(xy 303.20874 7.989095) (xy 303.126264 8.012562) (xy 303.046305 8.043538) (xy 302.969545 8.08176)
			(xy 302.896639 8.126901) (xy 302.82821 8.178577) (xy 302.76484 8.236346) (xy 302.707071 8.299716)
			(xy 302.655395 8.368145) (xy 302.610254 8.441051) (xy 302.572032 8.517811) (xy 302.541056 8.59777)
			(xy 302.517589 8.680246) (xy 302.501833 8.764536) (xy 302.493921 8.849919) (xy 297.998655 8.849919)
			(xy 297.990743 8.764536) (xy 297.974987 8.680246) (xy 297.95152 8.59777) (xy 297.920544 8.517811)
			(xy 297.882322 8.441051) (xy 297.837181 8.368145) (xy 297.785505 8.299716) (xy 297.727736 8.236346)
			(xy 297.664366 8.178577) (xy 297.595937 8.126901) (xy 297.523031 8.08176) (xy 297.446271 8.043538)
			(xy 297.366312 8.012562) (xy 297.283836 7.989095) (xy 297.199546 7.973339) (xy 297.114163 7.965427)
			(xy 297.028413 7.965427) (xy 296.94303 7.973339) (xy 296.85874 7.989095) (xy 296.776264 8.012562)
			(xy 296.696305 8.043538) (xy 296.619545 8.08176) (xy 296.546639 8.126901) (xy 296.47821 8.178577)
			(xy 296.41484 8.236346) (xy 296.357071 8.299716) (xy 296.305395 8.368145) (xy 296.260254 8.441051)
			(xy 296.222032 8.517811) (xy 296.191056 8.59777) (xy 296.167589 8.680246) (xy 296.151833 8.764536)
			(xy 296.143921 8.849919) (xy 216.865975 8.849919) (xy 216.858063 8.764536) (xy 216.842307 8.680246)
			(xy 216.81884 8.59777) (xy 216.787864 8.517811) (xy 216.749642 8.441051) (xy 216.704501 8.368145)
			(xy 216.652825 8.299716) (xy 216.595056 8.236346) (xy 216.531686 8.178577) (xy 216.463257 8.126901)
			(xy 216.390351 8.08176) (xy 216.313591 8.043538) (xy 216.233632 8.012562) (xy 216.151156 7.989095)
			(xy 216.066866 7.973339) (xy 215.981483 7.965427) (xy 215.895733 7.965427) (xy 215.81035 7.973339)
			(xy 215.72606 7.989095) (xy 215.643584 8.012562) (xy 215.563625 8.043538) (xy 215.486865 8.08176)
			(xy 215.413959 8.126901) (xy 215.34553 8.178577) (xy 215.28216 8.236346) (xy 215.224391 8.299716)
			(xy 215.172715 8.368145) (xy 215.127574 8.441051) (xy 215.089352 8.517811) (xy 215.058376 8.59777)
			(xy 215.034909 8.680246) (xy 215.019153 8.764536) (xy 215.011241 8.849919) (xy 210.515975 8.849919)
			(xy 210.508063 8.764536) (xy 210.492307 8.680246) (xy 210.46884 8.59777) (xy 210.437864 8.517811)
			(xy 210.399642 8.441051) (xy 210.354501 8.368145) (xy 210.302825 8.299716) (xy 210.245056 8.236346)
			(xy 210.181686 8.178577) (xy 210.113257 8.126901) (xy 210.040351 8.08176) (xy 209.963591 8.043538)
			(xy 209.883632 8.012562) (xy 209.801156 7.989095) (xy 209.716866 7.973339) (xy 209.631483 7.965427)
			(xy 209.545733 7.965427) (xy 209.46035 7.973339) (xy 209.37606 7.989095) (xy 209.293584 8.012562)
			(xy 209.213625 8.043538) (xy 209.136865 8.08176) (xy 209.063959 8.126901) (xy 208.99553 8.178577)
			(xy 208.93216 8.236346) (xy 208.874391 8.299716) (xy 208.822715 8.368145) (xy 208.777574 8.441051)
			(xy 208.739352 8.517811) (xy 208.708376 8.59777) (xy 208.684909 8.680246) (xy 208.669153 8.764536)
			(xy 208.661241 8.849919) (xy 6.51416 8.849919) (xy 6.592279 8.764226) (xy 6.67324 8.663616) (xy 6.747854 8.558213)
			(xy 6.815837 8.448416) (xy 6.876932 8.334642) (xy 6.930907 8.217323) (xy 6.977558 8.096904) (xy 7.016707 7.973841)
			(xy 7.048206 7.848602) (xy 7.071935 7.721661) (xy 7.087805 7.593501) (xy 7.095755 7.464606) (xy 7.096252 7.400036)
			(xy 7.095755 7.335466) (xy 7.092973 7.290359) (xy 93.985575 7.290359) (xy 93.985575 7.376109) (xy 93.993487 7.461492)
			(xy 94.009243 7.545782) (xy 94.03271 7.628258) (xy 94.063686 7.708217) (xy 94.101908 7.784977) (xy 94.147049 7.857883)
			(xy 94.198725 7.926312) (xy 94.256494 7.989682) (xy 94.319864 8.047451) (xy 94.388293 8.099127) (xy 94.461199 8.144268)
			(xy 94.537959 8.18249) (xy 94.617918 8.213466) (xy 94.700394 8.236933) (xy 94.784684 8.252689) (xy 94.870067 8.260601)
			(xy 94.955817 8.260601) (xy 95.0412 8.252689) (xy 95.12549 8.236933) (xy 95.207966 8.213466) (xy 95.287925 8.18249)
			(xy 95.364685 8.144268) (xy 95.437591 8.099127) (xy 95.50602 8.047451) (xy 95.56939 7.989682) (xy 95.627159 7.926312)
			(xy 95.678835 7.857883) (xy 95.723976 7.784977) (xy 95.762198 7.708217) (xy 95.793174 7.628258) (xy 95.816641 7.545782)
			(xy 95.832397 7.461492) (xy 95.840309 7.376109) (xy 95.840804 7.333234) (xy 95.840309 7.290359) (xy 100.335575 7.290359)
			(xy 100.335575 7.376109) (xy 100.343487 7.461492) (xy 100.359243 7.545782) (xy 100.38271 7.628258)
			(xy 100.413686 7.708217) (xy 100.451908 7.784977) (xy 100.497049 7.857883) (xy 100.548725 7.926312)
			(xy 100.606494 7.989682) (xy 100.669864 8.047451) (xy 100.738293 8.099127) (xy 100.811199 8.144268)
			(xy 100.887959 8.18249) (xy 100.967918 8.213466) (xy 101.050394 8.236933) (xy 101.134684 8.252689)
			(xy 101.220067 8.260601) (xy 101.305817 8.260601) (xy 101.3912 8.252689) (xy 101.47549 8.236933)
			(xy 101.557966 8.213466) (xy 101.637925 8.18249) (xy 101.714685 8.144268) (xy 101.787591 8.099127)
			(xy 101.85602 8.047451) (xy 101.91939 7.989682) (xy 101.977159 7.926312) (xy 102.028835 7.857883)
			(xy 102.073976 7.784977) (xy 102.112198 7.708217) (xy 102.143174 7.628258) (xy 102.166641 7.545782)
			(xy 102.182397 7.461492) (xy 102.190309 7.376109) (xy 102.190804 7.333234) (xy 102.190309 7.290359)
			(xy 181.468255 7.290359) (xy 181.468255 7.376109) (xy 181.476167 7.461492) (xy 181.491923 7.545782)
			(xy 181.51539 7.628258) (xy 181.546366 7.708217) (xy 181.584588 7.784977) (xy 181.629729 7.857883)
			(xy 181.681405 7.926312) (xy 181.739174 7.989682) (xy 181.802544 8.047451) (xy 181.870973 8.099127)
			(xy 181.943879 8.144268) (xy 182.020639 8.18249) (xy 182.100598 8.213466) (xy 182.183074 8.236933)
			(xy 182.267364 8.252689) (xy 182.352747 8.260601) (xy 182.438497 8.260601) (xy 182.52388 8.252689)
			(xy 182.60817 8.236933) (xy 182.690646 8.213466) (xy 182.770605 8.18249) (xy 182.847365 8.144268)
			(xy 182.920271 8.099127) (xy 182.9887 8.047451) (xy 183.05207 7.989682) (xy 183.109839 7.926312)
			(xy 183.161515 7.857883) (xy 183.206656 7.784977) (xy 183.244878 7.708217) (xy 183.275854 7.628258)
			(xy 183.299321 7.545782) (xy 183.315077 7.461492) (xy 183.322989 7.376109) (xy 183.323484 7.333234)
			(xy 183.322989 7.290359) (xy 187.818255 7.290359) (xy 187.818255 7.376109) (xy 187.826167 7.461492)
			(xy 187.841923 7.545782) (xy 187.86539 7.628258) (xy 187.896366 7.708217) (xy 187.934588 7.784977)
			(xy 187.979729 7.857883) (xy 188.031405 7.926312) (xy 188.089174 7.989682) (xy 188.152544 8.047451)
			(xy 188.220973 8.099127) (xy 188.293879 8.144268) (xy 188.370639 8.18249) (xy 188.450598 8.213466)
			(xy 188.533074 8.236933) (xy 188.617364 8.252689) (xy 188.702747 8.260601) (xy 188.788497 8.260601)
			(xy 188.87388 8.252689) (xy 188.95817 8.236933) (xy 189.040646 8.213466) (xy 189.120605 8.18249)
			(xy 189.197365 8.144268) (xy 189.270271 8.099127) (xy 189.3387 8.047451) (xy 189.40207 7.989682)
			(xy 189.459839 7.926312) (xy 189.511515 7.857883) (xy 189.556656 7.784977) (xy 189.594878 7.708217)
			(xy 189.625854 7.628258) (xy 189.649321 7.545782) (xy 189.665077 7.461492) (xy 189.672989 7.376109)
			(xy 189.673484 7.333234) (xy 189.672989 7.290359) (xy 189.665077 7.204976) (xy 189.649321 7.120686)
			(xy 189.625854 7.03821) (xy 189.594878 6.958251) (xy 189.556656 6.881491) (xy 189.511515 6.808585)
			(xy 189.459839 6.740156) (xy 189.40207 6.676786) (xy 189.3387 6.619017) (xy 189.270271 6.567341)
			(xy 189.197365 6.5222) (xy 189.120605 6.483978) (xy 189.040646 6.453002) (xy 188.95817 6.429535)
			(xy 188.87388 6.413779) (xy 188.788497 6.405867) (xy 188.702747 6.405867) (xy 188.617364 6.413779)
			(xy 188.533074 6.429535) (xy 188.450598 6.453002) (xy 188.370639 6.483978) (xy 188.293879 6.5222)
			(xy 188.220973 6.567341) (xy 188.152544 6.619017) (xy 188.089174 6.676786) (xy 188.031405 6.740156)
			(xy 187.979729 6.808585) (xy 187.934588 6.881491) (xy 187.896366 6.958251) (xy 187.86539 7.03821)
			(xy 187.841923 7.120686) (xy 187.826167 7.204976) (xy 187.818255 7.290359) (xy 183.322989 7.290359)
			(xy 183.315077 7.204976) (xy 183.299321 7.120686) (xy 183.275854 7.03821) (xy 183.244878 6.958251)
			(xy 183.206656 6.881491) (xy 183.161515 6.808585) (xy 183.109839 6.740156) (xy 183.05207 6.676786)
			(xy 182.9887 6.619017) (xy 182.920271 6.567341) (xy 182.847365 6.5222) (xy 182.770605 6.483978) (xy 182.690646 6.453002)
			(xy 182.60817 6.429535) (xy 182.52388 6.413779) (xy 182.438497 6.405867) (xy 182.352747 6.405867)
			(xy 182.267364 6.413779) (xy 182.183074 6.429535) (xy 182.100598 6.453002) (xy 182.020639 6.483978)
			(xy 181.943879 6.5222) (xy 181.870973 6.567341) (xy 181.802544 6.619017) (xy 181.739174 6.676786)
			(xy 181.681405 6.740156) (xy 181.629729 6.808585) (xy 181.584588 6.881491) (xy 181.546366 6.958251)
			(xy 181.51539 7.03821) (xy 181.491923 7.120686) (xy 181.476167 7.204976) (xy 181.468255 7.290359)
			(xy 102.190309 7.290359) (xy 102.182397 7.204976) (xy 102.166641 7.120686) (xy 102.143174 7.03821)
			(xy 102.112198 6.958251) (xy 102.073976 6.881491) (xy 102.028835 6.808585) (xy 101.977159 6.740156)
			(xy 101.91939 6.676786) (xy 101.85602 6.619017) (xy 101.787591 6.567341) (xy 101.714685 6.5222) (xy 101.637925 6.483978)
			(xy 101.557966 6.453002) (xy 101.47549 6.429535) (xy 101.3912 6.413779) (xy 101.305817 6.405867)
			(xy 101.220067 6.405867) (xy 101.134684 6.413779) (xy 101.050394 6.429535) (xy 100.967918 6.453002)
			(xy 100.887959 6.483978) (xy 100.811199 6.5222) (xy 100.738293 6.567341) (xy 100.669864 6.619017)
			(xy 100.606494 6.676786) (xy 100.548725 6.740156) (xy 100.497049 6.808585) (xy 100.451908 6.881491)
			(xy 100.413686 6.958251) (xy 100.38271 7.03821) (xy 100.359243 7.120686) (xy 100.343487 7.204976)
			(xy 100.335575 7.290359) (xy 95.840309 7.290359) (xy 95.832397 7.204976) (xy 95.816641 7.120686)
			(xy 95.793174 7.03821) (xy 95.762198 6.958251) (xy 95.723976 6.881491) (xy 95.678835 6.808585) (xy 95.627159 6.740156)
			(xy 95.56939 6.676786) (xy 95.50602 6.619017) (xy 95.437591 6.567341) (xy 95.364685 6.5222) (xy 95.287925 6.483978)
			(xy 95.207966 6.453002) (xy 95.12549 6.429535) (xy 95.0412 6.413779) (xy 94.955817 6.405867) (xy 94.870067 6.405867)
			(xy 94.784684 6.413779) (xy 94.700394 6.429535) (xy 94.617918 6.453002) (xy 94.537959 6.483978) (xy 94.461199 6.5222)
			(xy 94.388293 6.567341) (xy 94.319864 6.619017) (xy 94.256494 6.676786) (xy 94.198725 6.740156) (xy 94.147049 6.808585)
			(xy 94.101908 6.881491) (xy 94.063686 6.958251) (xy 94.03271 7.03821) (xy 94.009243 7.120686) (xy 93.993487 7.204976)
			(xy 93.985575 7.290359) (xy 7.092973 7.290359) (xy 7.087805 7.206571) (xy 7.071935 7.078411) (xy 7.048206 6.95147)
			(xy 7.016707 6.826231) (xy 6.977558 6.703168) (xy 6.930907 6.582749) (xy 6.876932 6.46543) (xy 6.815837 6.351656)
			(xy 6.747854 6.241859) (xy 6.67324 6.136456) (xy 6.592279 6.035846) (xy 6.505279 5.940411) (xy 6.412568 5.850512)
			(xy 6.314498 5.766491) (xy 6.211443 5.688667) (xy 6.103792 5.617335) (xy 5.991953 5.552765) (xy 5.876352 5.495203)
			(xy 5.757427 5.444866) (xy 5.635628 5.401946) (xy 5.511418 5.366605) (xy 5.385269 5.338978) (xy 5.257657 5.319169)
			(xy 5.129068 5.307253) (xy 4.99999 5.303277) (xy 4.870912 5.307253) (xy 4.742323 5.319169) (xy 4.614711 5.338978)
			(xy 4.488562 5.366605) (xy 4.364352 5.401946) (xy 4.242553 5.444866) (xy 4.123628 5.495203) (xy 4.008027 5.552765)
			(xy 3.896188 5.617335) (xy 3.788537 5.688667) (xy 3.685482 5.766491) (xy 3.587412 5.850512) (xy 3.494701 5.940411)
			(xy 3.407701 6.035846) (xy 3.32674 6.136456) (xy 3.252126 6.241859) (xy 3.184143 6.351656) (xy 3.123048 6.46543)
			(xy 3.069073 6.582749) (xy 3.022422 6.703168) (xy 2.983273 6.826231) (xy 2.951774 6.95147) (xy 2.928045 7.078411)
			(xy 2.912175 7.206571) (xy 2.904225 7.335466) (xy 0.509016 7.335466) (xy 0.509016 4.750359) (xy 93.985575 4.750359)
			(xy 93.985575 4.836109) (xy 93.993487 4.921492) (xy 94.009243 5.005782) (xy 94.03271 5.088258) (xy 94.063686 5.168217)
			(xy 94.101908 5.244977) (xy 94.147049 5.317883) (xy 94.198725 5.386312) (xy 94.256494 5.449682) (xy 94.319864 5.507451)
			(xy 94.388293 5.559127) (xy 94.461199 5.604268) (xy 94.537959 5.64249) (xy 94.617918 5.673466) (xy 94.700394 5.696933)
			(xy 94.784684 5.712689) (xy 94.870067 5.720601) (xy 94.955817 5.720601) (xy 95.0412 5.712689) (xy 95.12549 5.696933)
			(xy 95.207966 5.673466) (xy 95.287925 5.64249) (xy 95.308598 5.632196) (xy 98.842576 5.632196) (xy 98.842576 6.495796)
			(xy 98.84308 6.525332) (xy 98.851124 6.583854) (xy 98.867061 6.640736) (xy 98.890596 6.694918) (xy 98.921289 6.745391)
			(xy 98.958569 6.791214) (xy 99.001741 6.831534) (xy 99.050001 6.8656) (xy 99.102451 6.892777) (xy 99.158112 6.912559)
			(xy 99.215949 6.924578) (xy 99.274884 6.928609) (xy 99.333819 6.924578) (xy 99.391656 6.912559) (xy 99.447317 6.892777)
			(xy 99.499767 6.8656) (xy 99.548027 6.831534) (xy 99.591199 6.791214) (xy 99.628479 6.745391) (xy 99.659172 6.694918)
			(xy 99.682707 6.640736) (xy 99.698644 6.583854) (xy 99.706688 6.525332) (xy 99.707192 6.495796) (xy 99.707192 5.632196)
			(xy 99.706688 5.60266) (xy 99.698644 5.544138) (xy 99.682707 5.487256) (xy 99.659172 5.433074) (xy 99.628479 5.382601)
			(xy 99.591199 5.336778) (xy 99.548027 5.296458) (xy 99.499767 5.262392) (xy 99.447317 5.235215) (xy 99.391656 5.215433)
			(xy 99.333819 5.203414) (xy 99.274884 5.199383) (xy 99.215949 5.203414) (xy 99.158112 5.215433) (xy 99.102451 5.235215)
			(xy 99.050001 5.262392) (xy 99.001741 5.296458) (xy 98.958569 5.336778) (xy 98.921289 5.382601) (xy 98.890596 5.433074)
			(xy 98.867061 5.487256) (xy 98.851124 5.544138) (xy 98.84308 5.60266) (xy 98.842576 5.632196) (xy 95.308598 5.632196)
			(xy 95.364685 5.604268) (xy 95.437591 5.559127) (xy 95.50602 5.507451) (xy 95.56939 5.449682) (xy 95.627159 5.386312)
			(xy 95.678835 5.317883) (xy 95.723976 5.244977) (xy 95.762198 5.168217) (xy 95.793174 5.088258) (xy 95.816641 5.005782)
			(xy 95.832397 4.921492) (xy 95.840309 4.836109) (xy 95.840804 4.793234) (xy 95.840309 4.750359) (xy 100.335575 4.750359)
			(xy 100.335575 4.836109) (xy 100.343487 4.921492) (xy 100.359243 5.005782) (xy 100.38271 5.088258)
			(xy 100.413686 5.168217) (xy 100.451908 5.244977) (xy 100.497049 5.317883) (xy 100.548725 5.386312)
			(xy 100.606494 5.449682) (xy 100.669864 5.507451) (xy 100.738293 5.559127) (xy 100.811199 5.604268)
			(xy 100.887959 5.64249) (xy 100.967918 5.673466) (xy 101.050394 5.696933) (xy 101.134684 5.712689)
			(xy 101.220067 5.720601) (xy 101.305817 5.720601) (xy 101.3912 5.712689) (xy 101.47549 5.696933)
			(xy 101.557966 5.673466) (xy 101.637925 5.64249) (xy 101.714685 5.604268) (xy 101.787591 5.559127)
			(xy 101.85602 5.507451) (xy 101.91939 5.449682) (xy 101.977159 5.386312) (xy 102.028835 5.317883)
			(xy 102.073976 5.244977) (xy 102.112198 5.168217) (xy 102.143174 5.088258) (xy 102.166641 5.005782)
			(xy 102.182397 4.921492) (xy 102.190309 4.836109) (xy 102.190804 4.793234) (xy 102.190309 4.750359)
			(xy 181.468255 4.750359) (xy 181.468255 4.836109) (xy 181.476167 4.921492) (xy 181.491923 5.005782)
			(xy 181.51539 5.088258) (xy 181.546366 5.168217) (xy 181.584588 5.244977) (xy 181.629729 5.317883)
			(xy 181.681405 5.386312) (xy 181.739174 5.449682) (xy 181.802544 5.507451) (xy 181.870973 5.559127)
			(xy 181.943879 5.604268) (xy 182.020639 5.64249) (xy 182.100598 5.673466) (xy 182.183074 5.696933)
			(xy 182.267364 5.712689) (xy 182.352747 5.720601) (xy 182.438497 5.720601) (xy 182.52388 5.712689)
			(xy 182.60817 5.696933) (xy 182.690646 5.673466) (xy 182.770605 5.64249) (xy 182.791278 5.632196)
			(xy 183.953912 5.632196) (xy 183.953912 6.495796) (xy 183.954416 6.525332) (xy 183.96246 6.583854)
			(xy 183.978397 6.640736) (xy 184.001932 6.694918) (xy 184.032625 6.745391) (xy 184.069905 6.791214)
			(xy 184.113077 6.831534) (xy 184.161337 6.8656) (xy 184.213787 6.892777) (xy 184.269448 6.912559)
			(xy 184.327285 6.924578) (xy 184.38622 6.928609) (xy 184.445155 6.924578) (xy 184.502992 6.912559)
			(xy 184.558653 6.892777) (xy 184.611103 6.8656) (xy 184.659363 6.831534) (xy 184.702535 6.791214)
			(xy 184.739815 6.745391) (xy 184.770508 6.694918) (xy 184.794043 6.640736) (xy 184.80998 6.583854)
			(xy 184.818024 6.525332) (xy 184.818528 6.495796) (xy 184.818528 6.309919) (xy 208.661241 6.309919)
			(xy 208.661241 6.395669) (xy 208.669153 6.481052) (xy 208.684909 6.565342) (xy 208.708376 6.647818)
			(xy 208.739352 6.727777) (xy 208.777574 6.804537) (xy 208.822715 6.877443) (xy 208.874391 6.945872)
			(xy 208.93216 7.009242) (xy 208.99553 7.067011) (xy 209.063959 7.118687) (xy 209.136865 7.163828)
			(xy 209.213625 7.20205) (xy 209.293584 7.233026) (xy 209.37606 7.256493) (xy 209.46035 7.272249)
			(xy 209.545733 7.280161) (xy 209.631483 7.280161) (xy 209.716866 7.272249) (xy 209.801156 7.256493)
			(xy 209.883632 7.233026) (xy 209.963591 7.20205) (xy 210.040351 7.163828) (xy 210.113257 7.118687)
			(xy 210.181686 7.067011) (xy 210.245056 7.009242) (xy 210.302825 6.945872) (xy 210.354501 6.877443)
			(xy 210.399642 6.804537) (xy 210.437864 6.727777) (xy 210.46884 6.647818) (xy 210.492307 6.565342)
			(xy 210.508063 6.481052) (xy 210.515975 6.395669) (xy 210.51647 6.352794) (xy 210.515975 6.309919)
			(xy 215.011241 6.309919) (xy 215.011241 6.395669) (xy 215.019153 6.481052) (xy 215.034909 6.565342)
			(xy 215.058376 6.647818) (xy 215.089352 6.727777) (xy 215.127574 6.804537) (xy 215.172715 6.877443)
			(xy 215.224391 6.945872) (xy 215.28216 7.009242) (xy 215.34553 7.067011) (xy 215.413959 7.118687)
			(xy 215.486865 7.163828) (xy 215.563625 7.20205) (xy 215.643584 7.233026) (xy 215.72606 7.256493)
			(xy 215.81035 7.272249) (xy 215.895733 7.280161) (xy 215.981483 7.280161) (xy 216.066866 7.272249)
			(xy 216.151156 7.256493) (xy 216.233632 7.233026) (xy 216.313591 7.20205) (xy 216.390351 7.163828)
			(xy 216.463257 7.118687) (xy 216.531686 7.067011) (xy 216.595056 7.009242) (xy 216.652825 6.945872)
			(xy 216.704501 6.877443) (xy 216.749642 6.804537) (xy 216.787864 6.727777) (xy 216.81884 6.647818)
			(xy 216.842307 6.565342) (xy 216.858063 6.481052) (xy 216.865975 6.395669) (xy 216.86647 6.352794)
			(xy 216.865975 6.309919) (xy 296.143921 6.309919) (xy 296.143921 6.395669) (xy 296.151833 6.481052)
			(xy 296.167589 6.565342) (xy 296.191056 6.647818) (xy 296.222032 6.727777) (xy 296.260254 6.804537)
			(xy 296.305395 6.877443) (xy 296.357071 6.945872) (xy 296.41484 7.009242) (xy 296.47821 7.067011)
			(xy 296.546639 7.118687) (xy 296.619545 7.163828) (xy 296.696305 7.20205) (xy 296.776264 7.233026)
			(xy 296.85874 7.256493) (xy 296.94303 7.272249) (xy 297.028413 7.280161) (xy 297.114163 7.280161)
			(xy 297.199546 7.272249) (xy 297.283836 7.256493) (xy 297.366312 7.233026) (xy 297.446271 7.20205)
			(xy 297.523031 7.163828) (xy 297.595937 7.118687) (xy 297.664366 7.067011) (xy 297.727736 7.009242)
			(xy 297.785505 6.945872) (xy 297.837181 6.877443) (xy 297.882322 6.804537) (xy 297.920544 6.727777)
			(xy 297.95152 6.647818) (xy 297.974987 6.565342) (xy 297.990743 6.481052) (xy 297.998655 6.395669)
			(xy 297.99915 6.352794) (xy 297.998655 6.309919) (xy 302.493921 6.309919) (xy 302.493921 6.395669)
			(xy 302.501833 6.481052) (xy 302.517589 6.565342) (xy 302.541056 6.647818) (xy 302.572032 6.727777)
			(xy 302.610254 6.804537) (xy 302.655395 6.877443) (xy 302.707071 6.945872) (xy 302.76484 7.009242)
			(xy 302.82821 7.067011) (xy 302.896639 7.118687) (xy 302.969545 7.163828) (xy 303.046305 7.20205)
			(xy 303.126264 7.233026) (xy 303.20874 7.256493) (xy 303.29303 7.272249) (xy 303.378413 7.280161)
			(xy 303.464163 7.280161) (xy 303.549546 7.272249) (xy 303.633836 7.256493) (xy 303.716312 7.233026)
			(xy 303.796271 7.20205) (xy 303.873031 7.163828) (xy 303.945937 7.118687) (xy 304.014366 7.067011)
			(xy 304.077736 7.009242) (xy 304.135505 6.945872) (xy 304.187181 6.877443) (xy 304.232322 6.804537)
			(xy 304.270544 6.727777) (xy 304.30152 6.647818) (xy 304.324987 6.565342) (xy 304.340743 6.481052)
			(xy 304.348655 6.395669) (xy 304.34915 6.352794) (xy 304.348655 6.309919) (xy 311.155321 6.309919)
			(xy 311.155321 6.395669) (xy 311.163233 6.481052) (xy 311.178989 6.565342) (xy 311.202456 6.647818)
			(xy 311.233432 6.727777) (xy 311.271654 6.804537) (xy 311.316795 6.877443) (xy 311.368471 6.945872)
			(xy 311.42624 7.009242) (xy 311.48961 7.067011) (xy 311.558039 7.118687) (xy 311.630945 7.163828)
			(xy 311.707705 7.20205) (xy 311.787664 7.233026) (xy 311.87014 7.256493) (xy 311.95443 7.272249)
			(xy 312.039813 7.280161) (xy 312.125563 7.280161) (xy 312.210946 7.272249) (xy 312.295236 7.256493)
			(xy 312.377712 7.233026) (xy 312.457671 7.20205) (xy 312.478344 7.191756) (xy 316.012068 7.191756)
			(xy 316.012068 8.055356) (xy 316.012572 8.08491) (xy 316.020621 8.143466) (xy 316.036567 8.200381)
			(xy 316.060116 8.254595) (xy 316.090827 8.305098) (xy 316.128129 8.350948) (xy 316.171326 8.391291)
			(xy 316.219615 8.425377) (xy 316.272095 8.45257) (xy 316.32779 8.472364) (xy 316.385661 8.48439)
			(xy 316.44463 8.488424) (xy 316.503599 8.48439) (xy 316.56147 8.472364) (xy 316.617165 8.45257) (xy 316.669645 8.425377)
			(xy 316.717934 8.391291) (xy 316.761131 8.350948) (xy 316.798433 8.305098) (xy 316.829144 8.254595)
			(xy 316.852693 8.200381) (xy 316.868639 8.143466) (xy 316.876688 8.08491) (xy 316.877192 8.055356)
			(xy 316.877192 7.191756) (xy 316.876688 7.162202) (xy 316.868639 7.103646) (xy 316.852693 7.046731)
			(xy 316.829144 6.992517) (xy 316.798433 6.942014) (xy 316.761131 6.896164) (xy 316.717934 6.855821)
			(xy 316.669645 6.821735) (xy 316.617165 6.794542) (xy 316.56147 6.774748) (xy 316.503599 6.762722)
			(xy 316.44463 6.758689) (xy 316.385661 6.762722) (xy 316.32779 6.774748) (xy 316.272095 6.794542)
			(xy 316.219615 6.821735) (xy 316.171326 6.855821) (xy 316.128129 6.896164) (xy 316.090827 6.942014)
			(xy 316.060116 6.992517) (xy 316.036567 7.046731) (xy 316.020621 7.103646) (xy 316.012572 7.162202)
			(xy 316.012068 7.191756) (xy 312.478344 7.191756) (xy 312.534431 7.163828) (xy 312.607337 7.118687)
			(xy 312.675766 7.067011) (xy 312.739136 7.009242) (xy 312.796905 6.945872) (xy 312.848581 6.877443)
			(xy 312.893722 6.804537) (xy 312.931944 6.727777) (xy 312.96292 6.647818) (xy 312.986387 6.565342)
			(xy 313.002143 6.481052) (xy 313.010055 6.395669) (xy 313.01055 6.352794) (xy 313.010055 6.309919)
			(xy 317.505321 6.309919) (xy 317.505321 6.395669) (xy 317.513233 6.481052) (xy 317.528989 6.565342)
			(xy 317.552456 6.647818) (xy 317.583432 6.727777) (xy 317.621654 6.804537) (xy 317.666795 6.877443)
			(xy 317.718471 6.945872) (xy 317.77624 7.009242) (xy 317.83961 7.067011) (xy 317.908039 7.118687)
			(xy 317.980945 7.163828) (xy 318.057705 7.20205) (xy 318.137664 7.233026) (xy 318.22014 7.256493)
			(xy 318.30443 7.272249) (xy 318.389813 7.280161) (xy 318.475563 7.280161) (xy 318.560946 7.272249)
			(xy 318.645236 7.256493) (xy 318.727712 7.233026) (xy 318.807671 7.20205) (xy 318.884431 7.163828)
			(xy 318.957337 7.118687) (xy 319.025766 7.067011) (xy 319.089136 7.009242) (xy 319.146905 6.945872)
			(xy 319.198581 6.877443) (xy 319.243722 6.804537) (xy 319.281944 6.727777) (xy 319.31292 6.647818)
			(xy 319.336387 6.565342) (xy 319.352143 6.481052) (xy 319.360055 6.395669) (xy 319.36055 6.352794)
			(xy 319.360055 6.309919) (xy 361.894107 6.309919) (xy 361.894107 6.395669) (xy 361.902019 6.481052)
			(xy 361.917775 6.565342) (xy 361.941242 6.647818) (xy 361.972218 6.727777) (xy 362.01044 6.804537)
			(xy 362.055581 6.877443) (xy 362.107257 6.945872) (xy 362.165026 7.009242) (xy 362.228396 7.067011)
			(xy 362.296825 7.118687) (xy 362.369731 7.163828) (xy 362.446491 7.20205) (xy 362.52645 7.233026)
			(xy 362.608926 7.256493) (xy 362.693216 7.272249) (xy 362.778599 7.280161) (xy 362.864349 7.280161)
			(xy 362.949732 7.272249) (xy 363.034022 7.256493) (xy 363.116498 7.233026) (xy 363.196457 7.20205)
			(xy 363.21713 7.191756) (xy 364.379764 7.191756) (xy 364.379764 8.055356) (xy 364.380268 8.084892)
			(xy 364.388312 8.143414) (xy 364.404249 8.200296) (xy 364.427784 8.254478) (xy 364.458477 8.304951)
			(xy 364.495757 8.350774) (xy 364.538929 8.391094) (xy 364.587189 8.42516) (xy 364.639639 8.452337)
			(xy 364.6953 8.472119) (xy 364.753137 8.484138) (xy 364.812072 8.488169) (xy 364.871007 8.484138)
			(xy 364.928844 8.472119) (xy 364.984505 8.452337) (xy 365.036955 8.42516) (xy 365.085215 8.391094)
			(xy 365.128387 8.350774) (xy 365.165667 8.304951) (xy 365.19636 8.254478) (xy 365.219895 8.200296)
			(xy 365.235832 8.143414) (xy 365.243876 8.084892) (xy 365.24438 8.055356) (xy 365.24438 7.376973)
			(xy 385.651997 7.376973) (xy 385.651997 7.462723) (xy 385.659909 7.548106) (xy 385.675665 7.632396)
			(xy 385.699132 7.714872) (xy 385.730108 7.794831) (xy 385.76833 7.871591) (xy 385.813471 7.944497)
			(xy 385.865147 8.012926) (xy 385.922916 8.076296) (xy 385.986286 8.134065) (xy 386.054715 8.185741)
			(xy 386.127621 8.230882) (xy 386.204381 8.269104) (xy 386.28434 8.30008) (xy 386.366816 8.323547)
			(xy 386.451106 8.339303) (xy 386.536489 8.347215) (xy 386.622239 8.347215) (xy 386.707622 8.339303)
			(xy 386.791912 8.323547) (xy 386.874388 8.30008) (xy 386.954347 8.269104) (xy 386.97502 8.25881)
			(xy 390.508744 8.25881) (xy 390.508744 9.12241) (xy 390.509248 9.151964) (xy 390.517297 9.21052)
			(xy 390.533243 9.267435) (xy 390.556792 9.321649) (xy 390.587503 9.372152) (xy 390.624805 9.418002)
			(xy 390.668002 9.458345) (xy 390.716291 9.492431) (xy 390.768771 9.519624) (xy 390.824466 9.539418)
			(xy 390.882337 9.551444) (xy 390.941306 9.555478) (xy 391.000275 9.551444) (xy 391.058146 9.539418)
			(xy 391.113841 9.519624) (xy 391.166321 9.492431) (xy 391.21461 9.458345) (xy 391.257807 9.418002)
			(xy 391.295109 9.372152) (xy 391.32582 9.321649) (xy 391.349369 9.267435) (xy 391.365315 9.21052)
			(xy 391.373364 9.151964) (xy 391.373868 9.12241) (xy 391.373868 8.25881) (xy 391.373364 8.229256)
			(xy 391.365315 8.1707) (xy 391.349369 8.113785) (xy 391.32582 8.059571) (xy 391.295109 8.009068)
			(xy 391.257807 7.963218) (xy 391.21461 7.922875) (xy 391.166321 7.888789) (xy 391.113841 7.861596)
			(xy 391.058146 7.841802) (xy 391.000275 7.829776) (xy 390.941306 7.825743) (xy 390.882337 7.829776)
			(xy 390.824466 7.841802) (xy 390.768771 7.861596) (xy 390.716291 7.888789) (xy 390.668002 7.922875)
			(xy 390.624805 7.963218) (xy 390.587503 8.009068) (xy 390.556792 8.059571) (xy 390.533243 8.113785)
			(xy 390.517297 8.1707) (xy 390.509248 8.229256) (xy 390.508744 8.25881) (xy 386.97502 8.25881) (xy 387.031107 8.230882)
			(xy 387.104013 8.185741) (xy 387.172442 8.134065) (xy 387.235812 8.076296) (xy 387.293581 8.012926)
			(xy 387.345257 7.944497) (xy 387.390398 7.871591) (xy 387.42862 7.794831) (xy 387.459596 7.714872)
			(xy 387.483063 7.632396) (xy 387.498819 7.548106) (xy 387.506731 7.462723) (xy 387.507226 7.419848)
			(xy 387.506731 7.376973) (xy 392.001997 7.376973) (xy 392.001997 7.462723) (xy 392.009909 7.548106)
			(xy 392.025665 7.632396) (xy 392.049132 7.714872) (xy 392.080108 7.794831) (xy 392.11833 7.871591)
			(xy 392.163471 7.944497) (xy 392.215147 8.012926) (xy 392.272916 8.076296) (xy 392.336286 8.134065)
			(xy 392.404715 8.185741) (xy 392.477621 8.230882) (xy 392.554381 8.269104) (xy 392.63434 8.30008)
			(xy 392.716816 8.323547) (xy 392.801106 8.339303) (xy 392.886489 8.347215) (xy 392.972239 8.347215)
			(xy 393.057622 8.339303) (xy 393.141912 8.323547) (xy 393.224388 8.30008) (xy 393.304347 8.269104)
			(xy 393.381107 8.230882) (xy 393.454013 8.185741) (xy 393.522442 8.134065) (xy 393.585812 8.076296)
			(xy 393.643581 8.012926) (xy 393.695257 7.944497) (xy 393.740398 7.871591) (xy 393.77862 7.794831)
			(xy 393.809596 7.714872) (xy 393.833063 7.632396) (xy 393.848819 7.548106) (xy 393.856731 7.462723)
			(xy 393.857226 7.419848) (xy 393.856731 7.376973) (xy 436.390783 7.376973) (xy 436.390783 7.462723)
			(xy 436.398695 7.548106) (xy 436.414451 7.632396) (xy 436.437918 7.714872) (xy 436.468894 7.794831)
			(xy 436.507116 7.871591) (xy 436.552257 7.944497) (xy 436.603933 8.012926) (xy 436.661702 8.076296)
			(xy 436.725072 8.134065) (xy 436.793501 8.185741) (xy 436.866407 8.230882) (xy 436.943167 8.269104)
			(xy 437.023126 8.30008) (xy 437.105602 8.323547) (xy 437.189892 8.339303) (xy 437.275275 8.347215)
			(xy 437.361025 8.347215) (xy 437.446408 8.339303) (xy 437.530698 8.323547) (xy 437.613174 8.30008)
			(xy 437.693133 8.269104) (xy 437.713806 8.25881) (xy 438.87644 8.25881) (xy 438.87644 9.12241) (xy 438.876944 9.151946)
			(xy 438.884988 9.210468) (xy 438.900925 9.26735) (xy 438.92446 9.321532) (xy 438.955153 9.372005)
			(xy 438.992433 9.417828) (xy 439.035605 9.458148) (xy 439.083865 9.492214) (xy 439.136315 9.519391)
			(xy 439.191976 9.539173) (xy 439.249813 9.551192) (xy 439.308748 9.555223) (xy 439.367683 9.551192)
			(xy 439.42552 9.539173) (xy 439.481181 9.519391) (xy 439.533631 9.492214) (xy 439.581891 9.458148)
			(xy 439.625063 9.417828) (xy 439.662343 9.372005) (xy 439.693036 9.321532) (xy 439.716571 9.26735)
			(xy 439.732508 9.210468) (xy 439.740552 9.151946) (xy 439.741056 9.12241) (xy 439.741056 8.25881)
			(xy 439.740552 8.229274) (xy 439.732508 8.170752) (xy 439.716571 8.11387) (xy 439.693036 8.059688)
			(xy 439.662343 8.009215) (xy 439.625063 7.963392) (xy 439.581891 7.923072) (xy 439.533631 7.889006)
			(xy 439.481181 7.861829) (xy 439.42552 7.842047) (xy 439.367683 7.830028) (xy 439.308748 7.825997)
			(xy 439.249813 7.830028) (xy 439.191976 7.842047) (xy 439.136315 7.861829) (xy 439.083865 7.889006)
			(xy 439.035605 7.923072) (xy 438.992433 7.963392) (xy 438.955153 8.009215) (xy 438.92446 8.059688)
			(xy 438.900925 8.11387) (xy 438.884988 8.170752) (xy 438.876944 8.229274) (xy 438.87644 8.25881)
			(xy 437.713806 8.25881) (xy 437.769893 8.230882) (xy 437.842799 8.185741) (xy 437.911228 8.134065)
			(xy 437.974598 8.076296) (xy 438.032367 8.012926) (xy 438.084043 7.944497) (xy 438.129184 7.871591)
			(xy 438.167406 7.794831) (xy 438.198382 7.714872) (xy 438.221849 7.632396) (xy 438.237605 7.548106)
			(xy 438.245517 7.462723) (xy 438.246012 7.419848) (xy 438.245517 7.376973) (xy 442.740783 7.376973)
			(xy 442.740783 7.462723) (xy 442.748695 7.548106) (xy 442.764451 7.632396) (xy 442.787918 7.714872)
			(xy 442.818894 7.794831) (xy 442.857116 7.871591) (xy 442.902257 7.944497) (xy 442.953933 8.012926)
			(xy 443.011702 8.076296) (xy 443.075072 8.134065) (xy 443.143501 8.185741) (xy 443.216407 8.230882)
			(xy 443.293167 8.269104) (xy 443.373126 8.30008) (xy 443.455602 8.323547) (xy 443.539892 8.339303)
			(xy 443.625275 8.347215) (xy 443.711025 8.347215) (xy 443.796408 8.339303) (xy 443.880698 8.323547)
			(xy 443.963174 8.30008) (xy 444.043133 8.269104) (xy 444.119893 8.230882) (xy 444.192799 8.185741)
			(xy 444.261228 8.134065) (xy 444.324598 8.076296) (xy 444.382367 8.012926) (xy 444.434043 7.944497)
			(xy 444.479184 7.871591) (xy 444.517406 7.794831) (xy 444.548382 7.714872) (xy 444.571849 7.632396)
			(xy 444.587605 7.548106) (xy 444.595517 7.462723) (xy 444.596012 7.419848) (xy 444.595517 7.376973)
			(xy 444.587605 7.29159) (xy 444.571849 7.2073) (xy 444.548382 7.124824) (xy 444.517406 7.044865)
			(xy 444.479184 6.968105) (xy 444.434043 6.895199) (xy 444.382367 6.82677) (xy 444.324598 6.7634)
			(xy 444.261228 6.705631) (xy 444.192799 6.653955) (xy 444.119893 6.608814) (xy 444.043133 6.570592)
			(xy 443.963174 6.539616) (xy 443.880698 6.516149) (xy 443.796408 6.500393) (xy 443.711025 6.492481)
			(xy 443.625275 6.492481) (xy 443.539892 6.500393) (xy 443.455602 6.516149) (xy 443.373126 6.539616)
			(xy 443.293167 6.570592) (xy 443.216407 6.608814) (xy 443.143501 6.653955) (xy 443.075072 6.705631)
			(xy 443.011702 6.7634) (xy 442.953933 6.82677) (xy 442.902257 6.895199) (xy 442.857116 6.968105)
			(xy 442.818894 7.044865) (xy 442.787918 7.124824) (xy 442.764451 7.2073) (xy 442.748695 7.29159)
			(xy 442.740783 7.376973) (xy 438.245517 7.376973) (xy 438.237605 7.29159) (xy 438.221849 7.2073)
			(xy 438.198382 7.124824) (xy 438.167406 7.044865) (xy 438.129184 6.968105) (xy 438.084043 6.895199)
			(xy 438.032367 6.82677) (xy 437.974598 6.7634) (xy 437.911228 6.705631) (xy 437.842799 6.653955)
			(xy 437.769893 6.608814) (xy 437.693133 6.570592) (xy 437.613174 6.539616) (xy 437.530698 6.516149)
			(xy 437.446408 6.500393) (xy 437.361025 6.492481) (xy 437.275275 6.492481) (xy 437.189892 6.500393)
			(xy 437.105602 6.516149) (xy 437.023126 6.539616) (xy 436.943167 6.570592) (xy 436.866407 6.608814)
			(xy 436.793501 6.653955) (xy 436.725072 6.705631) (xy 436.661702 6.7634) (xy 436.603933 6.82677)
			(xy 436.552257 6.895199) (xy 436.507116 6.968105) (xy 436.468894 7.044865) (xy 436.437918 7.124824)
			(xy 436.414451 7.2073) (xy 436.398695 7.29159) (xy 436.390783 7.376973) (xy 393.856731 7.376973)
			(xy 393.848819 7.29159) (xy 393.833063 7.2073) (xy 393.809596 7.124824) (xy 393.77862 7.044865) (xy 393.740398 6.968105)
			(xy 393.695257 6.895199) (xy 393.643581 6.82677) (xy 393.585812 6.7634) (xy 393.522442 6.705631)
			(xy 393.454013 6.653955) (xy 393.381107 6.608814) (xy 393.304347 6.570592) (xy 393.224388 6.539616)
			(xy 393.141912 6.516149) (xy 393.057622 6.500393) (xy 392.972239 6.492481) (xy 392.886489 6.492481)
			(xy 392.801106 6.500393) (xy 392.716816 6.516149) (xy 392.63434 6.539616) (xy 392.554381 6.570592)
			(xy 392.477621 6.608814) (xy 392.404715 6.653955) (xy 392.336286 6.705631) (xy 392.272916 6.7634)
			(xy 392.215147 6.82677) (xy 392.163471 6.895199) (xy 392.11833 6.968105) (xy 392.080108 7.044865)
			(xy 392.049132 7.124824) (xy 392.025665 7.2073) (xy 392.009909 7.29159) (xy 392.001997 7.376973)
			(xy 387.506731 7.376973) (xy 387.498819 7.29159) (xy 387.483063 7.2073) (xy 387.459596 7.124824)
			(xy 387.42862 7.044865) (xy 387.390398 6.968105) (xy 387.345257 6.895199) (xy 387.293581 6.82677)
			(xy 387.235812 6.7634) (xy 387.172442 6.705631) (xy 387.104013 6.653955) (xy 387.031107 6.608814)
			(xy 386.954347 6.570592) (xy 386.874388 6.539616) (xy 386.791912 6.516149) (xy 386.707622 6.500393)
			(xy 386.622239 6.492481) (xy 386.536489 6.492481) (xy 386.451106 6.500393) (xy 386.366816 6.516149)
			(xy 386.28434 6.539616) (xy 386.204381 6.570592) (xy 386.127621 6.608814) (xy 386.054715 6.653955)
			(xy 385.986286 6.705631) (xy 385.922916 6.7634) (xy 385.865147 6.82677) (xy 385.813471 6.895199)
			(xy 385.76833 6.968105) (xy 385.730108 7.044865) (xy 385.699132 7.124824) (xy 385.675665 7.2073)
			(xy 385.659909 7.29159) (xy 385.651997 7.376973) (xy 365.24438 7.376973) (xy 365.24438 7.191756)
			(xy 365.243876 7.16222) (xy 365.235832 7.103698) (xy 365.219895 7.046816) (xy 365.19636 6.992634)
			(xy 365.165667 6.942161) (xy 365.128387 6.896338) (xy 365.085215 6.856018) (xy 365.036955 6.821952)
			(xy 364.984505 6.794775) (xy 364.928844 6.774993) (xy 364.871007 6.762974) (xy 364.812072 6.758943)
			(xy 364.753137 6.762974) (xy 364.6953 6.774993) (xy 364.639639 6.794775) (xy 364.587189 6.821952)
			(xy 364.538929 6.856018) (xy 364.495757 6.896338) (xy 364.458477 6.942161) (xy 364.427784 6.992634)
			(xy 364.404249 7.046816) (xy 364.388312 7.103698) (xy 364.380268 7.16222) (xy 364.379764 7.191756)
			(xy 363.21713 7.191756) (xy 363.273217 7.163828) (xy 363.346123 7.118687) (xy 363.414552 7.067011)
			(xy 363.477922 7.009242) (xy 363.535691 6.945872) (xy 363.587367 6.877443) (xy 363.632508 6.804537)
			(xy 363.67073 6.727777) (xy 363.701706 6.647818) (xy 363.725173 6.565342) (xy 363.740929 6.481052)
			(xy 363.748841 6.395669) (xy 363.749336 6.352794) (xy 363.748841 6.309919) (xy 368.244107 6.309919)
			(xy 368.244107 6.395669) (xy 368.252019 6.481052) (xy 368.267775 6.565342) (xy 368.291242 6.647818)
			(xy 368.322218 6.727777) (xy 368.36044 6.804537) (xy 368.405581 6.877443) (xy 368.457257 6.945872)
			(xy 368.515026 7.009242) (xy 368.578396 7.067011) (xy 368.646825 7.118687) (xy 368.719731 7.163828)
			(xy 368.796491 7.20205) (xy 368.87645 7.233026) (xy 368.958926 7.256493) (xy 369.043216 7.272249)
			(xy 369.128599 7.280161) (xy 369.214349 7.280161) (xy 369.299732 7.272249) (xy 369.384022 7.256493)
			(xy 369.466498 7.233026) (xy 369.546457 7.20205) (xy 369.623217 7.163828) (xy 369.696123 7.118687)
			(xy 369.764552 7.067011) (xy 369.827922 7.009242) (xy 369.885691 6.945872) (xy 369.937367 6.877443)
			(xy 369.982508 6.804537) (xy 370.02073 6.727777) (xy 370.051706 6.647818) (xy 370.075173 6.565342)
			(xy 370.090929 6.481052) (xy 370.098841 6.395669) (xy 370.099336 6.352794) (xy 370.098841 6.309919)
			(xy 370.090929 6.224536) (xy 370.075173 6.140246) (xy 370.051706 6.05777) (xy 370.02073 5.977811)
			(xy 369.982508 5.901051) (xy 369.937367 5.828145) (xy 369.885691 5.759716) (xy 369.827922 5.696346)
			(xy 369.764552 5.638577) (xy 369.696123 5.586901) (xy 369.623217 5.54176) (xy 369.546457 5.503538)
			(xy 369.466498 5.472562) (xy 369.384022 5.449095) (xy 369.299732 5.433339) (xy 369.214349 5.425427)
			(xy 369.128599 5.425427) (xy 369.043216 5.433339) (xy 368.958926 5.449095) (xy 368.87645 5.472562)
			(xy 368.796491 5.503538) (xy 368.719731 5.54176) (xy 368.646825 5.586901) (xy 368.578396 5.638577)
			(xy 368.515026 5.696346) (xy 368.457257 5.759716) (xy 368.405581 5.828145) (xy 368.36044 5.901051)
			(xy 368.322218 5.977811) (xy 368.291242 6.05777) (xy 368.267775 6.140246) (xy 368.252019 6.224536)
			(xy 368.244107 6.309919) (xy 363.748841 6.309919) (xy 363.740929 6.224536) (xy 363.725173 6.140246)
			(xy 363.701706 6.05777) (xy 363.67073 5.977811) (xy 363.632508 5.901051) (xy 363.587367 5.828145)
			(xy 363.535691 5.759716) (xy 363.477922 5.696346) (xy 363.414552 5.638577) (xy 363.346123 5.586901)
			(xy 363.273217 5.54176) (xy 363.196457 5.503538) (xy 363.116498 5.472562) (xy 363.034022 5.449095)
			(xy 362.949732 5.433339) (xy 362.864349 5.425427) (xy 362.778599 5.425427) (xy 362.693216 5.433339)
			(xy 362.608926 5.449095) (xy 362.52645 5.472562) (xy 362.446491 5.503538) (xy 362.369731 5.54176)
			(xy 362.296825 5.586901) (xy 362.228396 5.638577) (xy 362.165026 5.696346) (xy 362.107257 5.759716)
			(xy 362.055581 5.828145) (xy 362.01044 5.901051) (xy 361.972218 5.977811) (xy 361.941242 6.05777)
			(xy 361.917775 6.140246) (xy 361.902019 6.224536) (xy 361.894107 6.309919) (xy 319.360055 6.309919)
			(xy 319.352143 6.224536) (xy 319.336387 6.140246) (xy 319.31292 6.05777) (xy 319.281944 5.977811)
			(xy 319.243722 5.901051) (xy 319.198581 5.828145) (xy 319.146905 5.759716) (xy 319.089136 5.696346)
			(xy 319.025766 5.638577) (xy 318.957337 5.586901) (xy 318.884431 5.54176) (xy 318.807671 5.503538)
			(xy 318.727712 5.472562) (xy 318.645236 5.449095) (xy 318.560946 5.433339) (xy 318.475563 5.425427)
			(xy 318.389813 5.425427) (xy 318.30443 5.433339) (xy 318.22014 5.449095) (xy 318.137664 5.472562)
			(xy 318.057705 5.503538) (xy 317.980945 5.54176) (xy 317.908039 5.586901) (xy 317.83961 5.638577)
			(xy 317.77624 5.696346) (xy 317.718471 5.759716) (xy 317.666795 5.828145) (xy 317.621654 5.901051)
			(xy 317.583432 5.977811) (xy 317.552456 6.05777) (xy 317.528989 6.140246) (xy 317.513233 6.224536)
			(xy 317.505321 6.309919) (xy 313.010055 6.309919) (xy 313.002143 6.224536) (xy 312.986387 6.140246)
			(xy 312.96292 6.05777) (xy 312.931944 5.977811) (xy 312.893722 5.901051) (xy 312.848581 5.828145)
			(xy 312.796905 5.759716) (xy 312.739136 5.696346) (xy 312.675766 5.638577) (xy 312.607337 5.586901)
			(xy 312.534431 5.54176) (xy 312.457671 5.503538) (xy 312.377712 5.472562) (xy 312.295236 5.449095)
			(xy 312.210946 5.433339) (xy 312.125563 5.425427) (xy 312.039813 5.425427) (xy 311.95443 5.433339)
			(xy 311.87014 5.449095) (xy 311.787664 5.472562) (xy 311.707705 5.503538) (xy 311.630945 5.54176)
			(xy 311.558039 5.586901) (xy 311.48961 5.638577) (xy 311.42624 5.696346) (xy 311.368471 5.759716)
			(xy 311.316795 5.828145) (xy 311.271654 5.901051) (xy 311.233432 5.977811) (xy 311.202456 6.05777)
			(xy 311.178989 6.140246) (xy 311.163233 6.224536) (xy 311.155321 6.309919) (xy 304.348655 6.309919)
			(xy 304.340743 6.224536) (xy 304.324987 6.140246) (xy 304.30152 6.05777) (xy 304.270544 5.977811)
			(xy 304.232322 5.901051) (xy 304.187181 5.828145) (xy 304.135505 5.759716) (xy 304.077736 5.696346)
			(xy 304.014366 5.638577) (xy 303.945937 5.586901) (xy 303.873031 5.54176) (xy 303.796271 5.503538)
			(xy 303.716312 5.472562) (xy 303.633836 5.449095) (xy 303.549546 5.433339) (xy 303.464163 5.425427)
			(xy 303.378413 5.425427) (xy 303.29303 5.433339) (xy 303.20874 5.449095) (xy 303.126264 5.472562)
			(xy 303.046305 5.503538) (xy 302.969545 5.54176) (xy 302.896639 5.586901) (xy 302.82821 5.638577)
			(xy 302.76484 5.696346) (xy 302.707071 5.759716) (xy 302.655395 5.828145) (xy 302.610254 5.901051)
			(xy 302.572032 5.977811) (xy 302.541056 6.05777) (xy 302.517589 6.140246) (xy 302.501833 6.224536)
			(xy 302.493921 6.309919) (xy 297.998655 6.309919) (xy 297.990743 6.224536) (xy 297.974987 6.140246)
			(xy 297.95152 6.05777) (xy 297.920544 5.977811) (xy 297.882322 5.901051) (xy 297.837181 5.828145)
			(xy 297.785505 5.759716) (xy 297.727736 5.696346) (xy 297.664366 5.638577) (xy 297.595937 5.586901)
			(xy 297.523031 5.54176) (xy 297.446271 5.503538) (xy 297.366312 5.472562) (xy 297.283836 5.449095)
			(xy 297.199546 5.433339) (xy 297.114163 5.425427) (xy 297.028413 5.425427) (xy 296.94303 5.433339)
			(xy 296.85874 5.449095) (xy 296.776264 5.472562) (xy 296.696305 5.503538) (xy 296.619545 5.54176)
			(xy 296.546639 5.586901) (xy 296.47821 5.638577) (xy 296.41484 5.696346) (xy 296.357071 5.759716)
			(xy 296.305395 5.828145) (xy 296.260254 5.901051) (xy 296.222032 5.977811) (xy 296.191056 6.05777)
			(xy 296.167589 6.140246) (xy 296.151833 6.224536) (xy 296.143921 6.309919) (xy 216.865975 6.309919)
			(xy 216.858063 6.224536) (xy 216.842307 6.140246) (xy 216.81884 6.05777) (xy 216.787864 5.977811)
			(xy 216.749642 5.901051) (xy 216.704501 5.828145) (xy 216.652825 5.759716) (xy 216.595056 5.696346)
			(xy 216.531686 5.638577) (xy 216.463257 5.586901) (xy 216.390351 5.54176) (xy 216.313591 5.503538)
			(xy 216.233632 5.472562) (xy 216.151156 5.449095) (xy 216.066866 5.433339) (xy 215.981483 5.425427)
			(xy 215.895733 5.425427) (xy 215.81035 5.433339) (xy 215.72606 5.449095) (xy 215.643584 5.472562)
			(xy 215.563625 5.503538) (xy 215.486865 5.54176) (xy 215.413959 5.586901) (xy 215.34553 5.638577)
			(xy 215.28216 5.696346) (xy 215.224391 5.759716) (xy 215.172715 5.828145) (xy 215.127574 5.901051)
			(xy 215.089352 5.977811) (xy 215.058376 6.05777) (xy 215.034909 6.140246) (xy 215.019153 6.224536)
			(xy 215.011241 6.309919) (xy 210.515975 6.309919) (xy 210.508063 6.224536) (xy 210.492307 6.140246)
			(xy 210.46884 6.05777) (xy 210.437864 5.977811) (xy 210.399642 5.901051) (xy 210.354501 5.828145)
			(xy 210.302825 5.759716) (xy 210.245056 5.696346) (xy 210.181686 5.638577) (xy 210.113257 5.586901)
			(xy 210.040351 5.54176) (xy 209.963591 5.503538) (xy 209.883632 5.472562) (xy 209.801156 5.449095)
			(xy 209.716866 5.433339) (xy 209.631483 5.425427) (xy 209.545733 5.425427) (xy 209.46035 5.433339)
			(xy 209.37606 5.449095) (xy 209.293584 5.472562) (xy 209.213625 5.503538) (xy 209.136865 5.54176)
			(xy 209.063959 5.586901) (xy 208.99553 5.638577) (xy 208.93216 5.696346) (xy 208.874391 5.759716)
			(xy 208.822715 5.828145) (xy 208.777574 5.901051) (xy 208.739352 5.977811) (xy 208.708376 6.05777)
			(xy 208.684909 6.140246) (xy 208.669153 6.224536) (xy 208.661241 6.309919) (xy 184.818528 6.309919)
			(xy 184.818528 5.632196) (xy 184.818024 5.60266) (xy 184.80998 5.544138) (xy 184.794043 5.487256)
			(xy 184.770508 5.433074) (xy 184.739815 5.382601) (xy 184.702535 5.336778) (xy 184.659363 5.296458)
			(xy 184.611103 5.262392) (xy 184.558653 5.235215) (xy 184.502992 5.215433) (xy 184.445155 5.203414)
			(xy 184.38622 5.199383) (xy 184.327285 5.203414) (xy 184.269448 5.215433) (xy 184.213787 5.235215)
			(xy 184.161337 5.262392) (xy 184.113077 5.296458) (xy 184.069905 5.336778) (xy 184.032625 5.382601)
			(xy 184.001932 5.433074) (xy 183.978397 5.487256) (xy 183.96246 5.544138) (xy 183.954416 5.60266)
			(xy 183.953912 5.632196) (xy 182.791278 5.632196) (xy 182.847365 5.604268) (xy 182.920271 5.559127)
			(xy 182.9887 5.507451) (xy 183.05207 5.449682) (xy 183.109839 5.386312) (xy 183.161515 5.317883)
			(xy 183.206656 5.244977) (xy 183.244878 5.168217) (xy 183.275854 5.088258) (xy 183.299321 5.005782)
			(xy 183.315077 4.921492) (xy 183.322989 4.836109) (xy 183.323484 4.793234) (xy 183.322989 4.750359)
			(xy 187.818255 4.750359) (xy 187.818255 4.836109) (xy 187.826167 4.921492) (xy 187.841923 5.005782)
			(xy 187.86539 5.088258) (xy 187.896366 5.168217) (xy 187.934588 5.244977) (xy 187.979729 5.317883)
			(xy 188.031405 5.386312) (xy 188.089174 5.449682) (xy 188.152544 5.507451) (xy 188.220973 5.559127)
			(xy 188.293879 5.604268) (xy 188.370639 5.64249) (xy 188.450598 5.673466) (xy 188.533074 5.696933)
			(xy 188.617364 5.712689) (xy 188.702747 5.720601) (xy 188.788497 5.720601) (xy 188.87388 5.712689)
			(xy 188.95817 5.696933) (xy 189.040646 5.673466) (xy 189.120605 5.64249) (xy 189.197365 5.604268)
			(xy 189.270271 5.559127) (xy 189.3387 5.507451) (xy 189.40207 5.449682) (xy 189.459839 5.386312)
			(xy 189.511515 5.317883) (xy 189.556656 5.244977) (xy 189.594878 5.168217) (xy 189.625854 5.088258)
			(xy 189.649321 5.005782) (xy 189.665077 4.921492) (xy 189.672989 4.836109) (xy 189.673484 4.793234)
			(xy 189.672989 4.750359) (xy 189.665077 4.664976) (xy 189.649321 4.580686) (xy 189.625854 4.49821)
			(xy 189.594878 4.418251) (xy 189.556656 4.341491) (xy 189.511515 4.268585) (xy 189.459839 4.200156)
			(xy 189.40207 4.136786) (xy 189.3387 4.079017) (xy 189.270271 4.027341) (xy 189.197365 3.9822) (xy 189.120605 3.943978)
			(xy 189.040646 3.913002) (xy 188.95817 3.889535) (xy 188.87388 3.873779) (xy 188.788497 3.865867)
			(xy 188.702747 3.865867) (xy 188.617364 3.873779) (xy 188.533074 3.889535) (xy 188.450598 3.913002)
			(xy 188.370639 3.943978) (xy 188.293879 3.9822) (xy 188.220973 4.027341) (xy 188.152544 4.079017)
			(xy 188.089174 4.136786) (xy 188.031405 4.200156) (xy 187.979729 4.268585) (xy 187.934588 4.341491)
			(xy 187.896366 4.418251) (xy 187.86539 4.49821) (xy 187.841923 4.580686) (xy 187.826167 4.664976)
			(xy 187.818255 4.750359) (xy 183.322989 4.750359) (xy 183.315077 4.664976) (xy 183.299321 4.580686)
			(xy 183.275854 4.49821) (xy 183.244878 4.418251) (xy 183.206656 4.341491) (xy 183.161515 4.268585)
			(xy 183.109839 4.200156) (xy 183.05207 4.136786) (xy 182.9887 4.079017) (xy 182.920271 4.027341)
			(xy 182.847365 3.9822) (xy 182.770605 3.943978) (xy 182.690646 3.913002) (xy 182.60817 3.889535)
			(xy 182.52388 3.873779) (xy 182.438497 3.865867) (xy 182.352747 3.865867) (xy 182.267364 3.873779)
			(xy 182.183074 3.889535) (xy 182.100598 3.913002) (xy 182.020639 3.943978) (xy 181.943879 3.9822)
			(xy 181.870973 4.027341) (xy 181.802544 4.079017) (xy 181.739174 4.136786) (xy 181.681405 4.200156)
			(xy 181.629729 4.268585) (xy 181.584588 4.341491) (xy 181.546366 4.418251) (xy 181.51539 4.49821)
			(xy 181.491923 4.580686) (xy 181.476167 4.664976) (xy 181.468255 4.750359) (xy 102.190309 4.750359)
			(xy 102.182397 4.664976) (xy 102.166641 4.580686) (xy 102.143174 4.49821) (xy 102.112198 4.418251)
			(xy 102.073976 4.341491) (xy 102.028835 4.268585) (xy 101.977159 4.200156) (xy 101.91939 4.136786)
			(xy 101.85602 4.079017) (xy 101.787591 4.027341) (xy 101.714685 3.9822) (xy 101.637925 3.943978)
			(xy 101.557966 3.913002) (xy 101.47549 3.889535) (xy 101.3912 3.873779) (xy 101.305817 3.865867)
			(xy 101.220067 3.865867) (xy 101.134684 3.873779) (xy 101.050394 3.889535) (xy 100.967918 3.913002)
			(xy 100.887959 3.943978) (xy 100.811199 3.9822) (xy 100.738293 4.027341) (xy 100.669864 4.079017)
			(xy 100.606494 4.136786) (xy 100.548725 4.200156) (xy 100.497049 4.268585) (xy 100.451908 4.341491)
			(xy 100.413686 4.418251) (xy 100.38271 4.49821) (xy 100.359243 4.580686) (xy 100.343487 4.664976)
			(xy 100.335575 4.750359) (xy 95.840309 4.750359) (xy 95.832397 4.664976) (xy 95.816641 4.580686)
			(xy 95.793174 4.49821) (xy 95.762198 4.418251) (xy 95.723976 4.341491) (xy 95.678835 4.268585) (xy 95.627159 4.200156)
			(xy 95.56939 4.136786) (xy 95.50602 4.079017) (xy 95.437591 4.027341) (xy 95.364685 3.9822) (xy 95.287925 3.943978)
			(xy 95.207966 3.913002) (xy 95.12549 3.889535) (xy 95.0412 3.873779) (xy 94.955817 3.865867) (xy 94.870067 3.865867)
			(xy 94.784684 3.873779) (xy 94.700394 3.889535) (xy 94.617918 3.913002) (xy 94.537959 3.943978) (xy 94.461199 3.9822)
			(xy 94.388293 4.027341) (xy 94.319864 4.079017) (xy 94.256494 4.136786) (xy 94.198725 4.200156) (xy 94.147049 4.268585)
			(xy 94.101908 4.341491) (xy 94.063686 4.418251) (xy 94.03271 4.49821) (xy 94.009243 4.580686) (xy 93.993487 4.664976)
			(xy 93.985575 4.750359) (xy 0.509016 4.750359) (xy 0.509016 -7.78002) (xy 0.509537 -7.835789) (xy 0.517873 -7.947015)
			(xy 0.534497 -8.057308) (xy 0.559316 -8.166049) (xy 0.592193 -8.272632) (xy 0.632942 -8.37646) (xy 0.681336 -8.476953)
			(xy 0.737105 -8.573548) (xy 0.799937 -8.665705) (xy 0.86948 -8.752909) (xy 0.945345 -8.834672) (xy 1.027108 -8.910538)
			(xy 1.114312 -8.980081) (xy 1.206469 -9.042912) (xy 1.303064 -9.098682) (xy 1.403556 -9.147076) (xy 1.507384 -9.187826)
			(xy 1.613967 -9.220703) (xy 1.722708 -9.245523) (xy 1.833001 -9.262147) (xy 1.944227 -9.270482) (xy 1.999996 -9.271)
			(xy 9.10209 -9.271) (xy 9.15786 -9.270479) (xy 9.269087 -9.262144) (xy 9.37938 -9.245521) (xy 9.488123 -9.220702)
			(xy 9.594707 -9.187826) (xy 9.698536 -9.147077) (xy 9.79903 -9.098683) (xy 9.895626 -9.042915) (xy 9.987784 -8.980083)
			(xy 10.07499 -8.910541) (xy 10.156754 -8.834676) (xy 10.232621 -8.752912) (xy 10.302165 -8.665708)
			(xy 10.364999 -8.573551) (xy 10.420769 -8.476956) (xy 10.469165 -8.376463) (xy 10.509916 -8.272635)
			(xy 10.542794 -8.166052) (xy 10.567616 -8.05731) (xy 10.584241 -7.947017) (xy 10.592578 -7.83579)
			(xy 10.59307 -7.78002) (xy 10.59307 0.40005) (xy 10.593555 0.470432) (xy 10.601447 0.610976) (xy 10.617208 0.750856)
			(xy 10.640787 0.889632) (xy 10.67211 1.026868) (xy 10.711079 1.162131) (xy 10.757571 1.294997) (xy 10.811439 1.425046)
			(xy 10.872515 1.551871) (xy 10.940606 1.675072) (xy 11.015497 1.794261) (xy 11.096954 1.909063) (xy 11.184719 2.019118)
			(xy 11.278518 2.124078) (xy 11.378053 2.223614) (xy 11.483014 2.317412) (xy 11.593068 2.405178) (xy 11.707871 2.486634)
			(xy 11.82706 2.561525) (xy 11.950261 2.629616) (xy 12.077085 2.690692) (xy 12.207135 2.74456) (xy 12.340001 2.791052)
			(xy 12.475264 2.83002) (xy 12.6125 2.861343) (xy 12.751276 2.884922) (xy 12.891156 2.900683) (xy 13.0317 2.908575)
			(xy 13.102082 2.909062) (xy 81.701894 2.909062) (xy 81.772277 2.908568) (xy 81.912821 2.900676) (xy 82.052702 2.884916)
			(xy 82.191479 2.861337) (xy 82.328715 2.830015) (xy 82.46398 2.791046) (xy 82.596846 2.744555) (xy 82.726897 2.690688)
			(xy 82.853723 2.629613) (xy 82.976925 2.561522) (xy 83.096116 2.486632) (xy 83.210919 2.405176) (xy 83.320975 2.317411)
			(xy 83.425937 2.223613) (xy 83.439191 2.210359) (xy 93.985575 2.210359) (xy 93.985575 2.296109) (xy 93.993487 2.381492)
			(xy 94.009243 2.465782) (xy 94.03271 2.548258) (xy 94.063686 2.628217) (xy 94.101908 2.704977) (xy 94.147049 2.777883)
			(xy 94.198725 2.846312) (xy 94.256494 2.909682) (xy 94.319864 2.967451) (xy 94.388293 3.019127) (xy 94.461199 3.064268)
			(xy 94.537959 3.10249) (xy 94.617918 3.133466) (xy 94.700394 3.156933) (xy 94.784684 3.172689) (xy 94.870067 3.180601)
			(xy 94.955817 3.180601) (xy 95.0412 3.172689) (xy 95.12549 3.156933) (xy 95.207966 3.133466) (xy 95.287925 3.10249)
			(xy 95.308598 3.092196) (xy 98.842576 3.092196) (xy 98.842576 3.955796) (xy 98.84308 3.985332) (xy 98.851124 4.043854)
			(xy 98.867061 4.100736) (xy 98.890596 4.154918) (xy 98.921289 4.205391) (xy 98.958569 4.251214) (xy 99.001741 4.291534)
			(xy 99.050001 4.3256) (xy 99.102451 4.352777) (xy 99.158112 4.372559) (xy 99.215949 4.384578) (xy 99.274884 4.388609)
			(xy 99.333819 4.384578) (xy 99.391656 4.372559) (xy 99.447317 4.352777) (xy 99.499767 4.3256) (xy 99.548027 4.291534)
			(xy 99.591199 4.251214) (xy 99.628479 4.205391) (xy 99.659172 4.154918) (xy 99.682707 4.100736) (xy 99.698644 4.043854)
			(xy 99.706688 3.985332) (xy 99.707192 3.955796) (xy 99.707192 3.092196) (xy 99.706688 3.06266) (xy 99.698644 3.004138)
			(xy 99.682707 2.947256) (xy 99.659172 2.893074) (xy 99.628479 2.842601) (xy 99.591199 2.796778) (xy 99.548027 2.756458)
			(xy 99.499767 2.722392) (xy 99.447317 2.695215) (xy 99.391656 2.675433) (xy 99.333819 2.663414) (xy 99.274884 2.659383)
			(xy 99.215949 2.663414) (xy 99.158112 2.675433) (xy 99.102451 2.695215) (xy 99.050001 2.722392) (xy 99.001741 2.756458)
			(xy 98.958569 2.796778) (xy 98.921289 2.842601) (xy 98.890596 2.893074) (xy 98.867061 2.947256) (xy 98.851124 3.004138)
			(xy 98.84308 3.06266) (xy 98.842576 3.092196) (xy 95.308598 3.092196) (xy 95.364685 3.064268) (xy 95.437591 3.019127)
			(xy 95.50602 2.967451) (xy 95.56939 2.909682) (xy 95.627159 2.846312) (xy 95.678835 2.777883) (xy 95.723976 2.704977)
			(xy 95.762198 2.628217) (xy 95.793174 2.548258) (xy 95.816641 2.465782) (xy 95.832397 2.381492) (xy 95.840309 2.296109)
			(xy 95.840804 2.253234) (xy 95.840309 2.210359) (xy 100.335575 2.210359) (xy 100.335575 2.296109)
			(xy 100.343487 2.381492) (xy 100.359243 2.465782) (xy 100.38271 2.548258) (xy 100.413686 2.628217)
			(xy 100.451908 2.704977) (xy 100.497049 2.777883) (xy 100.548725 2.846312) (xy 100.606494 2.909682)
			(xy 100.669864 2.967451) (xy 100.738293 3.019127) (xy 100.811199 3.064268) (xy 100.887959 3.10249)
			(xy 100.967918 3.133466) (xy 101.050394 3.156933) (xy 101.134684 3.172689) (xy 101.220067 3.180601)
			(xy 101.305817 3.180601) (xy 101.3912 3.172689) (xy 101.47549 3.156933) (xy 101.557966 3.133466)
			(xy 101.637925 3.10249) (xy 101.714685 3.064268) (xy 101.787591 3.019127) (xy 101.85602 2.967451)
			(xy 101.91939 2.909682) (xy 101.977159 2.846312) (xy 102.028835 2.777883) (xy 102.073976 2.704977)
			(xy 102.112198 2.628217) (xy 102.143174 2.548258) (xy 102.166641 2.465782) (xy 102.182397 2.381492)
			(xy 102.190309 2.296109) (xy 102.190804 2.253234) (xy 102.190309 2.210359) (xy 181.468255 2.210359)
			(xy 181.468255 2.296109) (xy 181.476167 2.381492) (xy 181.491923 2.465782) (xy 181.51539 2.548258)
			(xy 181.546366 2.628217) (xy 181.584588 2.704977) (xy 181.629729 2.777883) (xy 181.681405 2.846312)
			(xy 181.739174 2.909682) (xy 181.802544 2.967451) (xy 181.870973 3.019127) (xy 181.943879 3.064268)
			(xy 182.020639 3.10249) (xy 182.100598 3.133466) (xy 182.183074 3.156933) (xy 182.267364 3.172689)
			(xy 182.352747 3.180601) (xy 182.438497 3.180601) (xy 182.52388 3.172689) (xy 182.60817 3.156933)
			(xy 182.690646 3.133466) (xy 182.770605 3.10249) (xy 182.791278 3.092196) (xy 183.953912 3.092196)
			(xy 183.953912 3.955796) (xy 183.954416 3.985332) (xy 183.96246 4.043854) (xy 183.978397 4.100736)
			(xy 184.001932 4.154918) (xy 184.032625 4.205391) (xy 184.069905 4.251214) (xy 184.113077 4.291534)
			(xy 184.161337 4.3256) (xy 184.213787 4.352777) (xy 184.269448 4.372559) (xy 184.327285 4.384578)
			(xy 184.38622 4.388609) (xy 184.445155 4.384578) (xy 184.502992 4.372559) (xy 184.558653 4.352777)
			(xy 184.611103 4.3256) (xy 184.659363 4.291534) (xy 184.702535 4.251214) (xy 184.739815 4.205391)
			(xy 184.770508 4.154918) (xy 184.794043 4.100736) (xy 184.80998 4.043854) (xy 184.818024 3.985332)
			(xy 184.818528 3.955796) (xy 184.818528 3.769919) (xy 208.661241 3.769919) (xy 208.661241 3.855669)
			(xy 208.669153 3.941052) (xy 208.684909 4.025342) (xy 208.708376 4.107818) (xy 208.739352 4.187777)
			(xy 208.777574 4.264537) (xy 208.822715 4.337443) (xy 208.874391 4.405872) (xy 208.93216 4.469242)
			(xy 208.99553 4.527011) (xy 209.063959 4.578687) (xy 209.136865 4.623828) (xy 209.213625 4.66205)
			(xy 209.293584 4.693026) (xy 209.37606 4.716493) (xy 209.46035 4.732249) (xy 209.545733 4.740161)
			(xy 209.631483 4.740161) (xy 209.716866 4.732249) (xy 209.801156 4.716493) (xy 209.883632 4.693026)
			(xy 209.963591 4.66205) (xy 209.984264 4.651756) (xy 213.517988 4.651756) (xy 213.517988 5.515356)
			(xy 213.518492 5.54491) (xy 213.526541 5.603466) (xy 213.542487 5.660381) (xy 213.566036 5.714595)
			(xy 213.596747 5.765098) (xy 213.634049 5.810948) (xy 213.677246 5.851291) (xy 213.725535 5.885377)
			(xy 213.778015 5.91257) (xy 213.83371 5.932364) (xy 213.891581 5.94439) (xy 213.95055 5.948424) (xy 214.009519 5.94439)
			(xy 214.06739 5.932364) (xy 214.123085 5.91257) (xy 214.175565 5.885377) (xy 214.223854 5.851291)
			(xy 214.267051 5.810948) (xy 214.304353 5.765098) (xy 214.335064 5.714595) (xy 214.358613 5.660381)
			(xy 214.374559 5.603466) (xy 214.382608 5.54491) (xy 214.383112 5.515356) (xy 214.383112 4.651756)
			(xy 214.382608 4.622202) (xy 214.374559 4.563646) (xy 214.358613 4.506731) (xy 214.335064 4.452517)
			(xy 214.304353 4.402014) (xy 214.267051 4.356164) (xy 214.223854 4.315821) (xy 214.175565 4.281735)
			(xy 214.123085 4.254542) (xy 214.06739 4.234748) (xy 214.009519 4.222722) (xy 213.95055 4.218689)
			(xy 213.891581 4.222722) (xy 213.83371 4.234748) (xy 213.778015 4.254542) (xy 213.725535 4.281735)
			(xy 213.677246 4.315821) (xy 213.634049 4.356164) (xy 213.596747 4.402014) (xy 213.566036 4.452517)
			(xy 213.542487 4.506731) (xy 213.526541 4.563646) (xy 213.518492 4.622202) (xy 213.517988 4.651756)
			(xy 209.984264 4.651756) (xy 210.040351 4.623828) (xy 210.113257 4.578687) (xy 210.181686 4.527011)
			(xy 210.245056 4.469242) (xy 210.302825 4.405872) (xy 210.354501 4.337443) (xy 210.399642 4.264537)
			(xy 210.437864 4.187777) (xy 210.46884 4.107818) (xy 210.492307 4.025342) (xy 210.508063 3.941052)
			(xy 210.515975 3.855669) (xy 210.51647 3.812794) (xy 210.515975 3.769919) (xy 215.011241 3.769919)
			(xy 215.011241 3.855669) (xy 215.019153 3.941052) (xy 215.034909 4.025342) (xy 215.058376 4.107818)
			(xy 215.089352 4.187777) (xy 215.127574 4.264537) (xy 215.172715 4.337443) (xy 215.224391 4.405872)
			(xy 215.28216 4.469242) (xy 215.34553 4.527011) (xy 215.413959 4.578687) (xy 215.486865 4.623828)
			(xy 215.563625 4.66205) (xy 215.643584 4.693026) (xy 215.72606 4.716493) (xy 215.81035 4.732249)
			(xy 215.895733 4.740161) (xy 215.981483 4.740161) (xy 216.066866 4.732249) (xy 216.151156 4.716493)
			(xy 216.233632 4.693026) (xy 216.313591 4.66205) (xy 216.390351 4.623828) (xy 216.463257 4.578687)
			(xy 216.531686 4.527011) (xy 216.595056 4.469242) (xy 216.652825 4.405872) (xy 216.704501 4.337443)
			(xy 216.749642 4.264537) (xy 216.787864 4.187777) (xy 216.81884 4.107818) (xy 216.842307 4.025342)
			(xy 216.858063 3.941052) (xy 216.865975 3.855669) (xy 216.86647 3.812794) (xy 216.865975 3.769919)
			(xy 296.143921 3.769919) (xy 296.143921 3.855669) (xy 296.151833 3.941052) (xy 296.167589 4.025342)
			(xy 296.191056 4.107818) (xy 296.222032 4.187777) (xy 296.260254 4.264537) (xy 296.305395 4.337443)
			(xy 296.357071 4.405872) (xy 296.41484 4.469242) (xy 296.47821 4.527011) (xy 296.546639 4.578687)
			(xy 296.619545 4.623828) (xy 296.696305 4.66205) (xy 296.776264 4.693026) (xy 296.85874 4.716493)
			(xy 296.94303 4.732249) (xy 297.028413 4.740161) (xy 297.114163 4.740161) (xy 297.199546 4.732249)
			(xy 297.283836 4.716493) (xy 297.366312 4.693026) (xy 297.446271 4.66205) (xy 297.466944 4.651756)
			(xy 298.629324 4.651756) (xy 298.629324 5.515356) (xy 298.629828 5.54491) (xy 298.637877 5.603466)
			(xy 298.653823 5.660381) (xy 298.677372 5.714595) (xy 298.708083 5.765098) (xy 298.745385 5.810948)
			(xy 298.788582 5.851291) (xy 298.836871 5.885377) (xy 298.889351 5.91257) (xy 298.945046 5.932364)
			(xy 299.002917 5.94439) (xy 299.061886 5.948424) (xy 299.120855 5.94439) (xy 299.178726 5.932364)
			(xy 299.234421 5.91257) (xy 299.286901 5.885377) (xy 299.33519 5.851291) (xy 299.378387 5.810948)
			(xy 299.415689 5.765098) (xy 299.4464 5.714595) (xy 299.469949 5.660381) (xy 299.485895 5.603466)
			(xy 299.493944 5.54491) (xy 299.494448 5.515356) (xy 299.494448 4.651756) (xy 299.493944 4.622202)
			(xy 299.485895 4.563646) (xy 299.469949 4.506731) (xy 299.4464 4.452517) (xy 299.415689 4.402014)
			(xy 299.378387 4.356164) (xy 299.33519 4.315821) (xy 299.286901 4.281735) (xy 299.234421 4.254542)
			(xy 299.178726 4.234748) (xy 299.120855 4.222722) (xy 299.061886 4.218689) (xy 299.002917 4.222722)
			(xy 298.945046 4.234748) (xy 298.889351 4.254542) (xy 298.836871 4.281735) (xy 298.788582 4.315821)
			(xy 298.745385 4.356164) (xy 298.708083 4.402014) (xy 298.677372 4.452517) (xy 298.653823 4.506731)
			(xy 298.637877 4.563646) (xy 298.629828 4.622202) (xy 298.629324 4.651756) (xy 297.466944 4.651756)
			(xy 297.523031 4.623828) (xy 297.595937 4.578687) (xy 297.664366 4.527011) (xy 297.727736 4.469242)
			(xy 297.785505 4.405872) (xy 297.837181 4.337443) (xy 297.882322 4.264537) (xy 297.920544 4.187777)
			(xy 297.95152 4.107818) (xy 297.974987 4.025342) (xy 297.990743 3.941052) (xy 297.998655 3.855669)
			(xy 297.99915 3.812794) (xy 297.998655 3.769919) (xy 302.493921 3.769919) (xy 302.493921 3.855669)
			(xy 302.501833 3.941052) (xy 302.517589 4.025342) (xy 302.541056 4.107818) (xy 302.572032 4.187777)
			(xy 302.610254 4.264537) (xy 302.655395 4.337443) (xy 302.707071 4.405872) (xy 302.76484 4.469242)
			(xy 302.82821 4.527011) (xy 302.896639 4.578687) (xy 302.969545 4.623828) (xy 303.046305 4.66205)
			(xy 303.126264 4.693026) (xy 303.20874 4.716493) (xy 303.29303 4.732249) (xy 303.378413 4.740161)
			(xy 303.464163 4.740161) (xy 303.549546 4.732249) (xy 303.633836 4.716493) (xy 303.716312 4.693026)
			(xy 303.796271 4.66205) (xy 303.873031 4.623828) (xy 303.945937 4.578687) (xy 304.014366 4.527011)
			(xy 304.077736 4.469242) (xy 304.135505 4.405872) (xy 304.187181 4.337443) (xy 304.232322 4.264537)
			(xy 304.270544 4.187777) (xy 304.30152 4.107818) (xy 304.324987 4.025342) (xy 304.340743 3.941052)
			(xy 304.348655 3.855669) (xy 304.34915 3.812794) (xy 304.348655 3.769919) (xy 311.155321 3.769919)
			(xy 311.155321 3.855669) (xy 311.163233 3.941052) (xy 311.178989 4.025342) (xy 311.202456 4.107818)
			(xy 311.233432 4.187777) (xy 311.271654 4.264537) (xy 311.316795 4.337443) (xy 311.368471 4.405872)
			(xy 311.42624 4.469242) (xy 311.48961 4.527011) (xy 311.558039 4.578687) (xy 311.630945 4.623828)
			(xy 311.707705 4.66205) (xy 311.787664 4.693026) (xy 311.87014 4.716493) (xy 311.95443 4.732249)
			(xy 312.039813 4.740161) (xy 312.125563 4.740161) (xy 312.210946 4.732249) (xy 312.295236 4.716493)
			(xy 312.377712 4.693026) (xy 312.457671 4.66205) (xy 312.478344 4.651756) (xy 316.012068 4.651756)
			(xy 316.012068 5.515356) (xy 316.012572 5.54491) (xy 316.020621 5.603466) (xy 316.036567 5.660381)
			(xy 316.060116 5.714595) (xy 316.090827 5.765098) (xy 316.128129 5.810948) (xy 316.171326 5.851291)
			(xy 316.219615 5.885377) (xy 316.272095 5.91257) (xy 316.32779 5.932364) (xy 316.385661 5.94439)
			(xy 316.44463 5.948424) (xy 316.503599 5.94439) (xy 316.56147 5.932364) (xy 316.617165 5.91257) (xy 316.669645 5.885377)
			(xy 316.717934 5.851291) (xy 316.761131 5.810948) (xy 316.798433 5.765098) (xy 316.829144 5.714595)
			(xy 316.852693 5.660381) (xy 316.868639 5.603466) (xy 316.876688 5.54491) (xy 316.877192 5.515356)
			(xy 316.877192 4.651756) (xy 316.876688 4.622202) (xy 316.868639 4.563646) (xy 316.852693 4.506731)
			(xy 316.829144 4.452517) (xy 316.798433 4.402014) (xy 316.761131 4.356164) (xy 316.717934 4.315821)
			(xy 316.669645 4.281735) (xy 316.617165 4.254542) (xy 316.56147 4.234748) (xy 316.503599 4.222722)
			(xy 316.44463 4.218689) (xy 316.385661 4.222722) (xy 316.32779 4.234748) (xy 316.272095 4.254542)
			(xy 316.219615 4.281735) (xy 316.171326 4.315821) (xy 316.128129 4.356164) (xy 316.090827 4.402014)
			(xy 316.060116 4.452517) (xy 316.036567 4.506731) (xy 316.020621 4.563646) (xy 316.012572 4.622202)
			(xy 316.012068 4.651756) (xy 312.478344 4.651756) (xy 312.534431 4.623828) (xy 312.607337 4.578687)
			(xy 312.675766 4.527011) (xy 312.739136 4.469242) (xy 312.796905 4.405872) (xy 312.848581 4.337443)
			(xy 312.893722 4.264537) (xy 312.931944 4.187777) (xy 312.96292 4.107818) (xy 312.986387 4.025342)
			(xy 313.002143 3.941052) (xy 313.010055 3.855669) (xy 313.01055 3.812794) (xy 313.010055 3.769919)
			(xy 317.505321 3.769919) (xy 317.505321 3.855669) (xy 317.513233 3.941052) (xy 317.528989 4.025342)
			(xy 317.552456 4.107818) (xy 317.583432 4.187777) (xy 317.621654 4.264537) (xy 317.666795 4.337443)
			(xy 317.718471 4.405872) (xy 317.77624 4.469242) (xy 317.83961 4.527011) (xy 317.908039 4.578687)
			(xy 317.980945 4.623828) (xy 318.057705 4.66205) (xy 318.137664 4.693026) (xy 318.22014 4.716493)
			(xy 318.30443 4.732249) (xy 318.389813 4.740161) (xy 318.475563 4.740161) (xy 318.560946 4.732249)
			(xy 318.645236 4.716493) (xy 318.727712 4.693026) (xy 318.807671 4.66205) (xy 318.884431 4.623828)
			(xy 318.957337 4.578687) (xy 319.025766 4.527011) (xy 319.089136 4.469242) (xy 319.146905 4.405872)
			(xy 319.198581 4.337443) (xy 319.243722 4.264537) (xy 319.281944 4.187777) (xy 319.31292 4.107818)
			(xy 319.336387 4.025342) (xy 319.352143 3.941052) (xy 319.360055 3.855669) (xy 319.36055 3.812794)
			(xy 319.360055 3.769919) (xy 361.894107 3.769919) (xy 361.894107 3.855669) (xy 361.902019 3.941052)
			(xy 361.917775 4.025342) (xy 361.941242 4.107818) (xy 361.972218 4.187777) (xy 362.01044 4.264537)
			(xy 362.055581 4.337443) (xy 362.107257 4.405872) (xy 362.165026 4.469242) (xy 362.228396 4.527011)
			(xy 362.296825 4.578687) (xy 362.369731 4.623828) (xy 362.446491 4.66205) (xy 362.52645 4.693026)
			(xy 362.608926 4.716493) (xy 362.693216 4.732249) (xy 362.778599 4.740161) (xy 362.864349 4.740161)
			(xy 362.949732 4.732249) (xy 363.034022 4.716493) (xy 363.116498 4.693026) (xy 363.196457 4.66205)
			(xy 363.21713 4.651756) (xy 364.379764 4.651756) (xy 364.379764 5.515356) (xy 364.380268 5.544892)
			(xy 364.388312 5.603414) (xy 364.404249 5.660296) (xy 364.427784 5.714478) (xy 364.458477 5.764951)
			(xy 364.495757 5.810774) (xy 364.538929 5.851094) (xy 364.587189 5.88516) (xy 364.639639 5.912337)
			(xy 364.6953 5.932119) (xy 364.753137 5.944138) (xy 364.812072 5.948169) (xy 364.871007 5.944138)
			(xy 364.928844 5.932119) (xy 364.984505 5.912337) (xy 365.036955 5.88516) (xy 365.085215 5.851094)
			(xy 365.128387 5.810774) (xy 365.165667 5.764951) (xy 365.19636 5.714478) (xy 365.219895 5.660296)
			(xy 365.235832 5.603414) (xy 365.243876 5.544892) (xy 365.24438 5.515356) (xy 365.24438 4.836973)
			(xy 385.651997 4.836973) (xy 385.651997 4.922723) (xy 385.659909 5.008106) (xy 385.675665 5.092396)
			(xy 385.699132 5.174872) (xy 385.730108 5.254831) (xy 385.76833 5.331591) (xy 385.813471 5.404497)
			(xy 385.865147 5.472926) (xy 385.922916 5.536296) (xy 385.986286 5.594065) (xy 386.054715 5.645741)
			(xy 386.127621 5.690882) (xy 386.204381 5.729104) (xy 386.28434 5.76008) (xy 386.366816 5.783547)
			(xy 386.451106 5.799303) (xy 386.536489 5.807215) (xy 386.622239 5.807215) (xy 386.707622 5.799303)
			(xy 386.791912 5.783547) (xy 386.874388 5.76008) (xy 386.954347 5.729104) (xy 386.97502 5.71881)
			(xy 390.508744 5.71881) (xy 390.508744 6.58241) (xy 390.509248 6.611964) (xy 390.517297 6.67052)
			(xy 390.533243 6.727435) (xy 390.556792 6.781649) (xy 390.587503 6.832152) (xy 390.624805 6.878002)
			(xy 390.668002 6.918345) (xy 390.716291 6.952431) (xy 390.768771 6.979624) (xy 390.824466 6.999418)
			(xy 390.882337 7.011444) (xy 390.941306 7.015478) (xy 391.000275 7.011444) (xy 391.058146 6.999418)
			(xy 391.113841 6.979624) (xy 391.166321 6.952431) (xy 391.21461 6.918345) (xy 391.257807 6.878002)
			(xy 391.295109 6.832152) (xy 391.32582 6.781649) (xy 391.349369 6.727435) (xy 391.365315 6.67052)
			(xy 391.373364 6.611964) (xy 391.373868 6.58241) (xy 391.373868 5.71881) (xy 391.373364 5.689256)
			(xy 391.365315 5.6307) (xy 391.349369 5.573785) (xy 391.32582 5.519571) (xy 391.295109 5.469068)
			(xy 391.257807 5.423218) (xy 391.21461 5.382875) (xy 391.166321 5.348789) (xy 391.113841 5.321596)
			(xy 391.058146 5.301802) (xy 391.000275 5.289776) (xy 390.941306 5.285743) (xy 390.882337 5.289776)
			(xy 390.824466 5.301802) (xy 390.768771 5.321596) (xy 390.716291 5.348789) (xy 390.668002 5.382875)
			(xy 390.624805 5.423218) (xy 390.587503 5.469068) (xy 390.556792 5.519571) (xy 390.533243 5.573785)
			(xy 390.517297 5.6307) (xy 390.509248 5.689256) (xy 390.508744 5.71881) (xy 386.97502 5.71881) (xy 387.031107 5.690882)
			(xy 387.104013 5.645741) (xy 387.172442 5.594065) (xy 387.235812 5.536296) (xy 387.293581 5.472926)
			(xy 387.345257 5.404497) (xy 387.390398 5.331591) (xy 387.42862 5.254831) (xy 387.459596 5.174872)
			(xy 387.483063 5.092396) (xy 387.498819 5.008106) (xy 387.506731 4.922723) (xy 387.507226 4.879848)
			(xy 387.506731 4.836973) (xy 392.001997 4.836973) (xy 392.001997 4.922723) (xy 392.009909 5.008106)
			(xy 392.025665 5.092396) (xy 392.049132 5.174872) (xy 392.080108 5.254831) (xy 392.11833 5.331591)
			(xy 392.163471 5.404497) (xy 392.215147 5.472926) (xy 392.272916 5.536296) (xy 392.336286 5.594065)
			(xy 392.404715 5.645741) (xy 392.477621 5.690882) (xy 392.554381 5.729104) (xy 392.63434 5.76008)
			(xy 392.716816 5.783547) (xy 392.801106 5.799303) (xy 392.886489 5.807215) (xy 392.972239 5.807215)
			(xy 393.057622 5.799303) (xy 393.141912 5.783547) (xy 393.224388 5.76008) (xy 393.304347 5.729104)
			(xy 393.381107 5.690882) (xy 393.454013 5.645741) (xy 393.522442 5.594065) (xy 393.585812 5.536296)
			(xy 393.643581 5.472926) (xy 393.695257 5.404497) (xy 393.740398 5.331591) (xy 393.77862 5.254831)
			(xy 393.809596 5.174872) (xy 393.833063 5.092396) (xy 393.848819 5.008106) (xy 393.856731 4.922723)
			(xy 393.857226 4.879848) (xy 393.856731 4.836973) (xy 436.390783 4.836973) (xy 436.390783 4.922723)
			(xy 436.398695 5.008106) (xy 436.414451 5.092396) (xy 436.437918 5.174872) (xy 436.468894 5.254831)
			(xy 436.507116 5.331591) (xy 436.552257 5.404497) (xy 436.603933 5.472926) (xy 436.661702 5.536296)
			(xy 436.725072 5.594065) (xy 436.793501 5.645741) (xy 436.866407 5.690882) (xy 436.943167 5.729104)
			(xy 437.023126 5.76008) (xy 437.105602 5.783547) (xy 437.189892 5.799303) (xy 437.275275 5.807215)
			(xy 437.361025 5.807215) (xy 437.446408 5.799303) (xy 437.530698 5.783547) (xy 437.613174 5.76008)
			(xy 437.693133 5.729104) (xy 437.713806 5.71881) (xy 438.87644 5.71881) (xy 438.87644 6.58241) (xy 438.876944 6.611946)
			(xy 438.884988 6.670468) (xy 438.900925 6.72735) (xy 438.92446 6.781532) (xy 438.955153 6.832005)
			(xy 438.992433 6.877828) (xy 439.035605 6.918148) (xy 439.083865 6.952214) (xy 439.136315 6.979391)
			(xy 439.191976 6.999173) (xy 439.249813 7.011192) (xy 439.308748 7.015223) (xy 439.367683 7.011192)
			(xy 439.42552 6.999173) (xy 439.481181 6.979391) (xy 439.533631 6.952214) (xy 439.581891 6.918148)
			(xy 439.625063 6.877828) (xy 439.662343 6.832005) (xy 439.693036 6.781532) (xy 439.716571 6.72735)
			(xy 439.732508 6.670468) (xy 439.740552 6.611946) (xy 439.741056 6.58241) (xy 439.741056 5.71881)
			(xy 439.740552 5.689274) (xy 439.732508 5.630752) (xy 439.716571 5.57387) (xy 439.693036 5.519688)
			(xy 439.662343 5.469215) (xy 439.625063 5.423392) (xy 439.581891 5.383072) (xy 439.533631 5.349006)
			(xy 439.481181 5.321829) (xy 439.42552 5.302047) (xy 439.367683 5.290028) (xy 439.308748 5.285997)
			(xy 439.249813 5.290028) (xy 439.191976 5.302047) (xy 439.136315 5.321829) (xy 439.083865 5.349006)
			(xy 439.035605 5.383072) (xy 438.992433 5.423392) (xy 438.955153 5.469215) (xy 438.92446 5.519688)
			(xy 438.900925 5.57387) (xy 438.884988 5.630752) (xy 438.876944 5.689274) (xy 438.87644 5.71881)
			(xy 437.713806 5.71881) (xy 437.769893 5.690882) (xy 437.842799 5.645741) (xy 437.911228 5.594065)
			(xy 437.974598 5.536296) (xy 438.032367 5.472926) (xy 438.084043 5.404497) (xy 438.129184 5.331591)
			(xy 438.167406 5.254831) (xy 438.198382 5.174872) (xy 438.221849 5.092396) (xy 438.237605 5.008106)
			(xy 438.245517 4.922723) (xy 438.246012 4.879848) (xy 438.245517 4.836973) (xy 442.740783 4.836973)
			(xy 442.740783 4.922723) (xy 442.748695 5.008106) (xy 442.764451 5.092396) (xy 442.787918 5.174872)
			(xy 442.818894 5.254831) (xy 442.857116 5.331591) (xy 442.902257 5.404497) (xy 442.953933 5.472926)
			(xy 443.011702 5.536296) (xy 443.075072 5.594065) (xy 443.143501 5.645741) (xy 443.216407 5.690882)
			(xy 443.293167 5.729104) (xy 443.373126 5.76008) (xy 443.455602 5.783547) (xy 443.539892 5.799303)
			(xy 443.625275 5.807215) (xy 443.711025 5.807215) (xy 443.796408 5.799303) (xy 443.880698 5.783547)
			(xy 443.963174 5.76008) (xy 444.043133 5.729104) (xy 444.119893 5.690882) (xy 444.192799 5.645741)
			(xy 444.261228 5.594065) (xy 444.324598 5.536296) (xy 444.382367 5.472926) (xy 444.434043 5.404497)
			(xy 444.479184 5.331591) (xy 444.517406 5.254831) (xy 444.548382 5.174872) (xy 444.571849 5.092396)
			(xy 444.587605 5.008106) (xy 444.595517 4.922723) (xy 444.596012 4.879848) (xy 444.595517 4.836973)
			(xy 444.587605 4.75159) (xy 444.571849 4.6673) (xy 444.548382 4.584824) (xy 444.517406 4.504865)
			(xy 444.479184 4.428105) (xy 444.434043 4.355199) (xy 444.382367 4.28677) (xy 444.324598 4.2234)
			(xy 444.261228 4.165631) (xy 444.192799 4.113955) (xy 444.119893 4.068814) (xy 444.043133 4.030592)
			(xy 443.963174 3.999616) (xy 443.880698 3.976149) (xy 443.796408 3.960393) (xy 443.711025 3.952481)
			(xy 443.625275 3.952481) (xy 443.539892 3.960393) (xy 443.455602 3.976149) (xy 443.373126 3.999616)
			(xy 443.293167 4.030592) (xy 443.216407 4.068814) (xy 443.143501 4.113955) (xy 443.075072 4.165631)
			(xy 443.011702 4.2234) (xy 442.953933 4.28677) (xy 442.902257 4.355199) (xy 442.857116 4.428105)
			(xy 442.818894 4.504865) (xy 442.787918 4.584824) (xy 442.764451 4.6673) (xy 442.748695 4.75159)
			(xy 442.740783 4.836973) (xy 438.245517 4.836973) (xy 438.237605 4.75159) (xy 438.221849 4.6673)
			(xy 438.198382 4.584824) (xy 438.167406 4.504865) (xy 438.129184 4.428105) (xy 438.084043 4.355199)
			(xy 438.032367 4.28677) (xy 437.974598 4.2234) (xy 437.911228 4.165631) (xy 437.842799 4.113955)
			(xy 437.769893 4.068814) (xy 437.693133 4.030592) (xy 437.613174 3.999616) (xy 437.530698 3.976149)
			(xy 437.446408 3.960393) (xy 437.361025 3.952481) (xy 437.275275 3.952481) (xy 437.189892 3.960393)
			(xy 437.105602 3.976149) (xy 437.023126 3.999616) (xy 436.943167 4.030592) (xy 436.866407 4.068814)
			(xy 436.793501 4.113955) (xy 436.725072 4.165631) (xy 436.661702 4.2234) (xy 436.603933 4.28677)
			(xy 436.552257 4.355199) (xy 436.507116 4.428105) (xy 436.468894 4.504865) (xy 436.437918 4.584824)
			(xy 436.414451 4.6673) (xy 436.398695 4.75159) (xy 436.390783 4.836973) (xy 393.856731 4.836973)
			(xy 393.848819 4.75159) (xy 393.833063 4.6673) (xy 393.809596 4.584824) (xy 393.77862 4.504865) (xy 393.740398 4.428105)
			(xy 393.695257 4.355199) (xy 393.643581 4.28677) (xy 393.585812 4.2234) (xy 393.522442 4.165631)
			(xy 393.454013 4.113955) (xy 393.381107 4.068814) (xy 393.304347 4.030592) (xy 393.224388 3.999616)
			(xy 393.141912 3.976149) (xy 393.057622 3.960393) (xy 392.972239 3.952481) (xy 392.886489 3.952481)
			(xy 392.801106 3.960393) (xy 392.716816 3.976149) (xy 392.63434 3.999616) (xy 392.554381 4.030592)
			(xy 392.477621 4.068814) (xy 392.404715 4.113955) (xy 392.336286 4.165631) (xy 392.272916 4.2234)
			(xy 392.215147 4.28677) (xy 392.163471 4.355199) (xy 392.11833 4.428105) (xy 392.080108 4.504865)
			(xy 392.049132 4.584824) (xy 392.025665 4.6673) (xy 392.009909 4.75159) (xy 392.001997 4.836973)
			(xy 387.506731 4.836973) (xy 387.498819 4.75159) (xy 387.483063 4.6673) (xy 387.459596 4.584824)
			(xy 387.42862 4.504865) (xy 387.390398 4.428105) (xy 387.345257 4.355199) (xy 387.293581 4.28677)
			(xy 387.235812 4.2234) (xy 387.172442 4.165631) (xy 387.104013 4.113955) (xy 387.031107 4.068814)
			(xy 386.954347 4.030592) (xy 386.874388 3.999616) (xy 386.791912 3.976149) (xy 386.707622 3.960393)
			(xy 386.622239 3.952481) (xy 386.536489 3.952481) (xy 386.451106 3.960393) (xy 386.366816 3.976149)
			(xy 386.28434 3.999616) (xy 386.204381 4.030592) (xy 386.127621 4.068814) (xy 386.054715 4.113955)
			(xy 385.986286 4.165631) (xy 385.922916 4.2234) (xy 385.865147 4.28677) (xy 385.813471 4.355199)
			(xy 385.76833 4.428105) (xy 385.730108 4.504865) (xy 385.699132 4.584824) (xy 385.675665 4.6673)
			(xy 385.659909 4.75159) (xy 385.651997 4.836973) (xy 365.24438 4.836973) (xy 365.24438 4.651756)
			(xy 365.243876 4.62222) (xy 365.235832 4.563698) (xy 365.219895 4.506816) (xy 365.19636 4.452634)
			(xy 365.165667 4.402161) (xy 365.128387 4.356338) (xy 365.085215 4.316018) (xy 365.036955 4.281952)
			(xy 364.984505 4.254775) (xy 364.928844 4.234993) (xy 364.871007 4.222974) (xy 364.812072 4.218943)
			(xy 364.753137 4.222974) (xy 364.6953 4.234993) (xy 364.639639 4.254775) (xy 364.587189 4.281952)
			(xy 364.538929 4.316018) (xy 364.495757 4.356338) (xy 364.458477 4.402161) (xy 364.427784 4.452634)
			(xy 364.404249 4.506816) (xy 364.388312 4.563698) (xy 364.380268 4.62222) (xy 364.379764 4.651756)
			(xy 363.21713 4.651756) (xy 363.273217 4.623828) (xy 363.346123 4.578687) (xy 363.414552 4.527011)
			(xy 363.477922 4.469242) (xy 363.535691 4.405872) (xy 363.587367 4.337443) (xy 363.632508 4.264537)
			(xy 363.67073 4.187777) (xy 363.701706 4.107818) (xy 363.725173 4.025342) (xy 363.740929 3.941052)
			(xy 363.748841 3.855669) (xy 363.749336 3.812794) (xy 363.748841 3.769919) (xy 368.244107 3.769919)
			(xy 368.244107 3.855669) (xy 368.252019 3.941052) (xy 368.267775 4.025342) (xy 368.291242 4.107818)
			(xy 368.322218 4.187777) (xy 368.36044 4.264537) (xy 368.405581 4.337443) (xy 368.457257 4.405872)
			(xy 368.515026 4.469242) (xy 368.578396 4.527011) (xy 368.646825 4.578687) (xy 368.719731 4.623828)
			(xy 368.796491 4.66205) (xy 368.87645 4.693026) (xy 368.958926 4.716493) (xy 369.043216 4.732249)
			(xy 369.128599 4.740161) (xy 369.214349 4.740161) (xy 369.299732 4.732249) (xy 369.384022 4.716493)
			(xy 369.466498 4.693026) (xy 369.546457 4.66205) (xy 369.623217 4.623828) (xy 369.696123 4.578687)
			(xy 369.764552 4.527011) (xy 369.827922 4.469242) (xy 369.885691 4.405872) (xy 369.937367 4.337443)
			(xy 369.982508 4.264537) (xy 370.02073 4.187777) (xy 370.051706 4.107818) (xy 370.075173 4.025342)
			(xy 370.090929 3.941052) (xy 370.098841 3.855669) (xy 370.099336 3.812794) (xy 370.098841 3.769919)
			(xy 370.090929 3.684536) (xy 370.075173 3.600246) (xy 370.051706 3.51777) (xy 370.02073 3.437811)
			(xy 369.982508 3.361051) (xy 369.937367 3.288145) (xy 369.885691 3.219716) (xy 369.827922 3.156346)
			(xy 369.764552 3.098577) (xy 369.696123 3.046901) (xy 369.623217 3.00176) (xy 369.546457 2.963538)
			(xy 369.466498 2.932562) (xy 369.384022 2.909095) (xy 369.299732 2.893339) (xy 369.214349 2.885427)
			(xy 369.128599 2.885427) (xy 369.043216 2.893339) (xy 368.958926 2.909095) (xy 368.87645 2.932562)
			(xy 368.796491 2.963538) (xy 368.719731 3.00176) (xy 368.646825 3.046901) (xy 368.578396 3.098577)
			(xy 368.515026 3.156346) (xy 368.457257 3.219716) (xy 368.405581 3.288145) (xy 368.36044 3.361051)
			(xy 368.322218 3.437811) (xy 368.291242 3.51777) (xy 368.267775 3.600246) (xy 368.252019 3.684536)
			(xy 368.244107 3.769919) (xy 363.748841 3.769919) (xy 363.740929 3.684536) (xy 363.725173 3.600246)
			(xy 363.701706 3.51777) (xy 363.67073 3.437811) (xy 363.632508 3.361051) (xy 363.587367 3.288145)
			(xy 363.535691 3.219716) (xy 363.477922 3.156346) (xy 363.414552 3.098577) (xy 363.346123 3.046901)
			(xy 363.273217 3.00176) (xy 363.196457 2.963538) (xy 363.116498 2.932562) (xy 363.034022 2.909095)
			(xy 362.949732 2.893339) (xy 362.864349 2.885427) (xy 362.778599 2.885427) (xy 362.693216 2.893339)
			(xy 362.608926 2.909095) (xy 362.52645 2.932562) (xy 362.446491 2.963538) (xy 362.369731 3.00176)
			(xy 362.296825 3.046901) (xy 362.228396 3.098577) (xy 362.165026 3.156346) (xy 362.107257 3.219716)
			(xy 362.055581 3.288145) (xy 362.01044 3.361051) (xy 361.972218 3.437811) (xy 361.941242 3.51777)
			(xy 361.917775 3.600246) (xy 361.902019 3.684536) (xy 361.894107 3.769919) (xy 319.360055 3.769919)
			(xy 319.352143 3.684536) (xy 319.336387 3.600246) (xy 319.31292 3.51777) (xy 319.281944 3.437811)
			(xy 319.243722 3.361051) (xy 319.198581 3.288145) (xy 319.146905 3.219716) (xy 319.089136 3.156346)
			(xy 319.025766 3.098577) (xy 318.957337 3.046901) (xy 318.884431 3.00176) (xy 318.807671 2.963538)
			(xy 318.727712 2.932562) (xy 318.645236 2.909095) (xy 318.560946 2.893339) (xy 318.475563 2.885427)
			(xy 318.389813 2.885427) (xy 318.30443 2.893339) (xy 318.22014 2.909095) (xy 318.137664 2.932562)
			(xy 318.057705 2.963538) (xy 317.980945 3.00176) (xy 317.908039 3.046901) (xy 317.83961 3.098577)
			(xy 317.77624 3.156346) (xy 317.718471 3.219716) (xy 317.666795 3.288145) (xy 317.621654 3.361051)
			(xy 317.583432 3.437811) (xy 317.552456 3.51777) (xy 317.528989 3.600246) (xy 317.513233 3.684536)
			(xy 317.505321 3.769919) (xy 313.010055 3.769919) (xy 313.002143 3.684536) (xy 312.986387 3.600246)
			(xy 312.96292 3.51777) (xy 312.931944 3.437811) (xy 312.893722 3.361051) (xy 312.848581 3.288145)
			(xy 312.796905 3.219716) (xy 312.739136 3.156346) (xy 312.675766 3.098577) (xy 312.607337 3.046901)
			(xy 312.534431 3.00176) (xy 312.457671 2.963538) (xy 312.377712 2.932562) (xy 312.295236 2.909095)
			(xy 312.210946 2.893339) (xy 312.125563 2.885427) (xy 312.039813 2.885427) (xy 311.95443 2.893339)
			(xy 311.87014 2.909095) (xy 311.787664 2.932562) (xy 311.707705 2.963538) (xy 311.630945 3.00176)
			(xy 311.558039 3.046901) (xy 311.48961 3.098577) (xy 311.42624 3.156346) (xy 311.368471 3.219716)
			(xy 311.316795 3.288145) (xy 311.271654 3.361051) (xy 311.233432 3.437811) (xy 311.202456 3.51777)
			(xy 311.178989 3.600246) (xy 311.163233 3.684536) (xy 311.155321 3.769919) (xy 304.348655 3.769919)
			(xy 304.340743 3.684536) (xy 304.324987 3.600246) (xy 304.30152 3.51777) (xy 304.270544 3.437811)
			(xy 304.232322 3.361051) (xy 304.187181 3.288145) (xy 304.135505 3.219716) (xy 304.077736 3.156346)
			(xy 304.014366 3.098577) (xy 303.945937 3.046901) (xy 303.873031 3.00176) (xy 303.796271 2.963538)
			(xy 303.716312 2.932562) (xy 303.633836 2.909095) (xy 303.549546 2.893339) (xy 303.464163 2.885427)
			(xy 303.378413 2.885427) (xy 303.29303 2.893339) (xy 303.20874 2.909095) (xy 303.126264 2.932562)
			(xy 303.046305 2.963538) (xy 302.969545 3.00176) (xy 302.896639 3.046901) (xy 302.82821 3.098577)
			(xy 302.76484 3.156346) (xy 302.707071 3.219716) (xy 302.655395 3.288145) (xy 302.610254 3.361051)
			(xy 302.572032 3.437811) (xy 302.541056 3.51777) (xy 302.517589 3.600246) (xy 302.501833 3.684536)
			(xy 302.493921 3.769919) (xy 297.998655 3.769919) (xy 297.990743 3.684536) (xy 297.974987 3.600246)
			(xy 297.95152 3.51777) (xy 297.920544 3.437811) (xy 297.882322 3.361051) (xy 297.837181 3.288145)
			(xy 297.785505 3.219716) (xy 297.727736 3.156346) (xy 297.664366 3.098577) (xy 297.595937 3.046901)
			(xy 297.523031 3.00176) (xy 297.446271 2.963538) (xy 297.366312 2.932562) (xy 297.283836 2.909095)
			(xy 297.199546 2.893339) (xy 297.114163 2.885427) (xy 297.028413 2.885427) (xy 296.94303 2.893339)
			(xy 296.85874 2.909095) (xy 296.776264 2.932562) (xy 296.696305 2.963538) (xy 296.619545 3.00176)
			(xy 296.546639 3.046901) (xy 296.47821 3.098577) (xy 296.41484 3.156346) (xy 296.357071 3.219716)
			(xy 296.305395 3.288145) (xy 296.260254 3.361051) (xy 296.222032 3.437811) (xy 296.191056 3.51777)
			(xy 296.167589 3.600246) (xy 296.151833 3.684536) (xy 296.143921 3.769919) (xy 216.865975 3.769919)
			(xy 216.858063 3.684536) (xy 216.842307 3.600246) (xy 216.81884 3.51777) (xy 216.787864 3.437811)
			(xy 216.749642 3.361051) (xy 216.704501 3.288145) (xy 216.652825 3.219716) (xy 216.595056 3.156346)
			(xy 216.531686 3.098577) (xy 216.463257 3.046901) (xy 216.390351 3.00176) (xy 216.313591 2.963538)
			(xy 216.233632 2.932562) (xy 216.151156 2.909095) (xy 216.066866 2.893339) (xy 215.981483 2.885427)
			(xy 215.895733 2.885427) (xy 215.81035 2.893339) (xy 215.72606 2.909095) (xy 215.643584 2.932562)
			(xy 215.563625 2.963538) (xy 215.486865 3.00176) (xy 215.413959 3.046901) (xy 215.34553 3.098577)
			(xy 215.28216 3.156346) (xy 215.224391 3.219716) (xy 215.172715 3.288145) (xy 215.127574 3.361051)
			(xy 215.089352 3.437811) (xy 215.058376 3.51777) (xy 215.034909 3.600246) (xy 215.019153 3.684536)
			(xy 215.011241 3.769919) (xy 210.515975 3.769919) (xy 210.508063 3.684536) (xy 210.492307 3.600246)
			(xy 210.46884 3.51777) (xy 210.437864 3.437811) (xy 210.399642 3.361051) (xy 210.354501 3.288145)
			(xy 210.302825 3.219716) (xy 210.245056 3.156346) (xy 210.181686 3.098577) (xy 210.113257 3.046901)
			(xy 210.040351 3.00176) (xy 209.963591 2.963538) (xy 209.883632 2.932562) (xy 209.801156 2.909095)
			(xy 209.716866 2.893339) (xy 209.631483 2.885427) (xy 209.545733 2.885427) (xy 209.46035 2.893339)
			(xy 209.37606 2.909095) (xy 209.293584 2.932562) (xy 209.213625 2.963538) (xy 209.136865 3.00176)
			(xy 209.063959 3.046901) (xy 208.99553 3.098577) (xy 208.93216 3.156346) (xy 208.874391 3.219716)
			(xy 208.822715 3.288145) (xy 208.777574 3.361051) (xy 208.739352 3.437811) (xy 208.708376 3.51777)
			(xy 208.684909 3.600246) (xy 208.669153 3.684536) (xy 208.661241 3.769919) (xy 184.818528 3.769919)
			(xy 184.818528 3.092196) (xy 184.818024 3.06266) (xy 184.80998 3.004138) (xy 184.794043 2.947256)
			(xy 184.770508 2.893074) (xy 184.739815 2.842601) (xy 184.702535 2.796778) (xy 184.659363 2.756458)
			(xy 184.611103 2.722392) (xy 184.558653 2.695215) (xy 184.502992 2.675433) (xy 184.445155 2.663414)
			(xy 184.38622 2.659383) (xy 184.327285 2.663414) (xy 184.269448 2.675433) (xy 184.213787 2.695215)
			(xy 184.161337 2.722392) (xy 184.113077 2.756458) (xy 184.069905 2.796778) (xy 184.032625 2.842601)
			(xy 184.001932 2.893074) (xy 183.978397 2.947256) (xy 183.96246 3.004138) (xy 183.954416 3.06266)
			(xy 183.953912 3.092196) (xy 182.791278 3.092196) (xy 182.847365 3.064268) (xy 182.920271 3.019127)
			(xy 182.9887 2.967451) (xy 183.05207 2.909682) (xy 183.109839 2.846312) (xy 183.161515 2.777883)
			(xy 183.206656 2.704977) (xy 183.244878 2.628217) (xy 183.275854 2.548258) (xy 183.299321 2.465782)
			(xy 183.315077 2.381492) (xy 183.322989 2.296109) (xy 183.323484 2.253234) (xy 183.322989 2.210359)
			(xy 187.818255 2.210359) (xy 187.818255 2.296109) (xy 187.826167 2.381492) (xy 187.841923 2.465782)
			(xy 187.86539 2.548258) (xy 187.896366 2.628217) (xy 187.934588 2.704977) (xy 187.979729 2.777883)
			(xy 188.031405 2.846312) (xy 188.089174 2.909682) (xy 188.152544 2.967451) (xy 188.220973 3.019127)
			(xy 188.293879 3.064268) (xy 188.370639 3.10249) (xy 188.450598 3.133466) (xy 188.533074 3.156933)
			(xy 188.617364 3.172689) (xy 188.702747 3.180601) (xy 188.788497 3.180601) (xy 188.87388 3.172689)
			(xy 188.95817 3.156933) (xy 189.040646 3.133466) (xy 189.120605 3.10249) (xy 189.197365 3.064268)
			(xy 189.270271 3.019127) (xy 189.3387 2.967451) (xy 189.40207 2.909682) (xy 189.459839 2.846312)
			(xy 189.511515 2.777883) (xy 189.556656 2.704977) (xy 189.594878 2.628217) (xy 189.625854 2.548258)
			(xy 189.649321 2.465782) (xy 189.665077 2.381492) (xy 189.672989 2.296109) (xy 189.673484 2.253234)
			(xy 189.672989 2.210359) (xy 189.665077 2.124976) (xy 189.649321 2.040686) (xy 189.625854 1.95821)
			(xy 189.594878 1.878251) (xy 189.556656 1.801491) (xy 189.511515 1.728585) (xy 189.459839 1.660156)
			(xy 189.40207 1.596786) (xy 189.3387 1.539017) (xy 189.270271 1.487341) (xy 189.197365 1.4422) (xy 189.120605 1.403978)
			(xy 189.040646 1.373002) (xy 188.95817 1.349535) (xy 188.87388 1.333779) (xy 188.788497 1.325867)
			(xy 188.702747 1.325867) (xy 188.617364 1.333779) (xy 188.533074 1.349535) (xy 188.450598 1.373002)
			(xy 188.370639 1.403978) (xy 188.293879 1.4422) (xy 188.220973 1.487341) (xy 188.152544 1.539017)
			(xy 188.089174 1.596786) (xy 188.031405 1.660156) (xy 187.979729 1.728585) (xy 187.934588 1.801491)
			(xy 187.896366 1.878251) (xy 187.86539 1.95821) (xy 187.841923 2.040686) (xy 187.826167 2.124976)
			(xy 187.818255 2.210359) (xy 183.322989 2.210359) (xy 183.315077 2.124976) (xy 183.299321 2.040686)
			(xy 183.275854 1.95821) (xy 183.244878 1.878251) (xy 183.206656 1.801491) (xy 183.161515 1.728585)
			(xy 183.109839 1.660156) (xy 183.05207 1.596786) (xy 182.9887 1.539017) (xy 182.920271 1.487341)
			(xy 182.847365 1.4422) (xy 182.770605 1.403978) (xy 182.690646 1.373002) (xy 182.60817 1.349535)
			(xy 182.52388 1.333779) (xy 182.438497 1.325867) (xy 182.352747 1.325867) (xy 182.267364 1.333779)
			(xy 182.183074 1.349535) (xy 182.100598 1.373002) (xy 182.020639 1.403978) (xy 181.943879 1.4422)
			(xy 181.870973 1.487341) (xy 181.802544 1.539017) (xy 181.739174 1.596786) (xy 181.681405 1.660156)
			(xy 181.629729 1.728585) (xy 181.584588 1.801491) (xy 181.546366 1.878251) (xy 181.51539 1.95821)
			(xy 181.491923 2.040686) (xy 181.476167 2.124976) (xy 181.468255 2.210359) (xy 102.190309 2.210359)
			(xy 102.182397 2.124976) (xy 102.166641 2.040686) (xy 102.143174 1.95821) (xy 102.112198 1.878251)
			(xy 102.073976 1.801491) (xy 102.028835 1.728585) (xy 101.977159 1.660156) (xy 101.91939 1.596786)
			(xy 101.85602 1.539017) (xy 101.787591 1.487341) (xy 101.714685 1.4422) (xy 101.637925 1.403978)
			(xy 101.557966 1.373002) (xy 101.47549 1.349535) (xy 101.3912 1.333779) (xy 101.305817 1.325867)
			(xy 101.220067 1.325867) (xy 101.134684 1.333779) (xy 101.050394 1.349535) (xy 100.967918 1.373002)
			(xy 100.887959 1.403978) (xy 100.811199 1.4422) (xy 100.738293 1.487341) (xy 100.669864 1.539017)
			(xy 100.606494 1.596786) (xy 100.548725 1.660156) (xy 100.497049 1.728585) (xy 100.451908 1.801491)
			(xy 100.413686 1.878251) (xy 100.38271 1.95821) (xy 100.359243 2.040686) (xy 100.343487 2.124976)
			(xy 100.335575 2.210359) (xy 95.840309 2.210359) (xy 95.832397 2.124976) (xy 95.816641 2.040686)
			(xy 95.793174 1.95821) (xy 95.762198 1.878251) (xy 95.723976 1.801491) (xy 95.678835 1.728585) (xy 95.627159 1.660156)
			(xy 95.56939 1.596786) (xy 95.50602 1.539017) (xy 95.437591 1.487341) (xy 95.364685 1.4422) (xy 95.287925 1.403978)
			(xy 95.207966 1.373002) (xy 95.12549 1.349535) (xy 95.0412 1.333779) (xy 94.955817 1.325867) (xy 94.870067 1.325867)
			(xy 94.784684 1.333779) (xy 94.700394 1.349535) (xy 94.617918 1.373002) (xy 94.537959 1.403978) (xy 94.461199 1.4422)
			(xy 94.388293 1.487341) (xy 94.319864 1.539017) (xy 94.256494 1.596786) (xy 94.198725 1.660156) (xy 94.147049 1.728585)
			(xy 94.101908 1.801491) (xy 94.063686 1.878251) (xy 94.03271 1.95821) (xy 94.009243 2.040686) (xy 93.993487 2.124976)
			(xy 93.985575 2.210359) (xy 83.439191 2.210359) (xy 83.525475 2.124078) (xy 83.619275 2.019118) (xy 83.707042 1.909064)
			(xy 83.788501 1.794262) (xy 83.863394 1.675073) (xy 83.931487 1.551873) (xy 83.992565 1.425048) (xy 84.046435 1.294999)
			(xy 84.069209 1.229919) (xy 208.661241 1.229919) (xy 208.661241 1.315669) (xy 208.669153 1.401052)
			(xy 208.684909 1.485342) (xy 208.708376 1.567818) (xy 208.739352 1.647777) (xy 208.777574 1.724537)
			(xy 208.822715 1.797443) (xy 208.874391 1.865872) (xy 208.93216 1.929242) (xy 208.99553 1.987011)
			(xy 209.063959 2.038687) (xy 209.136865 2.083828) (xy 209.213625 2.12205) (xy 209.293584 2.153026)
			(xy 209.37606 2.176493) (xy 209.46035 2.192249) (xy 209.545733 2.200161) (xy 209.631483 2.200161)
			(xy 209.716866 2.192249) (xy 209.801156 2.176493) (xy 209.883632 2.153026) (xy 209.963591 2.12205)
			(xy 209.984264 2.111756) (xy 213.517988 2.111756) (xy 213.517988 2.975356) (xy 213.518492 3.00491)
			(xy 213.526541 3.063466) (xy 213.542487 3.120381) (xy 213.566036 3.174595) (xy 213.596747 3.225098)
			(xy 213.634049 3.270948) (xy 213.677246 3.311291) (xy 213.725535 3.345377) (xy 213.778015 3.37257)
			(xy 213.83371 3.392364) (xy 213.891581 3.40439) (xy 213.95055 3.408424) (xy 214.009519 3.40439) (xy 214.06739 3.392364)
			(xy 214.123085 3.37257) (xy 214.175565 3.345377) (xy 214.223854 3.311291) (xy 214.267051 3.270948)
			(xy 214.304353 3.225098) (xy 214.335064 3.174595) (xy 214.358613 3.120381) (xy 214.374559 3.063466)
			(xy 214.382608 3.00491) (xy 214.383112 2.975356) (xy 214.383112 2.111756) (xy 214.382608 2.082202)
			(xy 214.374559 2.023646) (xy 214.358613 1.966731) (xy 214.335064 1.912517) (xy 214.304353 1.862014)
			(xy 214.267051 1.816164) (xy 214.223854 1.775821) (xy 214.175565 1.741735) (xy 214.123085 1.714542)
			(xy 214.06739 1.694748) (xy 214.009519 1.682722) (xy 213.95055 1.678689) (xy 213.891581 1.682722)
			(xy 213.83371 1.694748) (xy 213.778015 1.714542) (xy 213.725535 1.741735) (xy 213.677246 1.775821)
			(xy 213.634049 1.816164) (xy 213.596747 1.862014) (xy 213.566036 1.912517) (xy 213.542487 1.966731)
			(xy 213.526541 2.023646) (xy 213.518492 2.082202) (xy 213.517988 2.111756) (xy 209.984264 2.111756)
			(xy 210.040351 2.083828) (xy 210.113257 2.038687) (xy 210.181686 1.987011) (xy 210.245056 1.929242)
			(xy 210.302825 1.865872) (xy 210.354501 1.797443) (xy 210.399642 1.724537) (xy 210.437864 1.647777)
			(xy 210.46884 1.567818) (xy 210.492307 1.485342) (xy 210.508063 1.401052) (xy 210.515975 1.315669)
			(xy 210.51647 1.272794) (xy 210.515975 1.229919) (xy 215.011241 1.229919) (xy 215.011241 1.315669)
			(xy 215.019153 1.401052) (xy 215.034909 1.485342) (xy 215.058376 1.567818) (xy 215.089352 1.647777)
			(xy 215.127574 1.724537) (xy 215.172715 1.797443) (xy 215.224391 1.865872) (xy 215.28216 1.929242)
			(xy 215.34553 1.987011) (xy 215.413959 2.038687) (xy 215.486865 2.083828) (xy 215.563625 2.12205)
			(xy 215.643584 2.153026) (xy 215.72606 2.176493) (xy 215.81035 2.192249) (xy 215.895733 2.200161)
			(xy 215.981483 2.200161) (xy 216.066866 2.192249) (xy 216.151156 2.176493) (xy 216.233632 2.153026)
			(xy 216.313591 2.12205) (xy 216.390351 2.083828) (xy 216.463257 2.038687) (xy 216.531686 1.987011)
			(xy 216.595056 1.929242) (xy 216.652825 1.865872) (xy 216.704501 1.797443) (xy 216.749642 1.724537)
			(xy 216.787864 1.647777) (xy 216.81884 1.567818) (xy 216.842307 1.485342) (xy 216.858063 1.401052)
			(xy 216.865975 1.315669) (xy 216.86647 1.272794) (xy 216.865975 1.229919) (xy 296.143921 1.229919)
			(xy 296.143921 1.315669) (xy 296.151833 1.401052) (xy 296.167589 1.485342) (xy 296.191056 1.567818)
			(xy 296.222032 1.647777) (xy 296.260254 1.724537) (xy 296.305395 1.797443) (xy 296.357071 1.865872)
			(xy 296.41484 1.929242) (xy 296.47821 1.987011) (xy 296.546639 2.038687) (xy 296.619545 2.083828)
			(xy 296.696305 2.12205) (xy 296.776264 2.153026) (xy 296.85874 2.176493) (xy 296.94303 2.192249)
			(xy 297.028413 2.200161) (xy 297.114163 2.200161) (xy 297.199546 2.192249) (xy 297.283836 2.176493)
			(xy 297.366312 2.153026) (xy 297.446271 2.12205) (xy 297.466944 2.111756) (xy 298.629324 2.111756)
			(xy 298.629324 2.975356) (xy 298.629828 3.00491) (xy 298.637877 3.063466) (xy 298.653823 3.120381)
			(xy 298.677372 3.174595) (xy 298.708083 3.225098) (xy 298.745385 3.270948) (xy 298.788582 3.311291)
			(xy 298.836871 3.345377) (xy 298.889351 3.37257) (xy 298.945046 3.392364) (xy 299.002917 3.40439)
			(xy 299.061886 3.408424) (xy 299.120855 3.40439) (xy 299.178726 3.392364) (xy 299.234421 3.37257)
			(xy 299.286901 3.345377) (xy 299.33519 3.311291) (xy 299.378387 3.270948) (xy 299.415689 3.225098)
			(xy 299.4464 3.174595) (xy 299.469949 3.120381) (xy 299.485895 3.063466) (xy 299.493944 3.00491)
			(xy 299.494448 2.975356) (xy 299.494448 2.111756) (xy 299.493944 2.082202) (xy 299.485895 2.023646)
			(xy 299.469949 1.966731) (xy 299.4464 1.912517) (xy 299.415689 1.862014) (xy 299.378387 1.816164)
			(xy 299.33519 1.775821) (xy 299.286901 1.741735) (xy 299.234421 1.714542) (xy 299.178726 1.694748)
			(xy 299.120855 1.682722) (xy 299.061886 1.678689) (xy 299.002917 1.682722) (xy 298.945046 1.694748)
			(xy 298.889351 1.714542) (xy 298.836871 1.741735) (xy 298.788582 1.775821) (xy 298.745385 1.816164)
			(xy 298.708083 1.862014) (xy 298.677372 1.912517) (xy 298.653823 1.966731) (xy 298.637877 2.023646)
			(xy 298.629828 2.082202) (xy 298.629324 2.111756) (xy 297.466944 2.111756) (xy 297.523031 2.083828)
			(xy 297.595937 2.038687) (xy 297.664366 1.987011) (xy 297.727736 1.929242) (xy 297.785505 1.865872)
			(xy 297.837181 1.797443) (xy 297.882322 1.724537) (xy 297.920544 1.647777) (xy 297.95152 1.567818)
			(xy 297.974987 1.485342) (xy 297.990743 1.401052) (xy 297.998655 1.315669) (xy 297.99915 1.272794)
			(xy 297.998655 1.229919) (xy 302.493921 1.229919) (xy 302.493921 1.315669) (xy 302.501833 1.401052)
			(xy 302.517589 1.485342) (xy 302.541056 1.567818) (xy 302.572032 1.647777) (xy 302.610254 1.724537)
			(xy 302.655395 1.797443) (xy 302.707071 1.865872) (xy 302.76484 1.929242) (xy 302.82821 1.987011)
			(xy 302.896639 2.038687) (xy 302.969545 2.083828) (xy 303.046305 2.12205) (xy 303.126264 2.153026)
			(xy 303.20874 2.176493) (xy 303.29303 2.192249) (xy 303.378413 2.200161) (xy 303.464163 2.200161)
			(xy 303.549546 2.192249) (xy 303.633836 2.176493) (xy 303.716312 2.153026) (xy 303.796271 2.12205)
			(xy 303.873031 2.083828) (xy 303.945937 2.038687) (xy 304.014366 1.987011) (xy 304.077736 1.929242)
			(xy 304.135505 1.865872) (xy 304.187181 1.797443) (xy 304.232322 1.724537) (xy 304.270544 1.647777)
			(xy 304.30152 1.567818) (xy 304.324987 1.485342) (xy 304.340743 1.401052) (xy 304.348655 1.315669)
			(xy 304.34915 1.272794) (xy 304.348655 1.229919) (xy 311.155321 1.229919) (xy 311.155321 1.315669)
			(xy 311.163233 1.401052) (xy 311.178989 1.485342) (xy 311.202456 1.567818) (xy 311.233432 1.647777)
			(xy 311.271654 1.724537) (xy 311.316795 1.797443) (xy 311.368471 1.865872) (xy 311.42624 1.929242)
			(xy 311.48961 1.987011) (xy 311.558039 2.038687) (xy 311.630945 2.083828) (xy 311.707705 2.12205)
			(xy 311.787664 2.153026) (xy 311.87014 2.176493) (xy 311.95443 2.192249) (xy 312.039813 2.200161)
			(xy 312.125563 2.200161) (xy 312.210946 2.192249) (xy 312.295236 2.176493) (xy 312.377712 2.153026)
			(xy 312.457671 2.12205) (xy 312.534431 2.083828) (xy 312.607337 2.038687) (xy 312.675766 1.987011)
			(xy 312.739136 1.929242) (xy 312.796905 1.865872) (xy 312.848581 1.797443) (xy 312.893722 1.724537)
			(xy 312.931944 1.647777) (xy 312.96292 1.567818) (xy 312.986387 1.485342) (xy 313.002143 1.401052)
			(xy 313.010055 1.315669) (xy 313.01055 1.272794) (xy 313.010055 1.229919) (xy 317.505321 1.229919)
			(xy 317.505321 1.315669) (xy 317.513233 1.401052) (xy 317.528989 1.485342) (xy 317.552456 1.567818)
			(xy 317.583432 1.647777) (xy 317.621654 1.724537) (xy 317.666795 1.797443) (xy 317.718471 1.865872)
			(xy 317.77624 1.929242) (xy 317.83961 1.987011) (xy 317.908039 2.038687) (xy 317.980945 2.083828)
			(xy 318.057705 2.12205) (xy 318.137664 2.153026) (xy 318.22014 2.176493) (xy 318.30443 2.192249)
			(xy 318.389813 2.200161) (xy 318.475563 2.200161) (xy 318.560946 2.192249) (xy 318.645236 2.176493)
			(xy 318.727712 2.153026) (xy 318.807671 2.12205) (xy 318.884431 2.083828) (xy 318.957337 2.038687)
			(xy 319.025766 1.987011) (xy 319.089136 1.929242) (xy 319.146905 1.865872) (xy 319.198581 1.797443)
			(xy 319.243722 1.724537) (xy 319.281944 1.647777) (xy 319.31292 1.567818) (xy 319.336387 1.485342)
			(xy 319.352143 1.401052) (xy 319.360055 1.315669) (xy 319.36055 1.272794) (xy 319.360055 1.229919)
			(xy 361.894107 1.229919) (xy 361.894107 1.315669) (xy 361.902019 1.401052) (xy 361.917775 1.485342)
			(xy 361.941242 1.567818) (xy 361.972218 1.647777) (xy 362.01044 1.724537) (xy 362.055581 1.797443)
			(xy 362.107257 1.865872) (xy 362.165026 1.929242) (xy 362.228396 1.987011) (xy 362.296825 2.038687)
			(xy 362.369731 2.083828) (xy 362.446491 2.12205) (xy 362.52645 2.153026) (xy 362.608926 2.176493)
			(xy 362.693216 2.192249) (xy 362.778599 2.200161) (xy 362.864349 2.200161) (xy 362.949732 2.192249)
			(xy 363.034022 2.176493) (xy 363.116498 2.153026) (xy 363.196457 2.12205) (xy 363.273217 2.083828)
			(xy 363.346123 2.038687) (xy 363.414552 1.987011) (xy 363.477922 1.929242) (xy 363.535691 1.865872)
			(xy 363.587367 1.797443) (xy 363.632508 1.724537) (xy 363.67073 1.647777) (xy 363.701706 1.567818)
			(xy 363.725173 1.485342) (xy 363.740929 1.401052) (xy 363.748841 1.315669) (xy 363.749336 1.272794)
			(xy 363.748841 1.229919) (xy 368.244107 1.229919) (xy 368.244107 1.315669) (xy 368.252019 1.401052)
			(xy 368.267775 1.485342) (xy 368.291242 1.567818) (xy 368.322218 1.647777) (xy 368.36044 1.724537)
			(xy 368.405581 1.797443) (xy 368.457257 1.865872) (xy 368.515026 1.929242) (xy 368.578396 1.987011)
			(xy 368.646825 2.038687) (xy 368.719731 2.083828) (xy 368.796491 2.12205) (xy 368.87645 2.153026)
			(xy 368.958926 2.176493) (xy 369.043216 2.192249) (xy 369.128599 2.200161) (xy 369.214349 2.200161)
			(xy 369.299732 2.192249) (xy 369.384022 2.176493) (xy 369.466498 2.153026) (xy 369.546457 2.12205)
			(xy 369.623217 2.083828) (xy 369.696123 2.038687) (xy 369.764552 1.987011) (xy 369.827922 1.929242)
			(xy 369.885691 1.865872) (xy 369.937367 1.797443) (xy 369.982508 1.724537) (xy 370.02073 1.647777)
			(xy 370.051706 1.567818) (xy 370.075173 1.485342) (xy 370.090929 1.401052) (xy 370.098841 1.315669)
			(xy 370.099336 1.272794) (xy 370.098841 1.229919) (xy 370.090929 1.144536) (xy 370.075173 1.060246)
			(xy 370.051706 0.97777) (xy 370.02073 0.897811) (xy 369.982508 0.821051) (xy 369.937367 0.748145)
			(xy 369.885691 0.679716) (xy 369.827922 0.616346) (xy 369.764552 0.558577) (xy 369.696123 0.506901)
			(xy 369.623217 0.46176) (xy 369.546457 0.423538) (xy 369.466498 0.392562) (xy 369.384022 0.369095)
			(xy 369.299732 0.353339) (xy 369.214349 0.345427) (xy 369.128599 0.345427) (xy 369.043216 0.353339)
			(xy 368.958926 0.369095) (xy 368.87645 0.392562) (xy 368.796491 0.423538) (xy 368.719731 0.46176)
			(xy 368.646825 0.506901) (xy 368.578396 0.558577) (xy 368.515026 0.616346) (xy 368.457257 0.679716)
			(xy 368.405581 0.748145) (xy 368.36044 0.821051) (xy 368.322218 0.897811) (xy 368.291242 0.97777)
			(xy 368.267775 1.060246) (xy 368.252019 1.144536) (xy 368.244107 1.229919) (xy 363.748841 1.229919)
			(xy 363.740929 1.144536) (xy 363.725173 1.060246) (xy 363.701706 0.97777) (xy 363.67073 0.897811)
			(xy 363.632508 0.821051) (xy 363.587367 0.748145) (xy 363.535691 0.679716) (xy 363.477922 0.616346)
			(xy 363.414552 0.558577) (xy 363.346123 0.506901) (xy 363.273217 0.46176) (xy 363.196457 0.423538)
			(xy 363.116498 0.392562) (xy 363.034022 0.369095) (xy 362.949732 0.353339) (xy 362.864349 0.345427)
			(xy 362.778599 0.345427) (xy 362.693216 0.353339) (xy 362.608926 0.369095) (xy 362.52645 0.392562)
			(xy 362.446491 0.423538) (xy 362.369731 0.46176) (xy 362.296825 0.506901) (xy 362.228396 0.558577)
			(xy 362.165026 0.616346) (xy 362.107257 0.679716) (xy 362.055581 0.748145) (xy 362.01044 0.821051)
			(xy 361.972218 0.897811) (xy 361.941242 0.97777) (xy 361.917775 1.060246) (xy 361.902019 1.144536)
			(xy 361.894107 1.229919) (xy 319.360055 1.229919) (xy 319.352143 1.144536) (xy 319.336387 1.060246)
			(xy 319.31292 0.97777) (xy 319.281944 0.897811) (xy 319.243722 0.821051) (xy 319.198581 0.748145)
			(xy 319.146905 0.679716) (xy 319.089136 0.616346) (xy 319.025766 0.558577) (xy 318.957337 0.506901)
			(xy 318.884431 0.46176) (xy 318.807671 0.423538) (xy 318.727712 0.392562) (xy 318.645236 0.369095)
			(xy 318.560946 0.353339) (xy 318.475563 0.345427) (xy 318.389813 0.345427) (xy 318.30443 0.353339)
			(xy 318.22014 0.369095) (xy 318.137664 0.392562) (xy 318.057705 0.423538) (xy 317.980945 0.46176)
			(xy 317.908039 0.506901) (xy 317.83961 0.558577) (xy 317.77624 0.616346) (xy 317.718471 0.679716)
			(xy 317.666795 0.748145) (xy 317.621654 0.821051) (xy 317.583432 0.897811) (xy 317.552456 0.97777)
			(xy 317.528989 1.060246) (xy 317.513233 1.144536) (xy 317.505321 1.229919) (xy 313.010055 1.229919)
			(xy 313.002143 1.144536) (xy 312.986387 1.060246) (xy 312.96292 0.97777) (xy 312.931944 0.897811)
			(xy 312.893722 0.821051) (xy 312.848581 0.748145) (xy 312.796905 0.679716) (xy 312.739136 0.616346)
			(xy 312.675766 0.558577) (xy 312.607337 0.506901) (xy 312.534431 0.46176) (xy 312.457671 0.423538)
			(xy 312.377712 0.392562) (xy 312.295236 0.369095) (xy 312.210946 0.353339) (xy 312.125563 0.345427)
			(xy 312.039813 0.345427) (xy 311.95443 0.353339) (xy 311.87014 0.369095) (xy 311.787664 0.392562)
			(xy 311.707705 0.423538) (xy 311.630945 0.46176) (xy 311.558039 0.506901) (xy 311.48961 0.558577)
			(xy 311.42624 0.616346) (xy 311.368471 0.679716) (xy 311.316795 0.748145) (xy 311.271654 0.821051)
			(xy 311.233432 0.897811) (xy 311.202456 0.97777) (xy 311.178989 1.060246) (xy 311.163233 1.144536)
			(xy 311.155321 1.229919) (xy 304.348655 1.229919) (xy 304.340743 1.144536) (xy 304.324987 1.060246)
			(xy 304.30152 0.97777) (xy 304.270544 0.897811) (xy 304.232322 0.821051) (xy 304.187181 0.748145)
			(xy 304.135505 0.679716) (xy 304.077736 0.616346) (xy 304.014366 0.558577) (xy 303.945937 0.506901)
			(xy 303.873031 0.46176) (xy 303.796271 0.423538) (xy 303.716312 0.392562) (xy 303.633836 0.369095)
			(xy 303.549546 0.353339) (xy 303.464163 0.345427) (xy 303.378413 0.345427) (xy 303.29303 0.353339)
			(xy 303.20874 0.369095) (xy 303.126264 0.392562) (xy 303.046305 0.423538) (xy 302.969545 0.46176)
			(xy 302.896639 0.506901) (xy 302.82821 0.558577) (xy 302.76484 0.616346) (xy 302.707071 0.679716)
			(xy 302.655395 0.748145) (xy 302.610254 0.821051) (xy 302.572032 0.897811) (xy 302.541056 0.97777)
			(xy 302.517589 1.060246) (xy 302.501833 1.144536) (xy 302.493921 1.229919) (xy 297.998655 1.229919)
			(xy 297.990743 1.144536) (xy 297.974987 1.060246) (xy 297.95152 0.97777) (xy 297.920544 0.897811)
			(xy 297.882322 0.821051) (xy 297.837181 0.748145) (xy 297.785505 0.679716) (xy 297.727736 0.616346)
			(xy 297.664366 0.558577) (xy 297.595937 0.506901) (xy 297.523031 0.46176) (xy 297.446271 0.423538)
			(xy 297.366312 0.392562) (xy 297.283836 0.369095) (xy 297.199546 0.353339) (xy 297.114163 0.345427)
			(xy 297.028413 0.345427) (xy 296.94303 0.353339) (xy 296.85874 0.369095) (xy 296.776264 0.392562)
			(xy 296.696305 0.423538) (xy 296.619545 0.46176) (xy 296.546639 0.506901) (xy 296.47821 0.558577)
			(xy 296.41484 0.616346) (xy 296.357071 0.679716) (xy 296.305395 0.748145) (xy 296.260254 0.821051)
			(xy 296.222032 0.897811) (xy 296.191056 0.97777) (xy 296.167589 1.060246) (xy 296.151833 1.144536)
			(xy 296.143921 1.229919) (xy 216.865975 1.229919) (xy 216.858063 1.144536) (xy 216.842307 1.060246)
			(xy 216.81884 0.97777) (xy 216.787864 0.897811) (xy 216.749642 0.821051) (xy 216.704501 0.748145)
			(xy 216.652825 0.679716) (xy 216.595056 0.616346) (xy 216.531686 0.558577) (xy 216.463257 0.506901)
			(xy 216.390351 0.46176) (xy 216.313591 0.423538) (xy 216.233632 0.392562) (xy 216.151156 0.369095)
			(xy 216.066866 0.353339) (xy 215.981483 0.345427) (xy 215.895733 0.345427) (xy 215.81035 0.353339)
			(xy 215.72606 0.369095) (xy 215.643584 0.392562) (xy 215.563625 0.423538) (xy 215.486865 0.46176)
			(xy 215.413959 0.506901) (xy 215.34553 0.558577) (xy 215.28216 0.616346) (xy 215.224391 0.679716)
			(xy 215.172715 0.748145) (xy 215.127574 0.821051) (xy 215.089352 0.897811) (xy 215.058376 0.97777)
			(xy 215.034909 1.060246) (xy 215.019153 1.144536) (xy 215.011241 1.229919) (xy 210.515975 1.229919)
			(xy 210.508063 1.144536) (xy 210.492307 1.060246) (xy 210.46884 0.97777) (xy 210.437864 0.897811)
			(xy 210.399642 0.821051) (xy 210.354501 0.748145) (xy 210.302825 0.679716) (xy 210.245056 0.616346)
			(xy 210.181686 0.558577) (xy 210.113257 0.506901) (xy 210.040351 0.46176) (xy 209.963591 0.423538)
			(xy 209.883632 0.392562) (xy 209.801156 0.369095) (xy 209.716866 0.353339) (xy 209.631483 0.345427)
			(xy 209.545733 0.345427) (xy 209.46035 0.353339) (xy 209.37606 0.369095) (xy 209.293584 0.392562)
			(xy 209.213625 0.423538) (xy 209.136865 0.46176) (xy 209.063959 0.506901) (xy 208.99553 0.558577)
			(xy 208.93216 0.616346) (xy 208.874391 0.679716) (xy 208.822715 0.748145) (xy 208.777574 0.821051)
			(xy 208.739352 0.897811) (xy 208.708376 0.97777) (xy 208.684909 1.060246) (xy 208.669153 1.144536)
			(xy 208.661241 1.229919) (xy 84.069209 1.229919) (xy 84.092929 1.162133) (xy 84.131901 1.02687) (xy 84.163226 0.889634)
			(xy 84.186808 0.750857) (xy 84.202571 0.610977) (xy 84.210467 0.470433) (xy 84.210906 0.40005) (xy 84.210906 -1.310081)
			(xy 208.661241 -1.310081) (xy 208.661241 -1.224331) (xy 208.669153 -1.138948) (xy 208.684909 -1.054658)
			(xy 208.708376 -0.972182) (xy 208.739352 -0.892223) (xy 208.777574 -0.815463) (xy 208.822715 -0.742557)
			(xy 208.874391 -0.674128) (xy 208.93216 -0.610758) (xy 208.99553 -0.552989) (xy 209.063959 -0.501313)
			(xy 209.136865 -0.456172) (xy 209.213625 -0.41795) (xy 209.293584 -0.386974) (xy 209.37606 -0.363507)
			(xy 209.46035 -0.347751) (xy 209.545733 -0.339839) (xy 209.631483 -0.339839) (xy 209.716866 -0.347751)
			(xy 209.801156 -0.363507) (xy 209.883632 -0.386974) (xy 209.963591 -0.41795) (xy 210.040351 -0.456172)
			(xy 210.113257 -0.501313) (xy 210.181686 -0.552989) (xy 210.245056 -0.610758) (xy 210.302825 -0.674128)
			(xy 210.354501 -0.742557) (xy 210.399642 -0.815463) (xy 210.437864 -0.892223) (xy 210.46884 -0.972182)
			(xy 210.492307 -1.054658) (xy 210.508063 -1.138948) (xy 210.515975 -1.224331) (xy 210.51647 -1.267206)
			(xy 210.515975 -1.310081) (xy 215.011241 -1.310081) (xy 215.011241 -1.224331) (xy 215.019153 -1.138948)
			(xy 215.034909 -1.054658) (xy 215.058376 -0.972182) (xy 215.089352 -0.892223) (xy 215.127574 -0.815463)
			(xy 215.172715 -0.742557) (xy 215.224391 -0.674128) (xy 215.28216 -0.610758) (xy 215.34553 -0.552989)
			(xy 215.413959 -0.501313) (xy 215.486865 -0.456172) (xy 215.563625 -0.41795) (xy 215.643584 -0.386974)
			(xy 215.72606 -0.363507) (xy 215.81035 -0.347751) (xy 215.895733 -0.339839) (xy 215.981483 -0.339839)
			(xy 216.066866 -0.347751) (xy 216.151156 -0.363507) (xy 216.233632 -0.386974) (xy 216.313591 -0.41795)
			(xy 216.390351 -0.456172) (xy 216.463257 -0.501313) (xy 216.531686 -0.552989) (xy 216.595056 -0.610758)
			(xy 216.652825 -0.674128) (xy 216.704501 -0.742557) (xy 216.749642 -0.815463) (xy 216.787864 -0.892223)
			(xy 216.81884 -0.972182) (xy 216.842307 -1.054658) (xy 216.858063 -1.138948) (xy 216.865975 -1.224331)
			(xy 216.86647 -1.267206) (xy 216.865975 -1.310081) (xy 296.143921 -1.310081) (xy 296.143921 -1.224331)
			(xy 296.151833 -1.138948) (xy 296.167589 -1.054658) (xy 296.191056 -0.972182) (xy 296.222032 -0.892223)
			(xy 296.260254 -0.815463) (xy 296.305395 -0.742557) (xy 296.357071 -0.674128) (xy 296.41484 -0.610758)
			(xy 296.47821 -0.552989) (xy 296.546639 -0.501313) (xy 296.619545 -0.456172) (xy 296.696305 -0.41795)
			(xy 296.776264 -0.386974) (xy 296.85874 -0.363507) (xy 296.94303 -0.347751) (xy 297.028413 -0.339839)
			(xy 297.114163 -0.339839) (xy 297.199546 -0.347751) (xy 297.283836 -0.363507) (xy 297.366312 -0.386974)
			(xy 297.446271 -0.41795) (xy 297.523031 -0.456172) (xy 297.595937 -0.501313) (xy 297.664366 -0.552989)
			(xy 297.727736 -0.610758) (xy 297.785505 -0.674128) (xy 297.837181 -0.742557) (xy 297.882322 -0.815463)
			(xy 297.920544 -0.892223) (xy 297.95152 -0.972182) (xy 297.974987 -1.054658) (xy 297.990743 -1.138948)
			(xy 297.998655 -1.224331) (xy 297.99915 -1.267206) (xy 297.998655 -1.310081) (xy 302.493921 -1.310081)
			(xy 302.493921 -1.224331) (xy 302.501833 -1.138948) (xy 302.517589 -1.054658) (xy 302.541056 -0.972182)
			(xy 302.572032 -0.892223) (xy 302.610254 -0.815463) (xy 302.655395 -0.742557) (xy 302.707071 -0.674128)
			(xy 302.76484 -0.610758) (xy 302.82821 -0.552989) (xy 302.896639 -0.501313) (xy 302.969545 -0.456172)
			(xy 303.046305 -0.41795) (xy 303.126264 -0.386974) (xy 303.20874 -0.363507) (xy 303.29303 -0.347751)
			(xy 303.378413 -0.339839) (xy 303.464163 -0.339839) (xy 303.549546 -0.347751) (xy 303.633836 -0.363507)
			(xy 303.716312 -0.386974) (xy 303.796271 -0.41795) (xy 303.873031 -0.456172) (xy 303.945937 -0.501313)
			(xy 304.014366 -0.552989) (xy 304.077736 -0.610758) (xy 304.135505 -0.674128) (xy 304.187181 -0.742557)
			(xy 304.232322 -0.815463) (xy 304.270544 -0.892223) (xy 304.30152 -0.972182) (xy 304.324987 -1.054658)
			(xy 304.340743 -1.138948) (xy 304.348655 -1.224331) (xy 304.34915 -1.267206) (xy 304.348655 -1.310081)
			(xy 311.155321 -1.310081) (xy 311.155321 -1.224331) (xy 311.163233 -1.138948) (xy 311.178989 -1.054658)
			(xy 311.202456 -0.972182) (xy 311.233432 -0.892223) (xy 311.271654 -0.815463) (xy 311.316795 -0.742557)
			(xy 311.368471 -0.674128) (xy 311.42624 -0.610758) (xy 311.48961 -0.552989) (xy 311.558039 -0.501313)
			(xy 311.630945 -0.456172) (xy 311.707705 -0.41795) (xy 311.787664 -0.386974) (xy 311.87014 -0.363507)
			(xy 311.95443 -0.347751) (xy 312.039813 -0.339839) (xy 312.125563 -0.339839) (xy 312.210946 -0.347751)
			(xy 312.295236 -0.363507) (xy 312.377712 -0.386974) (xy 312.457671 -0.41795) (xy 312.478344 -0.428244)
			(xy 316.012068 -0.428244) (xy 316.012068 0.435356) (xy 316.012572 0.46491) (xy 316.020621 0.523466)
			(xy 316.036567 0.580381) (xy 316.060116 0.634595) (xy 316.090827 0.685098) (xy 316.128129 0.730948)
			(xy 316.171326 0.771291) (xy 316.219615 0.805377) (xy 316.272095 0.83257) (xy 316.32779 0.852364)
			(xy 316.385661 0.86439) (xy 316.44463 0.868424) (xy 316.503599 0.86439) (xy 316.56147 0.852364) (xy 316.617165 0.83257)
			(xy 316.669645 0.805377) (xy 316.717934 0.771291) (xy 316.761131 0.730948) (xy 316.798433 0.685098)
			(xy 316.829144 0.634595) (xy 316.852693 0.580381) (xy 316.868639 0.523466) (xy 316.876688 0.46491)
			(xy 316.877192 0.435356) (xy 316.877192 -0.428244) (xy 316.876688 -0.457798) (xy 316.868639 -0.516354)
			(xy 316.852693 -0.573269) (xy 316.829144 -0.627483) (xy 316.798433 -0.677986) (xy 316.761131 -0.723836)
			(xy 316.717934 -0.764179) (xy 316.669645 -0.798265) (xy 316.617165 -0.825458) (xy 316.56147 -0.845252)
			(xy 316.503599 -0.857278) (xy 316.44463 -0.861312) (xy 316.385661 -0.857278) (xy 316.32779 -0.845252)
			(xy 316.272095 -0.825458) (xy 316.219615 -0.798265) (xy 316.171326 -0.764179) (xy 316.128129 -0.723836)
			(xy 316.090827 -0.677986) (xy 316.060116 -0.627483) (xy 316.036567 -0.573269) (xy 316.020621 -0.516354)
			(xy 316.012572 -0.457798) (xy 316.012068 -0.428244) (xy 312.478344 -0.428244) (xy 312.534431 -0.456172)
			(xy 312.607337 -0.501313) (xy 312.675766 -0.552989) (xy 312.739136 -0.610758) (xy 312.796905 -0.674128)
			(xy 312.848581 -0.742557) (xy 312.893722 -0.815463) (xy 312.931944 -0.892223) (xy 312.96292 -0.972182)
			(xy 312.986387 -1.054658) (xy 313.002143 -1.138948) (xy 313.010055 -1.224331) (xy 313.01055 -1.267206)
			(xy 313.010055 -1.310081) (xy 317.505321 -1.310081) (xy 317.505321 -1.224331) (xy 317.513233 -1.138948)
			(xy 317.528989 -1.054658) (xy 317.552456 -0.972182) (xy 317.583432 -0.892223) (xy 317.621654 -0.815463)
			(xy 317.666795 -0.742557) (xy 317.718471 -0.674128) (xy 317.77624 -0.610758) (xy 317.83961 -0.552989)
			(xy 317.908039 -0.501313) (xy 317.980945 -0.456172) (xy 318.057705 -0.41795) (xy 318.137664 -0.386974)
			(xy 318.22014 -0.363507) (xy 318.30443 -0.347751) (xy 318.389813 -0.339839) (xy 318.475563 -0.339839)
			(xy 318.560946 -0.347751) (xy 318.645236 -0.363507) (xy 318.727712 -0.386974) (xy 318.807671 -0.41795)
			(xy 318.884431 -0.456172) (xy 318.957337 -0.501313) (xy 319.025766 -0.552989) (xy 319.089136 -0.610758)
			(xy 319.146905 -0.674128) (xy 319.198581 -0.742557) (xy 319.243722 -0.815463) (xy 319.281944 -0.892223)
			(xy 319.31292 -0.972182) (xy 319.336387 -1.054658) (xy 319.352143 -1.138948) (xy 319.360055 -1.224331)
			(xy 319.36055 -1.267206) (xy 319.360055 -1.310081) (xy 361.894107 -1.310081) (xy 361.894107 -1.224331)
			(xy 361.902019 -1.138948) (xy 361.917775 -1.054658) (xy 361.941242 -0.972182) (xy 361.972218 -0.892223)
			(xy 362.01044 -0.815463) (xy 362.055581 -0.742557) (xy 362.107257 -0.674128) (xy 362.165026 -0.610758)
			(xy 362.228396 -0.552989) (xy 362.296825 -0.501313) (xy 362.369731 -0.456172) (xy 362.446491 -0.41795)
			(xy 362.52645 -0.386974) (xy 362.608926 -0.363507) (xy 362.693216 -0.347751) (xy 362.778599 -0.339839)
			(xy 362.864349 -0.339839) (xy 362.949732 -0.347751) (xy 363.034022 -0.363507) (xy 363.116498 -0.386974)
			(xy 363.196457 -0.41795) (xy 363.21713 -0.428244) (xy 364.379764 -0.428244) (xy 364.379764 0.435356)
			(xy 364.380268 0.464892) (xy 364.388312 0.523414) (xy 364.404249 0.580296) (xy 364.427784 0.634478)
			(xy 364.458477 0.684951) (xy 364.495757 0.730774) (xy 364.538929 0.771094) (xy 364.587189 0.80516)
			(xy 364.639639 0.832337) (xy 364.6953 0.852119) (xy 364.753137 0.864138) (xy 364.812072 0.868169)
			(xy 364.871007 0.864138) (xy 364.928844 0.852119) (xy 364.984505 0.832337) (xy 365.036955 0.80516)
			(xy 365.085215 0.771094) (xy 365.128387 0.730774) (xy 365.165667 0.684951) (xy 365.19636 0.634478)
			(xy 365.219895 0.580296) (xy 365.235832 0.523414) (xy 365.243876 0.464892) (xy 365.24438 0.435356)
			(xy 365.24438 -0.428244) (xy 365.243876 -0.45778) (xy 365.235832 -0.516302) (xy 365.219895 -0.573184)
			(xy 365.19636 -0.627366) (xy 365.165667 -0.677839) (xy 365.128387 -0.723662) (xy 365.085215 -0.763982)
			(xy 365.036955 -0.798048) (xy 364.984505 -0.825225) (xy 364.928844 -0.845007) (xy 364.871007 -0.857026)
			(xy 364.812072 -0.861057) (xy 364.753137 -0.857026) (xy 364.6953 -0.845007) (xy 364.639639 -0.825225)
			(xy 364.587189 -0.798048) (xy 364.538929 -0.763982) (xy 364.495757 -0.723662) (xy 364.458477 -0.677839)
			(xy 364.427784 -0.627366) (xy 364.404249 -0.573184) (xy 364.388312 -0.516302) (xy 364.380268 -0.45778)
			(xy 364.379764 -0.428244) (xy 363.21713 -0.428244) (xy 363.273217 -0.456172) (xy 363.346123 -0.501313)
			(xy 363.414552 -0.552989) (xy 363.477922 -0.610758) (xy 363.535691 -0.674128) (xy 363.587367 -0.742557)
			(xy 363.632508 -0.815463) (xy 363.67073 -0.892223) (xy 363.701706 -0.972182) (xy 363.725173 -1.054658)
			(xy 363.740929 -1.138948) (xy 363.748841 -1.224331) (xy 363.749336 -1.267206) (xy 363.748841 -1.310081)
			(xy 368.244107 -1.310081) (xy 368.244107 -1.224331) (xy 368.252019 -1.138948) (xy 368.267775 -1.054658)
			(xy 368.291242 -0.972182) (xy 368.322218 -0.892223) (xy 368.36044 -0.815463) (xy 368.405581 -0.742557)
			(xy 368.457257 -0.674128) (xy 368.515026 -0.610758) (xy 368.578396 -0.552989) (xy 368.646825 -0.501313)
			(xy 368.719731 -0.456172) (xy 368.796491 -0.41795) (xy 368.87645 -0.386974) (xy 368.958926 -0.363507)
			(xy 369.043216 -0.347751) (xy 369.128599 -0.339839) (xy 369.214349 -0.339839) (xy 369.299732 -0.347751)
			(xy 369.384022 -0.363507) (xy 369.466498 -0.386974) (xy 369.546457 -0.41795) (xy 369.623217 -0.456172)
			(xy 369.696123 -0.501313) (xy 369.764552 -0.552989) (xy 369.827922 -0.610758) (xy 369.885691 -0.674128)
			(xy 369.937367 -0.742557) (xy 369.982508 -0.815463) (xy 370.02073 -0.892223) (xy 370.051706 -0.972182)
			(xy 370.075173 -1.054658) (xy 370.090929 -1.138948) (xy 370.098841 -1.224331) (xy 370.099336 -1.267206)
			(xy 370.098841 -1.310081) (xy 370.090929 -1.395464) (xy 370.075173 -1.479754) (xy 370.051706 -1.56223)
			(xy 370.02073 -1.642189) (xy 369.982508 -1.718949) (xy 369.937367 -1.791855) (xy 369.885691 -1.860284)
			(xy 369.827922 -1.923654) (xy 369.764552 -1.981423) (xy 369.696123 -2.033099) (xy 369.623217 -2.07824)
			(xy 369.546457 -2.116462) (xy 369.466498 -2.147438) (xy 369.384022 -2.170905) (xy 369.299732 -2.186661)
			(xy 369.214349 -2.194573) (xy 369.128599 -2.194573) (xy 369.043216 -2.186661) (xy 368.958926 -2.170905)
			(xy 368.87645 -2.147438) (xy 368.796491 -2.116462) (xy 368.719731 -2.07824) (xy 368.646825 -2.033099)
			(xy 368.578396 -1.981423) (xy 368.515026 -1.923654) (xy 368.457257 -1.860284) (xy 368.405581 -1.791855)
			(xy 368.36044 -1.718949) (xy 368.322218 -1.642189) (xy 368.291242 -1.56223) (xy 368.267775 -1.479754)
			(xy 368.252019 -1.395464) (xy 368.244107 -1.310081) (xy 363.748841 -1.310081) (xy 363.740929 -1.395464)
			(xy 363.725173 -1.479754) (xy 363.701706 -1.56223) (xy 363.67073 -1.642189) (xy 363.632508 -1.718949)
			(xy 363.587367 -1.791855) (xy 363.535691 -1.860284) (xy 363.477922 -1.923654) (xy 363.414552 -1.981423)
			(xy 363.346123 -2.033099) (xy 363.273217 -2.07824) (xy 363.196457 -2.116462) (xy 363.116498 -2.147438)
			(xy 363.034022 -2.170905) (xy 362.949732 -2.186661) (xy 362.864349 -2.194573) (xy 362.778599 -2.194573)
			(xy 362.693216 -2.186661) (xy 362.608926 -2.170905) (xy 362.52645 -2.147438) (xy 362.446491 -2.116462)
			(xy 362.369731 -2.07824) (xy 362.296825 -2.033099) (xy 362.228396 -1.981423) (xy 362.165026 -1.923654)
			(xy 362.107257 -1.860284) (xy 362.055581 -1.791855) (xy 362.01044 -1.718949) (xy 361.972218 -1.642189)
			(xy 361.941242 -1.56223) (xy 361.917775 -1.479754) (xy 361.902019 -1.395464) (xy 361.894107 -1.310081)
			(xy 319.360055 -1.310081) (xy 319.352143 -1.395464) (xy 319.336387 -1.479754) (xy 319.31292 -1.56223)
			(xy 319.281944 -1.642189) (xy 319.243722 -1.718949) (xy 319.198581 -1.791855) (xy 319.146905 -1.860284)
			(xy 319.089136 -1.923654) (xy 319.025766 -1.981423) (xy 318.957337 -2.033099) (xy 318.884431 -2.07824)
			(xy 318.807671 -2.116462) (xy 318.727712 -2.147438) (xy 318.645236 -2.170905) (xy 318.560946 -2.186661)
			(xy 318.475563 -2.194573) (xy 318.389813 -2.194573) (xy 318.30443 -2.186661) (xy 318.22014 -2.170905)
			(xy 318.137664 -2.147438) (xy 318.057705 -2.116462) (xy 317.980945 -2.07824) (xy 317.908039 -2.033099)
			(xy 317.83961 -1.981423) (xy 317.77624 -1.923654) (xy 317.718471 -1.860284) (xy 317.666795 -1.791855)
			(xy 317.621654 -1.718949) (xy 317.583432 -1.642189) (xy 317.552456 -1.56223) (xy 317.528989 -1.479754)
			(xy 317.513233 -1.395464) (xy 317.505321 -1.310081) (xy 313.010055 -1.310081) (xy 313.002143 -1.395464)
			(xy 312.986387 -1.479754) (xy 312.96292 -1.56223) (xy 312.931944 -1.642189) (xy 312.893722 -1.718949)
			(xy 312.848581 -1.791855) (xy 312.796905 -1.860284) (xy 312.739136 -1.923654) (xy 312.675766 -1.981423)
			(xy 312.607337 -2.033099) (xy 312.534431 -2.07824) (xy 312.457671 -2.116462) (xy 312.377712 -2.147438)
			(xy 312.295236 -2.170905) (xy 312.210946 -2.186661) (xy 312.125563 -2.194573) (xy 312.039813 -2.194573)
			(xy 311.95443 -2.186661) (xy 311.87014 -2.170905) (xy 311.787664 -2.147438) (xy 311.707705 -2.116462)
			(xy 311.630945 -2.07824) (xy 311.558039 -2.033099) (xy 311.48961 -1.981423) (xy 311.42624 -1.923654)
			(xy 311.368471 -1.860284) (xy 311.316795 -1.791855) (xy 311.271654 -1.718949) (xy 311.233432 -1.642189)
			(xy 311.202456 -1.56223) (xy 311.178989 -1.479754) (xy 311.163233 -1.395464) (xy 311.155321 -1.310081)
			(xy 304.348655 -1.310081) (xy 304.340743 -1.395464) (xy 304.324987 -1.479754) (xy 304.30152 -1.56223)
			(xy 304.270544 -1.642189) (xy 304.232322 -1.718949) (xy 304.187181 -1.791855) (xy 304.135505 -1.860284)
			(xy 304.077736 -1.923654) (xy 304.014366 -1.981423) (xy 303.945937 -2.033099) (xy 303.873031 -2.07824)
			(xy 303.796271 -2.116462) (xy 303.716312 -2.147438) (xy 303.633836 -2.170905) (xy 303.549546 -2.186661)
			(xy 303.464163 -2.194573) (xy 303.378413 -2.194573) (xy 303.29303 -2.186661) (xy 303.20874 -2.170905)
			(xy 303.126264 -2.147438) (xy 303.046305 -2.116462) (xy 302.969545 -2.07824) (xy 302.896639 -2.033099)
			(xy 302.82821 -1.981423) (xy 302.76484 -1.923654) (xy 302.707071 -1.860284) (xy 302.655395 -1.791855)
			(xy 302.610254 -1.718949) (xy 302.572032 -1.642189) (xy 302.541056 -1.56223) (xy 302.517589 -1.479754)
			(xy 302.501833 -1.395464) (xy 302.493921 -1.310081) (xy 297.998655 -1.310081) (xy 297.990743 -1.395464)
			(xy 297.974987 -1.479754) (xy 297.95152 -1.56223) (xy 297.920544 -1.642189) (xy 297.882322 -1.718949)
			(xy 297.837181 -1.791855) (xy 297.785505 -1.860284) (xy 297.727736 -1.923654) (xy 297.664366 -1.981423)
			(xy 297.595937 -2.033099) (xy 297.523031 -2.07824) (xy 297.446271 -2.116462) (xy 297.366312 -2.147438)
			(xy 297.283836 -2.170905) (xy 297.199546 -2.186661) (xy 297.114163 -2.194573) (xy 297.028413 -2.194573)
			(xy 296.94303 -2.186661) (xy 296.85874 -2.170905) (xy 296.776264 -2.147438) (xy 296.696305 -2.116462)
			(xy 296.619545 -2.07824) (xy 296.546639 -2.033099) (xy 296.47821 -1.981423) (xy 296.41484 -1.923654)
			(xy 296.357071 -1.860284) (xy 296.305395 -1.791855) (xy 296.260254 -1.718949) (xy 296.222032 -1.642189)
			(xy 296.191056 -1.56223) (xy 296.167589 -1.479754) (xy 296.151833 -1.395464) (xy 296.143921 -1.310081)
			(xy 216.865975 -1.310081) (xy 216.858063 -1.395464) (xy 216.842307 -1.479754) (xy 216.81884 -1.56223)
			(xy 216.787864 -1.642189) (xy 216.749642 -1.718949) (xy 216.704501 -1.791855) (xy 216.652825 -1.860284)
			(xy 216.595056 -1.923654) (xy 216.531686 -1.981423) (xy 216.463257 -2.033099) (xy 216.390351 -2.07824)
			(xy 216.313591 -2.116462) (xy 216.233632 -2.147438) (xy 216.151156 -2.170905) (xy 216.066866 -2.186661)
			(xy 215.981483 -2.194573) (xy 215.895733 -2.194573) (xy 215.81035 -2.186661) (xy 215.72606 -2.170905)
			(xy 215.643584 -2.147438) (xy 215.563625 -2.116462) (xy 215.486865 -2.07824) (xy 215.413959 -2.033099)
			(xy 215.34553 -1.981423) (xy 215.28216 -1.923654) (xy 215.224391 -1.860284) (xy 215.172715 -1.791855)
			(xy 215.127574 -1.718949) (xy 215.089352 -1.642189) (xy 215.058376 -1.56223) (xy 215.034909 -1.479754)
			(xy 215.019153 -1.395464) (xy 215.011241 -1.310081) (xy 210.515975 -1.310081) (xy 210.508063 -1.395464)
			(xy 210.492307 -1.479754) (xy 210.46884 -1.56223) (xy 210.437864 -1.642189) (xy 210.399642 -1.718949)
			(xy 210.354501 -1.791855) (xy 210.302825 -1.860284) (xy 210.245056 -1.923654) (xy 210.181686 -1.981423)
			(xy 210.113257 -2.033099) (xy 210.040351 -2.07824) (xy 209.963591 -2.116462) (xy 209.883632 -2.147438)
			(xy 209.801156 -2.170905) (xy 209.716866 -2.186661) (xy 209.631483 -2.194573) (xy 209.545733 -2.194573)
			(xy 209.46035 -2.186661) (xy 209.37606 -2.170905) (xy 209.293584 -2.147438) (xy 209.213625 -2.116462)
			(xy 209.136865 -2.07824) (xy 209.063959 -2.033099) (xy 208.99553 -1.981423) (xy 208.93216 -1.923654)
			(xy 208.874391 -1.860284) (xy 208.822715 -1.791855) (xy 208.777574 -1.718949) (xy 208.739352 -1.642189)
			(xy 208.708376 -1.56223) (xy 208.684909 -1.479754) (xy 208.669153 -1.395464) (xy 208.661241 -1.310081)
			(xy 84.210906 -1.310081) (xy 84.210906 -7.78002) (xy 84.211428 -7.835789) (xy 84.219765 -7.947014)
			(xy 84.23639 -8.057306) (xy 84.26121 -8.166046) (xy 84.294088 -8.272628) (xy 84.334838 -8.376455)
			(xy 84.383233 -8.476947) (xy 84.439002 -8.573541) (xy 84.501834 -8.665697) (xy 84.571376 -8.7529)
			(xy 84.647241 -8.834663) (xy 84.729004 -8.910527) (xy 84.816208 -8.98007) (xy 84.908364 -9.042901)
			(xy 85.004959 -9.09867) (xy 85.10545 -9.147065) (xy 85.209277 -9.187814) (xy 85.315859 -9.220691)
			(xy 85.4246 -9.245511) (xy 85.534892 -9.262136) (xy 85.646117 -9.270472) (xy 85.701886 -9.271) (xy 122.102118 -9.271)
			(xy 122.157887 -9.270478) (xy 122.269113 -9.262141) (xy 122.379404 -9.245517) (xy 122.488145 -9.220696)
			(xy 122.594728 -9.187819) (xy 122.698555 -9.147069) (xy 122.799047 -9.098674) (xy 122.895641 -9.042905)
			(xy 122.987798 -8.980073) (xy 123.075001 -8.910531) (xy 123.156764 -8.834666) (xy 123.232629 -8.752903)
			(xy 123.302172 -8.665699) (xy 123.365004 -8.573543) (xy 123.420773 -8.476948) (xy 123.469168 -8.376457)
			(xy 123.509918 -8.27263) (xy 123.542796 -8.166047) (xy 123.567616 -8.057306) (xy 123.584241 -7.947015)
			(xy 123.592578 -7.835789) (xy 123.593098 -7.78002) (xy 123.593098 -4.879848) (xy 123.593581 -4.809465)
			(xy 123.601472 -4.66892) (xy 123.61723 -4.529038) (xy 123.640807 -4.39026) (xy 123.672128 -4.253022)
			(xy 123.711095 -4.117757) (xy 123.757586 -3.984889) (xy 123.811453 -3.854837) (xy 123.872528 -3.72801)
			(xy 123.940618 -3.604807) (xy 124.015509 -3.485616) (xy 124.096965 -3.370811) (xy 124.184731 -3.260755)
			(xy 124.278529 -3.155793) (xy 124.378065 -3.056255) (xy 124.483026 -2.962455) (xy 124.593081 -2.874688)
			(xy 124.707884 -2.79323) (xy 124.827074 -2.718337) (xy 124.950276 -2.650245) (xy 125.077102 -2.589169)
			(xy 125.207153 -2.535299) (xy 125.340021 -2.488807) (xy 125.475285 -2.449838) (xy 125.612523 -2.418514)
			(xy 125.7513 -2.394935) (xy 125.891182 -2.379175) (xy 126.031727 -2.371282) (xy 126.10211 -2.370836)
			(xy 194.701922 -2.370836) (xy 194.772304 -2.371321) (xy 194.912845 -2.379215) (xy 195.052723 -2.394977)
			(xy 195.191497 -2.418557) (xy 195.328731 -2.449881) (xy 195.463992 -2.488851) (xy 195.596856 -2.535344)
			(xy 195.726904 -2.589213) (xy 195.853726 -2.650289) (xy 195.976925 -2.71838) (xy 196.096111 -2.793273)
			(xy 196.210911 -2.87473) (xy 196.320963 -2.962495) (xy 196.425921 -3.056294) (xy 196.525454 -3.15583)
			(xy 196.61925 -3.26079) (xy 196.707012 -3.370845) (xy 196.788466 -3.485647) (xy 196.863355 -3.604836)
			(xy 196.931443 -3.728036) (xy 196.990215 -3.850081) (xy 208.661241 -3.850081) (xy 208.661241 -3.764331)
			(xy 208.669153 -3.678948) (xy 208.684909 -3.594658) (xy 208.708376 -3.512182) (xy 208.739352 -3.432223)
			(xy 208.777574 -3.355463) (xy 208.822715 -3.282557) (xy 208.874391 -3.214128) (xy 208.93216 -3.150758)
			(xy 208.99553 -3.092989) (xy 209.063959 -3.041313) (xy 209.136865 -2.996172) (xy 209.213625 -2.95795)
			(xy 209.293584 -2.926974) (xy 209.37606 -2.903507) (xy 209.46035 -2.887751) (xy 209.545733 -2.879839)
			(xy 209.631483 -2.879839) (xy 209.716866 -2.887751) (xy 209.801156 -2.903507) (xy 209.883632 -2.926974)
			(xy 209.963591 -2.95795) (xy 209.984264 -2.968244) (xy 213.517988 -2.968244) (xy 213.517988 -2.104644)
			(xy 213.518492 -2.07509) (xy 213.526541 -2.016534) (xy 213.542487 -1.959619) (xy 213.566036 -1.905405)
			(xy 213.596747 -1.854902) (xy 213.634049 -1.809052) (xy 213.677246 -1.768709) (xy 213.725535 -1.734623)
			(xy 213.778015 -1.70743) (xy 213.83371 -1.687636) (xy 213.891581 -1.67561) (xy 213.95055 -1.671577)
			(xy 214.009519 -1.67561) (xy 214.06739 -1.687636) (xy 214.123085 -1.70743) (xy 214.175565 -1.734623)
			(xy 214.223854 -1.768709) (xy 214.267051 -1.809052) (xy 214.304353 -1.854902) (xy 214.335064 -1.905405)
			(xy 214.358613 -1.959619) (xy 214.374559 -2.016534) (xy 214.382608 -2.07509) (xy 214.383112 -2.104644)
			(xy 214.383112 -2.968244) (xy 214.382608 -2.997798) (xy 214.374559 -3.056354) (xy 214.358613 -3.113269)
			(xy 214.335064 -3.167483) (xy 214.304353 -3.217986) (xy 214.267051 -3.263836) (xy 214.223854 -3.304179)
			(xy 214.175565 -3.338265) (xy 214.123085 -3.365458) (xy 214.06739 -3.385252) (xy 214.009519 -3.397278)
			(xy 213.95055 -3.401312) (xy 213.891581 -3.397278) (xy 213.83371 -3.385252) (xy 213.778015 -3.365458)
			(xy 213.725535 -3.338265) (xy 213.677246 -3.304179) (xy 213.634049 -3.263836) (xy 213.596747 -3.217986)
			(xy 213.566036 -3.167483) (xy 213.542487 -3.113269) (xy 213.526541 -3.056354) (xy 213.518492 -2.997798)
			(xy 213.517988 -2.968244) (xy 209.984264 -2.968244) (xy 210.040351 -2.996172) (xy 210.113257 -3.041313)
			(xy 210.181686 -3.092989) (xy 210.245056 -3.150758) (xy 210.302825 -3.214128) (xy 210.354501 -3.282557)
			(xy 210.399642 -3.355463) (xy 210.437864 -3.432223) (xy 210.46884 -3.512182) (xy 210.492307 -3.594658)
			(xy 210.508063 -3.678948) (xy 210.515975 -3.764331) (xy 210.51647 -3.807206) (xy 210.515975 -3.850081)
			(xy 215.011241 -3.850081) (xy 215.011241 -3.764331) (xy 215.019153 -3.678948) (xy 215.034909 -3.594658)
			(xy 215.058376 -3.512182) (xy 215.089352 -3.432223) (xy 215.127574 -3.355463) (xy 215.172715 -3.282557)
			(xy 215.224391 -3.214128) (xy 215.28216 -3.150758) (xy 215.34553 -3.092989) (xy 215.413959 -3.041313)
			(xy 215.486865 -2.996172) (xy 215.563625 -2.95795) (xy 215.643584 -2.926974) (xy 215.72606 -2.903507)
			(xy 215.81035 -2.887751) (xy 215.895733 -2.879839) (xy 215.981483 -2.879839) (xy 216.066866 -2.887751)
			(xy 216.151156 -2.903507) (xy 216.233632 -2.926974) (xy 216.313591 -2.95795) (xy 216.390351 -2.996172)
			(xy 216.463257 -3.041313) (xy 216.531686 -3.092989) (xy 216.595056 -3.150758) (xy 216.652825 -3.214128)
			(xy 216.704501 -3.282557) (xy 216.749642 -3.355463) (xy 216.787864 -3.432223) (xy 216.81884 -3.512182)
			(xy 216.842307 -3.594658) (xy 216.858063 -3.678948) (xy 216.865975 -3.764331) (xy 216.86647 -3.807206)
			(xy 216.865975 -3.850081) (xy 296.143921 -3.850081) (xy 296.143921 -3.764331) (xy 296.151833 -3.678948)
			(xy 296.167589 -3.594658) (xy 296.191056 -3.512182) (xy 296.222032 -3.432223) (xy 296.260254 -3.355463)
			(xy 296.305395 -3.282557) (xy 296.357071 -3.214128) (xy 296.41484 -3.150758) (xy 296.47821 -3.092989)
			(xy 296.546639 -3.041313) (xy 296.619545 -2.996172) (xy 296.696305 -2.95795) (xy 296.776264 -2.926974)
			(xy 296.85874 -2.903507) (xy 296.94303 -2.887751) (xy 297.028413 -2.879839) (xy 297.114163 -2.879839)
			(xy 297.199546 -2.887751) (xy 297.283836 -2.903507) (xy 297.366312 -2.926974) (xy 297.446271 -2.95795)
			(xy 297.466944 -2.968244) (xy 298.629324 -2.968244) (xy 298.629324 -2.104644) (xy 298.629828 -2.07509)
			(xy 298.637877 -2.016534) (xy 298.653823 -1.959619) (xy 298.677372 -1.905405) (xy 298.708083 -1.854902)
			(xy 298.745385 -1.809052) (xy 298.788582 -1.768709) (xy 298.836871 -1.734623) (xy 298.889351 -1.70743)
			(xy 298.945046 -1.687636) (xy 299.002917 -1.67561) (xy 299.061886 -1.671577) (xy 299.120855 -1.67561)
			(xy 299.178726 -1.687636) (xy 299.234421 -1.70743) (xy 299.286901 -1.734623) (xy 299.33519 -1.768709)
			(xy 299.378387 -1.809052) (xy 299.415689 -1.854902) (xy 299.4464 -1.905405) (xy 299.469949 -1.959619)
			(xy 299.485895 -2.016534) (xy 299.493944 -2.07509) (xy 299.494448 -2.104644) (xy 299.494448 -2.968244)
			(xy 299.493944 -2.997798) (xy 299.485895 -3.056354) (xy 299.469949 -3.113269) (xy 299.4464 -3.167483)
			(xy 299.415689 -3.217986) (xy 299.378387 -3.263836) (xy 299.33519 -3.304179) (xy 299.286901 -3.338265)
			(xy 299.234421 -3.365458) (xy 299.178726 -3.385252) (xy 299.120855 -3.397278) (xy 299.061886 -3.401312)
			(xy 299.002917 -3.397278) (xy 298.945046 -3.385252) (xy 298.889351 -3.365458) (xy 298.836871 -3.338265)
			(xy 298.788582 -3.304179) (xy 298.745385 -3.263836) (xy 298.708083 -3.217986) (xy 298.677372 -3.167483)
			(xy 298.653823 -3.113269) (xy 298.637877 -3.056354) (xy 298.629828 -2.997798) (xy 298.629324 -2.968244)
			(xy 297.466944 -2.968244) (xy 297.523031 -2.996172) (xy 297.595937 -3.041313) (xy 297.664366 -3.092989)
			(xy 297.727736 -3.150758) (xy 297.785505 -3.214128) (xy 297.837181 -3.282557) (xy 297.882322 -3.355463)
			(xy 297.920544 -3.432223) (xy 297.95152 -3.512182) (xy 297.974987 -3.594658) (xy 297.990743 -3.678948)
			(xy 297.998655 -3.764331) (xy 297.99915 -3.807206) (xy 297.998655 -3.850081) (xy 302.493921 -3.850081)
			(xy 302.493921 -3.764331) (xy 302.501833 -3.678948) (xy 302.517589 -3.594658) (xy 302.541056 -3.512182)
			(xy 302.572032 -3.432223) (xy 302.610254 -3.355463) (xy 302.655395 -3.282557) (xy 302.707071 -3.214128)
			(xy 302.76484 -3.150758) (xy 302.82821 -3.092989) (xy 302.896639 -3.041313) (xy 302.969545 -2.996172)
			(xy 303.046305 -2.95795) (xy 303.126264 -2.926974) (xy 303.20874 -2.903507) (xy 303.29303 -2.887751)
			(xy 303.378413 -2.879839) (xy 303.464163 -2.879839) (xy 303.549546 -2.887751) (xy 303.633836 -2.903507)
			(xy 303.716312 -2.926974) (xy 303.796271 -2.95795) (xy 303.873031 -2.996172) (xy 303.945937 -3.041313)
			(xy 304.014366 -3.092989) (xy 304.077736 -3.150758) (xy 304.135505 -3.214128) (xy 304.187181 -3.282557)
			(xy 304.232322 -3.355463) (xy 304.270544 -3.432223) (xy 304.30152 -3.512182) (xy 304.324987 -3.594658)
			(xy 304.340743 -3.678948) (xy 304.348655 -3.764331) (xy 304.34915 -3.807206) (xy 304.348655 -3.850081)
			(xy 311.155321 -3.850081) (xy 311.155321 -3.764331) (xy 311.163233 -3.678948) (xy 311.178989 -3.594658)
			(xy 311.202456 -3.512182) (xy 311.233432 -3.432223) (xy 311.271654 -3.355463) (xy 311.316795 -3.282557)
			(xy 311.368471 -3.214128) (xy 311.42624 -3.150758) (xy 311.48961 -3.092989) (xy 311.558039 -3.041313)
			(xy 311.630945 -2.996172) (xy 311.707705 -2.95795) (xy 311.787664 -2.926974) (xy 311.87014 -2.903507)
			(xy 311.95443 -2.887751) (xy 312.039813 -2.879839) (xy 312.125563 -2.879839) (xy 312.210946 -2.887751)
			(xy 312.295236 -2.903507) (xy 312.377712 -2.926974) (xy 312.457671 -2.95795) (xy 312.478344 -2.968244)
			(xy 316.012068 -2.968244) (xy 316.012068 -2.104644) (xy 316.012572 -2.07509) (xy 316.020621 -2.016534)
			(xy 316.036567 -1.959619) (xy 316.060116 -1.905405) (xy 316.090827 -1.854902) (xy 316.128129 -1.809052)
			(xy 316.171326 -1.768709) (xy 316.219615 -1.734623) (xy 316.272095 -1.70743) (xy 316.32779 -1.687636)
			(xy 316.385661 -1.67561) (xy 316.44463 -1.671577) (xy 316.503599 -1.67561) (xy 316.56147 -1.687636)
			(xy 316.617165 -1.70743) (xy 316.669645 -1.734623) (xy 316.717934 -1.768709) (xy 316.761131 -1.809052)
			(xy 316.798433 -1.854902) (xy 316.829144 -1.905405) (xy 316.852693 -1.959619) (xy 316.868639 -2.016534)
			(xy 316.876688 -2.07509) (xy 316.877192 -2.104644) (xy 316.877192 -2.968244) (xy 316.876688 -2.997798)
			(xy 316.868639 -3.056354) (xy 316.852693 -3.113269) (xy 316.829144 -3.167483) (xy 316.798433 -3.217986)
			(xy 316.761131 -3.263836) (xy 316.717934 -3.304179) (xy 316.669645 -3.338265) (xy 316.617165 -3.365458)
			(xy 316.56147 -3.385252) (xy 316.503599 -3.397278) (xy 316.44463 -3.401312) (xy 316.385661 -3.397278)
			(xy 316.32779 -3.385252) (xy 316.272095 -3.365458) (xy 316.219615 -3.338265) (xy 316.171326 -3.304179)
			(xy 316.128129 -3.263836) (xy 316.090827 -3.217986) (xy 316.060116 -3.167483) (xy 316.036567 -3.113269)
			(xy 316.020621 -3.056354) (xy 316.012572 -2.997798) (xy 316.012068 -2.968244) (xy 312.478344 -2.968244)
			(xy 312.534431 -2.996172) (xy 312.607337 -3.041313) (xy 312.675766 -3.092989) (xy 312.739136 -3.150758)
			(xy 312.796905 -3.214128) (xy 312.848581 -3.282557) (xy 312.893722 -3.355463) (xy 312.931944 -3.432223)
			(xy 312.96292 -3.512182) (xy 312.986387 -3.594658) (xy 313.002143 -3.678948) (xy 313.010055 -3.764331)
			(xy 313.01055 -3.807206) (xy 313.010055 -3.850081) (xy 317.505321 -3.850081) (xy 317.505321 -3.764331)
			(xy 317.513233 -3.678948) (xy 317.528989 -3.594658) (xy 317.552456 -3.512182) (xy 317.583432 -3.432223)
			(xy 317.621654 -3.355463) (xy 317.666795 -3.282557) (xy 317.718471 -3.214128) (xy 317.77624 -3.150758)
			(xy 317.83961 -3.092989) (xy 317.908039 -3.041313) (xy 317.980945 -2.996172) (xy 318.057705 -2.95795)
			(xy 318.137664 -2.926974) (xy 318.22014 -2.903507) (xy 318.30443 -2.887751) (xy 318.389813 -2.879839)
			(xy 318.475563 -2.879839) (xy 318.560946 -2.887751) (xy 318.645236 -2.903507) (xy 318.727712 -2.926974)
			(xy 318.807671 -2.95795) (xy 318.884431 -2.996172) (xy 318.957337 -3.041313) (xy 319.025766 -3.092989)
			(xy 319.089136 -3.150758) (xy 319.146905 -3.214128) (xy 319.198581 -3.282557) (xy 319.243722 -3.355463)
			(xy 319.281944 -3.432223) (xy 319.31292 -3.512182) (xy 319.336387 -3.594658) (xy 319.352143 -3.678948)
			(xy 319.360055 -3.764331) (xy 319.36055 -3.807206) (xy 319.360055 -3.850081) (xy 361.894107 -3.850081)
			(xy 361.894107 -3.764331) (xy 361.902019 -3.678948) (xy 361.917775 -3.594658) (xy 361.941242 -3.512182)
			(xy 361.972218 -3.432223) (xy 362.01044 -3.355463) (xy 362.055581 -3.282557) (xy 362.107257 -3.214128)
			(xy 362.165026 -3.150758) (xy 362.228396 -3.092989) (xy 362.296825 -3.041313) (xy 362.369731 -2.996172)
			(xy 362.446491 -2.95795) (xy 362.52645 -2.926974) (xy 362.608926 -2.903507) (xy 362.693216 -2.887751)
			(xy 362.778599 -2.879839) (xy 362.864349 -2.879839) (xy 362.949732 -2.887751) (xy 363.034022 -2.903507)
			(xy 363.116498 -2.926974) (xy 363.196457 -2.95795) (xy 363.21713 -2.968244) (xy 364.379764 -2.968244)
			(xy 364.379764 -2.104644) (xy 364.380268 -2.075108) (xy 364.388312 -2.016586) (xy 364.404249 -1.959704)
			(xy 364.427784 -1.905522) (xy 364.458477 -1.855049) (xy 364.495757 -1.809226) (xy 364.538929 -1.768906)
			(xy 364.587189 -1.73484) (xy 364.639639 -1.707663) (xy 364.6953 -1.687881) (xy 364.753137 -1.675862)
			(xy 364.812072 -1.671831) (xy 364.871007 -1.675862) (xy 364.928844 -1.687881) (xy 364.984505 -1.707663)
			(xy 365.036955 -1.73484) (xy 365.085215 -1.768906) (xy 365.128387 -1.809226) (xy 365.165667 -1.855049)
			(xy 365.19636 -1.905522) (xy 365.219895 -1.959704) (xy 365.235832 -2.016586) (xy 365.243876 -2.075108)
			(xy 365.24438 -2.104644) (xy 365.24438 -2.968244) (xy 365.243876 -2.99778) (xy 365.235832 -3.056302)
			(xy 365.219895 -3.113184) (xy 365.19636 -3.167366) (xy 365.165667 -3.217839) (xy 365.128387 -3.263662)
			(xy 365.085215 -3.303982) (xy 365.036955 -3.338048) (xy 364.984505 -3.365225) (xy 364.928844 -3.385007)
			(xy 364.871007 -3.397026) (xy 364.812072 -3.401057) (xy 364.753137 -3.397026) (xy 364.6953 -3.385007)
			(xy 364.639639 -3.365225) (xy 364.587189 -3.338048) (xy 364.538929 -3.303982) (xy 364.495757 -3.263662)
			(xy 364.458477 -3.217839) (xy 364.427784 -3.167366) (xy 364.404249 -3.113184) (xy 364.388312 -3.056302)
			(xy 364.380268 -2.99778) (xy 364.379764 -2.968244) (xy 363.21713 -2.968244) (xy 363.273217 -2.996172)
			(xy 363.346123 -3.041313) (xy 363.414552 -3.092989) (xy 363.477922 -3.150758) (xy 363.535691 -3.214128)
			(xy 363.587367 -3.282557) (xy 363.632508 -3.355463) (xy 363.67073 -3.432223) (xy 363.701706 -3.512182)
			(xy 363.725173 -3.594658) (xy 363.740929 -3.678948) (xy 363.748841 -3.764331) (xy 363.749336 -3.807206)
			(xy 363.748841 -3.850081) (xy 368.244107 -3.850081) (xy 368.244107 -3.764331) (xy 368.252019 -3.678948)
			(xy 368.267775 -3.594658) (xy 368.291242 -3.512182) (xy 368.322218 -3.432223) (xy 368.36044 -3.355463)
			(xy 368.405581 -3.282557) (xy 368.457257 -3.214128) (xy 368.515026 -3.150758) (xy 368.578396 -3.092989)
			(xy 368.646825 -3.041313) (xy 368.719731 -2.996172) (xy 368.796491 -2.95795) (xy 368.87645 -2.926974)
			(xy 368.958926 -2.903507) (xy 369.043216 -2.887751) (xy 369.128599 -2.879839) (xy 369.214349 -2.879839)
			(xy 369.299732 -2.887751) (xy 369.384022 -2.903507) (xy 369.466498 -2.926974) (xy 369.546457 -2.95795)
			(xy 369.623217 -2.996172) (xy 369.696123 -3.041313) (xy 369.764552 -3.092989) (xy 369.827922 -3.150758)
			(xy 369.885691 -3.214128) (xy 369.937367 -3.282557) (xy 369.982508 -3.355463) (xy 370.02073 -3.432223)
			(xy 370.051706 -3.512182) (xy 370.075173 -3.594658) (xy 370.090929 -3.678948) (xy 370.098841 -3.764331)
			(xy 370.099336 -3.807206) (xy 370.098841 -3.850081) (xy 370.090929 -3.935464) (xy 370.075173 -4.019754)
			(xy 370.051706 -4.10223) (xy 370.02073 -4.182189) (xy 369.982508 -4.258949) (xy 369.937367 -4.331855)
			(xy 369.885691 -4.400284) (xy 369.827922 -4.463654) (xy 369.764552 -4.521423) (xy 369.696123 -4.573099)
			(xy 369.623217 -4.61824) (xy 369.546457 -4.656462) (xy 369.466498 -4.687438) (xy 369.384022 -4.710905)
			(xy 369.299732 -4.726661) (xy 369.214349 -4.734573) (xy 369.128599 -4.734573) (xy 369.043216 -4.726661)
			(xy 368.958926 -4.710905) (xy 368.87645 -4.687438) (xy 368.796491 -4.656462) (xy 368.719731 -4.61824)
			(xy 368.646825 -4.573099) (xy 368.578396 -4.521423) (xy 368.515026 -4.463654) (xy 368.457257 -4.400284)
			(xy 368.405581 -4.331855) (xy 368.36044 -4.258949) (xy 368.322218 -4.182189) (xy 368.291242 -4.10223)
			(xy 368.267775 -4.019754) (xy 368.252019 -3.935464) (xy 368.244107 -3.850081) (xy 363.748841 -3.850081)
			(xy 363.740929 -3.935464) (xy 363.725173 -4.019754) (xy 363.701706 -4.10223) (xy 363.67073 -4.182189)
			(xy 363.632508 -4.258949) (xy 363.587367 -4.331855) (xy 363.535691 -4.400284) (xy 363.477922 -4.463654)
			(xy 363.414552 -4.521423) (xy 363.346123 -4.573099) (xy 363.273217 -4.61824) (xy 363.196457 -4.656462)
			(xy 363.116498 -4.687438) (xy 363.034022 -4.710905) (xy 362.949732 -4.726661) (xy 362.864349 -4.734573)
			(xy 362.778599 -4.734573) (xy 362.693216 -4.726661) (xy 362.608926 -4.710905) (xy 362.52645 -4.687438)
			(xy 362.446491 -4.656462) (xy 362.369731 -4.61824) (xy 362.296825 -4.573099) (xy 362.228396 -4.521423)
			(xy 362.165026 -4.463654) (xy 362.107257 -4.400284) (xy 362.055581 -4.331855) (xy 362.01044 -4.258949)
			(xy 361.972218 -4.182189) (xy 361.941242 -4.10223) (xy 361.917775 -4.019754) (xy 361.902019 -3.935464)
			(xy 361.894107 -3.850081) (xy 319.360055 -3.850081) (xy 319.352143 -3.935464) (xy 319.336387 -4.019754)
			(xy 319.31292 -4.10223) (xy 319.281944 -4.182189) (xy 319.243722 -4.258949) (xy 319.198581 -4.331855)
			(xy 319.146905 -4.400284) (xy 319.089136 -4.463654) (xy 319.025766 -4.521423) (xy 318.957337 -4.573099)
			(xy 318.884431 -4.61824) (xy 318.807671 -4.656462) (xy 318.727712 -4.687438) (xy 318.645236 -4.710905)
			(xy 318.560946 -4.726661) (xy 318.475563 -4.734573) (xy 318.389813 -4.734573) (xy 318.30443 -4.726661)
			(xy 318.22014 -4.710905) (xy 318.137664 -4.687438) (xy 318.057705 -4.656462) (xy 317.980945 -4.61824)
			(xy 317.908039 -4.573099) (xy 317.83961 -4.521423) (xy 317.77624 -4.463654) (xy 317.718471 -4.400284)
			(xy 317.666795 -4.331855) (xy 317.621654 -4.258949) (xy 317.583432 -4.182189) (xy 317.552456 -4.10223)
			(xy 317.528989 -4.019754) (xy 317.513233 -3.935464) (xy 317.505321 -3.850081) (xy 313.010055 -3.850081)
			(xy 313.002143 -3.935464) (xy 312.986387 -4.019754) (xy 312.96292 -4.10223) (xy 312.931944 -4.182189)
			(xy 312.893722 -4.258949) (xy 312.848581 -4.331855) (xy 312.796905 -4.400284) (xy 312.739136 -4.463654)
			(xy 312.675766 -4.521423) (xy 312.607337 -4.573099) (xy 312.534431 -4.61824) (xy 312.457671 -4.656462)
			(xy 312.377712 -4.687438) (xy 312.295236 -4.710905) (xy 312.210946 -4.726661) (xy 312.125563 -4.734573)
			(xy 312.039813 -4.734573) (xy 311.95443 -4.726661) (xy 311.87014 -4.710905) (xy 311.787664 -4.687438)
			(xy 311.707705 -4.656462) (xy 311.630945 -4.61824) (xy 311.558039 -4.573099) (xy 311.48961 -4.521423)
			(xy 311.42624 -4.463654) (xy 311.368471 -4.400284) (xy 311.316795 -4.331855) (xy 311.271654 -4.258949)
			(xy 311.233432 -4.182189) (xy 311.202456 -4.10223) (xy 311.178989 -4.019754) (xy 311.163233 -3.935464)
			(xy 311.155321 -3.850081) (xy 304.348655 -3.850081) (xy 304.340743 -3.935464) (xy 304.324987 -4.019754)
			(xy 304.30152 -4.10223) (xy 304.270544 -4.182189) (xy 304.232322 -4.258949) (xy 304.187181 -4.331855)
			(xy 304.135505 -4.400284) (xy 304.077736 -4.463654) (xy 304.014366 -4.521423) (xy 303.945937 -4.573099)
			(xy 303.873031 -4.61824) (xy 303.796271 -4.656462) (xy 303.716312 -4.687438) (xy 303.633836 -4.710905)
			(xy 303.549546 -4.726661) (xy 303.464163 -4.734573) (xy 303.378413 -4.734573) (xy 303.29303 -4.726661)
			(xy 303.20874 -4.710905) (xy 303.126264 -4.687438) (xy 303.046305 -4.656462) (xy 302.969545 -4.61824)
			(xy 302.896639 -4.573099) (xy 302.82821 -4.521423) (xy 302.76484 -4.463654) (xy 302.707071 -4.400284)
			(xy 302.655395 -4.331855) (xy 302.610254 -4.258949) (xy 302.572032 -4.182189) (xy 302.541056 -4.10223)
			(xy 302.517589 -4.019754) (xy 302.501833 -3.935464) (xy 302.493921 -3.850081) (xy 297.998655 -3.850081)
			(xy 297.990743 -3.935464) (xy 297.974987 -4.019754) (xy 297.95152 -4.10223) (xy 297.920544 -4.182189)
			(xy 297.882322 -4.258949) (xy 297.837181 -4.331855) (xy 297.785505 -4.400284) (xy 297.727736 -4.463654)
			(xy 297.664366 -4.521423) (xy 297.595937 -4.573099) (xy 297.523031 -4.61824) (xy 297.446271 -4.656462)
			(xy 297.366312 -4.687438) (xy 297.283836 -4.710905) (xy 297.199546 -4.726661) (xy 297.114163 -4.734573)
			(xy 297.028413 -4.734573) (xy 296.94303 -4.726661) (xy 296.85874 -4.710905) (xy 296.776264 -4.687438)
			(xy 296.696305 -4.656462) (xy 296.619545 -4.61824) (xy 296.546639 -4.573099) (xy 296.47821 -4.521423)
			(xy 296.41484 -4.463654) (xy 296.357071 -4.400284) (xy 296.305395 -4.331855) (xy 296.260254 -4.258949)
			(xy 296.222032 -4.182189) (xy 296.191056 -4.10223) (xy 296.167589 -4.019754) (xy 296.151833 -3.935464)
			(xy 296.143921 -3.850081) (xy 216.865975 -3.850081) (xy 216.858063 -3.935464) (xy 216.842307 -4.019754)
			(xy 216.81884 -4.10223) (xy 216.787864 -4.182189) (xy 216.749642 -4.258949) (xy 216.704501 -4.331855)
			(xy 216.652825 -4.400284) (xy 216.595056 -4.463654) (xy 216.531686 -4.521423) (xy 216.463257 -4.573099)
			(xy 216.390351 -4.61824) (xy 216.313591 -4.656462) (xy 216.233632 -4.687438) (xy 216.151156 -4.710905)
			(xy 216.066866 -4.726661) (xy 215.981483 -4.734573) (xy 215.895733 -4.734573) (xy 215.81035 -4.726661)
			(xy 215.72606 -4.710905) (xy 215.643584 -4.687438) (xy 215.563625 -4.656462) (xy 215.486865 -4.61824)
			(xy 215.413959 -4.573099) (xy 215.34553 -4.521423) (xy 215.28216 -4.463654) (xy 215.224391 -4.400284)
			(xy 215.172715 -4.331855) (xy 215.127574 -4.258949) (xy 215.089352 -4.182189) (xy 215.058376 -4.10223)
			(xy 215.034909 -4.019754) (xy 215.019153 -3.935464) (xy 215.011241 -3.850081) (xy 210.515975 -3.850081)
			(xy 210.508063 -3.935464) (xy 210.492307 -4.019754) (xy 210.46884 -4.10223) (xy 210.437864 -4.182189)
			(xy 210.399642 -4.258949) (xy 210.354501 -4.331855) (xy 210.302825 -4.400284) (xy 210.245056 -4.463654)
			(xy 210.181686 -4.521423) (xy 210.113257 -4.573099) (xy 210.040351 -4.61824) (xy 209.963591 -4.656462)
			(xy 209.883632 -4.687438) (xy 209.801156 -4.710905) (xy 209.716866 -4.726661) (xy 209.631483 -4.734573)
			(xy 209.545733 -4.734573) (xy 209.46035 -4.726661) (xy 209.37606 -4.710905) (xy 209.293584 -4.687438)
			(xy 209.213625 -4.656462) (xy 209.136865 -4.61824) (xy 209.063959 -4.573099) (xy 208.99553 -4.521423)
			(xy 208.93216 -4.463654) (xy 208.874391 -4.400284) (xy 208.822715 -4.331855) (xy 208.777574 -4.258949)
			(xy 208.739352 -4.182189) (xy 208.708376 -4.10223) (xy 208.684909 -4.019754) (xy 208.669153 -3.935464)
			(xy 208.661241 -3.850081) (xy 196.990215 -3.850081) (xy 196.992516 -3.85486) (xy 197.046381 -3.984909)
			(xy 197.09287 -4.117774) (xy 197.131836 -4.253037) (xy 197.163157 -4.390271) (xy 197.186733 -4.529046)
			(xy 197.202491 -4.668924) (xy 197.210381 -4.809466) (xy 197.210934 -4.879848) (xy 197.210934 -6.390081)
			(xy 208.661241 -6.390081) (xy 208.661241 -6.304331) (xy 208.669153 -6.218948) (xy 208.684909 -6.134658)
			(xy 208.708376 -6.052182) (xy 208.739352 -5.972223) (xy 208.777574 -5.895463) (xy 208.822715 -5.822557)
			(xy 208.874391 -5.754128) (xy 208.93216 -5.690758) (xy 208.99553 -5.632989) (xy 209.063959 -5.581313)
			(xy 209.136865 -5.536172) (xy 209.213625 -5.49795) (xy 209.293584 -5.466974) (xy 209.37606 -5.443507)
			(xy 209.46035 -5.427751) (xy 209.545733 -5.419839) (xy 209.631483 -5.419839) (xy 209.716866 -5.427751)
			(xy 209.801156 -5.443507) (xy 209.883632 -5.466974) (xy 209.963591 -5.49795) (xy 209.984264 -5.508244)
			(xy 213.517988 -5.508244) (xy 213.517988 -4.644644) (xy 213.518492 -4.61509) (xy 213.526541 -4.556534)
			(xy 213.542487 -4.499619) (xy 213.566036 -4.445405) (xy 213.596747 -4.394902) (xy 213.634049 -4.349052)
			(xy 213.677246 -4.308709) (xy 213.725535 -4.274623) (xy 213.778015 -4.24743) (xy 213.83371 -4.227636)
			(xy 213.891581 -4.21561) (xy 213.95055 -4.211577) (xy 214.009519 -4.21561) (xy 214.06739 -4.227636)
			(xy 214.123085 -4.24743) (xy 214.175565 -4.274623) (xy 214.223854 -4.308709) (xy 214.267051 -4.349052)
			(xy 214.304353 -4.394902) (xy 214.335064 -4.445405) (xy 214.358613 -4.499619) (xy 214.374559 -4.556534)
			(xy 214.382608 -4.61509) (xy 214.383112 -4.644644) (xy 214.383112 -5.508244) (xy 214.382608 -5.537798)
			(xy 214.374559 -5.596354) (xy 214.358613 -5.653269) (xy 214.335064 -5.707483) (xy 214.304353 -5.757986)
			(xy 214.267051 -5.803836) (xy 214.223854 -5.844179) (xy 214.175565 -5.878265) (xy 214.123085 -5.905458)
			(xy 214.06739 -5.925252) (xy 214.009519 -5.937278) (xy 213.95055 -5.941312) (xy 213.891581 -5.937278)
			(xy 213.83371 -5.925252) (xy 213.778015 -5.905458) (xy 213.725535 -5.878265) (xy 213.677246 -5.844179)
			(xy 213.634049 -5.803836) (xy 213.596747 -5.757986) (xy 213.566036 -5.707483) (xy 213.542487 -5.653269)
			(xy 213.526541 -5.596354) (xy 213.518492 -5.537798) (xy 213.517988 -5.508244) (xy 209.984264 -5.508244)
			(xy 210.040351 -5.536172) (xy 210.113257 -5.581313) (xy 210.181686 -5.632989) (xy 210.245056 -5.690758)
			(xy 210.302825 -5.754128) (xy 210.354501 -5.822557) (xy 210.399642 -5.895463) (xy 210.437864 -5.972223)
			(xy 210.46884 -6.052182) (xy 210.492307 -6.134658) (xy 210.508063 -6.218948) (xy 210.515975 -6.304331)
			(xy 210.51647 -6.347206) (xy 210.515975 -6.390081) (xy 215.011241 -6.390081) (xy 215.011241 -6.304331)
			(xy 215.019153 -6.218948) (xy 215.034909 -6.134658) (xy 215.058376 -6.052182) (xy 215.089352 -5.972223)
			(xy 215.127574 -5.895463) (xy 215.172715 -5.822557) (xy 215.224391 -5.754128) (xy 215.28216 -5.690758)
			(xy 215.34553 -5.632989) (xy 215.413959 -5.581313) (xy 215.486865 -5.536172) (xy 215.563625 -5.49795)
			(xy 215.643584 -5.466974) (xy 215.72606 -5.443507) (xy 215.81035 -5.427751) (xy 215.895733 -5.419839)
			(xy 215.981483 -5.419839) (xy 216.066866 -5.427751) (xy 216.151156 -5.443507) (xy 216.233632 -5.466974)
			(xy 216.313591 -5.49795) (xy 216.390351 -5.536172) (xy 216.463257 -5.581313) (xy 216.531686 -5.632989)
			(xy 216.595056 -5.690758) (xy 216.652825 -5.754128) (xy 216.704501 -5.822557) (xy 216.749642 -5.895463)
			(xy 216.787864 -5.972223) (xy 216.81884 -6.052182) (xy 216.842307 -6.134658) (xy 216.858063 -6.218948)
			(xy 216.865975 -6.304331) (xy 216.86647 -6.347206) (xy 216.865975 -6.390081) (xy 296.143921 -6.390081)
			(xy 296.143921 -6.304331) (xy 296.151833 -6.218948) (xy 296.167589 -6.134658) (xy 296.191056 -6.052182)
			(xy 296.222032 -5.972223) (xy 296.260254 -5.895463) (xy 296.305395 -5.822557) (xy 296.357071 -5.754128)
			(xy 296.41484 -5.690758) (xy 296.47821 -5.632989) (xy 296.546639 -5.581313) (xy 296.619545 -5.536172)
			(xy 296.696305 -5.49795) (xy 296.776264 -5.466974) (xy 296.85874 -5.443507) (xy 296.94303 -5.427751)
			(xy 297.028413 -5.419839) (xy 297.114163 -5.419839) (xy 297.199546 -5.427751) (xy 297.283836 -5.443507)
			(xy 297.366312 -5.466974) (xy 297.446271 -5.49795) (xy 297.466944 -5.508244) (xy 298.629324 -5.508244)
			(xy 298.629324 -4.644644) (xy 298.629828 -4.61509) (xy 298.637877 -4.556534) (xy 298.653823 -4.499619)
			(xy 298.677372 -4.445405) (xy 298.708083 -4.394902) (xy 298.745385 -4.349052) (xy 298.788582 -4.308709)
			(xy 298.836871 -4.274623) (xy 298.889351 -4.24743) (xy 298.945046 -4.227636) (xy 299.002917 -4.21561)
			(xy 299.061886 -4.211577) (xy 299.120855 -4.21561) (xy 299.178726 -4.227636) (xy 299.234421 -4.24743)
			(xy 299.286901 -4.274623) (xy 299.33519 -4.308709) (xy 299.378387 -4.349052) (xy 299.415689 -4.394902)
			(xy 299.4464 -4.445405) (xy 299.469949 -4.499619) (xy 299.485895 -4.556534) (xy 299.493944 -4.61509)
			(xy 299.494448 -4.644644) (xy 299.494448 -5.508244) (xy 299.493944 -5.537798) (xy 299.485895 -5.596354)
			(xy 299.469949 -5.653269) (xy 299.4464 -5.707483) (xy 299.415689 -5.757986) (xy 299.378387 -5.803836)
			(xy 299.33519 -5.844179) (xy 299.286901 -5.878265) (xy 299.234421 -5.905458) (xy 299.178726 -5.925252)
			(xy 299.120855 -5.937278) (xy 299.061886 -5.941312) (xy 299.002917 -5.937278) (xy 298.945046 -5.925252)
			(xy 298.889351 -5.905458) (xy 298.836871 -5.878265) (xy 298.788582 -5.844179) (xy 298.745385 -5.803836)
			(xy 298.708083 -5.757986) (xy 298.677372 -5.707483) (xy 298.653823 -5.653269) (xy 298.637877 -5.596354)
			(xy 298.629828 -5.537798) (xy 298.629324 -5.508244) (xy 297.466944 -5.508244) (xy 297.523031 -5.536172)
			(xy 297.595937 -5.581313) (xy 297.664366 -5.632989) (xy 297.727736 -5.690758) (xy 297.785505 -5.754128)
			(xy 297.837181 -5.822557) (xy 297.882322 -5.895463) (xy 297.920544 -5.972223) (xy 297.95152 -6.052182)
			(xy 297.974987 -6.134658) (xy 297.990743 -6.218948) (xy 297.998655 -6.304331) (xy 297.99915 -6.347206)
			(xy 297.998655 -6.390081) (xy 302.493921 -6.390081) (xy 302.493921 -6.304331) (xy 302.501833 -6.218948)
			(xy 302.517589 -6.134658) (xy 302.541056 -6.052182) (xy 302.572032 -5.972223) (xy 302.610254 -5.895463)
			(xy 302.655395 -5.822557) (xy 302.707071 -5.754128) (xy 302.76484 -5.690758) (xy 302.82821 -5.632989)
			(xy 302.896639 -5.581313) (xy 302.969545 -5.536172) (xy 303.046305 -5.49795) (xy 303.126264 -5.466974)
			(xy 303.20874 -5.443507) (xy 303.29303 -5.427751) (xy 303.378413 -5.419839) (xy 303.464163 -5.419839)
			(xy 303.549546 -5.427751) (xy 303.633836 -5.443507) (xy 303.716312 -5.466974) (xy 303.796271 -5.49795)
			(xy 303.873031 -5.536172) (xy 303.945937 -5.581313) (xy 304.014366 -5.632989) (xy 304.077736 -5.690758)
			(xy 304.135505 -5.754128) (xy 304.187181 -5.822557) (xy 304.232322 -5.895463) (xy 304.270544 -5.972223)
			(xy 304.30152 -6.052182) (xy 304.324987 -6.134658) (xy 304.340743 -6.218948) (xy 304.348655 -6.304331)
			(xy 304.34915 -6.347206) (xy 304.348655 -6.390081) (xy 311.155321 -6.390081) (xy 311.155321 -6.304331)
			(xy 311.163233 -6.218948) (xy 311.178989 -6.134658) (xy 311.202456 -6.052182) (xy 311.233432 -5.972223)
			(xy 311.271654 -5.895463) (xy 311.316795 -5.822557) (xy 311.368471 -5.754128) (xy 311.42624 -5.690758)
			(xy 311.48961 -5.632989) (xy 311.558039 -5.581313) (xy 311.630945 -5.536172) (xy 311.707705 -5.49795)
			(xy 311.787664 -5.466974) (xy 311.87014 -5.443507) (xy 311.95443 -5.427751) (xy 312.039813 -5.419839)
			(xy 312.125563 -5.419839) (xy 312.210946 -5.427751) (xy 312.295236 -5.443507) (xy 312.377712 -5.466974)
			(xy 312.457671 -5.49795) (xy 312.534431 -5.536172) (xy 312.607337 -5.581313) (xy 312.675766 -5.632989)
			(xy 312.739136 -5.690758) (xy 312.796905 -5.754128) (xy 312.848581 -5.822557) (xy 312.893722 -5.895463)
			(xy 312.931944 -5.972223) (xy 312.96292 -6.052182) (xy 312.986387 -6.134658) (xy 313.002143 -6.218948)
			(xy 313.010055 -6.304331) (xy 313.01055 -6.347206) (xy 313.010055 -6.390081) (xy 317.505321 -6.390081)
			(xy 317.505321 -6.304331) (xy 317.513233 -6.218948) (xy 317.528989 -6.134658) (xy 317.552456 -6.052182)
			(xy 317.583432 -5.972223) (xy 317.621654 -5.895463) (xy 317.666795 -5.822557) (xy 317.718471 -5.754128)
			(xy 317.77624 -5.690758) (xy 317.83961 -5.632989) (xy 317.908039 -5.581313) (xy 317.980945 -5.536172)
			(xy 318.057705 -5.49795) (xy 318.137664 -5.466974) (xy 318.22014 -5.443507) (xy 318.30443 -5.427751)
			(xy 318.389813 -5.419839) (xy 318.475563 -5.419839) (xy 318.560946 -5.427751) (xy 318.645236 -5.443507)
			(xy 318.727712 -5.466974) (xy 318.807671 -5.49795) (xy 318.884431 -5.536172) (xy 318.957337 -5.581313)
			(xy 319.025766 -5.632989) (xy 319.089136 -5.690758) (xy 319.146905 -5.754128) (xy 319.198581 -5.822557)
			(xy 319.243722 -5.895463) (xy 319.281944 -5.972223) (xy 319.31292 -6.052182) (xy 319.336387 -6.134658)
			(xy 319.352143 -6.218948) (xy 319.360055 -6.304331) (xy 319.36055 -6.347206) (xy 319.360055 -6.390081)
			(xy 361.894107 -6.390081) (xy 361.894107 -6.304331) (xy 361.902019 -6.218948) (xy 361.917775 -6.134658)
			(xy 361.941242 -6.052182) (xy 361.972218 -5.972223) (xy 362.01044 -5.895463) (xy 362.055581 -5.822557)
			(xy 362.107257 -5.754128) (xy 362.165026 -5.690758) (xy 362.228396 -5.632989) (xy 362.296825 -5.581313)
			(xy 362.369731 -5.536172) (xy 362.446491 -5.49795) (xy 362.52645 -5.466974) (xy 362.608926 -5.443507)
			(xy 362.693216 -5.427751) (xy 362.778599 -5.419839) (xy 362.864349 -5.419839) (xy 362.949732 -5.427751)
			(xy 363.034022 -5.443507) (xy 363.116498 -5.466974) (xy 363.196457 -5.49795) (xy 363.273217 -5.536172)
			(xy 363.346123 -5.581313) (xy 363.414552 -5.632989) (xy 363.477922 -5.690758) (xy 363.535691 -5.754128)
			(xy 363.587367 -5.822557) (xy 363.632508 -5.895463) (xy 363.67073 -5.972223) (xy 363.701706 -6.052182)
			(xy 363.725173 -6.134658) (xy 363.740929 -6.218948) (xy 363.748841 -6.304331) (xy 363.749336 -6.347206)
			(xy 363.748841 -6.390081) (xy 368.244107 -6.390081) (xy 368.244107 -6.304331) (xy 368.252019 -6.218948)
			(xy 368.267775 -6.134658) (xy 368.291242 -6.052182) (xy 368.322218 -5.972223) (xy 368.36044 -5.895463)
			(xy 368.405581 -5.822557) (xy 368.457257 -5.754128) (xy 368.515026 -5.690758) (xy 368.578396 -5.632989)
			(xy 368.646825 -5.581313) (xy 368.719731 -5.536172) (xy 368.796491 -5.49795) (xy 368.87645 -5.466974)
			(xy 368.958926 -5.443507) (xy 369.043216 -5.427751) (xy 369.128599 -5.419839) (xy 369.214349 -5.419839)
			(xy 369.299732 -5.427751) (xy 369.384022 -5.443507) (xy 369.466498 -5.466974) (xy 369.546457 -5.49795)
			(xy 369.623217 -5.536172) (xy 369.696123 -5.581313) (xy 369.764552 -5.632989) (xy 369.827922 -5.690758)
			(xy 369.885691 -5.754128) (xy 369.937367 -5.822557) (xy 369.982508 -5.895463) (xy 370.02073 -5.972223)
			(xy 370.051706 -6.052182) (xy 370.075173 -6.134658) (xy 370.090929 -6.218948) (xy 370.098841 -6.304331)
			(xy 370.099336 -6.347206) (xy 370.098841 -6.390081) (xy 370.090929 -6.475464) (xy 370.075173 -6.559754)
			(xy 370.051706 -6.64223) (xy 370.02073 -6.722189) (xy 369.982508 -6.798949) (xy 369.937367 -6.871855)
			(xy 369.885691 -6.940284) (xy 369.827922 -7.003654) (xy 369.764552 -7.061423) (xy 369.696123 -7.113099)
			(xy 369.623217 -7.15824) (xy 369.546457 -7.196462) (xy 369.466498 -7.227438) (xy 369.384022 -7.250905)
			(xy 369.299732 -7.266661) (xy 369.214349 -7.274573) (xy 369.128599 -7.274573) (xy 369.043216 -7.266661)
			(xy 368.958926 -7.250905) (xy 368.87645 -7.227438) (xy 368.796491 -7.196462) (xy 368.719731 -7.15824)
			(xy 368.646825 -7.113099) (xy 368.578396 -7.061423) (xy 368.515026 -7.003654) (xy 368.457257 -6.940284)
			(xy 368.405581 -6.871855) (xy 368.36044 -6.798949) (xy 368.322218 -6.722189) (xy 368.291242 -6.64223)
			(xy 368.267775 -6.559754) (xy 368.252019 -6.475464) (xy 368.244107 -6.390081) (xy 363.748841 -6.390081)
			(xy 363.740929 -6.475464) (xy 363.725173 -6.559754) (xy 363.701706 -6.64223) (xy 363.67073 -6.722189)
			(xy 363.632508 -6.798949) (xy 363.587367 -6.871855) (xy 363.535691 -6.940284) (xy 363.477922 -7.003654)
			(xy 363.414552 -7.061423) (xy 363.346123 -7.113099) (xy 363.273217 -7.15824) (xy 363.196457 -7.196462)
			(xy 363.116498 -7.227438) (xy 363.034022 -7.250905) (xy 362.949732 -7.266661) (xy 362.864349 -7.274573)
			(xy 362.778599 -7.274573) (xy 362.693216 -7.266661) (xy 362.608926 -7.250905) (xy 362.52645 -7.227438)
			(xy 362.446491 -7.196462) (xy 362.369731 -7.15824) (xy 362.296825 -7.113099) (xy 362.228396 -7.061423)
			(xy 362.165026 -7.003654) (xy 362.107257 -6.940284) (xy 362.055581 -6.871855) (xy 362.01044 -6.798949)
			(xy 361.972218 -6.722189) (xy 361.941242 -6.64223) (xy 361.917775 -6.559754) (xy 361.902019 -6.475464)
			(xy 361.894107 -6.390081) (xy 319.360055 -6.390081) (xy 319.352143 -6.475464) (xy 319.336387 -6.559754)
			(xy 319.31292 -6.64223) (xy 319.281944 -6.722189) (xy 319.243722 -6.798949) (xy 319.198581 -6.871855)
			(xy 319.146905 -6.940284) (xy 319.089136 -7.003654) (xy 319.025766 -7.061423) (xy 318.957337 -7.113099)
			(xy 318.884431 -7.15824) (xy 318.807671 -7.196462) (xy 318.727712 -7.227438) (xy 318.645236 -7.250905)
			(xy 318.560946 -7.266661) (xy 318.475563 -7.274573) (xy 318.389813 -7.274573) (xy 318.30443 -7.266661)
			(xy 318.22014 -7.250905) (xy 318.137664 -7.227438) (xy 318.057705 -7.196462) (xy 317.980945 -7.15824)
			(xy 317.908039 -7.113099) (xy 317.83961 -7.061423) (xy 317.77624 -7.003654) (xy 317.718471 -6.940284)
			(xy 317.666795 -6.871855) (xy 317.621654 -6.798949) (xy 317.583432 -6.722189) (xy 317.552456 -6.64223)
			(xy 317.528989 -6.559754) (xy 317.513233 -6.475464) (xy 317.505321 -6.390081) (xy 313.010055 -6.390081)
			(xy 313.002143 -6.475464) (xy 312.986387 -6.559754) (xy 312.96292 -6.64223) (xy 312.931944 -6.722189)
			(xy 312.893722 -6.798949) (xy 312.848581 -6.871855) (xy 312.796905 -6.940284) (xy 312.739136 -7.003654)
			(xy 312.675766 -7.061423) (xy 312.607337 -7.113099) (xy 312.534431 -7.15824) (xy 312.457671 -7.196462)
			(xy 312.377712 -7.227438) (xy 312.295236 -7.250905) (xy 312.210946 -7.266661) (xy 312.125563 -7.274573)
			(xy 312.039813 -7.274573) (xy 311.95443 -7.266661) (xy 311.87014 -7.250905) (xy 311.787664 -7.227438)
			(xy 311.707705 -7.196462) (xy 311.630945 -7.15824) (xy 311.558039 -7.113099) (xy 311.48961 -7.061423)
			(xy 311.42624 -7.003654) (xy 311.368471 -6.940284) (xy 311.316795 -6.871855) (xy 311.271654 -6.798949)
			(xy 311.233432 -6.722189) (xy 311.202456 -6.64223) (xy 311.178989 -6.559754) (xy 311.163233 -6.475464)
			(xy 311.155321 -6.390081) (xy 304.348655 -6.390081) (xy 304.340743 -6.475464) (xy 304.324987 -6.559754)
			(xy 304.30152 -6.64223) (xy 304.270544 -6.722189) (xy 304.232322 -6.798949) (xy 304.187181 -6.871855)
			(xy 304.135505 -6.940284) (xy 304.077736 -7.003654) (xy 304.014366 -7.061423) (xy 303.945937 -7.113099)
			(xy 303.873031 -7.15824) (xy 303.796271 -7.196462) (xy 303.716312 -7.227438) (xy 303.633836 -7.250905)
			(xy 303.549546 -7.266661) (xy 303.464163 -7.274573) (xy 303.378413 -7.274573) (xy 303.29303 -7.266661)
			(xy 303.20874 -7.250905) (xy 303.126264 -7.227438) (xy 303.046305 -7.196462) (xy 302.969545 -7.15824)
			(xy 302.896639 -7.113099) (xy 302.82821 -7.061423) (xy 302.76484 -7.003654) (xy 302.707071 -6.940284)
			(xy 302.655395 -6.871855) (xy 302.610254 -6.798949) (xy 302.572032 -6.722189) (xy 302.541056 -6.64223)
			(xy 302.517589 -6.559754) (xy 302.501833 -6.475464) (xy 302.493921 -6.390081) (xy 297.998655 -6.390081)
			(xy 297.990743 -6.475464) (xy 297.974987 -6.559754) (xy 297.95152 -6.64223) (xy 297.920544 -6.722189)
			(xy 297.882322 -6.798949) (xy 297.837181 -6.871855) (xy 297.785505 -6.940284) (xy 297.727736 -7.003654)
			(xy 297.664366 -7.061423) (xy 297.595937 -7.113099) (xy 297.523031 -7.15824) (xy 297.446271 -7.196462)
			(xy 297.366312 -7.227438) (xy 297.283836 -7.250905) (xy 297.199546 -7.266661) (xy 297.114163 -7.274573)
			(xy 297.028413 -7.274573) (xy 296.94303 -7.266661) (xy 296.85874 -7.250905) (xy 296.776264 -7.227438)
			(xy 296.696305 -7.196462) (xy 296.619545 -7.15824) (xy 296.546639 -7.113099) (xy 296.47821 -7.061423)
			(xy 296.41484 -7.003654) (xy 296.357071 -6.940284) (xy 296.305395 -6.871855) (xy 296.260254 -6.798949)
			(xy 296.222032 -6.722189) (xy 296.191056 -6.64223) (xy 296.167589 -6.559754) (xy 296.151833 -6.475464)
			(xy 296.143921 -6.390081) (xy 216.865975 -6.390081) (xy 216.858063 -6.475464) (xy 216.842307 -6.559754)
			(xy 216.81884 -6.64223) (xy 216.787864 -6.722189) (xy 216.749642 -6.798949) (xy 216.704501 -6.871855)
			(xy 216.652825 -6.940284) (xy 216.595056 -7.003654) (xy 216.531686 -7.061423) (xy 216.463257 -7.113099)
			(xy 216.390351 -7.15824) (xy 216.313591 -7.196462) (xy 216.233632 -7.227438) (xy 216.151156 -7.250905)
			(xy 216.066866 -7.266661) (xy 215.981483 -7.274573) (xy 215.895733 -7.274573) (xy 215.81035 -7.266661)
			(xy 215.72606 -7.250905) (xy 215.643584 -7.227438) (xy 215.563625 -7.196462) (xy 215.486865 -7.15824)
			(xy 215.413959 -7.113099) (xy 215.34553 -7.061423) (xy 215.28216 -7.003654) (xy 215.224391 -6.940284)
			(xy 215.172715 -6.871855) (xy 215.127574 -6.798949) (xy 215.089352 -6.722189) (xy 215.058376 -6.64223)
			(xy 215.034909 -6.559754) (xy 215.019153 -6.475464) (xy 215.011241 -6.390081) (xy 210.515975 -6.390081)
			(xy 210.508063 -6.475464) (xy 210.492307 -6.559754) (xy 210.46884 -6.64223) (xy 210.437864 -6.722189)
			(xy 210.399642 -6.798949) (xy 210.354501 -6.871855) (xy 210.302825 -6.940284) (xy 210.245056 -7.003654)
			(xy 210.181686 -7.061423) (xy 210.113257 -7.113099) (xy 210.040351 -7.15824) (xy 209.963591 -7.196462)
			(xy 209.883632 -7.227438) (xy 209.801156 -7.250905) (xy 209.716866 -7.266661) (xy 209.631483 -7.274573)
			(xy 209.545733 -7.274573) (xy 209.46035 -7.266661) (xy 209.37606 -7.250905) (xy 209.293584 -7.227438)
			(xy 209.213625 -7.196462) (xy 209.136865 -7.15824) (xy 209.063959 -7.113099) (xy 208.99553 -7.061423)
			(xy 208.93216 -7.003654) (xy 208.874391 -6.940284) (xy 208.822715 -6.871855) (xy 208.777574 -6.798949)
			(xy 208.739352 -6.722189) (xy 208.708376 -6.64223) (xy 208.684909 -6.559754) (xy 208.669153 -6.475464)
			(xy 208.661241 -6.390081) (xy 197.210934 -6.390081) (xy 197.210934 -7.78002) (xy 197.211456 -7.835788)
			(xy 197.219793 -7.947013) (xy 197.236418 -8.057304) (xy 197.261239 -8.166044) (xy 197.294116 -8.272625)
			(xy 197.334866 -8.376451) (xy 197.383261 -8.476941) (xy 197.439031 -8.573534) (xy 197.501863 -8.66569)
			(xy 197.571406 -8.752892) (xy 197.647271 -8.834653) (xy 197.729034 -8.910516) (xy 197.816238 -8.980057)
			(xy 197.908394 -9.042887) (xy 198.004989 -9.098654) (xy 198.10548 -9.147047) (xy 198.209307 -9.187795)
			(xy 198.315889 -9.22067) (xy 198.42463 -9.245488) (xy 198.534921 -9.262111) (xy 198.646146 -9.270445)
			(xy 198.701914 -9.271) (xy 223.300036 -9.271) (xy 223.370417 -9.271495) (xy 223.510959 -9.279389)
			(xy 223.650836 -9.295152) (xy 223.78961 -9.318732) (xy 223.926844 -9.350057) (xy 224.062105 -9.389027)
			(xy 224.194968 -9.435519) (xy 224.325015 -9.489388) (xy 224.451838 -9.550465) (xy 224.575036 -9.618556)
			(xy 224.694222 -9.693447) (xy 224.809022 -9.774904) (xy 224.919074 -9.862669) (xy 225.024032 -9.956467)
			(xy 225.123566 -10.056003) (xy 225.217361 -10.160962) (xy 225.305125 -10.271016) (xy 225.386579 -10.385818)
			(xy 225.461469 -10.505006) (xy 225.529557 -10.628205) (xy 225.590631 -10.755029) (xy 225.644498 -10.885077)
			(xy 225.690988 -11.017941) (xy 225.729955 -11.153203) (xy 225.761277 -11.290437) (xy 225.784855 -11.429211)
			(xy 225.800615 -11.569089) (xy 225.808507 -11.709631) (xy 225.809048 -11.780012) (xy 225.809048 -33.120076)
			(xy 225.809549 -33.152224) (xy 225.817939 -33.21597) (xy 225.834578 -33.278076) (xy 225.859182 -33.337478)
			(xy 225.891329 -33.39316) (xy 225.93047 -33.44417) (xy 225.975934 -33.489634) (xy 226.026945 -33.528774)
			(xy 226.082627 -33.560921) (xy 226.14203 -33.585524) (xy 226.204136 -33.602162) (xy 226.267882 -33.610551)
			(xy 226.30003 -33.611058)
		)
		(stroke
			(width 0)
			(type solid)
		)
		(fill yes)
		(layer "In14.Cu")
		(net "DELTA_L_GND_1")
	)
	(gr_poly
		(pts
			(xy 194.445128 -441.480956) (xy 194.455142 -441.480531) (xy 194.473642 -441.472854) (xy 194.487795 -441.458682)
			(xy 194.495445 -441.440171) (xy 194.495928 -441.430156) (xy 194.495928 -441.17006) (xy 194.49641 -441.126022)
			(xy 194.50409 -441.03828) (xy 194.519387 -440.951542) (xy 194.542185 -440.866466) (xy 194.572311 -440.783702)
			(xy 194.609536 -440.703878) (xy 194.653576 -440.627602) (xy 194.704095 -440.555454) (xy 194.760711 -440.487984)
			(xy 194.822991 -440.425704) (xy 194.890462 -440.369089) (xy 194.96261 -440.31857) (xy 195.038887 -440.274531)
			(xy 195.118711 -440.237308) (xy 195.201476 -440.207182) (xy 195.286551 -440.184385) (xy 195.37329 -440.169088)
			(xy 195.461032 -440.16141) (xy 195.50507 -440.160918) (xy 276.314916 -440.160918) (xy 276.358955 -440.161399)
			(xy 276.446699 -440.169077) (xy 276.533439 -440.184372) (xy 276.618516 -440.207169) (xy 276.701283 -440.237294)
			(xy 276.781109 -440.274518) (xy 276.857388 -440.318557) (xy 276.929538 -440.369076) (xy 276.99701 -440.425692)
			(xy 277.059292 -440.487972) (xy 277.115909 -440.555443) (xy 277.16643 -440.627592) (xy 277.210471 -440.703869)
			(xy 277.247697 -440.783695) (xy 277.277823 -440.866461) (xy 277.300622 -440.951538) (xy 277.31592 -441.038278)
			(xy 277.3236 -441.126021) (xy 277.324058 -441.17006) (xy 277.324058 -441.430156) (xy 277.324469 -441.440186)
			(xy 277.33213 -441.458725) (xy 277.346302 -441.472922) (xy 277.364828 -441.480614) (xy 277.374858 -441.480956)
			(xy 463.300064 -441.480956) (xy 463.355834 -441.480449) (xy 463.467062 -441.472116) (xy 463.577357 -441.455494)
			(xy 463.686101 -441.430676) (xy 463.792686 -441.397801) (xy 463.896517 -441.357052) (xy 463.997011 -441.308658)
			(xy 464.093608 -441.252889) (xy 464.185768 -441.190057) (xy 464.272974 -441.120513) (xy 464.354739 -441.044647)
			(xy 464.430606 -440.962883) (xy 464.50015 -440.875677) (xy 464.562982 -440.783519) (xy 464.618752 -440.686922)
			(xy 464.667147 -440.586428) (xy 464.707897 -440.482598) (xy 464.740773 -440.376013) (xy 464.765592 -440.267269)
			(xy 464.782215 -440.156974) (xy 464.790548 -440.045746) (xy 464.791044 -439.989976) (xy 464.791044 -409.528264)
			(xy 464.791546 -409.457891) (xy 464.799454 -409.317366) (xy 464.815227 -409.177505) (xy 464.838815 -409.038749)
			(xy 464.870143 -408.901532) (xy 464.909113 -408.766288) (xy 464.955604 -408.633441) (xy 465.009467 -408.503408)
			(xy 465.070535 -408.376599) (xy 465.138615 -408.253413) (xy 465.213493 -408.134236) (xy 465.294933 -408.019444)
			(xy 465.38268 -407.909398) (xy 465.476458 -407.804443) (xy 465.525866 -407.754328) (xy 467.354412 -405.925782)
			(xy 467.391703 -405.887819) (xy 467.461396 -405.807388) (xy 467.525176 -405.722192) (xy 467.582717 -405.632663)
			(xy 467.633725 -405.539259) (xy 467.677942 -405.442454) (xy 467.715142 -405.342742) (xy 467.745135 -405.240631)
			(xy 467.767768 -405.136641) (xy 467.782928 -405.031301) (xy 467.790535 -404.925148) (xy 467.791038 -404.871936)
			(xy 467.791038 -82.82813) (xy 467.791541 -82.757757) (xy 467.799451 -82.617233) (xy 467.815226 -82.477373)
			(xy 467.838815 -82.338618) (xy 467.870145 -82.201402) (xy 467.909116 -82.066159) (xy 467.955608 -81.933313)
			(xy 468.009473 -81.803282) (xy 468.070541 -81.676474) (xy 468.138622 -81.553289) (xy 468.213501 -81.434114)
			(xy 468.294942 -81.319323) (xy 468.382689 -81.209278) (xy 468.476467 -81.104324) (xy 468.52586 -81.054194)
			(xy 470.854278 -78.725776) (xy 470.891569 -78.687813) (xy 470.961264 -78.607383) (xy 471.025045 -78.522187)
			(xy 471.082586 -78.432659) (xy 471.133596 -78.339255) (xy 471.177813 -78.24245) (xy 471.215013 -78.142738)
			(xy 471.245007 -78.040626) (xy 471.267641 -77.936636) (xy 471.2828 -77.831296) (xy 471.290407 -77.725143)
			(xy 471.290904 -77.67193) (xy 471.290904 -13.780008) (xy 471.290383 -13.724238) (xy 471.282048 -13.613011)
			(xy 471.265425 -13.502718) (xy 471.240606 -13.393975) (xy 471.20773 -13.287391) (xy 471.166981 -13.183562)
			(xy 471.118587 -13.083068) (xy 471.062818 -12.986472) (xy 470.999987 -12.894314) (xy 470.930444 -12.807108)
			(xy 470.854579 -12.725344) (xy 470.772816 -12.649477) (xy 470.685612 -12.579932) (xy 470.593455 -12.517099)
			(xy 470.49686 -12.461328) (xy 470.396367 -12.412932) (xy 470.292539 -12.372181) (xy 470.185956 -12.339303)
			(xy 470.077214 -12.314481) (xy 469.966921 -12.297855) (xy 469.855694 -12.289518) (xy 469.799924 -12.289028)
			(xy 458.20203 -12.289028) (xy 458.131647 -12.288544) (xy 457.991102 -12.280653) (xy 457.85122 -12.264894)
			(xy 457.712443 -12.241316) (xy 457.575205 -12.209994) (xy 457.43994 -12.171027) (xy 457.307072 -12.124536)
			(xy 457.177021 -12.070668) (xy 457.050194 -12.009593) (xy 456.926991 -11.941503) (xy 456.8078 -11.866612)
			(xy 456.692996 -11.785156) (xy 456.582939 -11.69739) (xy 456.477977 -11.603592) (xy 456.378439 -11.504056)
			(xy 456.284639 -11.399096) (xy 456.196872 -11.289041) (xy 456.115413 -11.174238) (xy 456.04052 -11.055048)
			(xy 455.972428 -10.931847) (xy 455.911351 -10.805021) (xy 455.857481 -10.674971) (xy 455.810987 -10.542104)
			(xy 455.772017 -10.406839) (xy 455.740693 -10.269603) (xy 455.717113 -10.130825) (xy 455.701351 -9.990944)
			(xy 455.693457 -9.850399) (xy 455.693018 -9.780016) (xy 455.693018 -0.559816) (xy 455.692533 -0.549805)
			(xy 455.684877 -0.531304) (xy 455.670724 -0.517142) (xy 455.652229 -0.509474) (xy 455.642218 -0.509016)
			(xy 388.161784 -0.509016) (xy 388.15178 -0.509507) (xy 388.133296 -0.51717) (xy 388.119152 -0.531323)
			(xy 388.111501 -0.549811) (xy 388.110984 -0.559816) (xy 388.110984 -5.169916) (xy 388.849877 -5.169916)
			(xy 388.853883 -5.081985) (xy 388.865869 -4.994782) (xy 388.885734 -4.90903) (xy 388.913316 -4.82544)
			(xy 388.948384 -4.744705) (xy 388.990649 -4.667493) (xy 389.03976 -4.594444) (xy 389.09531 -4.526164)
			(xy 389.156839 -4.463218) (xy 389.223837 -4.406129) (xy 389.295748 -4.355368) (xy 389.371978 -4.311356)
			(xy 389.451894 -4.274459) (xy 389.534835 -4.244982) (xy 389.620112 -4.22317) (xy 389.707019 -4.209202)
			(xy 389.794837 -4.203195) (xy 389.882836 -4.205199) (xy 389.970289 -4.215196) (xy 390.056471 -4.233105)
			(xy 390.140667 -4.258777) (xy 390.22218 -4.291998) (xy 390.300334 -4.332494) (xy 390.374481 -4.379929)
			(xy 390.444008 -4.433911) (xy 390.508339 -4.493991) (xy 390.566939 -4.559672) (xy 390.619323 -4.63041)
			(xy 390.665059 -4.705618) (xy 390.703765 -4.784674) (xy 390.735123 -4.866921) (xy 390.758871 -4.95168)
			(xy 390.766051 -4.990667) (xy 394.939038 -4.990667) (xy 394.939038 -4.936133) (xy 394.946799 -4.882155)
			(xy 394.962162 -4.82983) (xy 394.984815 -4.780224) (xy 395.014296 -4.734346) (xy 395.050007 -4.693131)
			(xy 395.091219 -4.657417) (xy 395.137094 -4.627931) (xy 395.186698 -4.605274) (xy 395.239021 -4.589906)
			(xy 395.292999 -4.582141) (xy 395.320266 -4.581652) (xy 396.183866 -4.581652) (xy 396.21114 -4.582085)
			(xy 396.265132 -4.589844) (xy 396.317471 -4.605208) (xy 396.36709 -4.627864) (xy 396.41298 -4.657352)
			(xy 396.454205 -4.693071) (xy 396.489928 -4.734293) (xy 396.51942 -4.78018) (xy 396.542081 -4.829797)
			(xy 396.557449 -4.882135) (xy 396.565212 -4.936126) (xy 396.565212 -4.99067) (xy 398.538915 -4.99067)
			(xy 398.538915 -4.93613) (xy 398.546678 -4.882144) (xy 398.562044 -4.829813) (xy 398.584701 -4.780201)
			(xy 398.614188 -4.734318) (xy 398.649905 -4.6931) (xy 398.691125 -4.657383) (xy 398.737008 -4.627897)
			(xy 398.78662 -4.605241) (xy 398.838952 -4.589876) (xy 398.892938 -4.582115) (xy 398.920208 -4.581652)
			(xy 399.783808 -4.581652) (xy 399.811078 -4.582111) (xy 399.865063 -4.589874) (xy 399.917393 -4.60524)
			(xy 399.967004 -4.627898) (xy 400.012886 -4.657385) (xy 400.054104 -4.693102) (xy 400.08982 -4.734321)
			(xy 400.119306 -4.780203) (xy 400.141962 -4.829814) (xy 400.157328 -4.882145) (xy 400.16509 -4.93613)
			(xy 400.16509 -4.990666) (xy 402.138938 -4.990666) (xy 402.138938 -4.936134) (xy 402.146698 -4.882157)
			(xy 402.162061 -4.829833) (xy 402.184712 -4.780228) (xy 402.214192 -4.734351) (xy 402.249901 -4.693136)
			(xy 402.291111 -4.657422) (xy 402.336984 -4.627936) (xy 402.386586 -4.605278) (xy 402.438908 -4.589909)
			(xy 402.492884 -4.582142) (xy 402.52015 -4.581652) (xy 403.38375 -4.581652) (xy 403.411024 -4.582084)
			(xy 403.465019 -4.589841) (xy 403.517359 -4.605203) (xy 403.56698 -4.627859) (xy 403.612872 -4.657346)
			(xy 403.6541 -4.693065) (xy 403.689824 -4.734288) (xy 403.719317 -4.780176) (xy 403.741979 -4.829794)
			(xy 403.757349 -4.882132) (xy 403.765112 -4.936126) (xy 403.765112 -4.990672) (xy 405.739016 -4.990672)
			(xy 405.739016 -4.936128) (xy 405.746779 -4.882139) (xy 405.762147 -4.829805) (xy 405.784807 -4.78019)
			(xy 405.814298 -4.734306) (xy 405.850019 -4.693086) (xy 405.891243 -4.65737) (xy 405.937131 -4.627885)
			(xy 405.986748 -4.605231) (xy 406.039084 -4.589869) (xy 406.093074 -4.582112) (xy 406.120346 -4.581652)
			(xy 406.983946 -4.581652) (xy 407.011214 -4.582114) (xy 407.065195 -4.589881) (xy 407.117521 -4.605251)
			(xy 407.167127 -4.62791) (xy 407.213004 -4.657399) (xy 407.254217 -4.693115) (xy 407.289929 -4.734333)
			(xy 407.319412 -4.780213) (xy 407.342065 -4.829822) (xy 407.357429 -4.88215) (xy 407.36519 -4.936132)
			(xy 407.36519 -4.990668) (xy 407.36519 -4.99067) (xy 414.849015 -4.99067) (xy 414.849015 -4.93613)
			(xy 414.856778 -4.882144) (xy 414.872144 -4.829812) (xy 414.894801 -4.7802) (xy 414.924289 -4.734318)
			(xy 414.960006 -4.693099) (xy 415.001226 -4.657383) (xy 415.047109 -4.627896) (xy 415.096722 -4.60524)
			(xy 415.149054 -4.589875) (xy 415.20304 -4.582115) (xy 415.23031 -4.581652) (xy 416.09391 -4.581652)
			(xy 416.12118 -4.582111) (xy 416.175164 -4.589874) (xy 416.227495 -4.605241) (xy 416.277105 -4.627899)
			(xy 416.322987 -4.657386) (xy 416.364205 -4.693102) (xy 416.39992 -4.734321) (xy 416.429406 -4.780203)
			(xy 416.452062 -4.829815) (xy 416.467428 -4.882145) (xy 416.47519 -4.93613) (xy 416.47519 -4.990666)
			(xy 418.449038 -4.990666) (xy 418.449038 -4.936134) (xy 418.456798 -4.882156) (xy 418.472161 -4.829833)
			(xy 418.494813 -4.780227) (xy 418.524293 -4.734351) (xy 418.560002 -4.693136) (xy 418.601212 -4.657422)
			(xy 418.647085 -4.627936) (xy 418.696688 -4.605278) (xy 418.749009 -4.589909) (xy 418.802986 -4.582142)
			(xy 418.830252 -4.581652) (xy 419.693852 -4.581652) (xy 419.721126 -4.582084) (xy 419.77512 -4.589841)
			(xy 419.827461 -4.605204) (xy 419.877082 -4.627859) (xy 419.922973 -4.657347) (xy 419.9642 -4.693066)
			(xy 419.999924 -4.734288) (xy 420.029418 -4.780176) (xy 420.052079 -4.829794) (xy 420.067449 -4.882133)
			(xy 420.075212 -4.936126) (xy 420.075212 -4.990672) (xy 426.059016 -4.990672) (xy 426.059016 -4.936128)
			(xy 426.066779 -4.882139) (xy 426.082147 -4.829805) (xy 426.104807 -4.78019) (xy 426.134298 -4.734306)
			(xy 426.170019 -4.693086) (xy 426.211243 -4.65737) (xy 426.257131 -4.627885) (xy 426.306748 -4.605231)
			(xy 426.359084 -4.589869) (xy 426.413074 -4.582112) (xy 426.440346 -4.581652) (xy 427.303946 -4.581652)
			(xy 427.331214 -4.582114) (xy 427.385195 -4.589881) (xy 427.437521 -4.605251) (xy 427.487127 -4.62791)
			(xy 427.533004 -4.657399) (xy 427.574217 -4.693115) (xy 427.609929 -4.734333) (xy 427.639412 -4.780213)
			(xy 427.662065 -4.829822) (xy 427.677429 -4.88215) (xy 427.68519 -4.936132) (xy 427.68519 -4.990668)
			(xy 429.659038 -4.990668) (xy 429.659038 -4.936132) (xy 429.666799 -4.882152) (xy 429.682164 -4.829825)
			(xy 429.704818 -4.780217) (xy 429.734302 -4.734339) (xy 429.770014 -4.693123) (xy 429.811229 -4.657409)
			(xy 429.857107 -4.627924) (xy 429.906714 -4.605268) (xy 429.95904 -4.589902) (xy 430.01302 -4.582139)
			(xy 430.040288 -4.581652) (xy 430.903888 -4.581652) (xy 430.931161 -4.582087) (xy 430.985151 -4.589848)
			(xy 431.037487 -4.605214) (xy 431.087103 -4.627871) (xy 431.13299 -4.65736) (xy 431.174213 -4.693078)
			(xy 431.209933 -4.7343) (xy 431.239423 -4.780186) (xy 431.262082 -4.829802) (xy 431.27745 -4.882138)
			(xy 431.285212 -4.936127) (xy 431.285212 -4.990673) (xy 431.27745 -5.044662) (xy 431.262082 -5.096998)
			(xy 431.239423 -5.146614) (xy 431.209933 -5.1925) (xy 431.174213 -5.233722) (xy 431.13299 -5.26944)
			(xy 431.087103 -5.298929) (xy 431.037487 -5.321586) (xy 430.985151 -5.336952) (xy 430.931161 -5.344713)
			(xy 430.903888 -5.345176) (xy 430.040288 -5.345176) (xy 430.01302 -5.344661) (xy 429.95904 -5.336898)
			(xy 429.906714 -5.321532) (xy 429.857107 -5.298876) (xy 429.811229 -5.269391) (xy 429.770014 -5.233677)
			(xy 429.734302 -5.192461) (xy 429.704818 -5.146583) (xy 429.682164 -5.096975) (xy 429.666799 -5.044648)
			(xy 429.659038 -4.990668) (xy 427.68519 -4.990668) (xy 427.677429 -5.04465) (xy 427.662065 -5.096978)
			(xy 427.639412 -5.146587) (xy 427.609929 -5.192467) (xy 427.574217 -5.233685) (xy 427.533004 -5.269401)
			(xy 427.487127 -5.29889) (xy 427.437521 -5.321549) (xy 427.385195 -5.336919) (xy 427.331214 -5.344686)
			(xy 427.303946 -5.345176) (xy 426.440346 -5.345176) (xy 426.413074 -5.344688) (xy 426.359084 -5.336931)
			(xy 426.306748 -5.321569) (xy 426.257131 -5.298915) (xy 426.211243 -5.26943) (xy 426.170019 -5.233714)
			(xy 426.134298 -5.192494) (xy 426.104807 -5.14661) (xy 426.082147 -5.096995) (xy 426.066779 -5.044661)
			(xy 426.059016 -4.990672) (xy 420.075212 -4.990672) (xy 420.075212 -4.990674) (xy 420.067449 -5.044667)
			(xy 420.052079 -5.097006) (xy 420.029418 -5.146624) (xy 419.999924 -5.192512) (xy 419.9642 -5.233734)
			(xy 419.922973 -5.269453) (xy 419.877082 -5.298941) (xy 419.827461 -5.321596) (xy 419.77512 -5.336959)
			(xy 419.721126 -5.344716) (xy 419.693852 -5.345176) (xy 418.830252 -5.345176) (xy 418.802986 -5.344658)
			(xy 418.749009 -5.336891) (xy 418.696688 -5.321522) (xy 418.647085 -5.298864) (xy 418.601212 -5.269378)
			(xy 418.560002 -5.233664) (xy 418.524293 -5.192449) (xy 418.494813 -5.146573) (xy 418.472161 -5.096967)
			(xy 418.456798 -5.044644) (xy 418.449038 -4.990666) (xy 416.47519 -4.990666) (xy 416.47519 -4.99067)
			(xy 416.467428 -5.044655) (xy 416.452062 -5.096985) (xy 416.429406 -5.146597) (xy 416.39992 -5.192479)
			(xy 416.364205 -5.233698) (xy 416.322987 -5.269414) (xy 416.277105 -5.298901) (xy 416.227495 -5.321559)
			(xy 416.175164 -5.336926) (xy 416.12118 -5.344689) (xy 416.09391 -5.345176) (xy 415.23031 -5.345176)
			(xy 415.20304 -5.344685) (xy 415.149054 -5.336925) (xy 415.096722 -5.32156) (xy 415.047109 -5.298904)
			(xy 415.001226 -5.269417) (xy 414.960006 -5.233701) (xy 414.924289 -5.192482) (xy 414.894801 -5.1466)
			(xy 414.872144 -5.096988) (xy 414.856778 -5.044656) (xy 414.849015 -4.99067) (xy 407.36519 -4.99067)
			(xy 407.357429 -5.04465) (xy 407.342065 -5.096978) (xy 407.319412 -5.146587) (xy 407.289929 -5.192467)
			(xy 407.254217 -5.233685) (xy 407.213004 -5.269401) (xy 407.167127 -5.29889) (xy 407.117521 -5.321549)
			(xy 407.065195 -5.336919) (xy 407.011214 -5.344686) (xy 406.983946 -5.345176) (xy 406.120346 -5.345176)
			(xy 406.093074 -5.344688) (xy 406.039084 -5.336931) (xy 405.986748 -5.321569) (xy 405.937131 -5.298915)
			(xy 405.891243 -5.26943) (xy 405.850019 -5.233714) (xy 405.814298 -5.192494) (xy 405.784807 -5.14661)
			(xy 405.762147 -5.096995) (xy 405.746779 -5.044661) (xy 405.739016 -4.990672) (xy 403.765112 -4.990672)
			(xy 403.765112 -4.990674) (xy 403.757349 -5.044668) (xy 403.741979 -5.097006) (xy 403.719317 -5.146624)
			(xy 403.689824 -5.192512) (xy 403.6541 -5.233735) (xy 403.612872 -5.269454) (xy 403.56698 -5.298941)
			(xy 403.517359 -5.321597) (xy 403.465019 -5.336959) (xy 403.411024 -5.344716) (xy 403.38375 -5.345176)
			(xy 402.52015 -5.345176) (xy 402.492884 -5.344658) (xy 402.438908 -5.336891) (xy 402.386586 -5.321522)
			(xy 402.336984 -5.298864) (xy 402.291111 -5.269378) (xy 402.249901 -5.233664) (xy 402.214192 -5.192449)
			(xy 402.184712 -5.146572) (xy 402.162061 -5.096967) (xy 402.146698 -5.044643) (xy 402.138938 -4.990666)
			(xy 400.16509 -4.990666) (xy 400.16509 -4.99067) (xy 400.157328 -5.044655) (xy 400.141962 -5.096986)
			(xy 400.119306 -5.146597) (xy 400.08982 -5.192479) (xy 400.054104 -5.233698) (xy 400.012886 -5.269415)
			(xy 399.967004 -5.298902) (xy 399.917393 -5.32156) (xy 399.865063 -5.336926) (xy 399.811078 -5.344689)
			(xy 399.783808 -5.345176) (xy 398.920208 -5.345176) (xy 398.892938 -5.344685) (xy 398.838952 -5.336924)
			(xy 398.78662 -5.321559) (xy 398.737008 -5.298903) (xy 398.691125 -5.269417) (xy 398.649905 -5.2337)
			(xy 398.614188 -5.192482) (xy 398.584701 -5.146599) (xy 398.562044 -5.096987) (xy 398.546678 -5.044656)
			(xy 398.538915 -4.99067) (xy 396.565212 -4.99067) (xy 396.565212 -4.990674) (xy 396.557449 -5.044665)
			(xy 396.542081 -5.097003) (xy 396.51942 -5.14662) (xy 396.489928 -5.192507) (xy 396.454205 -5.233729)
			(xy 396.41298 -5.269448) (xy 396.36709 -5.298936) (xy 396.317471 -5.321592) (xy 396.265132 -5.336956)
			(xy 396.21114 -5.344715) (xy 396.183866 -5.345176) (xy 395.320266 -5.345176) (xy 395.292999 -5.344659)
			(xy 395.239021 -5.336894) (xy 395.186698 -5.321526) (xy 395.137094 -5.298869) (xy 395.091219 -5.269383)
			(xy 395.050007 -5.233669) (xy 395.014296 -5.192454) (xy 394.984815 -5.146576) (xy 394.962162 -5.09697)
			(xy 394.946799 -5.044645) (xy 394.939038 -4.990667) (xy 390.766051 -4.990667) (xy 390.774813 -5.038247)
			(xy 390.782817 -5.125905) (xy 390.783318 -5.169916) (xy 390.782817 -5.213927) (xy 390.774813 -5.301585)
			(xy 390.758871 -5.388152) (xy 390.735123 -5.472911) (xy 390.703765 -5.555158) (xy 390.665059 -5.634214)
			(xy 390.619323 -5.709422) (xy 390.566939 -5.78016) (xy 390.508339 -5.845841) (xy 390.444008 -5.905921)
			(xy 390.374481 -5.959903) (xy 390.300334 -6.007338) (xy 390.22218 -6.047834) (xy 390.140667 -6.081055)
			(xy 390.056471 -6.106727) (xy 389.970289 -6.124636) (xy 389.882836 -6.134633) (xy 389.794837 -6.136637)
			(xy 389.707019 -6.13063) (xy 389.620112 -6.116662) (xy 389.534835 -6.09485) (xy 389.451894 -6.065373)
			(xy 389.371978 -6.028476) (xy 389.295748 -5.984464) (xy 389.223837 -5.933703) (xy 389.156839 -5.876614)
			(xy 389.09531 -5.813668) (xy 389.03976 -5.745388) (xy 388.990649 -5.672339) (xy 388.948384 -5.595127)
			(xy 388.913316 -5.514392) (xy 388.885734 -5.430802) (xy 388.865869 -5.34505) (xy 388.853883 -5.257847)
			(xy 388.849877 -5.169916) (xy 388.110984 -5.169916) (xy 388.110984 -6.169914) (xy 453.015103 -6.169914)
			(xy 453.019108 -6.082006) (xy 453.031091 -5.994826) (xy 453.050951 -5.909097) (xy 453.078526 -5.825529)
			(xy 453.113585 -5.744815) (xy 453.155838 -5.667623) (xy 453.204936 -5.594594) (xy 453.260472 -5.526332)
			(xy 453.321984 -5.463402) (xy 453.388965 -5.406328) (xy 453.460858 -5.35558) (xy 453.537067 -5.31158)
			(xy 453.616962 -5.274693) (xy 453.699881 -5.245224) (xy 453.785136 -5.223417) (xy 453.87202 -5.209453)
			(xy 453.959814 -5.203447) (xy 454.047791 -5.205451) (xy 454.135221 -5.215446) (xy 454.22138 -5.23335)
			(xy 454.305554 -5.259014) (xy 454.387045 -5.292227) (xy 454.465179 -5.332713) (xy 454.539307 -5.380135)
			(xy 454.608815 -5.434102) (xy 454.673129 -5.494167) (xy 454.731713 -5.559831) (xy 454.784084 -5.63055)
			(xy 454.829807 -5.705738) (xy 454.868504 -5.784773) (xy 454.899853 -5.866999) (xy 454.923595 -5.951735)
			(xy 454.939533 -6.038279) (xy 454.947535 -6.125914) (xy 454.948036 -6.169914) (xy 454.947535 -6.213914)
			(xy 454.939533 -6.301549) (xy 454.923595 -6.388093) (xy 454.899853 -6.472829) (xy 454.868504 -6.555055)
			(xy 454.829807 -6.63409) (xy 454.784084 -6.709278) (xy 454.731713 -6.779997) (xy 454.673129 -6.845661)
			(xy 454.608815 -6.905726) (xy 454.539307 -6.959693) (xy 454.465179 -7.007115) (xy 454.387045 -7.047601)
			(xy 454.305554 -7.080814) (xy 454.22138 -7.106478) (xy 454.135221 -7.124382) (xy 454.047791 -7.134377)
			(xy 453.959814 -7.136381) (xy 453.87202 -7.130375) (xy 453.785136 -7.116411) (xy 453.699881 -7.094604)
			(xy 453.616962 -7.065135) (xy 453.537067 -7.028248) (xy 453.460858 -6.984248) (xy 453.388965 -6.9335)
			(xy 453.321984 -6.876426) (xy 453.260472 -6.813496) (xy 453.204936 -6.745234) (xy 453.155838 -6.672205)
			(xy 453.113585 -6.595013) (xy 453.078526 -6.514299) (xy 453.050951 -6.430731) (xy 453.031091 -6.345002)
			(xy 453.019108 -6.257822) (xy 453.015103 -6.169914) (xy 388.110984 -6.169914) (xy 388.110984 -6.752472)
			(xy 393.134283 -6.752472) (xy 393.134283 -6.697928) (xy 393.142045 -6.643939) (xy 393.157412 -6.591604)
			(xy 393.18007 -6.541988) (xy 393.209559 -6.496103) (xy 393.245278 -6.454881) (xy 393.286499 -6.419161)
			(xy 393.332385 -6.389672) (xy 393.382 -6.367013) (xy 393.434335 -6.351646) (xy 393.488324 -6.343883)
			(xy 393.515596 -6.343396) (xy 394.379196 -6.343396) (xy 394.406464 -6.343943) (xy 394.460446 -6.351704)
			(xy 394.512773 -6.367068) (xy 394.562381 -6.389723) (xy 394.60826 -6.419207) (xy 394.649476 -6.454921)
			(xy 394.68519 -6.496136) (xy 394.714675 -6.542015) (xy 394.73733 -6.591623) (xy 394.752695 -6.643951)
			(xy 394.760457 -6.697932) (xy 394.760457 -6.752468) (xy 394.760456 -6.752476) (xy 396.73416 -6.752476)
			(xy 396.73416 -6.697924) (xy 396.741924 -6.643928) (xy 396.757294 -6.591587) (xy 396.779956 -6.541966)
			(xy 396.809451 -6.496075) (xy 396.845176 -6.454849) (xy 396.886405 -6.419128) (xy 396.932299 -6.389638)
			(xy 396.981922 -6.36698) (xy 397.034265 -6.351616) (xy 397.088262 -6.343857) (xy 397.115538 -6.343396)
			(xy 397.979138 -6.343396) (xy 398.006403 -6.343969) (xy 398.060376 -6.351734) (xy 398.112695 -6.367101)
			(xy 398.162295 -6.389757) (xy 398.208166 -6.419241) (xy 398.249375 -6.454952) (xy 398.285082 -6.496164)
			(xy 398.314561 -6.542038) (xy 398.337212 -6.59164) (xy 398.352574 -6.643961) (xy 398.360334 -6.697935)
			(xy 398.360334 -6.752465) (xy 398.360333 -6.752471) (xy 400.334182 -6.752471) (xy 400.334182 -6.697929)
			(xy 400.341944 -6.643941) (xy 400.35731 -6.591607) (xy 400.379968 -6.541993) (xy 400.409455 -6.496108)
			(xy 400.445172 -6.454886) (xy 400.486392 -6.419167) (xy 400.532275 -6.389677) (xy 400.581888 -6.367017)
			(xy 400.634221 -6.351649) (xy 400.688209 -6.343884) (xy 400.71548 -6.343396) (xy 401.57908 -6.343396)
			(xy 401.606349 -6.343942) (xy 401.660332 -6.351701) (xy 401.712661 -6.367064) (xy 401.762272 -6.389718)
			(xy 401.808153 -6.419202) (xy 401.849371 -6.454915) (xy 401.885086 -6.496131) (xy 401.914573 -6.542011)
			(xy 401.937229 -6.59162) (xy 401.952595 -6.643948) (xy 401.960357 -6.697931) (xy 401.960357 -6.752469)
			(xy 401.960357 -6.752471) (xy 403.934382 -6.752471) (xy 403.934382 -6.697929) (xy 403.942144 -6.643941)
			(xy 403.95751 -6.591608) (xy 403.980167 -6.541994) (xy 404.009654 -6.496109) (xy 404.045371 -6.454888)
			(xy 404.08659 -6.419168) (xy 404.132473 -6.389679) (xy 404.182085 -6.367019) (xy 404.234418 -6.351649)
			(xy 404.288405 -6.343884) (xy 404.315676 -6.343396) (xy 405.179276 -6.343396) (xy 405.206545 -6.343942)
			(xy 405.260529 -6.3517) (xy 405.312858 -6.367063) (xy 405.362469 -6.389716) (xy 405.408351 -6.4192)
			(xy 405.449569 -6.454914) (xy 405.485285 -6.49613) (xy 405.514772 -6.54201) (xy 405.537429 -6.591619)
			(xy 405.552795 -6.643948) (xy 405.560557 -6.697931) (xy 405.560557 -6.752469) (xy 405.560556 -6.752476)
			(xy 413.04426 -6.752476) (xy 413.04426 -6.697924) (xy 413.052024 -6.643928) (xy 413.067394 -6.591586)
			(xy 413.090057 -6.541965) (xy 413.119551 -6.496074) (xy 413.155277 -6.454849) (xy 413.196506 -6.419127)
			(xy 413.2424 -6.389638) (xy 413.292024 -6.36698) (xy 413.344367 -6.351615) (xy 413.398364 -6.343857)
			(xy 413.42564 -6.343396) (xy 414.28924 -6.343396) (xy 414.316504 -6.343969) (xy 414.370478 -6.351734)
			(xy 414.422797 -6.367102) (xy 414.472397 -6.389758) (xy 414.518267 -6.419241) (xy 414.559476 -6.454953)
			(xy 414.595183 -6.496165) (xy 414.624662 -6.542039) (xy 414.647312 -6.591641) (xy 414.662674 -6.643961)
			(xy 414.670434 -6.697935) (xy 414.670434 -6.752465) (xy 414.670433 -6.752472) (xy 416.644282 -6.752472)
			(xy 416.644282 -6.697928) (xy 416.652045 -6.64394) (xy 416.667411 -6.591607) (xy 416.690068 -6.541992)
			(xy 416.719555 -6.496107) (xy 416.755273 -6.454885) (xy 416.796493 -6.419166) (xy 416.842376 -6.389677)
			(xy 416.89199 -6.367017) (xy 416.944323 -6.351648) (xy 416.99831 -6.343884) (xy 417.025582 -6.343396)
			(xy 417.889182 -6.343396) (xy 417.916451 -6.343942) (xy 417.970434 -6.351701) (xy 418.022763 -6.367064)
			(xy 418.072373 -6.389718) (xy 418.118254 -6.419202) (xy 418.159471 -6.454916) (xy 418.195187 -6.496132)
			(xy 418.224673 -6.542011) (xy 418.247329 -6.59162) (xy 418.262695 -6.643949) (xy 418.270457 -6.697931)
			(xy 418.270457 -6.752469) (xy 418.270457 -6.752471) (xy 424.254382 -6.752471) (xy 424.254382 -6.697929)
			(xy 424.262144 -6.643941) (xy 424.27751 -6.591608) (xy 424.300167 -6.541994) (xy 424.329654 -6.496109)
			(xy 424.365371 -6.454888) (xy 424.40659 -6.419168) (xy 424.452473 -6.389679) (xy 424.502085 -6.367019)
			(xy 424.554418 -6.351649) (xy 424.608405 -6.343884) (xy 424.635676 -6.343396) (xy 425.499276 -6.343396)
			(xy 425.526545 -6.343942) (xy 425.580529 -6.3517) (xy 425.632858 -6.367063) (xy 425.682469 -6.389716)
			(xy 425.728351 -6.4192) (xy 425.769569 -6.454914) (xy 425.805285 -6.49613) (xy 425.834772 -6.54201)
			(xy 425.857429 -6.591619) (xy 425.872795 -6.643948) (xy 425.880557 -6.697931) (xy 425.880557 -6.752469)
			(xy 425.880556 -6.752475) (xy 427.85426 -6.752475) (xy 427.85426 -6.697925) (xy 427.862023 -6.643931)
			(xy 427.877392 -6.591591) (xy 427.900053 -6.541971) (xy 427.929546 -6.496082) (xy 427.965269 -6.454856)
			(xy 428.006496 -6.419135) (xy 428.052387 -6.389645) (xy 428.102008 -6.366986) (xy 428.154348 -6.351619)
			(xy 428.208343 -6.343858) (xy 428.235618 -6.343396) (xy 429.099218 -6.343396) (xy 429.126484 -6.343968)
			(xy 429.180459 -6.35173) (xy 429.232781 -6.367096) (xy 429.282383 -6.38975) (xy 429.328257 -6.419234)
			(xy 429.369468 -6.454945) (xy 429.405177 -6.496157) (xy 429.434658 -6.542032) (xy 429.457311 -6.591636)
			(xy 429.472673 -6.643958) (xy 429.480434 -6.697934) (xy 429.480434 -6.752466) (xy 429.479412 -6.759571)
			(xy 431.465194 -6.759571) (xy 431.465194 -6.705029) (xy 431.472956 -6.651043) (xy 431.488322 -6.598711)
			(xy 431.510979 -6.549098) (xy 431.540465 -6.503214) (xy 431.576181 -6.461994) (xy 431.6174 -6.426276)
			(xy 431.663282 -6.396787) (xy 431.712894 -6.374128) (xy 431.765225 -6.35876) (xy 431.819211 -6.350996)
			(xy 431.846482 -6.350508) (xy 432.710082 -6.350508) (xy 432.737352 -6.35103) (xy 432.791336 -6.35879)
			(xy 432.843667 -6.374153) (xy 432.893279 -6.396808) (xy 432.939161 -6.426293) (xy 432.98038 -6.462007)
			(xy 433.016096 -6.503225) (xy 433.045583 -6.549106) (xy 433.068241 -6.598716) (xy 433.083607 -6.651046)
			(xy 433.091369 -6.70503) (xy 433.091369 -6.75247) (xy 445.449182 -6.75247) (xy 445.449182 -6.69793)
			(xy 445.456944 -6.643944) (xy 445.472308 -6.591613) (xy 445.494963 -6.542001) (xy 445.524448 -6.496117)
			(xy 445.560162 -6.454896) (xy 445.601379 -6.419177) (xy 445.647258 -6.389686) (xy 445.696868 -6.367025)
			(xy 445.749198 -6.351654) (xy 445.803182 -6.343886) (xy 445.830452 -6.343396) (xy 446.694052 -6.343396)
			(xy 446.721322 -6.34394) (xy 446.775308 -6.351696) (xy 446.827641 -6.367056) (xy 446.877255 -6.389709)
			(xy 446.923139 -6.419192) (xy 446.964361 -6.454905) (xy 447.00008 -6.496122) (xy 447.029568 -6.542003)
			(xy 447.052227 -6.591614) (xy 447.067594 -6.643945) (xy 447.075356 -6.69793) (xy 447.075356 -6.75247)
			(xy 447.067594 -6.806455) (xy 447.052227 -6.858786) (xy 447.029568 -6.908397) (xy 447.000079 -6.954278)
			(xy 446.964361 -6.995495) (xy 446.923139 -7.031208) (xy 446.877255 -7.060691) (xy 446.827641 -7.083344)
			(xy 446.775308 -7.098704) (xy 446.721322 -7.10646) (xy 446.694052 -7.10692) (xy 445.830452 -7.10692)
			(xy 445.803182 -7.106514) (xy 445.749198 -7.098746) (xy 445.696868 -7.083375) (xy 445.647258 -7.060714)
			(xy 445.601378 -7.031223) (xy 445.560162 -6.995504) (xy 445.524448 -6.954283) (xy 445.494963 -6.908399)
			(xy 445.472308 -6.858787) (xy 445.456944 -6.806455) (xy 445.449182 -6.75247) (xy 433.091369 -6.75247)
			(xy 433.091369 -6.75957) (xy 433.083607 -6.813554) (xy 433.068241 -6.865884) (xy 433.045583 -6.915494)
			(xy 433.016096 -6.961375) (xy 432.98038 -7.002593) (xy 432.939161 -7.038307) (xy 432.893279 -7.067792)
			(xy 432.843667 -7.090447) (xy 432.791336 -7.10581) (xy 432.737352 -7.11357) (xy 432.710082 -7.114032)
			(xy 431.846482 -7.114032) (xy 431.819211 -7.113604) (xy 431.765225 -7.10584) (xy 431.712894 -7.090472)
			(xy 431.663282 -7.067813) (xy 431.6174 -7.038324) (xy 431.576181 -7.002606) (xy 431.540465 -6.961386)
			(xy 431.510979 -6.915502) (xy 431.488322 -6.865889) (xy 431.472956 -6.813557) (xy 431.465194 -6.759571)
			(xy 429.479412 -6.759571) (xy 429.472673 -6.806442) (xy 429.457311 -6.858764) (xy 429.434658 -6.908368)
			(xy 429.405177 -6.954243) (xy 429.369468 -6.995455) (xy 429.328257 -7.031166) (xy 429.282383 -7.06065)
			(xy 429.232781 -7.083304) (xy 429.180459 -7.09867) (xy 429.126484 -7.106432) (xy 429.099218 -7.10692)
			(xy 428.235618 -7.10692) (xy 428.208343 -7.106542) (xy 428.154348 -7.098781) (xy 428.102008 -7.083414)
			(xy 428.052387 -7.060755) (xy 428.006496 -7.031265) (xy 427.965269 -6.995544) (xy 427.929546 -6.954318)
			(xy 427.900053 -6.908429) (xy 427.877392 -6.858809) (xy 427.862023 -6.806469) (xy 427.85426 -6.752475)
			(xy 425.880556 -6.752475) (xy 425.872795 -6.806452) (xy 425.857429 -6.858781) (xy 425.834772 -6.90839)
			(xy 425.805285 -6.95427) (xy 425.769569 -6.995486) (xy 425.728351 -7.0312) (xy 425.682469 -7.060684)
			(xy 425.632858 -7.083337) (xy 425.580529 -7.0987) (xy 425.526545 -7.106458) (xy 425.499276 -7.10692)
			(xy 424.635676 -7.10692) (xy 424.608405 -7.106516) (xy 424.554418 -7.098751) (xy 424.502085 -7.083381)
			(xy 424.452473 -7.060721) (xy 424.40659 -7.031232) (xy 424.365371 -6.995512) (xy 424.329654 -6.954291)
			(xy 424.300167 -6.908406) (xy 424.27751 -6.858792) (xy 424.262144 -6.806459) (xy 424.254382 -6.752471)
			(xy 418.270457 -6.752471) (xy 418.262695 -6.806451) (xy 418.247329 -6.85878) (xy 418.224673 -6.908389)
			(xy 418.195187 -6.954268) (xy 418.159471 -6.995484) (xy 418.118254 -7.031198) (xy 418.072373 -7.060682)
			(xy 418.022763 -7.083336) (xy 417.970434 -7.098699) (xy 417.916451 -7.106458) (xy 417.889182 -7.10692)
			(xy 417.025582 -7.10692) (xy 416.99831 -7.106516) (xy 416.944323 -7.098752) (xy 416.89199 -7.083383)
			(xy 416.842376 -7.060723) (xy 416.796493 -7.031234) (xy 416.755273 -6.995515) (xy 416.719555 -6.954293)
			(xy 416.690068 -6.908408) (xy 416.667411 -6.858793) (xy 416.652045 -6.806459) (xy 416.644282 -6.752472)
			(xy 414.670433 -6.752472) (xy 414.662674 -6.806439) (xy 414.647312 -6.858759) (xy 414.624662 -6.908361)
			(xy 414.595183 -6.954235) (xy 414.559476 -6.995447) (xy 414.518267 -7.031159) (xy 414.472397 -7.060642)
			(xy 414.422797 -7.083298) (xy 414.370478 -7.098666) (xy 414.316505 -7.106431) (xy 414.28924 -7.10692)
			(xy 413.42564 -7.10692) (xy 413.398364 -7.106543) (xy 413.344367 -7.098785) (xy 413.292024 -7.08342)
			(xy 413.2424 -7.060762) (xy 413.196506 -7.031273) (xy 413.155277 -6.995551) (xy 413.119551 -6.954326)
			(xy 413.090057 -6.908435) (xy 413.067394 -6.858814) (xy 413.052024 -6.806472) (xy 413.04426 -6.752476)
			(xy 405.560556 -6.752476) (xy 405.552795 -6.806452) (xy 405.537429 -6.858781) (xy 405.514772 -6.90839)
			(xy 405.485285 -6.95427) (xy 405.449569 -6.995486) (xy 405.408351 -7.0312) (xy 405.362469 -7.060684)
			(xy 405.312858 -7.083337) (xy 405.260529 -7.0987) (xy 405.206545 -7.106458) (xy 405.179276 -7.10692)
			(xy 404.315676 -7.10692) (xy 404.288405 -7.106516) (xy 404.234418 -7.098751) (xy 404.182085 -7.083381)
			(xy 404.132473 -7.060721) (xy 404.08659 -7.031232) (xy 404.045371 -6.995512) (xy 404.009654 -6.954291)
			(xy 403.980167 -6.908406) (xy 403.95751 -6.858792) (xy 403.942144 -6.806459) (xy 403.934382 -6.752471)
			(xy 401.960357 -6.752471) (xy 401.952595 -6.806452) (xy 401.937229 -6.85878) (xy 401.914573 -6.908389)
			(xy 401.885086 -6.954269) (xy 401.849371 -6.995485) (xy 401.808153 -7.031198) (xy 401.762272 -7.060682)
			(xy 401.712661 -7.083336) (xy 401.660332 -7.098699) (xy 401.606349 -7.106458) (xy 401.57908 -7.10692)
			(xy 400.71548 -7.10692) (xy 400.688209 -7.106516) (xy 400.634221 -7.098751) (xy 400.581888 -7.083383)
			(xy 400.532275 -7.060723) (xy 400.486392 -7.031233) (xy 400.445172 -6.995514) (xy 400.409455 -6.954292)
			(xy 400.379968 -6.908407) (xy 400.35731 -6.858793) (xy 400.341944 -6.806459) (xy 400.334182 -6.752471)
			(xy 398.360333 -6.752471) (xy 398.352574 -6.806439) (xy 398.337212 -6.85876) (xy 398.314561 -6.908362)
			(xy 398.285082 -6.954236) (xy 398.249375 -6.995448) (xy 398.208166 -7.031159) (xy 398.162295 -7.060643)
			(xy 398.112695 -7.083299) (xy 398.060376 -7.098666) (xy 398.006403 -7.106431) (xy 397.979138 -7.10692)
			(xy 397.115538 -7.10692) (xy 397.088262 -7.106543) (xy 397.034265 -7.098784) (xy 396.981922 -7.08342)
			(xy 396.932299 -7.060762) (xy 396.886405 -7.031272) (xy 396.845176 -6.995551) (xy 396.809451 -6.954325)
			(xy 396.779956 -6.908434) (xy 396.757294 -6.858813) (xy 396.741924 -6.806472) (xy 396.73416 -6.752476)
			(xy 394.760456 -6.752476) (xy 394.752695 -6.806449) (xy 394.73733 -6.858777) (xy 394.714675 -6.908385)
			(xy 394.68519 -6.954264) (xy 394.649476 -6.995479) (xy 394.60826 -7.031193) (xy 394.562381 -7.060677)
			(xy 394.512773 -7.083332) (xy 394.460446 -7.098696) (xy 394.406464 -7.106457) (xy 394.379196 -7.10692)
			(xy 393.515596 -7.10692) (xy 393.488324 -7.106517) (xy 393.434335 -7.098754) (xy 393.382 -7.083387)
			(xy 393.332385 -7.060728) (xy 393.286499 -7.031239) (xy 393.245278 -6.995519) (xy 393.209559 -6.954297)
			(xy 393.18007 -6.908412) (xy 393.157412 -6.858796) (xy 393.142045 -6.806461) (xy 393.134283 -6.752472)
			(xy 388.110984 -6.752472) (xy 388.110984 -9.780016) (xy 388.110499 -9.850398) (xy 388.102605 -9.99094)
			(xy 388.086844 -10.130819) (xy 388.063264 -10.269594) (xy 388.03194 -10.406828) (xy 387.992971 -10.54209)
			(xy 387.946478 -10.674954) (xy 387.892609 -10.805003) (xy 387.831533 -10.931826) (xy 387.763442 -11.055026)
			(xy 387.68855 -11.174213) (xy 387.607093 -11.289014) (xy 387.519328 -11.399067) (xy 387.425529 -11.504025)
			(xy 387.325993 -11.60356) (xy 387.221033 -11.697356) (xy 387.110979 -11.78512) (xy 386.996176 -11.866575)
			(xy 386.876988 -11.941465) (xy 386.753787 -12.009554) (xy 386.626963 -12.070627) (xy 386.496913 -12.124494)
			(xy 386.364048 -12.170984) (xy 386.228785 -12.209951) (xy 386.091551 -12.241273) (xy 385.952775 -12.26485)
			(xy 385.812896 -12.280609) (xy 385.672354 -12.2885) (xy 385.601972 -12.289028) (xy 260.800088 -12.289028)
			(xy 260.744319 -12.28955) (xy 260.633094 -12.297886) (xy 260.522803 -12.314511) (xy 260.414062 -12.339331)
			(xy 260.30748 -12.372208) (xy 260.234662 -12.400788) (xy 436.813452 -12.400788) (xy 436.813941 -12.359678)
			(xy 436.821529 -12.27781) (xy 436.83664 -12.196991) (xy 436.859145 -12.117912) (xy 436.888851 -12.041247)
			(xy 436.925505 -11.96765) (xy 436.968795 -11.89775) (xy 437.01835 -11.832142) (xy 437.073748 -11.771388)
			(xy 437.134516 -11.716006) (xy 437.200136 -11.666467) (xy 437.270047 -11.623195) (xy 437.343653 -11.58656)
			(xy 437.420326 -11.556873) (xy 437.499411 -11.534389) (xy 437.580234 -11.519298) (xy 437.662104 -11.511731)
			(xy 437.703214 -11.51128) (xy 437.747029 -11.511772) (xy 437.83424 -11.520318) (xy 437.920187 -11.537406)
			(xy 438.004035 -11.562868) (xy 438.084971 -11.596458) (xy 438.123838 -11.61669) (xy 438.135191 -11.622017)
			(xy 438.160237 -11.622017) (xy 438.17159 -11.61669) (xy 438.210465 -11.596477) (xy 438.291405 -11.562905)
			(xy 438.375252 -11.537448) (xy 438.461195 -11.520353) (xy 438.548401 -11.511784) (xy 438.592214 -11.51128)
			(xy 438.636029 -11.511772) (xy 438.72324 -11.520318) (xy 438.809187 -11.537406) (xy 438.893035 -11.562868)
			(xy 438.973971 -11.596458) (xy 439.012838 -11.61669) (xy 439.024191 -11.622017) (xy 439.049237 -11.622017)
			(xy 439.06059 -11.61669) (xy 439.099465 -11.596477) (xy 439.180405 -11.562905) (xy 439.264252 -11.537448)
			(xy 439.350195 -11.520353) (xy 439.437401 -11.511784) (xy 439.481214 -11.51128) (xy 439.521951 -11.511719)
			(xy 439.603086 -11.519152) (xy 439.683202 -11.533973) (xy 439.761626 -11.556057) (xy 439.837703 -11.585219)
			(xy 439.910794 -11.621216) (xy 439.94578 -11.64209) (xy 439.954798 -11.647053) (xy 439.975154 -11.650004)
			(xy 439.995036 -11.644737) (xy 440.003438 -11.638788) (xy 440.091322 -11.570462) (xy 440.10072 -11.54049)
			(xy 440.095894 -11.52525) (xy 440.083229 -11.482506) (xy 440.065483 -11.395136) (xy 440.056563 -11.306429)
			(xy 440.056016 -11.261852) (xy 440.056016 -11.26109) (xy 440.056438 -11.22287) (xy 440.062998 -11.146712)
			(xy 440.076079 -11.071399) (xy 440.095582 -10.997489) (xy 440.108086 -10.96137) (xy 440.110695 -10.953059)
			(xy 440.110679 -10.935651) (xy 440.108086 -10.927334) (xy 440.095582 -10.891215) (xy 440.076095 -10.817302)
			(xy 440.063015 -10.74199) (xy 440.056437 -10.665834) (xy 440.056016 -10.627614) (xy 440.056016 -10.626852)
			(xy 440.05652 -10.584504) (xy 440.064571 -10.50019) (xy 440.0806 -10.417024) (xy 440.104461 -10.335757)
			(xy 440.13594 -10.257127) (xy 440.174751 -10.181846) (xy 440.220541 -10.110594) (xy 440.272897 -10.044018)
			(xy 440.331345 -9.98272) (xy 440.395355 -9.927255) (xy 440.464347 -9.878126) (xy 440.537697 -9.835777)
			(xy 440.61474 -9.800593) (xy 440.694779 -9.772891) (xy 440.777088 -9.752923) (xy 440.860923 -9.74087)
			(xy 440.945524 -9.73684) (xy 441.030125 -9.74087) (xy 441.11396 -9.752923) (xy 441.196269 -9.772891)
			(xy 441.276308 -9.800593) (xy 441.353351 -9.835777) (xy 441.426701 -9.878126) (xy 441.495693 -9.927255)
			(xy 441.559703 -9.98272) (xy 441.618151 -10.044018) (xy 441.670507 -10.110594) (xy 441.716297 -10.181846)
			(xy 441.755108 -10.257127) (xy 441.786587 -10.335757) (xy 441.810448 -10.417024) (xy 441.826477 -10.50019)
			(xy 441.834528 -10.584504) (xy 441.835032 -10.626852) (xy 441.835032 -10.627614) (xy 441.834614 -10.665834)
			(xy 441.828053 -10.741992) (xy 441.814972 -10.817305) (xy 441.795467 -10.891215) (xy 441.782962 -10.927334)
			(xy 441.780399 -10.935656) (xy 441.780383 -10.953054) (xy 441.782962 -10.96137) (xy 441.795465 -10.997489)
			(xy 441.814952 -11.071403) (xy 441.828033 -11.146715) (xy 441.834611 -11.22287) (xy 441.835032 -11.26109)
			(xy 441.835032 -11.261852) (xy 441.834502 -11.302954) (xy 441.826922 -11.384807) (xy 441.811821 -11.465611)
			(xy 441.789329 -11.544677) (xy 441.759637 -11.621331) (xy 441.722999 -11.694918) (xy 441.679728 -11.764811)
			(xy 441.630192 -11.830413) (xy 441.574815 -11.891164) (xy 441.514068 -11.946546) (xy 441.44847 -11.996087)
			(xy 441.378581 -12.039364) (xy 441.304997 -12.076008) (xy 441.228346 -12.105706) (xy 441.149281 -12.128204)
			(xy 441.068478 -12.143312) (xy 440.986626 -12.150899) (xy 440.945524 -12.15136) (xy 440.945016 -12.15136)
			(xy 440.904322 -12.150875) (xy 440.823276 -12.143416) (xy 440.74325 -12.128584) (xy 440.664913 -12.106505)
			(xy 440.58892 -12.077363) (xy 440.515907 -12.041401) (xy 440.480958 -12.02055) (xy 440.471926 -12.015614)
			(xy 440.451579 -12.012649) (xy 440.431701 -12.017907) (xy 440.4233 -12.023852) (xy 440.335416 -12.092178)
			(xy 440.326018 -12.12215) (xy 440.330844 -12.13739) (xy 440.343568 -12.180123) (xy 440.361398 -12.267491)
			(xy 440.370394 -12.356204) (xy 440.370976 -12.400788) (xy 440.370415 -12.444238) (xy 440.361895 -12.530719)
			(xy 440.344992 -12.615959) (xy 440.319868 -12.699148) (xy 440.286761 -12.779495) (xy 440.266836 -12.81811)
			(xy 440.262961 -12.82623) (xy 440.260628 -12.84406) (xy 440.262264 -12.852908) (xy 440.272023 -12.900055)
			(xy 440.282457 -12.995773) (xy 440.283092 -13.043916) (xy 440.282667 -13.085188) (xy 440.275027 -13.167377)
			(xy 440.259804 -13.248505) (xy 440.23713 -13.327874) (xy 440.2072 -13.4048) (xy 440.170271 -13.478622)
			(xy 440.126661 -13.548705) (xy 440.076745 -13.614446) (xy 440.020952 -13.675279) (xy 439.959763 -13.730681)
			(xy 439.893704 -13.780175) (xy 439.823344 -13.823336) (xy 439.786522 -13.841984) (xy 439.778885 -13.846179)
			(xy 439.766763 -13.858679) (xy 439.759479 -13.874495) (xy 439.758328 -13.883132) (xy 439.755251 -13.911241)
			(xy 439.741951 -13.966197) (xy 439.720685 -14.018587) (xy 439.69192 -14.067266) (xy 439.656285 -14.111165)
			(xy 439.643167 -14.123162) (xy 440.58586 -14.123162) (xy 440.586283 -14.084873) (xy 440.592885 -14.008579)
			(xy 440.60603 -13.933136) (xy 440.625619 -13.859105) (xy 440.638184 -13.822934) (xy 440.640853 -13.814502)
			(xy 440.64084 -13.796827) (xy 440.638184 -13.78839) (xy 440.625655 -13.752208) (xy 440.606078 -13.678176)
			(xy 440.592927 -13.602738) (xy 440.586298 -13.52645) (xy 440.58586 -13.488162) (xy 440.586364 -13.445801)
			(xy 440.594417 -13.361464) (xy 440.610451 -13.278274) (xy 440.634319 -13.196984) (xy 440.665807 -13.118332)
			(xy 440.704629 -13.043029) (xy 440.750432 -12.971757) (xy 440.802803 -12.905161) (xy 440.861268 -12.843846)
			(xy 440.925296 -12.788365) (xy 440.994308 -12.739222) (xy 441.067678 -12.696862) (xy 441.144743 -12.661667)
			(xy 441.224805 -12.633958) (xy 441.307138 -12.613984) (xy 441.390997 -12.601927) (xy 441.475622 -12.597896)
			(xy 441.560247 -12.601927) (xy 441.644106 -12.613984) (xy 441.726439 -12.633958) (xy 441.806501 -12.661667)
			(xy 441.883566 -12.696862) (xy 441.956936 -12.739222) (xy 442.025948 -12.788365) (xy 442.089976 -12.843846)
			(xy 442.135955 -12.892066) (xy 445.44847 -12.892066) (xy 445.44847 -12.837534) (xy 445.456231 -12.783558)
			(xy 445.471594 -12.731236) (xy 445.494246 -12.681632) (xy 445.523728 -12.635757) (xy 445.559438 -12.594545)
			(xy 445.600649 -12.558834) (xy 445.646523 -12.529351) (xy 445.696126 -12.506697) (xy 445.748448 -12.491333)
			(xy 445.802424 -12.483571) (xy 445.82969 -12.483084) (xy 446.69329 -12.483084) (xy 446.720565 -12.483455)
			(xy 446.774559 -12.491217) (xy 446.826899 -12.506584) (xy 446.87652 -12.529244) (xy 446.92241 -12.558735)
			(xy 446.963636 -12.594456) (xy 446.999359 -12.635682) (xy 447.028851 -12.681571) (xy 447.051512 -12.731191)
			(xy 447.066881 -12.783531) (xy 447.074644 -12.837525) (xy 447.074644 -12.892075) (xy 447.066881 -12.946069)
			(xy 447.051512 -12.998409) (xy 447.028851 -13.048029) (xy 446.999359 -13.093918) (xy 446.963636 -13.135144)
			(xy 446.92241 -13.170865) (xy 446.87652 -13.200356) (xy 446.826899 -13.223016) (xy 446.774559 -13.238383)
			(xy 446.720565 -13.246145) (xy 446.69329 -13.246608) (xy 445.82969 -13.246608) (xy 445.802424 -13.246029)
			(xy 445.748448 -13.238267) (xy 445.696126 -13.222903) (xy 445.646523 -13.200249) (xy 445.600649 -13.170766)
			(xy 445.559438 -13.135055) (xy 445.523728 -13.093843) (xy 445.494246 -13.047968) (xy 445.471594 -12.998364)
			(xy 445.456231 -12.946042) (xy 445.44847 -12.892066) (xy 442.135955 -12.892066) (xy 442.148441 -12.905161)
			(xy 442.200812 -12.971757) (xy 442.246615 -13.043029) (xy 442.285437 -13.118332) (xy 442.316925 -13.196984)
			(xy 442.340793 -13.278274) (xy 442.356827 -13.361464) (xy 442.36488 -13.445801) (xy 442.365384 -13.488162)
			(xy 442.364966 -13.526452) (xy 442.358362 -13.602745) (xy 442.345216 -13.678188) (xy 442.325626 -13.752219)
			(xy 442.31306 -13.78839) (xy 442.310428 -13.796831) (xy 442.310415 -13.814498) (xy 442.31306 -13.822934)
			(xy 442.325598 -13.859113) (xy 442.345172 -13.933146) (xy 442.358321 -14.008585) (xy 442.364947 -14.084874)
			(xy 442.365384 -14.123162) (xy 442.36488 -14.165523) (xy 442.356827 -14.24986) (xy 442.340793 -14.33305)
			(xy 442.316925 -14.41434) (xy 442.285437 -14.492992) (xy 442.268155 -14.526514) (xy 449.780152 -14.526514)
			(xy 449.780656 -14.484153) (xy 449.788709 -14.399816) (xy 449.804743 -14.316626) (xy 449.828611 -14.235336)
			(xy 449.860099 -14.156684) (xy 449.898921 -14.081381) (xy 449.944724 -14.010109) (xy 449.997095 -13.943513)
			(xy 450.05556 -13.882198) (xy 450.119588 -13.826717) (xy 450.1886 -13.777574) (xy 450.26197 -13.735214)
			(xy 450.339035 -13.700019) (xy 450.419097 -13.67231) (xy 450.50143 -13.652336) (xy 450.585289 -13.640279)
			(xy 450.669914 -13.636248) (xy 450.754539 -13.640279) (xy 450.838398 -13.652336) (xy 450.920731 -13.67231)
			(xy 451.000793 -13.700019) (xy 451.077858 -13.735214) (xy 451.151228 -13.777574) (xy 451.22024 -13.826717)
			(xy 451.284268 -13.882198) (xy 451.342733 -13.943513) (xy 451.395104 -14.010109) (xy 451.440907 -14.081381)
			(xy 451.479729 -14.156684) (xy 451.511217 -14.235336) (xy 451.535085 -14.316626) (xy 451.551119 -14.399816)
			(xy 451.559172 -14.484153) (xy 451.559676 -14.526514) (xy 451.559114 -14.571839) (xy 451.549887 -14.662018)
			(xy 451.531531 -14.750791) (xy 451.504235 -14.837234) (xy 451.486778 -14.879066) (xy 451.483143 -14.888844)
			(xy 451.483128 -14.909681) (xy 451.486778 -14.919452) (xy 451.504363 -14.961485) (xy 451.531877 -15.048351)
			(xy 451.550364 -15.137575) (xy 451.559632 -15.228222) (xy 451.560184 -15.273782) (xy 451.559623 -15.318552)
			(xy 451.550621 -15.407639) (xy 451.532717 -15.495371) (xy 451.506092 -15.580861) (xy 451.489064 -15.62227)
			(xy 451.485509 -15.631864) (xy 451.485503 -15.652304) (xy 451.489064 -15.661894) (xy 451.50607 -15.703278)
			(xy 451.532693 -15.788702) (xy 451.550602 -15.876368) (xy 451.559616 -15.96539) (xy 451.560184 -16.010128)
			(xy 451.560184 -16.010382) (xy 451.55968 -16.05273) (xy 451.551629 -16.137044) (xy 451.5356 -16.22021)
			(xy 451.511739 -16.301477) (xy 451.48026 -16.380107) (xy 451.441449 -16.455388) (xy 451.395659 -16.52664)
			(xy 451.343303 -16.593216) (xy 451.284855 -16.654514) (xy 451.220845 -16.709979) (xy 451.151853 -16.759108)
			(xy 451.078503 -16.801457) (xy 451.00146 -16.836641) (xy 450.921421 -16.864343) (xy 450.839112 -16.884311)
			(xy 450.755277 -16.896364) (xy 450.670676 -16.900395) (xy 450.586075 -16.896364) (xy 450.50224 -16.884311)
			(xy 450.419931 -16.864343) (xy 450.339892 -16.836641) (xy 450.262849 -16.801457) (xy 450.189499 -16.759108)
			(xy 450.120507 -16.709979) (xy 450.056497 -16.654514) (xy 449.998049 -16.593216) (xy 449.945693 -16.52664)
			(xy 449.899903 -16.455388) (xy 449.861092 -16.380107) (xy 449.829613 -16.301477) (xy 449.805752 -16.22021)
			(xy 449.789723 -16.137044) (xy 449.781672 -16.05273) (xy 449.781168 -16.010382) (xy 449.781168 -16.010128)
			(xy 449.781731 -15.96539) (xy 449.790749 -15.876368) (xy 449.808655 -15.788701) (xy 449.83527 -15.703273)
			(xy 449.852288 -15.661894) (xy 449.855865 -15.652307) (xy 449.855859 -15.63186) (xy 449.852288 -15.62227)
			(xy 449.835263 -15.580859) (xy 449.808628 -15.495372) (xy 449.790721 -15.40764) (xy 449.781723 -15.318552)
			(xy 449.781168 -15.273782) (xy 449.781749 -15.228458) (xy 449.79099 -15.138283) (xy 449.809345 -15.049513)
			(xy 449.836623 -14.963067) (xy 449.854066 -14.92123) (xy 449.857691 -14.911438) (xy 449.857571 -14.890584)
			(xy 449.853812 -14.880844) (xy 449.836183 -14.838823) (xy 449.808624 -14.751958) (xy 449.790079 -14.662732)
			(xy 449.780742 -14.57208) (xy 449.780152 -14.526514) (xy 442.268155 -14.526514) (xy 442.246615 -14.568295)
			(xy 442.200812 -14.639567) (xy 442.148441 -14.706163) (xy 442.089976 -14.767478) (xy 442.025948 -14.822959)
			(xy 441.956936 -14.872102) (xy 441.883566 -14.914462) (xy 441.806501 -14.949657) (xy 441.726439 -14.977366)
			(xy 441.644106 -14.99734) (xy 441.560247 -15.009397) (xy 441.475622 -15.013429) (xy 441.390997 -15.009397)
			(xy 441.307138 -14.99734) (xy 441.224805 -14.977366) (xy 441.144743 -14.949657) (xy 441.067678 -14.914462)
			(xy 440.994308 -14.872102) (xy 440.925296 -14.822959) (xy 440.861268 -14.767478) (xy 440.802803 -14.706163)
			(xy 440.750432 -14.639567) (xy 440.704629 -14.568295) (xy 440.665807 -14.492992) (xy 440.634319 -14.41434)
			(xy 440.610451 -14.33305) (xy 440.594417 -14.24986) (xy 440.586364 -14.165523) (xy 440.58586 -14.123162)
			(xy 439.643167 -14.123162) (xy 439.614561 -14.149324) (xy 439.567661 -14.180907) (xy 439.516614 -14.205222)
			(xy 439.462537 -14.221736) (xy 439.406615 -14.230088) (xy 439.378344 -14.230604) (xy 439.350975 -14.230111)
			(xy 439.296797 -14.2223) (xy 439.244294 -14.206817) (xy 439.194547 -14.183981) (xy 439.148579 -14.154262)
			(xy 439.127646 -14.136624) (xy 439.127392 -14.13637) (xy 439.120314 -14.130771) (xy 439.103391 -14.124533)
			(xy 439.094372 -14.124178) (xy 439.027316 -14.124178) (xy 439.018301 -14.124547) (xy 439.001384 -14.130787)
			(xy 438.994296 -14.13637) (xy 438.994296 -14.136624) (xy 438.994042 -14.136624) (xy 438.973108 -14.154261)
			(xy 438.927135 -14.183972) (xy 438.877388 -14.206808) (xy 438.824888 -14.2223) (xy 438.770713 -14.230129)
			(xy 438.743344 -14.230604) (xy 438.713998 -14.230028) (xy 438.656001 -14.221024) (xy 438.600065 -14.203253)
			(xy 438.547506 -14.177132) (xy 438.499563 -14.143277) (xy 438.457364 -14.102486) (xy 438.421903 -14.055718)
			(xy 438.394015 -14.004075) (xy 438.38368 -13.976604) (xy 438.380221 -13.968026) (xy 438.368225 -13.953963)
			(xy 438.360312 -13.949172) (xy 438.333388 -13.93444) (xy 438.324705 -13.93016) (xy 438.305508 -13.927807)
			(xy 438.29605 -13.929868) (xy 438.259095 -13.939128) (xy 438.184005 -13.952036) (xy 438.108086 -13.958466)
			(xy 438.06999 -13.958824) (xy 438.028658 -13.958363) (xy 437.94635 -13.95071) (xy 437.865107 -13.935453)
			(xy 437.78563 -13.912724) (xy 437.708605 -13.882718) (xy 437.634696 -13.845694) (xy 437.564542 -13.801972)
			(xy 437.498747 -13.751929) (xy 437.43788 -13.695998) (xy 437.382465 -13.634659) (xy 437.332981 -13.568444)
			(xy 437.289854 -13.497922) (xy 437.253456 -13.423703) (xy 437.224103 -13.346427) (xy 437.202046 -13.266761)
			(xy 437.187477 -13.185391) (xy 437.18353 -13.144246) (xy 437.182106 -13.133691) (xy 437.171856 -13.11505)
			(xy 437.163718 -13.108178) (xy 437.131484 -13.082996) (xy 437.071245 -13.027653) (xy 437.016344 -12.967011)
			(xy 436.967245 -12.901582) (xy 436.924364 -12.831919) (xy 436.888063 -12.758612) (xy 436.858649 -12.682281)
			(xy 436.83637 -12.603571) (xy 436.821416 -12.523147) (xy 436.813913 -12.441689) (xy 436.813452 -12.400788)
			(xy 260.234662 -12.400788) (xy 260.203654 -12.412958) (xy 260.103162 -12.461353) (xy 260.006569 -12.517122)
			(xy 259.914413 -12.579954) (xy 259.82721 -12.649497) (xy 259.745448 -12.725362) (xy 259.669584 -12.807125)
			(xy 259.601843 -12.89207) (xy 431.453248 -12.89207) (xy 431.453248 -12.83753) (xy 431.46101 -12.783546)
			(xy 431.476376 -12.731216) (xy 431.499035 -12.681606) (xy 431.528523 -12.635726) (xy 431.564241 -12.594509)
			(xy 431.605461 -12.558796) (xy 431.651345 -12.529313) (xy 431.700957 -12.506661) (xy 431.753289 -12.4913)
			(xy 431.807274 -12.483544) (xy 431.834544 -12.483084) (xy 432.698144 -12.483084) (xy 432.725415 -12.483482)
			(xy 432.7794 -12.491249) (xy 432.83173 -12.50662) (xy 432.881341 -12.529282) (xy 432.927222 -12.558772)
			(xy 432.968439 -12.594492) (xy 433.004154 -12.635713) (xy 433.033639 -12.681598) (xy 433.056295 -12.731211)
			(xy 433.07166 -12.783543) (xy 433.079422 -12.837529) (xy 433.079422 -12.892071) (xy 433.07166 -12.946057)
			(xy 433.056295 -12.998389) (xy 433.033639 -13.048002) (xy 433.004154 -13.093887) (xy 432.968439 -13.135108)
			(xy 432.927222 -13.170828) (xy 432.881341 -13.200318) (xy 432.83173 -13.22298) (xy 432.7794 -13.238351)
			(xy 432.725415 -13.246118) (xy 432.698144 -13.246608) (xy 431.834544 -13.246608) (xy 431.807274 -13.246056)
			(xy 431.753289 -13.2383) (xy 431.700957 -13.222939) (xy 431.651345 -13.200287) (xy 431.605461 -13.170804)
			(xy 431.564241 -13.135091) (xy 431.528523 -13.093874) (xy 431.499035 -13.047994) (xy 431.476376 -12.998384)
			(xy 431.46101 -12.946054) (xy 431.453248 -12.89207) (xy 259.601843 -12.89207) (xy 259.600042 -12.894329)
			(xy 259.537211 -12.986486) (xy 259.481443 -13.08308) (xy 259.43305 -13.183572) (xy 259.392301 -13.287399)
			(xy 259.359426 -13.393981) (xy 259.334607 -13.502722) (xy 259.317984 -13.613014) (xy 259.309649 -13.724239)
			(xy 259.309108 -13.780008) (xy 259.309108 -17.126458) (xy 310.265572 -17.126458) (xy 310.265992 -17.082972)
			(xy 310.273576 -16.996331) (xy 310.288682 -16.910681) (xy 310.311195 -16.826674) (xy 310.340944 -16.744948)
			(xy 310.377702 -16.666126) (xy 310.421191 -16.590808) (xy 310.471078 -16.519566) (xy 310.526985 -16.452943)
			(xy 310.588485 -16.391447) (xy 310.65511 -16.335544) (xy 310.726355 -16.285661) (xy 310.801676 -16.242177)
			(xy 310.8805 -16.205422) (xy 310.962227 -16.175678) (xy 311.046236 -16.15317) (xy 311.131887 -16.138068)
			(xy 311.218528 -16.13049) (xy 311.262014 -16.130016) (xy 311.287414 -16.130016) (xy 311.33271 -16.130609)
			(xy 311.422936 -16.13873) (xy 311.512071 -16.154907) (xy 311.599397 -16.179009) (xy 311.684211 -16.210841)
			(xy 311.76583 -16.250148) (xy 311.843598 -16.296613) (xy 311.916887 -16.349861) (xy 311.985108 -16.409465)
			(xy 312.047712 -16.474944) (xy 312.104194 -16.545772) (xy 312.1541 -16.621377) (xy 312.197028 -16.701151)
			(xy 312.232632 -16.784452) (xy 312.260626 -16.870609) (xy 312.280784 -16.958929) (xy 312.292944 -17.0487)
			(xy 312.297009 -17.1392) (xy 312.292944 -17.2297) (xy 312.280784 -17.319471) (xy 312.260626 -17.407791)
			(xy 312.232632 -17.493948) (xy 312.197028 -17.577249) (xy 312.163448 -17.639652) (xy 389.652738 -17.639652)
			(xy 389.652738 -17.585148) (xy 389.660494 -17.531197) (xy 389.675849 -17.4789) (xy 389.69849 -17.42932)
			(xy 389.727956 -17.383466) (xy 389.763647 -17.342273) (xy 389.804838 -17.306578) (xy 389.850688 -17.277107)
			(xy 389.900266 -17.254462) (xy 389.952562 -17.239102) (xy 390.006512 -17.23134) (xy 390.033764 -17.230852)
			(xy 390.897364 -17.230852) (xy 390.924616 -17.231393) (xy 390.978565 -17.239145) (xy 391.030862 -17.254496)
			(xy 391.080441 -17.277134) (xy 391.126294 -17.306598) (xy 391.167486 -17.342288) (xy 391.20318 -17.383477)
			(xy 391.232649 -17.429327) (xy 391.255291 -17.478905) (xy 391.270648 -17.5312) (xy 391.278405 -17.585148)
			(xy 391.278405 -17.639652) (xy 395.240738 -17.639652) (xy 395.240738 -17.585148) (xy 395.248494 -17.531197)
			(xy 395.263849 -17.4789) (xy 395.28649 -17.42932) (xy 395.315956 -17.383466) (xy 395.351647 -17.342273)
			(xy 395.392838 -17.306578) (xy 395.438688 -17.277107) (xy 395.488266 -17.254462) (xy 395.540562 -17.239102)
			(xy 395.594512 -17.23134) (xy 395.621764 -17.230852) (xy 396.485364 -17.230852) (xy 396.512616 -17.231393)
			(xy 396.566565 -17.239145) (xy 396.618862 -17.254496) (xy 396.668441 -17.277134) (xy 396.714294 -17.306598)
			(xy 396.755486 -17.342288) (xy 396.79118 -17.383477) (xy 396.820649 -17.429327) (xy 396.843291 -17.478905)
			(xy 396.858648 -17.5312) (xy 396.866405 -17.585148) (xy 396.866405 -17.639652) (xy 400.828738 -17.639652)
			(xy 400.828738 -17.585148) (xy 400.836494 -17.531197) (xy 400.851849 -17.4789) (xy 400.87449 -17.42932)
			(xy 400.903956 -17.383466) (xy 400.939647 -17.342273) (xy 400.980838 -17.306578) (xy 401.026688 -17.277107)
			(xy 401.076266 -17.254462) (xy 401.128562 -17.239102) (xy 401.182512 -17.23134) (xy 401.209764 -17.230852)
			(xy 402.073364 -17.230852) (xy 402.100616 -17.231393) (xy 402.154565 -17.239145) (xy 402.206862 -17.254496)
			(xy 402.256441 -17.277134) (xy 402.302294 -17.306598) (xy 402.343486 -17.342288) (xy 402.37918 -17.383477)
			(xy 402.408649 -17.429327) (xy 402.431291 -17.478905) (xy 402.446648 -17.5312) (xy 402.454405 -17.585148)
			(xy 402.454405 -17.639652) (xy 402.454301 -17.640372) (xy 406.415424 -17.640372) (xy 406.415424 -17.585828)
			(xy 406.423187 -17.53184) (xy 406.438554 -17.479507) (xy 406.461214 -17.429893) (xy 406.490704 -17.38401)
			(xy 406.526425 -17.342791) (xy 406.567649 -17.307076) (xy 406.613536 -17.277591) (xy 406.663152 -17.254938)
			(xy 406.715487 -17.239576) (xy 406.769476 -17.23182) (xy 406.796748 -17.23136) (xy 407.660348 -17.23136)
			(xy 407.687617 -17.231806) (xy 407.741598 -17.239573) (xy 407.793925 -17.254944) (xy 407.843532 -17.277604)
			(xy 407.88941 -17.307093) (xy 407.930624 -17.34281) (xy 407.966336 -17.384029) (xy 407.995819 -17.42991)
			(xy 408.018473 -17.47952) (xy 408.033837 -17.531849) (xy 408.041598 -17.585831) (xy 408.041598 -17.640369)
			(xy 408.041598 -17.640372) (xy 412.003424 -17.640372) (xy 412.003424 -17.585828) (xy 412.011187 -17.53184)
			(xy 412.026554 -17.479507) (xy 412.049214 -17.429893) (xy 412.078704 -17.38401) (xy 412.114425 -17.342791)
			(xy 412.155649 -17.307076) (xy 412.201536 -17.277591) (xy 412.251152 -17.254938) (xy 412.303487 -17.239576)
			(xy 412.357476 -17.23182) (xy 412.384748 -17.23136) (xy 413.248348 -17.23136) (xy 413.275617 -17.231806)
			(xy 413.329598 -17.239573) (xy 413.381925 -17.254944) (xy 413.431532 -17.277604) (xy 413.47741 -17.307093)
			(xy 413.518624 -17.34281) (xy 413.554336 -17.384029) (xy 413.583819 -17.42991) (xy 413.606473 -17.47952)
			(xy 413.621837 -17.531849) (xy 413.629598 -17.585831) (xy 413.629598 -17.639653) (xy 417.898538 -17.639653)
			(xy 417.898538 -17.585147) (xy 417.906295 -17.531195) (xy 417.92165 -17.478897) (xy 417.944292 -17.429315)
			(xy 417.97376 -17.383461) (xy 418.009453 -17.342267) (xy 418.050645 -17.306572) (xy 418.096498 -17.277102)
			(xy 418.146078 -17.254457) (xy 418.198376 -17.239099) (xy 418.252327 -17.231339) (xy 418.27958 -17.230852)
			(xy 419.14318 -17.230852) (xy 419.170431 -17.231394) (xy 419.224378 -17.239148) (xy 419.276673 -17.2545)
			(xy 419.326251 -17.277139) (xy 419.372101 -17.306604) (xy 419.413292 -17.342294) (xy 419.448984 -17.383483)
			(xy 419.478451 -17.429332) (xy 419.501093 -17.478908) (xy 419.516448 -17.531202) (xy 419.524205 -17.585149)
			(xy 419.524205 -17.639651) (xy 419.524205 -17.639653) (xy 423.486538 -17.639653) (xy 423.486538 -17.585147)
			(xy 423.494295 -17.531195) (xy 423.50965 -17.478897) (xy 423.532292 -17.429315) (xy 423.56176 -17.383461)
			(xy 423.597453 -17.342267) (xy 423.638645 -17.306572) (xy 423.684498 -17.277102) (xy 423.734078 -17.254457)
			(xy 423.786376 -17.239099) (xy 423.840327 -17.231339) (xy 423.86758 -17.230852) (xy 424.73118 -17.230852)
			(xy 424.758431 -17.231394) (xy 424.812378 -17.239148) (xy 424.864673 -17.2545) (xy 424.914251 -17.277139)
			(xy 424.960101 -17.306604) (xy 425.001292 -17.342294) (xy 425.036984 -17.383483) (xy 425.066451 -17.429332)
			(xy 425.089093 -17.478908) (xy 425.104448 -17.531202) (xy 425.112205 -17.585149) (xy 425.112205 -17.639651)
			(xy 425.112102 -17.640368) (xy 429.107346 -17.640368) (xy 429.107346 -17.585832) (xy 429.115108 -17.531852)
			(xy 429.130472 -17.479525) (xy 429.153127 -17.429918) (xy 429.182611 -17.38404) (xy 429.218324 -17.342824)
			(xy 429.25954 -17.307111) (xy 429.305418 -17.277627) (xy 429.355025 -17.254972) (xy 429.407352 -17.239608)
			(xy 429.461332 -17.231846) (xy 429.4886 -17.23136) (xy 430.3522 -17.23136) (xy 430.379471 -17.231802)
			(xy 430.433458 -17.239565) (xy 430.48579 -17.254931) (xy 430.535403 -17.277588) (xy 430.581287 -17.307076)
			(xy 430.622507 -17.342793) (xy 430.658224 -17.384013) (xy 430.687712 -17.429897) (xy 430.710369 -17.47951)
			(xy 430.725735 -17.531842) (xy 430.733498 -17.585829) (xy 430.733498 -17.640371) (xy 430.725735 -17.694358)
			(xy 430.710369 -17.74669) (xy 430.687712 -17.796303) (xy 430.658224 -17.842187) (xy 430.622507 -17.883407)
			(xy 430.581287 -17.919124) (xy 430.535403 -17.948612) (xy 430.48579 -17.971269) (xy 430.433458 -17.986635)
			(xy 430.379471 -17.994398) (xy 430.3522 -17.994884) (xy 429.4886 -17.994884) (xy 429.461332 -17.994354)
			(xy 429.407352 -17.986592) (xy 429.355025 -17.971228) (xy 429.305418 -17.948573) (xy 429.25954 -17.919089)
			(xy 429.218324 -17.883376) (xy 429.182611 -17.84216) (xy 429.153127 -17.796282) (xy 429.130472 -17.746675)
			(xy 429.115108 -17.694348) (xy 429.107346 -17.640368) (xy 425.112102 -17.640368) (xy 425.104448 -17.693598)
			(xy 425.089093 -17.745892) (xy 425.066451 -17.795468) (xy 425.036984 -17.841317) (xy 425.001292 -17.882506)
			(xy 424.960101 -17.918196) (xy 424.914251 -17.947661) (xy 424.864673 -17.9703) (xy 424.812378 -17.985652)
			(xy 424.758431 -17.993406) (xy 424.73118 -17.993868) (xy 423.86758 -17.993868) (xy 423.840327 -17.993461)
			(xy 423.786376 -17.985701) (xy 423.734078 -17.970343) (xy 423.684498 -17.947698) (xy 423.638645 -17.918228)
			(xy 423.597453 -17.882533) (xy 423.56176 -17.841339) (xy 423.532292 -17.795485) (xy 423.50965 -17.745903)
			(xy 423.494295 -17.693605) (xy 423.486538 -17.639653) (xy 419.524205 -17.639653) (xy 419.516448 -17.693598)
			(xy 419.501093 -17.745892) (xy 419.478451 -17.795468) (xy 419.448984 -17.841317) (xy 419.413292 -17.882506)
			(xy 419.372101 -17.918196) (xy 419.326251 -17.947661) (xy 419.276673 -17.9703) (xy 419.224378 -17.985652)
			(xy 419.170431 -17.993406) (xy 419.14318 -17.993868) (xy 418.27958 -17.993868) (xy 418.252327 -17.993461)
			(xy 418.198376 -17.985701) (xy 418.146078 -17.970343) (xy 418.096498 -17.947698) (xy 418.050645 -17.918228)
			(xy 418.009453 -17.882533) (xy 417.97376 -17.841339) (xy 417.944292 -17.795485) (xy 417.92165 -17.745903)
			(xy 417.906295 -17.693605) (xy 417.898538 -17.639653) (xy 413.629598 -17.639653) (xy 413.629598 -17.640369)
			(xy 413.621837 -17.694351) (xy 413.606473 -17.74668) (xy 413.583819 -17.79629) (xy 413.554336 -17.842171)
			(xy 413.518624 -17.88339) (xy 413.47741 -17.919107) (xy 413.431532 -17.948596) (xy 413.381925 -17.971256)
			(xy 413.329598 -17.986627) (xy 413.275617 -17.994394) (xy 413.248348 -17.994884) (xy 412.384748 -17.994884)
			(xy 412.357476 -17.99438) (xy 412.303487 -17.986624) (xy 412.251152 -17.971262) (xy 412.201536 -17.948609)
			(xy 412.155649 -17.919124) (xy 412.114425 -17.883409) (xy 412.078704 -17.84219) (xy 412.049214 -17.796307)
			(xy 412.026554 -17.746693) (xy 412.011187 -17.69436) (xy 412.003424 -17.640372) (xy 408.041598 -17.640372)
			(xy 408.033837 -17.694351) (xy 408.018473 -17.74668) (xy 407.995819 -17.79629) (xy 407.966336 -17.842171)
			(xy 407.930624 -17.88339) (xy 407.88941 -17.919107) (xy 407.843532 -17.948596) (xy 407.793925 -17.971256)
			(xy 407.741598 -17.986627) (xy 407.687617 -17.994394) (xy 407.660348 -17.994884) (xy 406.796748 -17.994884)
			(xy 406.769476 -17.99438) (xy 406.715487 -17.986624) (xy 406.663152 -17.971262) (xy 406.613536 -17.948609)
			(xy 406.567649 -17.919124) (xy 406.526425 -17.883409) (xy 406.490704 -17.84219) (xy 406.461214 -17.796307)
			(xy 406.438554 -17.746693) (xy 406.423187 -17.69436) (xy 406.415424 -17.640372) (xy 402.454301 -17.640372)
			(xy 402.446648 -17.6936) (xy 402.431291 -17.745895) (xy 402.408649 -17.795473) (xy 402.37918 -17.841323)
			(xy 402.343486 -17.882512) (xy 402.302294 -17.918202) (xy 402.256441 -17.947666) (xy 402.206862 -17.970304)
			(xy 402.154565 -17.985655) (xy 402.100616 -17.993407) (xy 402.073364 -17.993868) (xy 401.209764 -17.993868)
			(xy 401.182512 -17.99346) (xy 401.128562 -17.985698) (xy 401.076266 -17.970338) (xy 401.026688 -17.947693)
			(xy 400.980838 -17.918222) (xy 400.939647 -17.882527) (xy 400.903956 -17.841334) (xy 400.87449 -17.79548)
			(xy 400.851849 -17.7459) (xy 400.836494 -17.693603) (xy 400.828738 -17.639652) (xy 396.866405 -17.639652)
			(xy 396.858648 -17.6936) (xy 396.843291 -17.745895) (xy 396.820649 -17.795473) (xy 396.79118 -17.841323)
			(xy 396.755486 -17.882512) (xy 396.714294 -17.918202) (xy 396.668441 -17.947666) (xy 396.618862 -17.970304)
			(xy 396.566565 -17.985655) (xy 396.512616 -17.993407) (xy 396.485364 -17.993868) (xy 395.621764 -17.993868)
			(xy 395.594512 -17.99346) (xy 395.540562 -17.985698) (xy 395.488266 -17.970338) (xy 395.438688 -17.947693)
			(xy 395.392838 -17.918222) (xy 395.351647 -17.882527) (xy 395.315956 -17.841334) (xy 395.28649 -17.79548)
			(xy 395.263849 -17.7459) (xy 395.248494 -17.693603) (xy 395.240738 -17.639652) (xy 391.278405 -17.639652)
			(xy 391.270648 -17.6936) (xy 391.255291 -17.745895) (xy 391.232649 -17.795473) (xy 391.20318 -17.841323)
			(xy 391.167486 -17.882512) (xy 391.126294 -17.918202) (xy 391.080441 -17.947666) (xy 391.030862 -17.970304)
			(xy 390.978565 -17.985655) (xy 390.924616 -17.993407) (xy 390.897364 -17.993868) (xy 390.033764 -17.993868)
			(xy 390.006512 -17.99346) (xy 389.952562 -17.985698) (xy 389.900266 -17.970338) (xy 389.850688 -17.947693)
			(xy 389.804838 -17.918222) (xy 389.763647 -17.882527) (xy 389.727956 -17.841334) (xy 389.69849 -17.79548)
			(xy 389.675849 -17.7459) (xy 389.660494 -17.693603) (xy 389.652738 -17.639652) (xy 312.163448 -17.639652)
			(xy 312.1541 -17.657023) (xy 312.104194 -17.732628) (xy 312.047712 -17.803456) (xy 311.985108 -17.868935)
			(xy 311.916887 -17.928539) (xy 311.843598 -17.981787) (xy 311.76583 -18.028252) (xy 311.684211 -18.067559)
			(xy 311.599397 -18.099391) (xy 311.512071 -18.123493) (xy 311.422936 -18.13967) (xy 311.33271 -18.147791)
			(xy 311.287414 -18.1483) (xy 311.28716 -18.1483) (xy 311.242573 -18.147831) (xy 311.153739 -18.140039)
			(xy 311.065923 -18.124536) (xy 310.979792 -18.101438) (xy 310.896001 -18.070922) (xy 310.815188 -18.033221)
			(xy 310.737969 -17.988621) (xy 310.664929 -17.937461) (xy 310.596626 -17.88013) (xy 310.533579 -17.817066)
			(xy 310.476268 -17.748747) (xy 310.425128 -17.675693) (xy 310.380549 -17.598461) (xy 310.34287 -17.517638)
			(xy 310.312377 -17.433839) (xy 310.289303 -17.347701) (xy 310.273824 -17.259881) (xy 310.266056 -17.171045)
			(xy 310.265572 -17.126458) (xy 259.309108 -17.126458) (xy 259.309108 -19.164372) (xy 392.445424 -19.164372)
			(xy 392.445424 -19.109828) (xy 392.453187 -19.05584) (xy 392.468554 -19.003507) (xy 392.491214 -18.953893)
			(xy 392.520704 -18.90801) (xy 392.556425 -18.866791) (xy 392.597649 -18.831076) (xy 392.643536 -18.801591)
			(xy 392.693152 -18.778938) (xy 392.745487 -18.763576) (xy 392.799476 -18.75582) (xy 392.826748 -18.75536)
			(xy 393.690348 -18.75536) (xy 393.717617 -18.755806) (xy 393.771598 -18.763573) (xy 393.823925 -18.778944)
			(xy 393.873532 -18.801604) (xy 393.91941 -18.831093) (xy 393.960624 -18.86681) (xy 393.996336 -18.908029)
			(xy 394.025819 -18.95391) (xy 394.048473 -19.00352) (xy 394.063837 -19.055849) (xy 394.071598 -19.109831)
			(xy 394.071598 -19.163652) (xy 398.034738 -19.163652) (xy 398.034738 -19.109148) (xy 398.042494 -19.055197)
			(xy 398.057849 -19.0029) (xy 398.08049 -18.95332) (xy 398.109956 -18.907466) (xy 398.145647 -18.866273)
			(xy 398.186838 -18.830578) (xy 398.232688 -18.801107) (xy 398.282266 -18.778462) (xy 398.334562 -18.763102)
			(xy 398.388512 -18.75534) (xy 398.415764 -18.754852) (xy 399.279364 -18.754852) (xy 399.306616 -18.755393)
			(xy 399.360565 -18.763145) (xy 399.412862 -18.778496) (xy 399.462441 -18.801134) (xy 399.508294 -18.830598)
			(xy 399.549486 -18.866288) (xy 399.58518 -18.907477) (xy 399.614649 -18.953327) (xy 399.637291 -19.002905)
			(xy 399.652648 -19.0552) (xy 399.660405 -19.109148) (xy 399.660405 -19.163652) (xy 403.622738 -19.163652)
			(xy 403.622738 -19.109148) (xy 403.630494 -19.055197) (xy 403.645849 -19.0029) (xy 403.66849 -18.95332)
			(xy 403.697956 -18.907466) (xy 403.733647 -18.866273) (xy 403.774838 -18.830578) (xy 403.820688 -18.801107)
			(xy 403.870266 -18.778462) (xy 403.922562 -18.763102) (xy 403.976512 -18.75534) (xy 404.003764 -18.754852)
			(xy 404.867364 -18.754852) (xy 404.894616 -18.755393) (xy 404.948565 -18.763145) (xy 405.000862 -18.778496)
			(xy 405.050441 -18.801134) (xy 405.096294 -18.830598) (xy 405.137486 -18.866288) (xy 405.17318 -18.907477)
			(xy 405.202649 -18.953327) (xy 405.225291 -19.002905) (xy 405.240648 -19.0552) (xy 405.248405 -19.109148)
			(xy 405.248405 -19.163652) (xy 409.210738 -19.163652) (xy 409.210738 -19.109148) (xy 409.218494 -19.055197)
			(xy 409.233849 -19.0029) (xy 409.25649 -18.95332) (xy 409.285956 -18.907466) (xy 409.321647 -18.866273)
			(xy 409.362838 -18.830578) (xy 409.408688 -18.801107) (xy 409.458266 -18.778462) (xy 409.510562 -18.763102)
			(xy 409.564512 -18.75534) (xy 409.591764 -18.754852) (xy 410.455364 -18.754852) (xy 410.482616 -18.755393)
			(xy 410.536565 -18.763145) (xy 410.588862 -18.778496) (xy 410.638441 -18.801134) (xy 410.684294 -18.830598)
			(xy 410.725486 -18.866288) (xy 410.76118 -18.907477) (xy 410.790649 -18.953327) (xy 410.813291 -19.002905)
			(xy 410.828648 -19.0552) (xy 410.836405 -19.109148) (xy 410.836405 -19.163652) (xy 410.836405 -19.163653)
			(xy 415.104538 -19.163653) (xy 415.104538 -19.109147) (xy 415.112295 -19.055195) (xy 415.12765 -19.002897)
			(xy 415.150292 -18.953315) (xy 415.17976 -18.907461) (xy 415.215453 -18.866267) (xy 415.256645 -18.830572)
			(xy 415.302498 -18.801102) (xy 415.352078 -18.778457) (xy 415.404376 -18.763099) (xy 415.458327 -18.755339)
			(xy 415.48558 -18.754852) (xy 416.34918 -18.754852) (xy 416.376431 -18.755394) (xy 416.430378 -18.763148)
			(xy 416.482673 -18.7785) (xy 416.532251 -18.801139) (xy 416.578101 -18.830604) (xy 416.619292 -18.866294)
			(xy 416.654984 -18.907483) (xy 416.684451 -18.953332) (xy 416.707093 -19.002908) (xy 416.722448 -19.055202)
			(xy 416.730205 -19.109149) (xy 416.730205 -19.163651) (xy 416.730102 -19.164366) (xy 420.691346 -19.164366)
			(xy 420.691346 -19.109834) (xy 420.699107 -19.055857) (xy 420.714469 -19.003533) (xy 420.737121 -18.953928)
			(xy 420.766602 -18.908051) (xy 420.802312 -18.866837) (xy 420.843523 -18.831124) (xy 420.889396 -18.801639)
			(xy 420.938999 -18.778982) (xy 420.991321 -18.763614) (xy 421.045298 -18.755849) (xy 421.072564 -18.75536)
			(xy 421.936164 -18.75536) (xy 421.963438 -18.755777) (xy 422.017432 -18.763536) (xy 422.069772 -18.7789)
			(xy 422.119393 -18.801556) (xy 422.165284 -18.831045) (xy 422.20651 -18.866764) (xy 422.242234 -18.907988)
			(xy 422.271726 -18.953876) (xy 422.294388 -19.003494) (xy 422.309757 -19.055833) (xy 422.31752 -19.109826)
			(xy 422.31752 -19.163656) (xy 426.314515 -19.163656) (xy 426.314515 -19.109144) (xy 426.322273 -19.055185)
			(xy 426.337632 -19.002881) (xy 426.360278 -18.953294) (xy 426.38975 -18.907436) (xy 426.42545 -18.866238)
			(xy 426.466648 -18.830541) (xy 426.512508 -18.80107) (xy 426.562096 -18.778426) (xy 426.614401 -18.76307)
			(xy 426.66836 -18.755314) (xy 426.695616 -18.754852) (xy 427.559216 -18.754852) (xy 427.586464 -18.755419)
			(xy 427.640404 -18.763177) (xy 427.692691 -18.778532) (xy 427.742261 -18.801171) (xy 427.788105 -18.830635)
			(xy 427.829289 -18.866323) (xy 427.864975 -18.907508) (xy 427.894436 -18.953353) (xy 427.917074 -19.002924)
			(xy 427.932427 -19.055212) (xy 427.940182 -19.109152) (xy 427.940182 -19.163648) (xy 427.940181 -19.163656)
			(xy 431.902515 -19.163656) (xy 431.902515 -19.109144) (xy 431.910273 -19.055185) (xy 431.925632 -19.002881)
			(xy 431.948278 -18.953294) (xy 431.97775 -18.907436) (xy 432.01345 -18.866238) (xy 432.054648 -18.830541)
			(xy 432.100508 -18.80107) (xy 432.150096 -18.778426) (xy 432.202401 -18.76307) (xy 432.25636 -18.755314)
			(xy 432.283616 -18.754852) (xy 433.147216 -18.754852) (xy 433.174464 -18.755419) (xy 433.228404 -18.763177)
			(xy 433.280691 -18.778532) (xy 433.330261 -18.801171) (xy 433.376105 -18.830635) (xy 433.417289 -18.866323)
			(xy 433.452975 -18.907508) (xy 433.482436 -18.953353) (xy 433.505074 -19.002924) (xy 433.520427 -19.055212)
			(xy 433.528182 -19.109152) (xy 433.528182 -19.163648) (xy 433.520427 -19.217588) (xy 433.505074 -19.269876)
			(xy 433.482436 -19.319447) (xy 433.452975 -19.365292) (xy 433.417289 -19.406477) (xy 433.376105 -19.442165)
			(xy 433.330261 -19.471629) (xy 433.280691 -19.494268) (xy 433.228404 -19.509623) (xy 433.174464 -19.517381)
			(xy 433.147216 -19.517868) (xy 432.283616 -19.517868) (xy 432.25636 -19.517486) (xy 432.202401 -19.50973)
			(xy 432.150096 -19.494374) (xy 432.100508 -19.47173) (xy 432.054648 -19.442259) (xy 432.01345 -19.406562)
			(xy 431.97775 -19.365364) (xy 431.948278 -19.319506) (xy 431.925632 -19.269919) (xy 431.910273 -19.217615)
			(xy 431.902515 -19.163656) (xy 427.940181 -19.163656) (xy 427.932427 -19.217588) (xy 427.917074 -19.269876)
			(xy 427.894436 -19.319447) (xy 427.864975 -19.365292) (xy 427.829289 -19.406477) (xy 427.788105 -19.442165)
			(xy 427.742261 -19.471629) (xy 427.692691 -19.494268) (xy 427.640404 -19.509623) (xy 427.586464 -19.517381)
			(xy 427.559216 -19.517868) (xy 426.695616 -19.517868) (xy 426.66836 -19.517486) (xy 426.614401 -19.50973)
			(xy 426.562096 -19.494374) (xy 426.512508 -19.47173) (xy 426.466648 -19.442259) (xy 426.42545 -19.406562)
			(xy 426.38975 -19.365364) (xy 426.360278 -19.319506) (xy 426.337632 -19.269919) (xy 426.322273 -19.217615)
			(xy 426.314515 -19.163656) (xy 422.31752 -19.163656) (xy 422.31752 -19.164374) (xy 422.309757 -19.218367)
			(xy 422.294388 -19.270706) (xy 422.271726 -19.320324) (xy 422.242234 -19.366212) (xy 422.20651 -19.407436)
			(xy 422.165284 -19.443155) (xy 422.119393 -19.472644) (xy 422.069772 -19.4953) (xy 422.017432 -19.510664)
			(xy 421.963438 -19.518423) (xy 421.936164 -19.518884) (xy 421.072564 -19.518884) (xy 421.045298 -19.518351)
			(xy 420.991321 -19.510586) (xy 420.938999 -19.495218) (xy 420.889396 -19.472561) (xy 420.843523 -19.443076)
			(xy 420.802312 -19.407363) (xy 420.766602 -19.366149) (xy 420.737121 -19.320272) (xy 420.714469 -19.270667)
			(xy 420.699107 -19.218343) (xy 420.691346 -19.164366) (xy 416.730102 -19.164366) (xy 416.722448 -19.217598)
			(xy 416.707093 -19.269892) (xy 416.684451 -19.319468) (xy 416.654984 -19.365317) (xy 416.619292 -19.406506)
			(xy 416.578101 -19.442196) (xy 416.532251 -19.471661) (xy 416.482673 -19.4943) (xy 416.430378 -19.509652)
			(xy 416.376431 -19.517406) (xy 416.34918 -19.517868) (xy 415.48558 -19.517868) (xy 415.458327 -19.517461)
			(xy 415.404376 -19.509701) (xy 415.352078 -19.494343) (xy 415.302498 -19.471698) (xy 415.256645 -19.442228)
			(xy 415.215453 -19.406533) (xy 415.17976 -19.365339) (xy 415.150292 -19.319485) (xy 415.12765 -19.269903)
			(xy 415.112295 -19.217605) (xy 415.104538 -19.163653) (xy 410.836405 -19.163653) (xy 410.828648 -19.2176)
			(xy 410.813291 -19.269895) (xy 410.790649 -19.319473) (xy 410.76118 -19.365323) (xy 410.725486 -19.406512)
			(xy 410.684294 -19.442202) (xy 410.638441 -19.471666) (xy 410.588862 -19.494304) (xy 410.536565 -19.509655)
			(xy 410.482616 -19.517407) (xy 410.455364 -19.517868) (xy 409.591764 -19.517868) (xy 409.564512 -19.51746)
			(xy 409.510562 -19.509698) (xy 409.458266 -19.494338) (xy 409.408688 -19.471693) (xy 409.362838 -19.442222)
			(xy 409.321647 -19.406527) (xy 409.285956 -19.365334) (xy 409.25649 -19.31948) (xy 409.233849 -19.2699)
			(xy 409.218494 -19.217603) (xy 409.210738 -19.163652) (xy 405.248405 -19.163652) (xy 405.240648 -19.2176)
			(xy 405.225291 -19.269895) (xy 405.202649 -19.319473) (xy 405.17318 -19.365323) (xy 405.137486 -19.406512)
			(xy 405.096294 -19.442202) (xy 405.050441 -19.471666) (xy 405.000862 -19.494304) (xy 404.948565 -19.509655)
			(xy 404.894616 -19.517407) (xy 404.867364 -19.517868) (xy 404.003764 -19.517868) (xy 403.976512 -19.51746)
			(xy 403.922562 -19.509698) (xy 403.870266 -19.494338) (xy 403.820688 -19.471693) (xy 403.774838 -19.442222)
			(xy 403.733647 -19.406527) (xy 403.697956 -19.365334) (xy 403.66849 -19.31948) (xy 403.645849 -19.2699)
			(xy 403.630494 -19.217603) (xy 403.622738 -19.163652) (xy 399.660405 -19.163652) (xy 399.652648 -19.2176)
			(xy 399.637291 -19.269895) (xy 399.614649 -19.319473) (xy 399.58518 -19.365323) (xy 399.549486 -19.406512)
			(xy 399.508294 -19.442202) (xy 399.462441 -19.471666) (xy 399.412862 -19.494304) (xy 399.360565 -19.509655)
			(xy 399.306616 -19.517407) (xy 399.279364 -19.517868) (xy 398.415764 -19.517868) (xy 398.388512 -19.51746)
			(xy 398.334562 -19.509698) (xy 398.282266 -19.494338) (xy 398.232688 -19.471693) (xy 398.186838 -19.442222)
			(xy 398.145647 -19.406527) (xy 398.109956 -19.365334) (xy 398.08049 -19.31948) (xy 398.057849 -19.2699)
			(xy 398.042494 -19.217603) (xy 398.034738 -19.163652) (xy 394.071598 -19.163652) (xy 394.071598 -19.164369)
			(xy 394.063837 -19.218351) (xy 394.048473 -19.27068) (xy 394.025819 -19.32029) (xy 393.996336 -19.366171)
			(xy 393.960624 -19.40739) (xy 393.91941 -19.443107) (xy 393.873532 -19.472596) (xy 393.823925 -19.495256)
			(xy 393.771598 -19.510627) (xy 393.717617 -19.518394) (xy 393.690348 -19.518884) (xy 392.826748 -19.518884)
			(xy 392.799476 -19.51838) (xy 392.745487 -19.510624) (xy 392.693152 -19.495262) (xy 392.643536 -19.472609)
			(xy 392.597649 -19.443124) (xy 392.556425 -19.407409) (xy 392.520704 -19.36619) (xy 392.491214 -19.320307)
			(xy 392.468554 -19.270693) (xy 392.453187 -19.21836) (xy 392.445424 -19.164372) (xy 259.309108 -19.164372)
			(xy 259.309108 -20.4061) (xy 368.50594 -20.4061) (xy 368.510005 -20.315592) (xy 368.522167 -20.225813)
			(xy 368.542328 -20.137486) (xy 368.570325 -20.051322) (xy 368.605934 -19.968014) (xy 368.648867 -19.888233)
			(xy 368.698779 -19.812623) (xy 368.755267 -19.741791) (xy 368.817878 -19.676308) (xy 368.886107 -19.616701)
			(xy 368.959405 -19.56345) (xy 369.037181 -19.516984) (xy 369.118809 -19.477677) (xy 369.203632 -19.445846)
			(xy 369.290966 -19.421746) (xy 369.38011 -19.405573) (xy 369.470345 -19.397455) (xy 369.515644 -19.396964)
			(xy 369.560233 -19.397442) (xy 369.649072 -19.405219) (xy 369.736895 -19.420711) (xy 369.823033 -19.443798)
			(xy 369.906831 -19.474305) (xy 369.987651 -19.512001) (xy 370.064878 -19.556597) (xy 370.137923 -19.607756)
			(xy 370.206232 -19.665086) (xy 370.269283 -19.728153) (xy 370.326597 -19.796475) (xy 370.377737 -19.869533)
			(xy 370.422315 -19.946771) (xy 370.459991 -20.0276) (xy 370.490478 -20.111405) (xy 370.513544 -20.197549)
			(xy 370.529013 -20.285376) (xy 370.536768 -20.374217) (xy 370.537232 -20.418806) (xy 370.536774 -20.462284)
			(xy 370.529196 -20.54891) (xy 370.514098 -20.634545) (xy 370.491595 -20.71854) (xy 370.485037 -20.73656)
			(xy 440.464956 -20.73656) (xy 440.465378 -20.698271) (xy 440.471981 -20.621977) (xy 440.485126 -20.546534)
			(xy 440.504715 -20.472503) (xy 440.51728 -20.436332) (xy 440.51995 -20.4279) (xy 440.519937 -20.410225)
			(xy 440.51728 -20.401788) (xy 440.50475 -20.365606) (xy 440.485173 -20.291575) (xy 440.472022 -20.216136)
			(xy 440.465394 -20.139848) (xy 440.464956 -20.10156) (xy 440.46549 -20.057765) (xy 440.474106 -19.9706)
			(xy 440.49125 -19.884704) (xy 440.516756 -19.80091) (xy 440.550377 -19.72003) (xy 440.57062 -19.68119)
			(xy 440.576064 -19.669733) (xy 440.576046 -19.644397) (xy 440.57062 -19.63293) (xy 440.550398 -19.594081)
			(xy 440.51679 -19.513198) (xy 440.491286 -19.429406) (xy 440.474133 -19.343514) (xy 440.465497 -19.256354)
			(xy 440.464956 -19.21256) (xy 440.465378 -19.174271) (xy 440.471981 -19.097977) (xy 440.485126 -19.022534)
			(xy 440.504715 -18.948503) (xy 440.51728 -18.912332) (xy 440.51995 -18.9039) (xy 440.519937 -18.886225)
			(xy 440.51728 -18.877788) (xy 440.50475 -18.841606) (xy 440.485173 -18.767575) (xy 440.472022 -18.692136)
			(xy 440.465394 -18.615848) (xy 440.464956 -18.57756) (xy 440.465414 -18.53645) (xy 440.473005 -18.45458)
			(xy 440.488119 -18.373761) (xy 440.510626 -18.294681) (xy 440.540334 -18.218015) (xy 440.576991 -18.144418)
			(xy 440.620282 -18.074518) (xy 440.66984 -18.008911) (xy 440.72524 -17.948157) (xy 440.78601 -17.892775)
			(xy 440.851631 -17.843237) (xy 440.921544 -17.799965) (xy 440.995152 -17.76333) (xy 441.071826 -17.733644)
			(xy 441.150912 -17.71116) (xy 441.231736 -17.69607) (xy 441.313608 -17.688502) (xy 441.354718 -17.688052)
			(xy 441.395668 -17.688478) (xy 441.477223 -17.695989) (xy 441.557742 -17.710965) (xy 441.636544 -17.733279)
			(xy 441.712961 -17.762742) (xy 441.786347 -17.799105) (xy 441.856079 -17.842059) (xy 441.921567 -17.891241)
			(xy 441.982258 -17.946234) (xy 442.010292 -17.976088) (xy 442.017449 -17.983101) (xy 442.035585 -17.991562)
			(xy 442.055576 -17.99248) (xy 442.065156 -17.98955) (xy 442.102033 -17.976445) (xy 442.177582 -17.955997)
			(xy 442.254637 -17.94227) (xy 442.3326 -17.935373) (xy 442.371734 -17.93494) (xy 442.412849 -17.93538)
			(xy 442.494727 -17.942971) (xy 442.575557 -17.958083) (xy 442.654646 -17.980589) (xy 442.731323 -18.010296)
			(xy 442.804931 -18.046951) (xy 442.874843 -18.090241) (xy 442.940462 -18.139797) (xy 443.001229 -18.195196)
			(xy 443.056626 -18.255966) (xy 443.106179 -18.321587) (xy 443.149467 -18.391501) (xy 443.186119 -18.46511)
			(xy 443.213248 -18.535142) (xy 451.165468 -18.535142) (xy 451.165468 -18.534888) (xy 451.166052 -18.49015)
			(xy 451.175063 -18.401129) (xy 451.192964 -18.313462) (xy 451.219572 -18.228034) (xy 451.236588 -18.186654)
			(xy 451.240131 -18.177057) (xy 451.240147 -18.15662) (xy 451.236588 -18.14703) (xy 451.219555 -18.105656)
			(xy 451.192939 -18.020228) (xy 451.175038 -17.932559) (xy 451.166032 -17.843535) (xy 451.165468 -17.798796)
			(xy 451.165468 -17.798542) (xy 451.165972 -17.756194) (xy 451.174023 -17.67188) (xy 451.190052 -17.588714)
			(xy 451.213913 -17.507447) (xy 451.245392 -17.428817) (xy 451.284203 -17.353536) (xy 451.329993 -17.282284)
			(xy 451.382349 -17.215708) (xy 451.440797 -17.15441) (xy 451.504807 -17.098945) (xy 451.573799 -17.049816)
			(xy 451.647149 -17.007467) (xy 451.724192 -16.972283) (xy 451.804231 -16.944581) (xy 451.88654 -16.924613)
			(xy 451.970375 -16.91256) (xy 452.054976 -16.90853) (xy 452.139577 -16.91256) (xy 452.223412 -16.924613)
			(xy 452.305721 -16.944581) (xy 452.38576 -16.972283) (xy 452.462803 -17.007467) (xy 452.536153 -17.049816)
			(xy 452.605145 -17.098945) (xy 452.669155 -17.15441) (xy 452.727603 -17.215708) (xy 452.779959 -17.282284)
			(xy 452.825749 -17.353536) (xy 452.86456 -17.428817) (xy 452.896039 -17.507447) (xy 452.9199 -17.588714)
			(xy 452.935929 -17.67188) (xy 452.94398 -17.756194) (xy 452.944484 -17.798542) (xy 452.944484 -17.798796)
			(xy 452.943898 -17.843534) (xy 452.934888 -17.932555) (xy 452.916988 -18.020222) (xy 452.890379 -18.10565)
			(xy 452.873364 -18.14703) (xy 452.869775 -18.156614) (xy 452.869791 -18.177063) (xy 452.873364 -18.186654)
			(xy 452.890389 -18.228031) (xy 452.917007 -18.313458) (xy 452.934911 -18.401126) (xy 452.943919 -18.490149)
			(xy 452.944484 -18.534888) (xy 452.944484 -18.535142) (xy 452.94398 -18.57749) (xy 452.935929 -18.661804)
			(xy 452.9199 -18.74497) (xy 452.896039 -18.826237) (xy 452.86456 -18.904867) (xy 452.825749 -18.980148)
			(xy 452.779959 -19.0514) (xy 452.727603 -19.117976) (xy 452.669155 -19.179274) (xy 452.605145 -19.234739)
			(xy 452.536153 -19.283868) (xy 452.462803 -19.326217) (xy 452.38576 -19.361401) (xy 452.305721 -19.389103)
			(xy 452.223412 -19.409071) (xy 452.139577 -19.421124) (xy 452.054976 -19.425155) (xy 451.970375 -19.421124)
			(xy 451.88654 -19.409071) (xy 451.804231 -19.389103) (xy 451.724192 -19.361401) (xy 451.647149 -19.326217)
			(xy 451.573799 -19.283868) (xy 451.504807 -19.234739) (xy 451.440797 -19.179274) (xy 451.382349 -19.117976)
			(xy 451.329993 -19.0514) (xy 451.284203 -18.980148) (xy 451.245392 -18.904867) (xy 451.213913 -18.826237)
			(xy 451.190052 -18.74497) (xy 451.174023 -18.661804) (xy 451.165972 -18.57749) (xy 451.165468 -18.535142)
			(xy 443.213248 -18.535142) (xy 443.215823 -18.541788) (xy 443.238325 -18.620878) (xy 443.253434 -18.701708)
			(xy 443.261021 -18.783587) (xy 443.261496 -18.824702) (xy 443.261095 -18.862992) (xy 443.254486 -18.939286)
			(xy 443.241336 -19.014729) (xy 443.221741 -19.088759) (xy 443.209172 -19.12493) (xy 443.206519 -19.133366)
			(xy 443.20652 -19.151037) (xy 443.209172 -19.159474) (xy 443.221718 -19.195651) (xy 443.24129 -19.269684)
			(xy 443.254437 -19.345124) (xy 443.261061 -19.421414) (xy 443.261496 -19.459702) (xy 443.260982 -19.503497)
			(xy 443.252361 -19.590663) (xy 443.235212 -19.676559) (xy 443.209701 -19.760353) (xy 443.176076 -19.841233)
			(xy 443.155832 -19.880072) (xy 443.15041 -19.891537) (xy 443.150411 -19.916866) (xy 443.155832 -19.928332)
			(xy 443.176073 -19.967172) (xy 443.209679 -20.048057) (xy 443.235179 -20.131851) (xy 443.252328 -20.217745)
			(xy 443.260958 -20.304908) (xy 443.261496 -20.348702) (xy 443.261095 -20.386992) (xy 443.254486 -20.463286)
			(xy 443.241336 -20.538729) (xy 443.221741 -20.612759) (xy 443.209172 -20.64893) (xy 443.206519 -20.657366)
			(xy 443.20652 -20.675037) (xy 443.209172 -20.683474) (xy 443.221718 -20.719651) (xy 443.24129 -20.793684)
			(xy 443.254437 -20.869124) (xy 443.261061 -20.945414) (xy 443.261496 -20.983702) (xy 443.260989 -21.024815)
			(xy 443.253402 -21.106691) (xy 443.238293 -21.187518) (xy 443.215791 -21.266605) (xy 443.186088 -21.343279)
			(xy 443.149437 -21.416886) (xy 443.106152 -21.486797) (xy 443.0566 -21.552416) (xy 443.001205 -21.613183)
			(xy 442.94044 -21.66858) (xy 442.874823 -21.718133) (xy 442.804914 -21.761422) (xy 442.731309 -21.798075)
			(xy 442.654636 -21.827781) (xy 442.575549 -21.850286) (xy 442.494723 -21.865398) (xy 442.412847 -21.872988)
			(xy 442.371734 -21.873464) (xy 442.330778 -21.872996) (xy 442.249213 -21.865468) (xy 442.168686 -21.850472)
			(xy 442.089879 -21.828136) (xy 442.013459 -21.798648) (xy 441.940074 -21.762259) (xy 441.870346 -21.719277)
			(xy 441.804865 -21.670066) (xy 441.744186 -21.615042) (xy 441.71616 -21.585174) (xy 441.709037 -21.578124)
			(xy 441.690882 -21.569676) (xy 441.670879 -21.568774) (xy 441.661296 -21.571712) (xy 441.624502 -21.584749)
			(xy 441.549137 -21.605106) (xy 441.472276 -21.618771) (xy 441.394513 -21.625637) (xy 441.35548 -21.626068)
			(xy 441.354718 -21.626068) (xy 441.313612 -21.62557) (xy 441.23175 -21.617988) (xy 441.150936 -21.602885)
			(xy 441.07186 -21.580392) (xy 440.995197 -21.5507) (xy 440.9216 -21.514062) (xy 440.851696 -21.470791)
			(xy 440.786082 -21.421255) (xy 440.725318 -21.365878) (xy 440.669922 -21.305132) (xy 440.620366 -21.239533)
			(xy 440.577073 -21.169643) (xy 440.540412 -21.096058) (xy 440.510696 -21.019403) (xy 440.488178 -20.940335)
			(xy 440.473051 -20.859526) (xy 440.465443 -20.777666) (xy 440.464956 -20.73656) (xy 370.485037 -20.73656)
			(xy 370.461858 -20.800254) (xy 370.425114 -20.879065) (xy 370.381641 -20.954375) (xy 370.331772 -21.02561)
			(xy 370.275884 -21.092228) (xy 370.214404 -21.153723) (xy 370.147799 -21.209627) (xy 370.076576 -21.259513)
			(xy 370.001276 -21.303004) (xy 369.922473 -21.339767) (xy 369.840767 -21.369523) (xy 369.756778 -21.392046)
			(xy 369.671146 -21.407165) (xy 369.584522 -21.414763) (xy 369.541044 -21.415248) (xy 369.515644 -21.415248)
			(xy 369.470345 -21.414745) (xy 369.38011 -21.406627) (xy 369.290966 -21.390454) (xy 369.203632 -21.366354)
			(xy 369.118809 -21.334523) (xy 369.037181 -21.295216) (xy 368.959405 -21.24875) (xy 368.886107 -21.195499)
			(xy 368.817878 -21.135892) (xy 368.755267 -21.070409) (xy 368.698779 -20.999577) (xy 368.648867 -20.923967)
			(xy 368.605934 -20.844186) (xy 368.570325 -20.760878) (xy 368.542328 -20.674714) (xy 368.522167 -20.586387)
			(xy 368.510005 -20.496608) (xy 368.50594 -20.4061) (xy 259.309108 -20.4061) (xy 259.309108 -25.982422)
			(xy 440.239912 -25.982422) (xy 440.240419 -25.939461) (xy 440.248702 -25.85394) (xy 440.265193 -25.769616)
			(xy 440.289738 -25.687275) (xy 440.322109 -25.607684) (xy 440.362003 -25.531586) (xy 440.40905 -25.459689)
			(xy 440.46281 -25.392664) (xy 440.522782 -25.331135) (xy 440.588408 -25.275676) (xy 440.659076 -25.226803)
			(xy 440.69635 -25.205436) (xy 440.704332 -25.200469) (xy 440.716316 -25.186006) (xy 440.719718 -25.177242)
			(xy 440.733823 -25.137039) (xy 440.768699 -25.059297) (xy 440.810847 -24.985247) (xy 440.859883 -24.915565)
			(xy 440.915357 -24.850891) (xy 440.97676 -24.791817) (xy 441.043529 -24.738885) (xy 441.115054 -24.692579)
			(xy 441.190679 -24.653323) (xy 441.26971 -24.621478) (xy 441.351424 -24.597336) (xy 441.435072 -24.581116)
			(xy 441.519887 -24.572969) (xy 441.56249 -24.572468) (xy 441.562998 -24.572468) (xy 441.606762 -24.572982)
			(xy 441.693869 -24.581557) (xy 441.77971 -24.598653) (xy 441.863455 -24.624106) (xy 441.944293 -24.657667)
			(xy 441.983114 -24.677878) (xy 441.994467 -24.683205) (xy 442.019513 -24.683205) (xy 442.030866 -24.677878)
			(xy 442.069745 -24.657673) (xy 442.150684 -24.6241) (xy 442.23453 -24.598641) (xy 442.320472 -24.581544)
			(xy 442.407677 -24.572973) (xy 442.45149 -24.572468) (xy 442.495305 -24.572971) (xy 442.582516 -24.581515)
			(xy 442.668462 -24.5986) (xy 442.752311 -24.62406) (xy 442.833246 -24.657648) (xy 442.872114 -24.677878)
			(xy 442.883467 -24.683205) (xy 442.908513 -24.683205) (xy 442.919866 -24.677878) (xy 442.959061 -24.657499)
			(xy 443.040701 -24.623735) (xy 443.125286 -24.598229) (xy 443.211982 -24.581233) (xy 443.255908 -24.576532)
			(xy 443.266358 -24.575008) (xy 443.284755 -24.564681) (xy 443.297434 -24.547819) (xy 443.300358 -24.53767)
			(xy 443.310609 -24.496358) (xy 443.337964 -24.415751) (xy 443.372893 -24.338124) (xy 443.415077 -24.264189)
			(xy 443.464129 -24.19462) (xy 443.519603 -24.130055) (xy 443.580989 -24.071084) (xy 443.647727 -24.018245)
			(xy 443.719207 -23.972023) (xy 443.794775 -23.932839) (xy 443.87374 -23.901052) (xy 443.955381 -23.876952)
			(xy 444.038949 -23.86076) (xy 444.123683 -23.852625) (xy 444.166244 -23.852124) (xy 444.207348 -23.852525)
			(xy 444.289205 -23.860114) (xy 444.370013 -23.875224) (xy 444.449082 -23.897725) (xy 444.525738 -23.927425)
			(xy 444.599326 -23.964072) (xy 444.669219 -24.007352) (xy 444.734821 -24.056897) (xy 444.795571 -24.112283)
			(xy 444.850952 -24.173038) (xy 444.900491 -24.238644) (xy 444.943765 -24.30854) (xy 444.980405 -24.382132)
			(xy 445.0101 -24.45879) (xy 445.032594 -24.537861) (xy 445.047697 -24.61867) (xy 445.055279 -24.700528)
			(xy 445.055752 -24.741632) (xy 445.055238 -24.782654) (xy 445.04768 -24.864348) (xy 445.032631 -24.944999)
			(xy 445.01022 -25.023921) (xy 444.980635 -25.100445) (xy 444.94413 -25.173919) (xy 444.901014 -25.243719)
			(xy 444.851653 -25.309252) (xy 444.796467 -25.369961) (xy 444.735925 -25.425331) (xy 444.670542 -25.47489)
			(xy 444.600873 -25.518217) (xy 444.52751 -25.554945) (xy 444.451076 -25.584761) (xy 444.372222 -25.607412)
			(xy 444.291617 -25.622705) (xy 444.250826 -25.627076) (xy 444.240379 -25.628618) (xy 444.221981 -25.638935)
			(xy 444.2093 -25.655791) (xy 444.206376 -25.665938) (xy 444.196473 -25.705794) (xy 444.170375 -25.783666)
			(xy 444.137208 -25.8588) (xy 444.097254 -25.930555) (xy 444.050854 -25.998321) (xy 443.998403 -26.061519)
			(xy 443.940348 -26.119612) (xy 443.877184 -26.172104) (xy 443.809448 -26.218548) (xy 443.773814 -26.238962)
			(xy 443.765845 -26.243946) (xy 443.753852 -26.258396) (xy 443.750446 -26.267156) (xy 443.736369 -26.307378)
			(xy 443.701515 -26.385148) (xy 443.659384 -26.459228) (xy 443.61036 -26.528939) (xy 443.554893 -26.593641)
			(xy 443.493492 -26.652741) (xy 443.42672 -26.705698) (xy 443.355189 -26.752025) (xy 443.279554 -26.791298)
			(xy 443.200511 -26.823158) (xy 443.118782 -26.847311) (xy 443.035118 -26.863536) (xy 442.950285 -26.871685)
			(xy 442.907674 -26.872184) (xy 442.863879 -26.871639) (xy 442.776715 -26.863025) (xy 442.690819 -26.845883)
			(xy 442.607025 -26.82038) (xy 442.526144 -26.786761) (xy 442.487304 -26.76652) (xy 442.475838 -26.761102)
			(xy 442.45051 -26.761102) (xy 442.439044 -26.76652) (xy 442.400209 -26.786769) (xy 442.319322 -26.820374)
			(xy 442.235526 -26.845873) (xy 442.149632 -26.863019) (xy 442.062468 -26.871647) (xy 442.018674 -26.872184)
			(xy 441.974879 -26.871639) (xy 441.887715 -26.863025) (xy 441.801819 -26.845883) (xy 441.718025 -26.82038)
			(xy 441.637144 -26.786761) (xy 441.598304 -26.76652) (xy 441.586838 -26.761102) (xy 441.56151 -26.761102)
			(xy 441.550044 -26.76652) (xy 441.511209 -26.786769) (xy 441.430322 -26.820374) (xy 441.346526 -26.845873)
			(xy 441.260632 -26.863019) (xy 441.173468 -26.871647) (xy 441.129674 -26.872184) (xy 441.08856 -26.871712)
			(xy 441.006683 -26.864123) (xy 440.925855 -26.849012) (xy 440.846767 -26.826507) (xy 440.770092 -26.796802)
			(xy 440.696485 -26.760149) (xy 440.626574 -26.71686) (xy 440.560955 -26.667306) (xy 440.500188 -26.61191)
			(xy 440.444791 -26.551142) (xy 440.395237 -26.485523) (xy 440.351949 -26.415612) (xy 440.315297 -26.342004)
			(xy 440.285592 -26.265329) (xy 440.263088 -26.186241) (xy 440.247977 -26.105413) (xy 440.240388 -26.023536)
			(xy 440.239912 -25.982422) (xy 259.309108 -25.982422) (xy 259.309108 -32.117846) (xy 455.218281 -32.117846)
			(xy 455.218281 -31.988706) (xy 455.226231 -31.859811) (xy 455.242101 -31.731651) (xy 455.26583 -31.60471)
			(xy 455.297329 -31.479471) (xy 455.336478 -31.356408) (xy 455.383129 -31.235989) (xy 455.437104 -31.11867)
			(xy 455.498199 -31.004896) (xy 455.566182 -30.895099) (xy 455.640796 -30.789696) (xy 455.721757 -30.689086)
			(xy 455.808757 -30.593651) (xy 455.901468 -30.503752) (xy 455.999538 -30.419731) (xy 456.102593 -30.341907)
			(xy 456.210244 -30.270575) (xy 456.322083 -30.206005) (xy 456.437684 -30.148443) (xy 456.556609 -30.098106)
			(xy 456.678408 -30.055186) (xy 456.802618 -30.019845) (xy 456.928767 -29.992218) (xy 457.056379 -29.972409)
			(xy 457.184968 -29.960493) (xy 457.314046 -29.956517) (xy 457.443124 -29.960493) (xy 457.571713 -29.972409)
			(xy 457.699325 -29.992218) (xy 457.825474 -30.019845) (xy 457.949684 -30.055186) (xy 458.071483 -30.098106)
			(xy 458.190408 -30.148443) (xy 458.306009 -30.206005) (xy 458.417848 -30.270575) (xy 458.525499 -30.341907)
			(xy 458.628554 -30.419731) (xy 458.726624 -30.503752) (xy 458.819335 -30.593651) (xy 458.906335 -30.689086)
			(xy 458.987296 -30.789696) (xy 459.06191 -30.895099) (xy 459.129893 -31.004896) (xy 459.190988 -31.11867)
			(xy 459.244963 -31.235989) (xy 459.291614 -31.356408) (xy 459.330763 -31.479471) (xy 459.362262 -31.60471)
			(xy 459.385991 -31.731651) (xy 459.401861 -31.859811) (xy 459.409811 -31.988706) (xy 459.410308 -32.053276)
			(xy 459.409811 -32.117846) (xy 459.401861 -32.246741) (xy 459.385991 -32.374901) (xy 459.362262 -32.501842)
			(xy 459.330763 -32.627081) (xy 459.291614 -32.750144) (xy 459.244963 -32.870563) (xy 459.190988 -32.987882)
			(xy 459.129893 -33.101656) (xy 459.06191 -33.211453) (xy 458.987296 -33.316856) (xy 458.906335 -33.417466)
			(xy 458.819335 -33.512901) (xy 458.726624 -33.6028) (xy 458.628554 -33.686821) (xy 458.525499 -33.764645)
			(xy 458.417848 -33.835977) (xy 458.307206 -33.899856) (xy 461.798924 -33.899856) (xy 461.798924 -32.299656)
			(xy 461.799422 -32.222373) (xy 461.807378 -32.068013) (xy 461.823271 -31.914267) (xy 461.847057 -31.761543)
			(xy 461.878674 -31.610247) (xy 461.918037 -31.460778) (xy 461.965042 -31.313534) (xy 462.019566 -31.168904)
			(xy 462.081462 -31.027274) (xy 462.150567 -30.889017) (xy 462.226698 -30.754502) (xy 462.309652 -30.624083)
			(xy 462.399211 -30.498108) (xy 462.495135 -30.376911) (xy 462.597172 -30.260812) (xy 462.705049 -30.15012)
			(xy 462.818482 -30.045128) (xy 462.93717 -29.946115) (xy 463.060797 -29.853342) (xy 463.189036 -29.767057)
			(xy 463.321547 -29.687488) (xy 463.457979 -29.614846) (xy 463.597969 -29.549324) (xy 463.741146 -29.491095)
			(xy 463.887131 -29.440314) (xy 464.035537 -29.397115) (xy 464.185969 -29.361613) (xy 464.33803 -29.333903)
			(xy 464.491316 -29.314057) (xy 464.64542 -29.302128) (xy 464.799934 -29.298149) (xy 464.954448 -29.302128)
			(xy 465.108552 -29.314057) (xy 465.261838 -29.333903) (xy 465.413899 -29.361613) (xy 465.564331 -29.397115)
			(xy 465.712737 -29.440314) (xy 465.858722 -29.491095) (xy 466.001899 -29.549324) (xy 466.141889 -29.614846)
			(xy 466.278321 -29.687488) (xy 466.410832 -29.767057) (xy 466.539071 -29.853342) (xy 466.662698 -29.946115)
			(xy 466.781386 -30.045128) (xy 466.894819 -30.15012) (xy 467.002696 -30.260812) (xy 467.104733 -30.376911)
			(xy 467.200657 -30.498108) (xy 467.290216 -30.624083) (xy 467.37317 -30.754502) (xy 467.449301 -30.889017)
			(xy 467.518406 -31.027274) (xy 467.580302 -31.168904) (xy 467.634826 -31.313534) (xy 467.681831 -31.460778)
			(xy 467.721194 -31.610247) (xy 467.752811 -31.761543) (xy 467.776597 -31.914267) (xy 467.79249 -32.068013)
			(xy 467.800446 -32.222373) (xy 467.800944 -32.299656) (xy 467.800944 -33.899856) (xy 467.800446 -33.977139)
			(xy 467.79249 -34.131499) (xy 467.776597 -34.285245) (xy 467.752811 -34.437969) (xy 467.721194 -34.589265)
			(xy 467.681831 -34.738734) (xy 467.634826 -34.885978) (xy 467.580302 -35.030608) (xy 467.518406 -35.172238)
			(xy 467.449301 -35.310495) (xy 467.37317 -35.44501) (xy 467.290216 -35.575429) (xy 467.200657 -35.701404)
			(xy 467.104733 -35.822601) (xy 467.002696 -35.9387) (xy 466.894819 -36.049392) (xy 466.781386 -36.154384)
			(xy 466.662698 -36.253397) (xy 466.539071 -36.34617) (xy 466.410832 -36.432455) (xy 466.278321 -36.512024)
			(xy 466.141889 -36.584666) (xy 466.001899 -36.650188) (xy 465.858722 -36.708417) (xy 465.712737 -36.759198)
			(xy 465.564331 -36.802397) (xy 465.413899 -36.837899) (xy 465.261838 -36.865609) (xy 465.108552 -36.885455)
			(xy 464.954448 -36.897384) (xy 464.799934 -36.901364) (xy 464.64542 -36.897384) (xy 464.491316 -36.885455)
			(xy 464.33803 -36.865609) (xy 464.185969 -36.837899) (xy 464.035537 -36.802397) (xy 463.887131 -36.759198)
			(xy 463.741146 -36.708417) (xy 463.597969 -36.650188) (xy 463.457979 -36.584666) (xy 463.321547 -36.512024)
			(xy 463.189036 -36.432455) (xy 463.060797 -36.34617) (xy 462.93717 -36.253397) (xy 462.818482 -36.154384)
			(xy 462.705049 -36.049392) (xy 462.597172 -35.9387) (xy 462.495135 -35.822601) (xy 462.399211 -35.701404)
			(xy 462.309652 -35.575429) (xy 462.226698 -35.44501) (xy 462.150567 -35.310495) (xy 462.081462 -35.172238)
			(xy 462.019566 -35.030608) (xy 461.965042 -34.885978) (xy 461.918037 -34.738734) (xy 461.878674 -34.589265)
			(xy 461.847057 -34.437969) (xy 461.823271 -34.285245) (xy 461.807378 -34.131499) (xy 461.799422 -33.977139)
			(xy 461.798924 -33.899856) (xy 458.307206 -33.899856) (xy 458.306009 -33.900547) (xy 458.190408 -33.958109)
			(xy 458.071483 -34.008446) (xy 457.949684 -34.051366) (xy 457.825474 -34.086707) (xy 457.699325 -34.114334)
			(xy 457.571713 -34.134143) (xy 457.443124 -34.146059) (xy 457.314046 -34.150036) (xy 457.184968 -34.146059)
			(xy 457.056379 -34.134143) (xy 456.928767 -34.114334) (xy 456.802618 -34.086707) (xy 456.678408 -34.051366)
			(xy 456.556609 -34.008446) (xy 456.437684 -33.958109) (xy 456.322083 -33.900547) (xy 456.210244 -33.835977)
			(xy 456.102593 -33.764645) (xy 455.999538 -33.686821) (xy 455.901468 -33.6028) (xy 455.808757 -33.512901)
			(xy 455.721757 -33.417466) (xy 455.640796 -33.316856) (xy 455.566182 -33.211453) (xy 455.498199 -33.101656)
			(xy 455.437104 -32.987882) (xy 455.383129 -32.870563) (xy 455.336478 -32.750144) (xy 455.297329 -32.627081)
			(xy 455.26583 -32.501842) (xy 455.242101 -32.374901) (xy 455.226231 -32.246741) (xy 455.218281 -32.117846)
			(xy 259.309108 -32.117846) (xy 259.309108 -34.120074) (xy 259.308624 -34.190457) (xy 259.300733 -34.331001)
			(xy 259.284973 -34.470882) (xy 259.261395 -34.609659) (xy 259.230073 -34.746896) (xy 259.191105 -34.882161)
			(xy 259.144614 -35.015028) (xy 259.090747 -35.145079) (xy 259.029671 -35.271905) (xy 258.961581 -35.395107)
			(xy 258.88669 -35.514297) (xy 258.805233 -35.629101) (xy 258.717468 -35.739156) (xy 258.62367 -35.844118)
			(xy 258.524134 -35.943655) (xy 258.419173 -36.037454) (xy 258.309118 -36.12522) (xy 258.194315 -36.206678)
			(xy 258.075126 -36.28157) (xy 257.951924 -36.349661) (xy 257.825099 -36.410738) (xy 257.695048 -36.464606)
			(xy 257.562182 -36.511099) (xy 257.426917 -36.550068) (xy 257.289681 -36.581391) (xy 257.150904 -36.60497)
			(xy 257.011023 -36.620731) (xy 256.870479 -36.628623) (xy 256.800096 -36.629086) (xy 225.300032 -36.629086)
			(xy 225.229649 -36.628602) (xy 225.089105 -36.620711) (xy 224.949224 -36.604952) (xy 224.810447 -36.581374)
			(xy 224.673211 -36.550052) (xy 224.537946 -36.511084) (xy 224.40508 -36.464594) (xy 224.275029 -36.410726)
			(xy 224.148203 -36.349651) (xy 224.025001 -36.28156) (xy 223.905811 -36.206669) (xy 223.791008 -36.125213)
			(xy 223.680953 -36.037447) (xy 223.575992 -35.943648) (xy 223.476456 -35.844112) (xy 223.382657 -35.739152)
			(xy 223.294891 -35.629097) (xy 223.213434 -35.514294) (xy 223.138543 -35.395104) (xy 223.070452 -35.271902)
			(xy 223.009377 -35.145077) (xy 222.955509 -35.015026) (xy 222.909017 -34.882159) (xy 222.870049 -34.746895)
			(xy 222.838727 -34.609659) (xy 222.815149 -34.470882) (xy 222.799389 -34.331001) (xy 222.791498 -34.190457)
			(xy 222.79102 -34.120074) (xy 222.79102 -13.780008) (xy 222.790499 -13.724238) (xy 222.782164 -13.613011)
			(xy 222.765541 -13.502717) (xy 222.740722 -13.393974) (xy 222.707846 -13.287389) (xy 222.667097 -13.183559)
			(xy 222.618703 -13.083065) (xy 222.562935 -12.986469) (xy 222.500103 -12.894309) (xy 222.430561 -12.807103)
			(xy 222.354696 -12.725338) (xy 222.272933 -12.64947) (xy 222.185729 -12.579925) (xy 222.093572 -12.517091)
			(xy 221.996977 -12.461319) (xy 221.896485 -12.412922) (xy 221.792656 -12.37217) (xy 221.686073 -12.339291)
			(xy 221.57733 -12.314468) (xy 221.467037 -12.297841) (xy 221.35581 -12.289503) (xy 221.30004 -12.289028)
			(xy 196.701918 -12.289028) (xy 196.631535 -12.288544) (xy 196.49099 -12.280652) (xy 196.35111 -12.264892)
			(xy 196.212332 -12.241314) (xy 196.075095 -12.209992) (xy 195.939831 -12.171024) (xy 195.806964 -12.124532)
			(xy 195.676913 -12.070665) (xy 195.550086 -12.009589) (xy 195.426884 -11.941499) (xy 195.307694 -11.866608)
			(xy 195.19289 -11.785152) (xy 195.082834 -11.697386) (xy 194.977873 -11.603588) (xy 194.878335 -11.504052)
			(xy 194.784536 -11.399092) (xy 194.696769 -11.289037) (xy 194.615311 -11.174234) (xy 194.540418 -11.055045)
			(xy 194.472326 -10.931844) (xy 194.411249 -10.805018) (xy 194.35738 -10.674968) (xy 194.310887 -10.542102)
			(xy 194.271917 -10.406837) (xy 194.240593 -10.269601) (xy 194.217013 -10.130824) (xy 194.201251 -9.990943)
			(xy 194.193357 -9.850399) (xy 194.192906 -9.780016) (xy 194.192906 -5.839714) (xy 194.192489 -5.82969)
			(xy 194.184822 -5.811168) (xy 194.170649 -5.79699) (xy 194.152129 -5.789315) (xy 194.142106 -5.788914)
			(xy 126.661926 -5.788914) (xy 126.651902 -5.789329) (xy 126.633379 -5.796995) (xy 126.619202 -5.811169)
			(xy 126.611531 -5.82969) (xy 126.611126 -5.839714) (xy 126.611126 -9.780016) (xy 126.610632 -9.850398)
			(xy 126.602738 -9.990941) (xy 126.586977 -10.13082) (xy 126.563397 -10.269595) (xy 126.532074 -10.40683)
			(xy 126.51969 -10.449814) (xy 127.350019 -10.449814) (xy 127.354025 -10.361883) (xy 127.366011 -10.27468)
			(xy 127.385876 -10.188928) (xy 127.413458 -10.105338) (xy 127.448526 -10.024603) (xy 127.490791 -9.947391)
			(xy 127.539902 -9.874342) (xy 127.595452 -9.806062) (xy 127.656981 -9.743116) (xy 127.723979 -9.686027)
			(xy 127.79589 -9.635266) (xy 127.87212 -9.591254) (xy 127.952036 -9.554357) (xy 128.034977 -9.52488)
			(xy 128.120254 -9.503068) (xy 128.207161 -9.4891) (xy 128.294979 -9.483093) (xy 128.382978 -9.485097)
			(xy 128.470431 -9.495094) (xy 128.556613 -9.513003) (xy 128.640809 -9.538675) (xy 128.722322 -9.571896)
			(xy 128.800476 -9.612392) (xy 128.874623 -9.659827) (xy 128.94415 -9.713809) (xy 129.008481 -9.773889)
			(xy 129.067081 -9.83957) (xy 129.119465 -9.910308) (xy 129.165201 -9.985516) (xy 129.203907 -10.064572)
			(xy 129.235265 -10.146819) (xy 129.259013 -10.231578) (xy 129.26619 -10.270552) (xy 131.639267 -10.270552)
			(xy 131.639267 -10.216048) (xy 131.647024 -10.162097) (xy 131.66238 -10.1098) (xy 131.685023 -10.060221)
			(xy 131.714491 -10.014369) (xy 131.750185 -9.973177) (xy 131.791377 -9.937485) (xy 131.83723 -9.908018)
			(xy 131.88681 -9.885377) (xy 131.939107 -9.870022) (xy 131.993058 -9.862267) (xy 132.02031 -9.861804)
			(xy 132.88391 -9.861804) (xy 132.911162 -9.862266) (xy 132.96511 -9.870024) (xy 133.017405 -9.885381)
			(xy 133.066983 -9.908023) (xy 133.112833 -9.937491) (xy 133.154024 -9.973183) (xy 133.189715 -10.014375)
			(xy 133.219181 -10.060226) (xy 133.241823 -10.109804) (xy 133.257178 -10.1621) (xy 133.264934 -10.216048)
			(xy 133.264934 -10.270552) (xy 133.257178 -10.3245) (xy 133.241823 -10.376796) (xy 133.219181 -10.426374)
			(xy 133.189715 -10.472225) (xy 133.154024 -10.513417) (xy 133.112833 -10.549109) (xy 133.066983 -10.578577)
			(xy 133.017405 -10.601219) (xy 132.96511 -10.616576) (xy 132.911162 -10.624334) (xy 132.88391 -10.62482)
			(xy 132.02031 -10.62482) (xy 131.993058 -10.624333) (xy 131.939107 -10.616578) (xy 131.88681 -10.601223)
			(xy 131.83723 -10.578582) (xy 131.791377 -10.549115) (xy 131.750185 -10.513423) (xy 131.714491 -10.472231)
			(xy 131.685023 -10.426379) (xy 131.66238 -10.3768) (xy 131.647024 -10.324503) (xy 131.639267 -10.270552)
			(xy 129.26619 -10.270552) (xy 129.274955 -10.318145) (xy 129.282959 -10.405803) (xy 129.28346 -10.449814)
			(xy 129.282959 -10.493825) (xy 129.274955 -10.581483) (xy 129.259013 -10.66805) (xy 129.235265 -10.752809)
			(xy 129.212257 -10.813156) (xy 169.954611 -10.813156) (xy 169.954611 -10.758644) (xy 169.962369 -10.704687)
			(xy 169.977727 -10.652382) (xy 170.000372 -10.602796) (xy 170.029844 -10.556938) (xy 170.065542 -10.51574)
			(xy 170.106739 -10.480043) (xy 170.152598 -10.450571) (xy 170.202184 -10.427926) (xy 170.254488 -10.412568)
			(xy 170.308446 -10.404811) (xy 170.335702 -10.404348) (xy 171.199302 -10.404348) (xy 171.22655 -10.404922)
			(xy 171.280491 -10.412678) (xy 171.33278 -10.428032) (xy 171.382351 -10.45067) (xy 171.428196 -10.480133)
			(xy 171.469381 -10.515821) (xy 171.505068 -10.557006) (xy 171.534531 -10.602851) (xy 171.557169 -10.652422)
			(xy 171.572522 -10.704711) (xy 171.580278 -10.758652) (xy 171.580278 -10.813148) (xy 171.572522 -10.867089)
			(xy 171.557169 -10.919378) (xy 171.534531 -10.968949) (xy 171.505068 -11.014794) (xy 171.469381 -11.055979)
			(xy 171.428196 -11.091667) (xy 171.382351 -11.12113) (xy 171.33278 -11.143768) (xy 171.280491 -11.159122)
			(xy 171.22655 -11.166878) (xy 171.199302 -11.167364) (xy 170.335702 -11.167364) (xy 170.308446 -11.166989)
			(xy 170.254488 -11.159232) (xy 170.202184 -11.143874) (xy 170.152598 -11.121229) (xy 170.106739 -11.091757)
			(xy 170.065542 -11.05606) (xy 170.029844 -11.014862) (xy 170.000372 -10.969004) (xy 169.977727 -10.919418)
			(xy 169.962369 -10.867113) (xy 169.954611 -10.813156) (xy 129.212257 -10.813156) (xy 129.203907 -10.835056)
			(xy 129.165201 -10.914112) (xy 129.119465 -10.98932) (xy 129.067081 -11.060058) (xy 129.008481 -11.125739)
			(xy 128.94415 -11.185819) (xy 128.874623 -11.239801) (xy 128.800476 -11.287236) (xy 128.722322 -11.327732)
			(xy 128.640809 -11.360953) (xy 128.556613 -11.386625) (xy 128.470431 -11.404534) (xy 128.382978 -11.414531)
			(xy 128.294979 -11.416535) (xy 128.207161 -11.410528) (xy 128.120254 -11.39656) (xy 128.034977 -11.374748)
			(xy 127.952036 -11.345271) (xy 127.87212 -11.308374) (xy 127.79589 -11.264362) (xy 127.723979 -11.213601)
			(xy 127.656981 -11.156512) (xy 127.595452 -11.093566) (xy 127.539902 -11.025286) (xy 127.490791 -10.952237)
			(xy 127.448526 -10.875025) (xy 127.413458 -10.79429) (xy 127.385876 -10.7107) (xy 127.366011 -10.624948)
			(xy 127.354025 -10.537745) (xy 127.350019 -10.449814) (xy 126.51969 -10.449814) (xy 126.493105 -10.542092)
			(xy 126.446613 -10.674957) (xy 126.392744 -10.805006) (xy 126.331668 -10.93183) (xy 126.263578 -11.05503)
			(xy 126.188687 -11.174218) (xy 126.10723 -11.28902) (xy 126.019465 -11.399074) (xy 125.925667 -11.504033)
			(xy 125.826132 -11.603569) (xy 125.721172 -11.697366) (xy 125.611118 -11.785131) (xy 125.496317 -11.866588)
			(xy 125.495706 -11.866972) (xy 129.833804 -11.866972) (xy 129.833804 -11.812428) (xy 129.841567 -11.758438)
			(xy 129.856934 -11.706103) (xy 129.879594 -11.656488) (xy 129.909085 -11.610603) (xy 129.944805 -11.569383)
			(xy 129.986029 -11.533665) (xy 130.031916 -11.504179) (xy 130.081533 -11.481523) (xy 130.13387 -11.46616)
			(xy 130.18786 -11.458401) (xy 130.215132 -11.45794) (xy 131.078732 -11.45794) (xy 131.106 -11.458425)
			(xy 131.15998 -11.46619) (xy 131.212306 -11.481558) (xy 131.261913 -11.504216) (xy 131.30779 -11.533703)
			(xy 131.349004 -11.569419) (xy 131.384716 -11.610636) (xy 131.414199 -11.656515) (xy 131.436853 -11.706124)
			(xy 131.452217 -11.758451) (xy 131.459978 -11.812432) (xy 131.459978 -11.866968) (xy 131.452217 -11.920949)
			(xy 131.436853 -11.973276) (xy 131.432747 -11.982267) (xy 135.233942 -11.982267) (xy 135.233942 -11.927733)
			(xy 135.241703 -11.873755) (xy 135.257066 -11.82143) (xy 135.279719 -11.771824) (xy 135.309201 -11.725946)
			(xy 135.344912 -11.684731) (xy 135.386124 -11.649018) (xy 135.431999 -11.619533) (xy 135.481603 -11.596876)
			(xy 135.533927 -11.581509) (xy 135.587905 -11.573744) (xy 135.615172 -11.573256) (xy 136.478772 -11.573256)
			(xy 136.506046 -11.573682) (xy 136.560038 -11.581441) (xy 136.612377 -11.596805) (xy 136.661996 -11.619462)
			(xy 136.707885 -11.648951) (xy 136.74911 -11.68467) (xy 136.784832 -11.725893) (xy 136.814324 -11.77178)
			(xy 136.836985 -11.821397) (xy 136.852353 -11.873735) (xy 136.860116 -11.927726) (xy 136.860116 -11.982274)
			(xy 136.852353 -12.036265) (xy 136.836985 -12.088603) (xy 136.814324 -12.13822) (xy 136.784832 -12.184107)
			(xy 136.74911 -12.22533) (xy 136.707885 -12.261049) (xy 136.661996 -12.290538) (xy 136.612377 -12.313195)
			(xy 136.560038 -12.328559) (xy 136.506046 -12.336318) (xy 136.478772 -12.33678) (xy 135.615172 -12.33678)
			(xy 135.587905 -12.336256) (xy 135.533927 -12.328491) (xy 135.481603 -12.313124) (xy 135.431999 -12.290467)
			(xy 135.386124 -12.260982) (xy 135.344912 -12.225269) (xy 135.309201 -12.184054) (xy 135.279719 -12.138176)
			(xy 135.257066 -12.08857) (xy 135.241703 -12.036245) (xy 135.233942 -11.982267) (xy 131.432747 -11.982267)
			(xy 131.414199 -12.022885) (xy 131.384716 -12.068764) (xy 131.349004 -12.109981) (xy 131.30779 -12.145697)
			(xy 131.261913 -12.175184) (xy 131.212306 -12.197842) (xy 131.15998 -12.21321) (xy 131.106 -12.220975)
			(xy 131.078732 -12.221464) (xy 130.215132 -12.221464) (xy 130.18786 -12.220999) (xy 130.13387 -12.21324)
			(xy 130.081533 -12.197877) (xy 130.031916 -12.175221) (xy 129.986029 -12.145735) (xy 129.944805 -12.110017)
			(xy 129.909085 -12.068797) (xy 129.879594 -12.022912) (xy 129.856934 -11.973297) (xy 129.841567 -11.920962)
			(xy 129.833804 -11.866972) (xy 125.495706 -11.866972) (xy 125.377128 -11.941479) (xy 125.253928 -12.009569)
			(xy 125.127104 -12.070645) (xy 124.997055 -12.124513) (xy 124.86419 -12.171005) (xy 124.728928 -12.209974)
			(xy 124.591693 -12.241298) (xy 124.452918 -12.264877) (xy 124.313039 -12.280639) (xy 124.172496 -12.288532)
			(xy 124.102114 -12.289028) (xy 83.70189 -12.289028) (xy 83.631508 -12.288534) (xy 83.490965 -12.280641)
			(xy 83.351086 -12.26488) (xy 83.21231 -12.2413) (xy 83.075075 -12.209977) (xy 82.939812 -12.171008)
			(xy 82.806947 -12.124516) (xy 82.676898 -12.070648) (xy 82.550073 -12.009572) (xy 82.426873 -11.941482)
			(xy 82.307684 -11.866591) (xy 82.192882 -11.785134) (xy 82.082828 -11.697369) (xy 81.977868 -11.603571)
			(xy 81.878333 -11.504036) (xy 81.784535 -11.399076) (xy 81.696769 -11.289022) (xy 81.615313 -11.174221)
			(xy 81.540421 -11.055032) (xy 81.47233 -10.931832) (xy 81.411254 -10.805008) (xy 81.357386 -10.674959)
			(xy 81.310894 -10.542094) (xy 81.271924 -10.406831) (xy 81.240601 -10.269596) (xy 81.217021 -10.13082)
			(xy 81.20126 -9.990941) (xy 81.193366 -9.850398) (xy 81.192878 -9.780016) (xy 81.192878 -0.559816)
			(xy 81.192461 -0.549794) (xy 81.184793 -0.531276) (xy 81.170619 -0.517104) (xy 81.1521 -0.509438)
			(xy 81.142078 -0.509016) (xy 13.661898 -0.509016) (xy 13.651878 -0.509436) (xy 13.633365 -0.517107)
			(xy 13.619197 -0.53128) (xy 13.611532 -0.549796) (xy 13.611098 -0.559816) (xy 13.611098 -5.169916)
			(xy 14.349991 -5.169916) (xy 14.353997 -5.081985) (xy 14.365983 -4.994782) (xy 14.385848 -4.90903)
			(xy 14.41343 -4.82544) (xy 14.448498 -4.744705) (xy 14.490763 -4.667493) (xy 14.539874 -4.594444)
			(xy 14.595424 -4.526164) (xy 14.656953 -4.463218) (xy 14.723951 -4.406129) (xy 14.795862 -4.355368)
			(xy 14.872092 -4.311356) (xy 14.952008 -4.274459) (xy 15.034949 -4.244982) (xy 15.120226 -4.22317)
			(xy 15.207133 -4.209202) (xy 15.294951 -4.203195) (xy 15.38295 -4.205199) (xy 15.470403 -4.215196)
			(xy 15.556585 -4.233105) (xy 15.640781 -4.258777) (xy 15.722294 -4.291998) (xy 15.800448 -4.332494)
			(xy 15.874595 -4.379929) (xy 15.944122 -4.433911) (xy 16.008453 -4.493991) (xy 16.067053 -4.559672)
			(xy 16.119437 -4.63041) (xy 16.165173 -4.705618) (xy 16.203879 -4.784674) (xy 16.235237 -4.866921)
			(xy 16.258985 -4.95168) (xy 16.266165 -4.990667) (xy 20.439138 -4.990667) (xy 20.439138 -4.936133)
			(xy 20.446899 -4.882153) (xy 20.462263 -4.829827) (xy 20.484917 -4.78022) (xy 20.5144 -4.734341)
			(xy 20.550112 -4.693126) (xy 20.591325 -4.657412) (xy 20.637202 -4.627926) (xy 20.686808 -4.60527)
			(xy 20.739133 -4.589903) (xy 20.793113 -4.58214) (xy 20.82038 -4.581652) (xy 21.68398 -4.581652)
			(xy 21.711253 -4.582086) (xy 21.765244 -4.589846) (xy 21.817581 -4.605211) (xy 21.867198 -4.627869)
			(xy 21.913086 -4.657357) (xy 21.95431 -4.693076) (xy 21.990031 -4.734298) (xy 22.019522 -4.780184)
			(xy 22.042182 -4.8298) (xy 22.057549 -4.882136) (xy 22.065312 -4.936127) (xy 22.065312 -4.990671)
			(xy 24.039016 -4.990671) (xy 24.039016 -4.936129) (xy 24.046778 -4.882142) (xy 24.062145 -4.82981)
			(xy 24.084803 -4.780197) (xy 24.114292 -4.734314) (xy 24.15001 -4.693095) (xy 24.191231 -4.657379)
			(xy 24.237116 -4.627893) (xy 24.28673 -4.605237) (xy 24.339064 -4.589873) (xy 24.393051 -4.582114)
			(xy 24.420322 -4.581652) (xy 25.283922 -4.581652) (xy 25.311191 -4.582112) (xy 25.365175 -4.589876)
			(xy 25.417503 -4.605244) (xy 25.467113 -4.627903) (xy 25.512992 -4.65739) (xy 25.554209 -4.693107)
			(xy 25.589923 -4.734325) (xy 25.619408 -4.780207) (xy 25.642063 -4.829817) (xy 25.657428 -4.882147)
			(xy 25.66519 -4.936131) (xy 25.66519 -4.990667) (xy 27.639038 -4.990667) (xy 27.639038 -4.936133)
			(xy 27.646799 -4.882155) (xy 27.662162 -4.82983) (xy 27.684814 -4.780224) (xy 27.714296 -4.734347)
			(xy 27.750006 -4.693131) (xy 27.791218 -4.657417) (xy 27.837092 -4.627932) (xy 27.886696 -4.605274)
			(xy 27.93902 -4.589906) (xy 27.992997 -4.582141) (xy 28.020264 -4.581652) (xy 28.883864 -4.581652)
			(xy 28.911138 -4.582085) (xy 28.96513 -4.589843) (xy 29.017469 -4.605207) (xy 29.067089 -4.627863)
			(xy 29.112979 -4.657351) (xy 29.154205 -4.69307) (xy 29.189927 -4.734292) (xy 29.219419 -4.78018)
			(xy 29.24208 -4.829797) (xy 29.257449 -4.882134) (xy 29.265212 -4.936126) (xy 29.265212 -4.990667)
			(xy 31.239238 -4.990667) (xy 31.239238 -4.936133) (xy 31.246999 -4.882155) (xy 31.262361 -4.829831)
			(xy 31.285014 -4.780225) (xy 31.314495 -4.734348) (xy 31.350205 -4.693133) (xy 31.391416 -4.657419)
			(xy 31.43729 -4.627933) (xy 31.486893 -4.605275) (xy 31.539216 -4.589907) (xy 31.593193 -4.582141)
			(xy 31.62046 -4.581652) (xy 32.48406 -4.581652) (xy 32.511334 -4.582085) (xy 32.565327 -4.589843)
			(xy 32.617666 -4.605206) (xy 32.667286 -4.627862) (xy 32.713177 -4.65735) (xy 32.754403 -4.693068)
			(xy 32.790126 -4.734291) (xy 32.819619 -4.780178) (xy 32.84228 -4.829796) (xy 32.857649 -4.882134)
			(xy 32.865412 -4.936126) (xy 32.865412 -4.990671) (xy 40.349116 -4.990671) (xy 40.349116 -4.936129)
			(xy 40.356878 -4.882142) (xy 40.372245 -4.829809) (xy 40.394903 -4.780196) (xy 40.424392 -4.734313)
			(xy 40.460111 -4.693094) (xy 40.501332 -4.657378) (xy 40.547217 -4.627892) (xy 40.596832 -4.605237)
			(xy 40.649165 -4.589873) (xy 40.703153 -4.582114) (xy 40.730424 -4.581652) (xy 41.594024 -4.581652)
			(xy 41.621293 -4.582112) (xy 41.675276 -4.589877) (xy 41.727605 -4.605245) (xy 41.777214 -4.627903)
			(xy 41.823093 -4.657391) (xy 41.86431 -4.693107) (xy 41.900024 -4.734326) (xy 41.929508 -4.780207)
			(xy 41.952164 -4.829818) (xy 41.967528 -4.882147) (xy 41.97529 -4.936131) (xy 41.97529 -4.990667)
			(xy 43.949138 -4.990667) (xy 43.949138 -4.936133) (xy 43.956899 -4.882155) (xy 43.972262 -4.82983)
			(xy 43.994915 -4.780224) (xy 44.024396 -4.734346) (xy 44.060107 -4.693131) (xy 44.101319 -4.657417)
			(xy 44.147194 -4.627931) (xy 44.196798 -4.605274) (xy 44.249121 -4.589906) (xy 44.303099 -4.582141)
			(xy 44.330366 -4.581652) (xy 45.193966 -4.581652) (xy 45.22124 -4.582085) (xy 45.275232 -4.589844)
			(xy 45.327571 -4.605208) (xy 45.37719 -4.627864) (xy 45.42308 -4.657352) (xy 45.464305 -4.693071)
			(xy 45.500028 -4.734293) (xy 45.52952 -4.78018) (xy 45.552181 -4.829797) (xy 45.567549 -4.882135)
			(xy 45.575312 -4.936126) (xy 45.575312 -4.990667) (xy 51.559238 -4.990667) (xy 51.559238 -4.936133)
			(xy 51.566999 -4.882155) (xy 51.582361 -4.829831) (xy 51.605014 -4.780225) (xy 51.634495 -4.734348)
			(xy 51.670205 -4.693133) (xy 51.711416 -4.657419) (xy 51.75729 -4.627933) (xy 51.806893 -4.605275)
			(xy 51.859216 -4.589907) (xy 51.913193 -4.582141) (xy 51.94046 -4.581652) (xy 52.80406 -4.581652)
			(xy 52.831334 -4.582085) (xy 52.885327 -4.589843) (xy 52.937666 -4.605206) (xy 52.987286 -4.627862)
			(xy 53.033177 -4.65735) (xy 53.074403 -4.693068) (xy 53.110126 -4.734291) (xy 53.139619 -4.780178)
			(xy 53.16228 -4.829796) (xy 53.177649 -4.882134) (xy 53.185412 -4.936126) (xy 53.185412 -4.99067)
			(xy 55.159115 -4.99067) (xy 55.159115 -4.93613) (xy 55.166877 -4.882145) (xy 55.182243 -4.829814)
			(xy 55.2049 -4.780202) (xy 55.234387 -4.73432) (xy 55.270103 -4.693102) (xy 55.311322 -4.657386)
			(xy 55.357204 -4.627899) (xy 55.406816 -4.605242) (xy 55.459147 -4.589877) (xy 55.513132 -4.582115)
			(xy 55.540402 -4.581652) (xy 56.404002 -4.581652) (xy 56.431272 -4.582111) (xy 56.485258 -4.589873)
			(xy 56.537589 -4.605239) (xy 56.587201 -4.627896) (xy 56.633083 -4.657383) (xy 56.674302 -4.6931)
			(xy 56.710018 -4.734319) (xy 56.739505 -4.780201) (xy 56.762162 -4.829813) (xy 56.777528 -4.882144)
			(xy 56.78529 -4.93613) (xy 56.78529 -4.99067) (xy 56.777528 -5.044656) (xy 56.762162 -5.096987) (xy 56.739505 -5.146599)
			(xy 56.710018 -5.192481) (xy 56.674302 -5.2337) (xy 56.633083 -5.269417) (xy 56.587201 -5.298904)
			(xy 56.537589 -5.321561) (xy 56.485258 -5.336927) (xy 56.431272 -5.344689) (xy 56.404002 -5.345176)
			(xy 55.540402 -5.345176) (xy 55.513132 -5.344685) (xy 55.459147 -5.336923) (xy 55.406816 -5.321558)
			(xy 55.357204 -5.298901) (xy 55.311322 -5.269414) (xy 55.270103 -5.233698) (xy 55.234387 -5.19248)
			(xy 55.2049 -5.146598) (xy 55.182243 -5.096986) (xy 55.166877 -5.044655) (xy 55.159115 -4.99067)
			(xy 53.185412 -4.99067) (xy 53.185412 -4.990674) (xy 53.177649 -5.044666) (xy 53.16228 -5.097004)
			(xy 53.139619 -5.146622) (xy 53.110126 -5.192509) (xy 53.074403 -5.233732) (xy 53.033177 -5.26945)
			(xy 52.987286 -5.298938) (xy 52.937666 -5.321594) (xy 52.885327 -5.336957) (xy 52.831334 -5.344715)
			(xy 52.80406 -5.345176) (xy 51.94046 -5.345176) (xy 51.913194 -5.344659) (xy 51.859216 -5.336893)
			(xy 51.806893 -5.321525) (xy 51.75729 -5.298867) (xy 51.711416 -5.269381) (xy 51.670205 -5.233667)
			(xy 51.634495 -5.192452) (xy 51.605014 -5.146575) (xy 51.582361 -5.096969) (xy 51.566999 -5.044645)
			(xy 51.559238 -4.990667) (xy 45.575312 -4.990667) (xy 45.575312 -4.990674) (xy 45.567549 -5.044665)
			(xy 45.552181 -5.097003) (xy 45.52952 -5.14662) (xy 45.500028 -5.192507) (xy 45.464305 -5.233729)
			(xy 45.42308 -5.269448) (xy 45.37719 -5.298936) (xy 45.327571 -5.321592) (xy 45.275232 -5.336956)
			(xy 45.22124 -5.344715) (xy 45.193966 -5.345176) (xy 44.330366 -5.345176) (xy 44.303099 -5.344659)
			(xy 44.249121 -5.336894) (xy 44.196798 -5.321526) (xy 44.147194 -5.298869) (xy 44.101319 -5.269383)
			(xy 44.060107 -5.233669) (xy 44.024396 -5.192454) (xy 43.994915 -5.146576) (xy 43.972262 -5.09697)
			(xy 43.956899 -5.044645) (xy 43.949138 -4.990667) (xy 41.97529 -4.990667) (xy 41.97529 -4.990669)
			(xy 41.967528 -5.044653) (xy 41.952164 -5.096982) (xy 41.929508 -5.146593) (xy 41.900024 -5.192474)
			(xy 41.86431 -5.233693) (xy 41.823093 -5.269409) (xy 41.777214 -5.298897) (xy 41.727605 -5.321555)
			(xy 41.675276 -5.336923) (xy 41.621293 -5.344688) (xy 41.594024 -5.345176) (xy 40.730424 -5.345176)
			(xy 40.703153 -5.344686) (xy 40.649165 -5.336927) (xy 40.596832 -5.321563) (xy 40.547217 -5.298908)
			(xy 40.501332 -5.269422) (xy 40.460111 -5.233706) (xy 40.424392 -5.192487) (xy 40.394903 -5.146604)
			(xy 40.372245 -5.096991) (xy 40.356878 -5.044658) (xy 40.349116 -4.990671) (xy 32.865412 -4.990671)
			(xy 32.865412 -4.990674) (xy 32.857649 -5.044666) (xy 32.84228 -5.097004) (xy 32.819619 -5.146622)
			(xy 32.790126 -5.192509) (xy 32.754403 -5.233732) (xy 32.713177 -5.26945) (xy 32.667286 -5.298938)
			(xy 32.617666 -5.321594) (xy 32.565327 -5.336957) (xy 32.511334 -5.344715) (xy 32.48406 -5.345176)
			(xy 31.62046 -5.345176) (xy 31.593194 -5.344659) (xy 31.539216 -5.336893) (xy 31.486893 -5.321525)
			(xy 31.43729 -5.298867) (xy 31.391416 -5.269381) (xy 31.350205 -5.233667) (xy 31.314495 -5.192452)
			(xy 31.285014 -5.146575) (xy 31.262361 -5.096969) (xy 31.246999 -5.044645) (xy 31.239238 -4.990667)
			(xy 29.265212 -4.990667) (xy 29.265212 -4.990674) (xy 29.257449 -5.044666) (xy 29.24208 -5.097003)
			(xy 29.219419 -5.14662) (xy 29.189927 -5.192508) (xy 29.154205 -5.23373) (xy 29.112979 -5.269449)
			(xy 29.067089 -5.298937) (xy 29.017469 -5.321593) (xy 28.96513 -5.336957) (xy 28.911138 -5.344715)
			(xy 28.883864 -5.345176) (xy 28.020264 -5.345176) (xy 27.992997 -5.344659) (xy 27.93902 -5.336894)
			(xy 27.886696 -5.321526) (xy 27.837092 -5.298868) (xy 27.791218 -5.269383) (xy 27.750006 -5.233669)
			(xy 27.714296 -5.192453) (xy 27.684814 -5.146576) (xy 27.662162 -5.09697) (xy 27.646799 -5.044645)
			(xy 27.639038 -4.990667) (xy 25.66519 -4.990667) (xy 25.66519 -4.990669) (xy 25.657428 -5.044653)
			(xy 25.642063 -5.096983) (xy 25.619408 -5.146593) (xy 25.589923 -5.192475) (xy 25.554209 -5.233693)
			(xy 25.512992 -5.26941) (xy 25.467113 -5.298897) (xy 25.417503 -5.321556) (xy 25.365175 -5.336924)
			(xy 25.311191 -5.344688) (xy 25.283922 -5.345176) (xy 24.420322 -5.345176) (xy 24.393051 -5.344686)
			(xy 24.339064 -5.336927) (xy 24.28673 -5.321563) (xy 24.237116 -5.298907) (xy 24.191231 -5.269421)
			(xy 24.15001 -5.233705) (xy 24.114292 -5.192486) (xy 24.084803 -5.146603) (xy 24.062145 -5.09699)
			(xy 24.046778 -5.044658) (xy 24.039016 -4.990671) (xy 22.065312 -4.990671) (xy 22.065312 -4.990673)
			(xy 22.057549 -5.044664) (xy 22.042182 -5.097) (xy 22.019522 -5.146616) (xy 21.990031 -5.192502)
			(xy 21.95431 -5.233724) (xy 21.913086 -5.269443) (xy 21.867198 -5.298931) (xy 21.817581 -5.321589)
			(xy 21.765244 -5.336954) (xy 21.711253 -5.344714) (xy 21.68398 -5.345176) (xy 20.82038 -5.345176)
			(xy 20.793113 -5.34466) (xy 20.739133 -5.336897) (xy 20.686808 -5.32153) (xy 20.637202 -5.298874)
			(xy 20.591325 -5.269388) (xy 20.550112 -5.233674) (xy 20.5144 -5.192459) (xy 20.484917 -5.14658)
			(xy 20.462263 -5.096973) (xy 20.446899 -5.044647) (xy 20.439138 -4.990667) (xy 16.266165 -4.990667)
			(xy 16.274927 -5.038247) (xy 16.282931 -5.125905) (xy 16.283432 -5.169916) (xy 16.282931 -5.213927)
			(xy 16.274927 -5.301585) (xy 16.258985 -5.388152) (xy 16.235237 -5.472911) (xy 16.203879 -5.555158)
			(xy 16.165173 -5.634214) (xy 16.119437 -5.709422) (xy 16.067053 -5.78016) (xy 16.008453 -5.845841)
			(xy 15.944122 -5.905921) (xy 15.874595 -5.959903) (xy 15.800448 -6.007338) (xy 15.722294 -6.047834)
			(xy 15.640781 -6.081055) (xy 15.556585 -6.106727) (xy 15.470403 -6.124636) (xy 15.38295 -6.134633)
			(xy 15.294951 -6.136637) (xy 15.207133 -6.13063) (xy 15.120226 -6.116662) (xy 15.034949 -6.09485)
			(xy 14.952008 -6.065373) (xy 14.872092 -6.028476) (xy 14.795862 -5.984464) (xy 14.723951 -5.933703)
			(xy 14.656953 -5.876614) (xy 14.595424 -5.813668) (xy 14.539874 -5.745388) (xy 14.490763 -5.672339)
			(xy 14.448498 -5.595127) (xy 14.41343 -5.514392) (xy 14.385848 -5.430802) (xy 14.365983 -5.34505)
			(xy 14.353997 -5.257847) (xy 14.349991 -5.169916) (xy 13.611098 -5.169916) (xy 13.611098 -6.169914)
			(xy 78.515217 -6.169914) (xy 78.519222 -6.082006) (xy 78.531205 -5.994826) (xy 78.551065 -5.909097)
			(xy 78.57864 -5.825529) (xy 78.613699 -5.744815) (xy 78.655952 -5.667623) (xy 78.70505 -5.594594)
			(xy 78.760586 -5.526332) (xy 78.822098 -5.463402) (xy 78.889079 -5.406328) (xy 78.960972 -5.35558)
			(xy 79.037181 -5.31158) (xy 79.117076 -5.274693) (xy 79.199995 -5.245224) (xy 79.28525 -5.223417)
			(xy 79.372134 -5.209453) (xy 79.459928 -5.203447) (xy 79.547905 -5.205451) (xy 79.635335 -5.215446)
			(xy 79.721494 -5.23335) (xy 79.805668 -5.259014) (xy 79.887159 -5.292227) (xy 79.965293 -5.332713)
			(xy 80.039421 -5.380135) (xy 80.108929 -5.434102) (xy 80.173243 -5.494167) (xy 80.231827 -5.559831)
			(xy 80.284198 -5.63055) (xy 80.329921 -5.705738) (xy 80.368618 -5.784773) (xy 80.399967 -5.866999)
			(xy 80.423709 -5.951735) (xy 80.439647 -6.038279) (xy 80.447649 -6.125914) (xy 80.44815 -6.169914)
			(xy 80.447649 -6.213914) (xy 80.439647 -6.301549) (xy 80.423709 -6.388093) (xy 80.399967 -6.472829)
			(xy 80.368618 -6.555055) (xy 80.329921 -6.63409) (xy 80.284198 -6.709278) (xy 80.231827 -6.779997)
			(xy 80.173243 -6.845661) (xy 80.108929 -6.905726) (xy 80.039421 -6.959693) (xy 79.965293 -7.007115)
			(xy 79.887159 -7.047601) (xy 79.805668 -7.080814) (xy 79.721494 -7.106478) (xy 79.635335 -7.124382)
			(xy 79.547905 -7.134377) (xy 79.459928 -7.136381) (xy 79.372134 -7.130375) (xy 79.28525 -7.116411)
			(xy 79.199995 -7.094604) (xy 79.117076 -7.065135) (xy 79.037181 -7.028248) (xy 78.960972 -6.984248)
			(xy 78.889079 -6.9335) (xy 78.822098 -6.876426) (xy 78.760586 -6.813496) (xy 78.70505 -6.745234)
			(xy 78.655952 -6.672205) (xy 78.613699 -6.595013) (xy 78.57864 -6.514299) (xy 78.551065 -6.430731)
			(xy 78.531205 -6.345002) (xy 78.519222 -6.257822) (xy 78.515217 -6.169914) (xy 13.611098 -6.169914)
			(xy 13.611098 -6.75243) (xy 18.634432 -6.75243) (xy 18.634432 -6.69789) (xy 18.642194 -6.643907)
			(xy 18.65756 -6.591577) (xy 18.680216 -6.541966) (xy 18.709702 -6.496085) (xy 18.745417 -6.454867)
			(xy 18.786635 -6.419152) (xy 18.832516 -6.389666) (xy 18.882127 -6.36701) (xy 18.934457 -6.351644)
			(xy 18.98844 -6.343882) (xy 19.01571 -6.343396) (xy 19.87931 -6.343396) (xy 19.906579 -6.343886)
			(xy 19.960563 -6.351648) (xy 20.012892 -6.367013) (xy 20.062502 -6.389669) (xy 20.108382 -6.419155)
			(xy 20.1496 -6.45487) (xy 20.185315 -6.496088) (xy 20.214801 -6.541968) (xy 20.237457 -6.591578)
			(xy 20.252822 -6.643907) (xy 20.260584 -6.697891) (xy 20.260584 -6.752429) (xy 20.260584 -6.752431)
			(xy 22.234349 -6.752431) (xy 22.234349 -6.697889) (xy 22.242112 -6.643901) (xy 22.257478 -6.591568)
			(xy 22.280136 -6.541955) (xy 22.309624 -6.496071) (xy 22.345342 -6.45485) (xy 22.386562 -6.419133)
			(xy 22.432447 -6.389645) (xy 22.48206 -6.366987) (xy 22.534393 -6.351621) (xy 22.588381 -6.343859)
			(xy 22.615652 -6.343396) (xy 23.479252 -6.343396) (xy 23.506521 -6.343887) (xy 23.560504 -6.351648)
			(xy 23.612833 -6.367014) (xy 23.662443 -6.38967) (xy 23.708323 -6.419156) (xy 23.749541 -6.454871)
			(xy 23.785255 -6.496088) (xy 23.814741 -6.541969) (xy 23.837397 -6.591579) (xy 23.852762 -6.643908)
			(xy 23.860524 -6.697891) (xy 23.860524 -6.752429) (xy 23.860518 -6.752472) (xy 25.834283 -6.752472)
			(xy 25.834283 -6.697928) (xy 25.842045 -6.643939) (xy 25.857412 -6.591604) (xy 25.88007 -6.541989)
			(xy 25.909558 -6.496103) (xy 25.945277 -6.454881) (xy 25.986498 -6.419162) (xy 26.032384 -6.389673)
			(xy 26.081998 -6.367014) (xy 26.134333 -6.351646) (xy 26.188322 -6.343883) (xy 26.215594 -6.343396)
			(xy 27.079194 -6.343396) (xy 27.106462 -6.343943) (xy 27.160444 -6.351704) (xy 27.212772 -6.367068)
			(xy 27.26238 -6.389722) (xy 27.308259 -6.419207) (xy 27.349476 -6.45492) (xy 27.38519 -6.496136)
			(xy 27.414675 -6.542015) (xy 27.43733 -6.591623) (xy 27.452695 -6.64395) (xy 27.460457 -6.697932)
			(xy 27.460457 -6.752468) (xy 27.460456 -6.752472) (xy 29.434483 -6.752472) (xy 29.434483 -6.697928)
			(xy 29.442245 -6.643939) (xy 29.457611 -6.591605) (xy 29.480269 -6.54199) (xy 29.509757 -6.496105)
			(xy 29.545476 -6.454883) (xy 29.586697 -6.419163) (xy 29.632581 -6.389674) (xy 29.682196 -6.367015)
			(xy 29.73453 -6.351647) (xy 29.788518 -6.343883) (xy 29.81579 -6.343396) (xy 30.67939 -6.343396)
			(xy 30.706658 -6.343943) (xy 30.76064 -6.351703) (xy 30.812969 -6.367067) (xy 30.862578 -6.389721)
			(xy 30.908457 -6.419205) (xy 30.949674 -6.454919) (xy 30.985389 -6.496135) (xy 31.014874 -6.542014)
			(xy 31.03753 -6.591622) (xy 31.052895 -6.64395) (xy 31.060657 -6.697932) (xy 31.060657 -6.752468)
			(xy 31.060657 -6.75247) (xy 38.544482 -6.75247) (xy 38.544482 -6.69793) (xy 38.552244 -6.643944)
			(xy 38.567608 -6.591613) (xy 38.590264 -6.542) (xy 38.619749 -6.496116) (xy 38.655463 -6.454895)
			(xy 38.696679 -6.419176) (xy 38.74256 -6.389686) (xy 38.792169 -6.367025) (xy 38.844499 -6.351654)
			(xy 38.898484 -6.343886) (xy 38.925754 -6.343396) (xy 39.789354 -6.343396) (xy 39.816624 -6.34394)
			(xy 39.87061 -6.351696) (xy 39.922943 -6.367057) (xy 39.972556 -6.389709) (xy 40.01844 -6.419192)
			(xy 40.059662 -6.454906) (xy 40.09538 -6.496123) (xy 40.124869 -6.542004) (xy 40.147527 -6.591614)
			(xy 40.162894 -6.643945) (xy 40.170656 -6.69793) (xy 40.170656 -6.75247) (xy 40.170656 -6.752472)
			(xy 42.144383 -6.752472) (xy 42.144383 -6.697928) (xy 42.152145 -6.643939) (xy 42.167512 -6.591604)
			(xy 42.19017 -6.541988) (xy 42.219659 -6.496103) (xy 42.255378 -6.454881) (xy 42.296599 -6.419161)
			(xy 42.342485 -6.389672) (xy 42.3921 -6.367013) (xy 42.444435 -6.351646) (xy 42.498424 -6.343883)
			(xy 42.525696 -6.343396) (xy 43.389296 -6.343396) (xy 43.416564 -6.343943) (xy 43.470546 -6.351704)
			(xy 43.522873 -6.367068) (xy 43.572481 -6.389723) (xy 43.61836 -6.419207) (xy 43.659576 -6.454921)
			(xy 43.69529 -6.496136) (xy 43.724775 -6.542015) (xy 43.74743 -6.591623) (xy 43.762795 -6.643951)
			(xy 43.770557 -6.697932) (xy 43.770557 -6.752468) (xy 43.770556 -6.752472) (xy 49.754483 -6.752472)
			(xy 49.754483 -6.697928) (xy 49.762245 -6.643939) (xy 49.777611 -6.591605) (xy 49.800269 -6.54199)
			(xy 49.829757 -6.496105) (xy 49.865476 -6.454883) (xy 49.906697 -6.419163) (xy 49.952581 -6.389674)
			(xy 50.002196 -6.367015) (xy 50.05453 -6.351647) (xy 50.108518 -6.343883) (xy 50.13579 -6.343396)
			(xy 50.99939 -6.343396) (xy 51.026658 -6.343943) (xy 51.08064 -6.351703) (xy 51.132969 -6.367067)
			(xy 51.182578 -6.389721) (xy 51.228457 -6.419205) (xy 51.269674 -6.454919) (xy 51.305389 -6.496135)
			(xy 51.334874 -6.542014) (xy 51.35753 -6.591622) (xy 51.372895 -6.64395) (xy 51.380657 -6.697932)
			(xy 51.380657 -6.752468) (xy 51.380656 -6.752475) (xy 53.35436 -6.752475) (xy 53.35436 -6.697925)
			(xy 53.362124 -6.643929) (xy 53.377493 -6.591588) (xy 53.400155 -6.541967) (xy 53.429649 -6.496077)
			(xy 53.465374 -6.454851) (xy 53.506603 -6.41913) (xy 53.552495 -6.38964) (xy 53.602118 -6.366982)
			(xy 53.65446 -6.351617) (xy 53.708457 -6.343857) (xy 53.735732 -6.343396) (xy 54.599332 -6.343396)
			(xy 54.626597 -6.343969) (xy 54.680571 -6.351733) (xy 54.732891 -6.367099) (xy 54.782492 -6.389755)
			(xy 54.828364 -6.419238) (xy 54.869573 -6.45495) (xy 54.905281 -6.496162) (xy 54.93476 -6.542036)
			(xy 54.957412 -6.591639) (xy 54.972774 -6.64396) (xy 54.980534 -6.697935) (xy 54.980534 -6.752465)
			(xy 54.980533 -6.752471) (xy 56.954382 -6.752471) (xy 56.954382 -6.697929) (xy 56.962144 -6.643942)
			(xy 56.97751 -6.591608) (xy 57.000167 -6.541994) (xy 57.029654 -6.49611) (xy 57.06537 -6.454888)
			(xy 57.106589 -6.419169) (xy 57.152472 -6.389679) (xy 57.202084 -6.367019) (xy 57.254416 -6.35165)
			(xy 57.308403 -6.343884) (xy 57.335674 -6.343396) (xy 58.199274 -6.343396) (xy 58.226543 -6.343942)
			(xy 58.280527 -6.3517) (xy 58.332857 -6.367062) (xy 58.382468 -6.389716) (xy 58.42835 -6.4192) (xy 58.469569 -6.454913)
			(xy 58.505285 -6.496129) (xy 58.534772 -6.542009) (xy 58.557429 -6.591619) (xy 58.564228 -6.614772)
			(xy 70.948992 -6.614772) (xy 70.948992 -6.560228) (xy 70.956754 -6.506238) (xy 70.972121 -6.453903)
			(xy 70.994781 -6.404288) (xy 71.02427 -6.358403) (xy 71.05999 -6.317181) (xy 71.101212 -6.281463)
			(xy 71.147099 -6.251975) (xy 71.196715 -6.229317) (xy 71.24905 -6.213952) (xy 71.30304 -6.206191)
			(xy 71.330312 -6.205728) (xy 72.193912 -6.205728) (xy 72.22118 -6.206235) (xy 72.275161 -6.213998)
			(xy 72.327488 -6.229364) (xy 72.377095 -6.25202) (xy 72.422973 -6.281506) (xy 72.464188 -6.31722)
			(xy 72.499901 -6.358436) (xy 72.529385 -6.404315) (xy 72.55204 -6.453924) (xy 72.567404 -6.506251)
			(xy 72.575166 -6.560232) (xy 72.575166 -6.614768) (xy 72.567404 -6.668749) (xy 72.55204 -6.721076)
			(xy 72.529385 -6.770685) (xy 72.499901 -6.816564) (xy 72.464188 -6.85778) (xy 72.422973 -6.893494)
			(xy 72.377095 -6.92298) (xy 72.327488 -6.945636) (xy 72.275161 -6.961002) (xy 72.22118 -6.968765)
			(xy 72.193912 -6.969252) (xy 71.330312 -6.969252) (xy 71.30304 -6.968809) (xy 71.24905 -6.961048)
			(xy 71.196715 -6.945683) (xy 71.147099 -6.923025) (xy 71.101212 -6.893537) (xy 71.05999 -6.857819)
			(xy 71.02427 -6.816597) (xy 70.994781 -6.770712) (xy 70.972121 -6.721097) (xy 70.956754 -6.668762)
			(xy 70.948992 -6.614772) (xy 58.564228 -6.614772) (xy 58.572795 -6.643948) (xy 58.580557 -6.697931)
			(xy 58.580557 -6.752469) (xy 58.572795 -6.806452) (xy 58.557429 -6.858781) (xy 58.534772 -6.908391)
			(xy 58.505285 -6.954271) (xy 58.469569 -6.995487) (xy 58.42835 -7.0312) (xy 58.382468 -7.060684)
			(xy 58.332857 -7.083338) (xy 58.280527 -7.0987) (xy 58.226543 -7.106458) (xy 58.199274 -7.10692)
			(xy 57.335674 -7.10692) (xy 57.308403 -7.106516) (xy 57.254416 -7.09875) (xy 57.202084 -7.083381)
			(xy 57.152472 -7.060721) (xy 57.106589 -7.031231) (xy 57.06537 -6.995512) (xy 57.029654 -6.95429)
			(xy 57.000167 -6.908406) (xy 56.97751 -6.858792) (xy 56.962144 -6.806458) (xy 56.954382 -6.752471)
			(xy 54.980533 -6.752471) (xy 54.972774 -6.80644) (xy 54.957412 -6.858761) (xy 54.93476 -6.908364)
			(xy 54.905281 -6.954238) (xy 54.869573 -6.99545) (xy 54.828364 -7.031162) (xy 54.782492 -7.060645)
			(xy 54.732891 -7.083301) (xy 54.680571 -7.098667) (xy 54.626597 -7.106431) (xy 54.599332 -7.10692)
			(xy 53.735732 -7.10692) (xy 53.708457 -7.106543) (xy 53.65446 -7.098783) (xy 53.602118 -7.083418)
			(xy 53.552495 -7.06076) (xy 53.506603 -7.03127) (xy 53.465374 -6.995549) (xy 53.429649 -6.954323)
			(xy 53.400155 -6.908433) (xy 53.377493 -6.858812) (xy 53.362124 -6.806471) (xy 53.35436 -6.752475)
			(xy 51.380656 -6.752475) (xy 51.372895 -6.80645) (xy 51.35753 -6.858778) (xy 51.334874 -6.908386)
			(xy 51.305389 -6.954265) (xy 51.269674 -6.995481) (xy 51.228457 -7.031195) (xy 51.182578 -7.060679)
			(xy 51.132969 -7.083333) (xy 51.08064 -7.098697) (xy 51.026658 -7.106457) (xy 50.99939 -7.10692)
			(xy 50.13579 -7.10692) (xy 50.108518 -7.106517) (xy 50.05453 -7.098753) (xy 50.002196 -7.083385)
			(xy 49.952581 -7.060726) (xy 49.906697 -7.031237) (xy 49.865476 -6.995517) (xy 49.829757 -6.954295)
			(xy 49.800269 -6.90841) (xy 49.777611 -6.858795) (xy 49.762245 -6.806461) (xy 49.754483 -6.752472)
			(xy 43.770556 -6.752472) (xy 43.762795 -6.806449) (xy 43.74743 -6.858777) (xy 43.724775 -6.908385)
			(xy 43.69529 -6.954264) (xy 43.659576 -6.995479) (xy 43.61836 -7.031193) (xy 43.572481 -7.060677)
			(xy 43.522873 -7.083332) (xy 43.470546 -7.098696) (xy 43.416564 -7.106457) (xy 43.389296 -7.10692)
			(xy 42.525696 -7.10692) (xy 42.498424 -7.106517) (xy 42.444435 -7.098754) (xy 42.3921 -7.083387)
			(xy 42.342485 -7.060728) (xy 42.296599 -7.031239) (xy 42.255378 -6.995519) (xy 42.219659 -6.954297)
			(xy 42.19017 -6.908412) (xy 42.167512 -6.858796) (xy 42.152145 -6.806461) (xy 42.144383 -6.752472)
			(xy 40.170656 -6.752472) (xy 40.162894 -6.806455) (xy 40.147527 -6.858786) (xy 40.124869 -6.908396)
			(xy 40.09538 -6.954277) (xy 40.059661 -6.995494) (xy 40.01844 -7.031208) (xy 39.972556 -7.060691)
			(xy 39.922943 -7.083343) (xy 39.87061 -7.098704) (xy 39.816624 -7.10646) (xy 39.789354 -7.10692)
			(xy 38.925754 -7.10692) (xy 38.898484 -7.106514) (xy 38.844499 -7.098746) (xy 38.792169 -7.083375)
			(xy 38.74256 -7.060714) (xy 38.696679 -7.031224) (xy 38.655463 -6.995505) (xy 38.619749 -6.954284)
			(xy 38.590264 -6.9084) (xy 38.567608 -6.858787) (xy 38.552244 -6.806456) (xy 38.544482 -6.75247)
			(xy 31.060657 -6.75247) (xy 31.052895 -6.80645) (xy 31.03753 -6.858778) (xy 31.014874 -6.908386)
			(xy 30.985389 -6.954265) (xy 30.949674 -6.995481) (xy 30.908457 -7.031195) (xy 30.862578 -7.060679)
			(xy 30.812969 -7.083333) (xy 30.76064 -7.098697) (xy 30.706658 -7.106457) (xy 30.67939 -7.10692)
			(xy 29.81579 -7.10692) (xy 29.788518 -7.106517) (xy 29.73453 -7.098753) (xy 29.682196 -7.083385)
			(xy 29.632581 -7.060726) (xy 29.586697 -7.031237) (xy 29.545476 -6.995517) (xy 29.509757 -6.954295)
			(xy 29.480269 -6.90841) (xy 29.457611 -6.858795) (xy 29.442245 -6.806461) (xy 29.434483 -6.752472)
			(xy 27.460456 -6.752472) (xy 27.452695 -6.80645) (xy 27.43733 -6.858777) (xy 27.414675 -6.908385)
			(xy 27.38519 -6.954264) (xy 27.349476 -6.99548) (xy 27.308259 -7.031193) (xy 27.26238 -7.060678)
			(xy 27.212772 -7.083332) (xy 27.160444 -7.098696) (xy 27.106462 -7.106457) (xy 27.079194 -7.10692)
			(xy 26.215594 -7.10692) (xy 26.188322 -7.106517) (xy 26.134333 -7.098754) (xy 26.081998 -7.083386)
			(xy 26.032384 -7.060727) (xy 25.986498 -7.031238) (xy 25.945277 -6.995519) (xy 25.909558 -6.954297)
			(xy 25.88007 -6.908411) (xy 25.857412 -6.858796) (xy 25.842045 -6.806461) (xy 25.834283 -6.752472)
			(xy 23.860518 -6.752472) (xy 23.852762 -6.806412) (xy 23.837397 -6.858741) (xy 23.814741 -6.908351)
			(xy 23.785255 -6.954232) (xy 23.749541 -6.995449) (xy 23.708323 -7.031164) (xy 23.662443 -7.06065)
			(xy 23.612833 -7.083306) (xy 23.560504 -7.098672) (xy 23.506521 -7.106433) (xy 23.479252 -7.10692)
			(xy 22.615652 -7.10692) (xy 22.588381 -7.106461) (xy 22.534393 -7.098699) (xy 22.48206 -7.083333)
			(xy 22.432447 -7.060675) (xy 22.386562 -7.031187) (xy 22.345342 -6.99547) (xy 22.309624 -6.954249)
			(xy 22.280136 -6.908365) (xy 22.257478 -6.858752) (xy 22.242112 -6.806419) (xy 22.234349 -6.752431)
			(xy 20.260584 -6.752431) (xy 20.252822 -6.806413) (xy 20.237457 -6.858742) (xy 20.214801 -6.908352)
			(xy 20.185315 -6.954232) (xy 20.1496 -6.99545) (xy 20.108382 -7.031165) (xy 20.062502 -7.060651)
			(xy 20.012892 -7.083307) (xy 19.960563 -7.098672) (xy 19.906579 -7.106434) (xy 19.87931 -7.10692)
			(xy 19.01571 -7.10692) (xy 18.98844 -7.106438) (xy 18.934457 -7.098676) (xy 18.882127 -7.08331) (xy 18.832516 -7.060654)
			(xy 18.786635 -7.031168) (xy 18.745417 -6.995453) (xy 18.709702 -6.954235) (xy 18.680216 -6.908354)
			(xy 18.65756 -6.858743) (xy 18.642194 -6.806413) (xy 18.634432 -6.75243) (xy 13.611098 -6.75243)
			(xy 13.611098 -9.780016) (xy 13.610604 -9.850398) (xy 13.602711 -9.990941) (xy 13.58695 -10.13082)
			(xy 13.563371 -10.269596) (xy 13.532048 -10.406831) (xy 13.493079 -10.542094) (xy 13.446587 -10.674959)
			(xy 13.392719 -10.805008) (xy 13.331643 -10.931832) (xy 13.263553 -11.055033) (xy 13.188662 -11.174221)
			(xy 13.107205 -11.289023) (xy 13.01944 -11.399077) (xy 12.925642 -11.504037) (xy 12.826107 -11.603572)
			(xy 12.721147 -11.69737) (xy 12.611093 -11.785135) (xy 12.496291 -11.866592) (xy 12.377103 -11.941483)
			(xy 12.253902 -12.009573) (xy 12.127078 -12.070649) (xy 11.997029 -12.124517) (xy 11.864164 -12.171009)
			(xy 11.728901 -12.209978) (xy 11.591666 -12.241301) (xy 11.45289 -12.26488) (xy 11.313011 -12.280641)
			(xy 11.172468 -12.288534) (xy 11.102086 -12.289028) (xy 1.999996 -12.289028) (xy 1.944227 -12.289537)
			(xy 1.833 -12.297872) (xy 1.722707 -12.314497) (xy 1.613965 -12.339317) (xy 1.507382 -12.372193)
			(xy 1.403554 -12.412943) (xy 1.353372 -12.43711) (xy 62.309756 -12.43711) (xy 62.310222 -12.396003)
			(xy 62.317806 -12.314139) (xy 62.332909 -12.233324) (xy 62.355404 -12.154247) (xy 62.385098 -12.077583)
			(xy 62.421737 -12.003984) (xy 62.46501 -11.93408) (xy 62.514548 -11.868466) (xy 62.569927 -11.807701)
			(xy 62.630676 -11.752305) (xy 62.696277 -11.70275) (xy 62.766169 -11.659457) (xy 62.839757 -11.622797)
			(xy 62.916414 -11.593082) (xy 62.995485 -11.570566) (xy 63.076295 -11.55544) (xy 63.158157 -11.547833)
			(xy 63.199264 -11.547348) (xy 63.243059 -11.547873) (xy 63.330225 -11.556491) (xy 63.416121 -11.573637)
			(xy 63.499915 -11.599145) (xy 63.580795 -11.632768) (xy 63.619634 -11.653012) (xy 63.6311 -11.65843)
			(xy 63.656428 -11.65843) (xy 63.667894 -11.653012) (xy 63.706738 -11.632781) (xy 63.787623 -11.599174)
			(xy 63.871416 -11.573672) (xy 63.957309 -11.556521) (xy 64.04447 -11.547888) (xy 64.088264 -11.547348)
			(xy 64.132059 -11.547873) (xy 64.219225 -11.556491) (xy 64.305121 -11.573637) (xy 64.388915 -11.599145)
			(xy 64.469795 -11.632768) (xy 64.508634 -11.653012) (xy 64.5201 -11.65843) (xy 64.545428 -11.65843)
			(xy 64.556894 -11.653012) (xy 64.595738 -11.632781) (xy 64.676623 -11.599174) (xy 64.760416 -11.573672)
			(xy 64.846309 -11.556521) (xy 64.93347 -11.547888) (xy 64.977264 -11.547348) (xy 65.021059 -11.547873)
			(xy 65.108225 -11.556491) (xy 65.194121 -11.573637) (xy 65.277915 -11.599145) (xy 65.358795 -11.632768)
			(xy 65.397634 -11.653012) (xy 65.4091 -11.65843) (xy 65.434428 -11.65843) (xy 65.445894 -11.653012)
			(xy 65.484738 -11.632781) (xy 65.565623 -11.599174) (xy 65.649416 -11.573672) (xy 65.735309 -11.556521)
			(xy 65.82247 -11.547888) (xy 65.866264 -11.547348) (xy 65.904554 -11.547763) (xy 65.980848 -11.554368)
			(xy 66.05629 -11.567515) (xy 66.130321 -11.587105) (xy 66.166492 -11.599672) (xy 66.174929 -11.602323)
			(xy 66.192599 -11.602323) (xy 66.201036 -11.599672) (xy 66.237216 -11.587135) (xy 66.311248 -11.56756)
			(xy 66.386687 -11.554411) (xy 66.462976 -11.547785) (xy 66.501264 -11.547348) (xy 66.54268 -11.547848)
			(xy 66.625149 -11.555593) (xy 66.706543 -11.570964) (xy 66.786158 -11.593827) (xy 66.863305 -11.623986)
			(xy 66.937318 -11.661178) (xy 66.972688 -11.68273) (xy 66.980074 -11.686987) (xy 66.996689 -11.690769)
			(xy 67.013625 -11.688896) (xy 67.021456 -11.685524) (xy 67.057233 -11.668994) (xy 67.131154 -11.641645)
			(xy 67.207206 -11.620946) (xy 67.284791 -11.607058) (xy 67.363301 -11.600092) (xy 67.40271 -11.599672)
			(xy 67.443826 -11.600089) (xy 67.525707 -11.607677) (xy 67.606539 -11.622789) (xy 67.685632 -11.645294)
			(xy 67.76231 -11.675001) (xy 67.835921 -11.711656) (xy 67.905835 -11.754947) (xy 67.971457 -11.804505)
			(xy 68.032226 -11.859906) (xy 68.087623 -11.920677) (xy 68.137178 -11.986301) (xy 68.180465 -12.056218)
			(xy 68.217117 -12.12983) (xy 68.24682 -12.20651) (xy 68.269321 -12.285604) (xy 68.284429 -12.366436)
			(xy 68.292013 -12.448318) (xy 68.292472 -12.489434) (xy 68.291907 -12.533047) (xy 68.283357 -12.619854)
			(xy 68.266352 -12.705408) (xy 68.241056 -12.788886) (xy 68.207711 -12.869488) (xy 68.195659 -12.892068)
			(xy 70.948547 -12.892068) (xy 70.948547 -12.837532) (xy 70.956309 -12.783551) (xy 70.971673 -12.731225)
			(xy 70.994328 -12.681617) (xy 71.023813 -12.635739) (xy 71.059526 -12.594524) (xy 71.100742 -12.558811)
			(xy 71.146621 -12.529327) (xy 71.196228 -12.506672) (xy 71.248555 -12.491308) (xy 71.302536 -12.483547)
			(xy 71.329804 -12.483084) (xy 72.193404 -12.483084) (xy 72.220676 -12.483479) (xy 72.274666 -12.491242)
			(xy 72.327001 -12.506609) (xy 72.376617 -12.529269) (xy 72.422503 -12.558758) (xy 72.463725 -12.594478)
			(xy 72.499444 -12.6357) (xy 72.528933 -12.681586) (xy 72.551592 -12.731202) (xy 72.566959 -12.783538)
			(xy 72.574721 -12.837528) (xy 72.574721 -12.892072) (xy 72.566959 -12.946062) (xy 72.551592 -12.998398)
			(xy 72.528933 -13.048014) (xy 72.499444 -13.0939) (xy 72.488173 -13.106908) (xy 191.037972 -13.106908)
			(xy 191.03849 -13.065179) (xy 191.046314 -12.98209) (xy 191.061883 -12.900098) (xy 191.085062 -12.819924)
			(xy 191.115646 -12.742273) (xy 191.153367 -12.667827) (xy 191.197893 -12.59724) (xy 191.248833 -12.531132)
			(xy 191.305739 -12.470085) (xy 191.368112 -12.414635) (xy 191.435403 -12.365269) (xy 191.507021 -12.32242)
			(xy 191.582336 -12.286466) (xy 191.660687 -12.257723) (xy 191.700912 -12.24661) (xy 191.713612 -12.243308)
			(xy 191.732408 -12.225274) (xy 191.765936 -12.117578) (xy 191.760348 -12.091924) (xy 191.751712 -12.082018)
			(xy 191.723476 -12.048682) (xy 191.672486 -11.977736) (xy 191.628113 -11.902474) (xy 191.590718 -11.823512)
			(xy 191.560607 -11.741496) (xy 191.538028 -11.657095) (xy 191.523163 -11.571) (xy 191.516135 -11.483915)
			(xy 191.517001 -11.39655) (xy 191.525753 -11.309621) (xy 191.542322 -11.223837) (xy 191.56657 -11.139901)
			(xy 191.5983 -11.058497) (xy 191.637253 -10.980292) (xy 191.683109 -10.905925) (xy 191.735495 -10.836003)
			(xy 191.793982 -10.771099) (xy 191.858092 -10.711742) (xy 191.927301 -10.658417) (xy 192.001043 -10.611562)
			(xy 192.078715 -10.571558) (xy 192.159684 -10.538733) (xy 192.243285 -10.513355) (xy 192.328838 -10.495631)
			(xy 192.415641 -10.485707) (xy 192.502986 -10.483662) (xy 192.590159 -10.489515) (xy 192.676446 -10.503218)
			(xy 192.761144 -10.524657) (xy 192.843559 -10.553659) (xy 192.923018 -10.589985) (xy 192.998871 -10.63334)
			(xy 193.070499 -10.683368) (xy 193.137315 -10.739661) (xy 193.198774 -10.801758) (xy 193.254374 -10.869153)
			(xy 193.303659 -10.941294) (xy 193.346227 -11.017591) (xy 193.381731 -11.097421) (xy 193.409879 -11.180131)
			(xy 193.430442 -11.265046) (xy 193.443252 -11.35147) (xy 193.448204 -11.438699) (xy 193.445257 -11.526018)
			(xy 193.434436 -11.612714) (xy 193.415829 -11.698079) (xy 193.389589 -11.781414) (xy 193.355929 -11.862038)
			(xy 193.315124 -11.939293) (xy 193.267509 -12.012547) (xy 193.213473 -12.081201) (xy 193.153457 -12.144694)
			(xy 193.121026 -12.173966) (xy 193.112347 -12.182457) (xy 193.103466 -12.205016) (xy 193.104008 -12.217146)
			(xy 193.112136 -12.298934) (xy 193.113935 -12.310868) (xy 193.126948 -12.331156) (xy 193.137028 -12.337796)
			(xy 193.137282 -12.33805) (xy 193.173525 -12.359702) (xy 193.242152 -12.408882) (xy 193.305811 -12.464344)
			(xy 193.363928 -12.525589) (xy 193.415979 -12.592065) (xy 193.461498 -12.663174) (xy 193.500073 -12.738277)
			(xy 193.531358 -12.816697) (xy 193.555071 -12.897729) (xy 193.570999 -12.980643) (xy 193.578999 -13.064693)
			(xy 193.579496 -13.106908) (xy 193.579055 -13.148019) (xy 193.571467 -13.22989) (xy 193.556355 -13.310712)
			(xy 193.533849 -13.389794) (xy 193.504141 -13.466462) (xy 193.467484 -13.540061) (xy 193.424192 -13.609963)
			(xy 193.374634 -13.675571) (xy 193.319232 -13.736326) (xy 193.25846 -13.791709) (xy 193.192836 -13.841247)
			(xy 193.122921 -13.884518) (xy 193.049311 -13.921151) (xy 192.972634 -13.950836) (xy 192.893545 -13.973317)
			(xy 192.812719 -13.988404) (xy 192.730845 -13.995968) (xy 192.689734 -13.996416) (xy 192.643339 -13.99582)
			(xy 192.551051 -13.986179) (xy 192.460267 -13.966987) (xy 192.371973 -13.938452) (xy 192.329308 -13.920216)
			(xy 192.319366 -13.91641) (xy 192.298102 -13.91641) (xy 192.28816 -13.920216) (xy 192.245553 -13.938427)
			(xy 192.157387 -13.966948) (xy 192.066733 -13.986143) (xy 191.974574 -13.995806) (xy 191.928242 -13.996416)
			(xy 191.927734 -13.996416) (xy 191.886626 -13.995955) (xy 191.804762 -13.988373) (xy 191.723946 -13.973271)
			(xy 191.644867 -13.950778) (xy 191.568202 -13.921085) (xy 191.494602 -13.884445) (xy 191.424697 -13.841172)
			(xy 191.359082 -13.791634) (xy 191.298317 -13.736254) (xy 191.24292 -13.675504) (xy 191.193365 -13.609903)
			(xy 191.150073 -13.540009) (xy 191.113413 -13.46642) (xy 191.083699 -13.389762) (xy 191.061184 -13.31069)
			(xy 191.04606 -13.229878) (xy 191.038456 -13.148015) (xy 191.037972 -13.106908) (xy 72.488173 -13.106908)
			(xy 72.463725 -13.135122) (xy 72.422503 -13.170842) (xy 72.376617 -13.200331) (xy 72.327001 -13.222991)
			(xy 72.274666 -13.238358) (xy 72.220676 -13.246121) (xy 72.193404 -13.246608) (xy 71.329804 -13.246608)
			(xy 71.302536 -13.246053) (xy 71.248555 -13.238292) (xy 71.196228 -13.222928) (xy 71.146621 -13.200273)
			(xy 71.100742 -13.170789) (xy 71.059526 -13.135076) (xy 71.023813 -13.093861) (xy 70.994328 -13.047983)
			(xy 70.971673 -12.998375) (xy 70.956309 -12.946049) (xy 70.948547 -12.892068) (xy 68.195659 -12.892068)
			(xy 68.166638 -12.946439) (xy 68.118231 -13.019001) (xy 68.062955 -13.086478) (xy 68.00134 -13.14822)
			(xy 67.933978 -13.203636) (xy 67.861516 -13.252193) (xy 67.823334 -13.273278) (xy 67.814055 -13.278811)
			(xy 67.800889 -13.295908) (xy 67.797934 -13.306298) (xy 67.787525 -13.3474) (xy 67.759881 -13.427561)
			(xy 67.724737 -13.504728) (xy 67.682409 -13.578201) (xy 67.633283 -13.647314) (xy 67.577804 -13.711439)
			(xy 67.516475 -13.769995) (xy 67.449854 -13.82245) (xy 67.378544 -13.868328) (xy 67.303192 -13.907213)
			(xy 67.224482 -13.938753) (xy 67.143129 -13.96266) (xy 67.05987 -13.978719) (xy 66.975461 -13.986784)
			(xy 66.933064 -13.987272) (xy 66.894775 -13.986847) (xy 66.818481 -13.980245) (xy 66.743038 -13.967101)
			(xy 66.669007 -13.947513) (xy 66.632836 -13.934948) (xy 66.624399 -13.932297) (xy 66.606729 -13.932297)
			(xy 66.598292 -13.934948) (xy 66.56211 -13.947478) (xy 66.488079 -13.967055) (xy 66.41264 -13.980205)
			(xy 66.336352 -13.986834) (xy 66.298064 -13.987272) (xy 66.254269 -13.986733) (xy 66.167104 -13.978118)
			(xy 66.081208 -13.960975) (xy 65.997414 -13.93547) (xy 65.916534 -13.90185) (xy 65.877694 -13.881608)
			(xy 65.866228 -13.87619) (xy 65.8409 -13.87619) (xy 65.829434 -13.881608) (xy 65.790581 -13.901822)
			(xy 65.709699 -13.935433) (xy 65.625908 -13.96094) (xy 65.540018 -13.978094) (xy 65.452857 -13.986731)
			(xy 65.409064 -13.987272) (xy 65.365269 -13.986733) (xy 65.278104 -13.978118) (xy 65.192208 -13.960975)
			(xy 65.108414 -13.93547) (xy 65.027534 -13.90185) (xy 64.988694 -13.881608) (xy 64.977228 -13.87619)
			(xy 64.9519 -13.87619) (xy 64.940434 -13.881608) (xy 64.901581 -13.901822) (xy 64.820699 -13.935433)
			(xy 64.736908 -13.96094) (xy 64.651018 -13.978094) (xy 64.563857 -13.986731) (xy 64.520064 -13.987272)
			(xy 64.476269 -13.986733) (xy 64.389104 -13.978118) (xy 64.303208 -13.960975) (xy 64.219414 -13.93547)
			(xy 64.138534 -13.90185) (xy 64.099694 -13.881608) (xy 64.088228 -13.87619) (xy 64.0629 -13.87619)
			(xy 64.051434 -13.881608) (xy 64.012581 -13.901822) (xy 63.931699 -13.935433) (xy 63.847908 -13.96094)
			(xy 63.762018 -13.978094) (xy 63.674857 -13.986731) (xy 63.631064 -13.987272) (xy 63.588804 -13.98679)
			(xy 63.504665 -13.978779) (xy 63.421665 -13.962822) (xy 63.340553 -13.939064) (xy 63.26206 -13.907718)
			(xy 63.186895 -13.869068) (xy 63.115735 -13.823463) (xy 63.049222 -13.771312) (xy 62.987956 -13.713088)
			(xy 62.93249 -13.649314) (xy 62.883323 -13.580566) (xy 62.840899 -13.507464) (xy 62.805601 -13.430668)
			(xy 62.777747 -13.35087) (xy 62.757589 -13.268789) (xy 62.750954 -13.22705) (xy 62.748768 -13.216225)
			(xy 62.736658 -13.197787) (xy 62.727586 -13.19149) (xy 62.693115 -13.169417) (xy 62.628004 -13.119803)
			(xy 62.567725 -13.064419) (xy 62.512788 -13.003732) (xy 62.463657 -12.938255) (xy 62.420747 -12.868543)
			(xy 62.384422 -12.795185) (xy 62.354987 -12.7188) (xy 62.332693 -12.640034) (xy 62.317728 -12.559554)
			(xy 62.310218 -12.47804) (xy 62.309756 -12.43711) (xy 1.353372 -12.43711) (xy 1.303061 -12.461339)
			(xy 1.206466 -12.517108) (xy 1.114309 -12.579941) (xy 1.027105 -12.649484) (xy 0.945341 -12.72535)
			(xy 0.869476 -12.807114) (xy 0.801731 -12.892064) (xy 56.95347 -12.892064) (xy 56.95347 -12.837536)
			(xy 56.96123 -12.783562) (xy 56.976591 -12.731243) (xy 56.999242 -12.681641) (xy 57.02872 -12.635768)
			(xy 57.064426 -12.594556) (xy 57.105634 -12.558845) (xy 57.151504 -12.529362) (xy 57.201103 -12.506706)
			(xy 57.253421 -12.491339) (xy 57.307394 -12.483573) (xy 57.334658 -12.483084) (xy 58.198258 -12.483084)
			(xy 58.225534 -12.483453) (xy 58.279532 -12.491211) (xy 58.331876 -12.506575) (xy 58.381501 -12.529233)
			(xy 58.427395 -12.558723) (xy 58.468625 -12.594445) (xy 58.504351 -12.635671) (xy 58.533847 -12.681562)
			(xy 58.55651 -12.731184) (xy 58.57188 -12.783527) (xy 58.579644 -12.837524) (xy 58.579644 -12.892076)
			(xy 58.57188 -12.946073) (xy 58.55651 -12.998416) (xy 58.533847 -13.048037) (xy 58.504351 -13.093929)
			(xy 58.468625 -13.135155) (xy 58.427395 -13.170877) (xy 58.381501 -13.200367) (xy 58.331876 -13.223025)
			(xy 58.279532 -13.238389) (xy 58.225534 -13.246147) (xy 58.198258 -13.246608) (xy 57.334658 -13.246608)
			(xy 57.307394 -13.246027) (xy 57.253421 -13.238261) (xy 57.201103 -13.222894) (xy 57.151504 -13.200238)
			(xy 57.105634 -13.170755) (xy 57.064426 -13.135044) (xy 57.02872 -13.093832) (xy 56.999242 -13.047959)
			(xy 56.976591 -12.998357) (xy 56.96123 -12.946038) (xy 56.95347 -12.892064) (xy 0.801731 -12.892064)
			(xy 0.799933 -12.894318) (xy 0.737102 -12.986476) (xy 0.681333 -13.083072) (xy 0.632939 -13.183565)
			(xy 0.59219 -13.287393) (xy 0.559313 -13.393977) (xy 0.534494 -13.502719) (xy 0.517871 -13.613012)
			(xy 0.509536 -13.724239) (xy 0.509016 -13.780008) (xy 0.509016 -16.5207) (xy 76.28834 -16.5207) (xy 76.29237 -16.436094)
			(xy 76.304425 -16.352254) (xy 76.324394 -16.26994) (xy 76.352098 -16.189896) (xy 76.387284 -16.112849)
			(xy 76.429635 -16.039495) (xy 76.478768 -15.970499) (xy 76.534236 -15.906485) (xy 76.595538 -15.848035)
			(xy 76.662118 -15.795676) (xy 76.733375 -15.749883) (xy 76.808661 -15.711071) (xy 76.887296 -15.679591)
			(xy 76.968567 -15.655728) (xy 77.051738 -15.639698) (xy 77.136057 -15.631648) (xy 77.178408 -15.63116)
			(xy 77.178916 -15.63116) (xy 77.224101 -15.631724) (xy 77.314005 -15.640873) (xy 77.402518 -15.659097)
			(xy 77.488725 -15.686205) (xy 77.530452 -15.70355) (xy 77.539034 -15.706862) (xy 77.557395 -15.707764)
			(xy 77.566266 -15.705328) (xy 77.610936 -15.69133) (xy 77.702468 -15.671687) (xy 77.795557 -15.661772)
			(xy 77.842364 -15.661132) (xy 77.84338 -15.661132) (xy 77.885732 -15.661539) (xy 77.970052 -15.669589)
			(xy 78.053225 -15.685618) (xy 78.134498 -15.70948) (xy 78.213134 -15.74096) (xy 78.288422 -15.779772)
			(xy 78.35968 -15.825565) (xy 78.426262 -15.877924) (xy 78.487566 -15.936376) (xy 78.543035 -16.00039)
			(xy 78.592169 -16.069387) (xy 78.634521 -16.142742) (xy 78.669709 -16.219791) (xy 78.697413 -16.299835)
			(xy 78.717383 -16.382151) (xy 78.722326 -16.416528) (xy 191.571372 -16.416528) (xy 191.571784 -16.378238)
			(xy 191.57839 -16.301944) (xy 191.591537 -16.226502) (xy 191.611129 -16.152471) (xy 191.623696 -16.1163)
			(xy 191.626331 -16.10786) (xy 191.62634 -16.090193) (xy 191.623696 -16.081756) (xy 191.611158 -16.045577)
			(xy 191.591583 -15.971544) (xy 191.578434 -15.896105) (xy 191.571809 -15.819816) (xy 191.571372 -15.781528)
			(xy 191.571879 -15.740418) (xy 191.579464 -15.65855) (xy 191.594572 -15.577731) (xy 191.617074 -15.498651)
			(xy 191.646778 -15.421985) (xy 191.68343 -15.348387) (xy 191.726718 -15.278486) (xy 191.776272 -15.212878)
			(xy 191.831669 -15.152124) (xy 191.892437 -15.096741) (xy 191.958056 -15.047202) (xy 192.027967 -15.00393)
			(xy 192.101573 -14.967295) (xy 192.178246 -14.937609) (xy 192.257331 -14.915125) (xy 192.338154 -14.900036)
			(xy 192.420024 -14.89247) (xy 192.461134 -14.89202) (xy 192.499451 -14.892376) (xy 192.575804 -14.898912)
			(xy 192.651311 -14.912) (xy 192.72541 -14.931543) (xy 192.761616 -14.94409) (xy 192.769932 -14.946676)
			(xy 192.787336 -14.946676) (xy 192.795652 -14.94409) (xy 192.831863 -14.931562) (xy 192.905965 -14.912041)
			(xy 192.981469 -14.898959) (xy 193.057819 -14.892413) (xy 193.096134 -14.89202) (xy 193.134451 -14.892376)
			(xy 193.210804 -14.898912) (xy 193.286311 -14.912) (xy 193.36041 -14.931543) (xy 193.396616 -14.94409)
			(xy 193.404932 -14.946676) (xy 193.422336 -14.946676) (xy 193.430652 -14.94409) (xy 193.466772 -14.93159)
			(xy 193.540685 -14.912102) (xy 193.615997 -14.899021) (xy 193.692153 -14.892442) (xy 193.730372 -14.89202)
			(xy 193.731134 -14.89202) (xy 193.772241 -14.89248) (xy 193.854104 -14.900067) (xy 193.934917 -14.915174)
			(xy 194.013993 -14.937671) (xy 194.090656 -14.967367) (xy 194.164253 -15.004008) (xy 194.234156 -15.047282)
			(xy 194.299769 -15.09682) (xy 194.360532 -15.152199) (xy 194.415928 -15.212948) (xy 194.465484 -15.278547)
			(xy 194.508776 -15.348439) (xy 194.545437 -15.422026) (xy 194.575153 -15.498681) (xy 194.597672 -15.577751)
			(xy 194.6128 -15.658561) (xy 194.620409 -15.740421) (xy 194.620896 -15.781528) (xy 194.620451 -15.819809)
			(xy 194.613795 -15.896082) (xy 194.600605 -15.971499) (xy 194.591178 -16.008604) (xy 194.588893 -16.019174)
			(xy 194.592456 -16.040487) (xy 194.598036 -16.049752) (xy 194.621836 -16.08633) (xy 194.662956 -16.163308)
			(xy 194.696348 -16.24394) (xy 194.721691 -16.327453) (xy 194.738741 -16.413043) (xy 194.747336 -16.499892)
			(xy 194.747896 -16.543528) (xy 194.747474 -16.584639) (xy 194.739884 -16.666511) (xy 194.72477 -16.747333)
			(xy 194.702263 -16.826416) (xy 194.672553 -16.903083) (xy 194.635895 -16.976682) (xy 194.592602 -17.046584)
			(xy 194.543042 -17.112192) (xy 194.487639 -17.172947) (xy 194.426866 -17.22833) (xy 194.361241 -17.277868)
			(xy 194.291325 -17.321138) (xy 194.217714 -17.357772) (xy 194.141037 -17.387456) (xy 194.061947 -17.409938)
			(xy 193.98112 -17.425024) (xy 193.899246 -17.432588) (xy 193.858134 -17.433036) (xy 193.814503 -17.432505)
			(xy 193.727659 -17.42397) (xy 193.642069 -17.40697) (xy 193.558556 -17.381667) (xy 193.477923 -17.348306)
			(xy 193.400945 -17.307207) (xy 193.364358 -17.28343) (xy 193.355108 -17.277824) (xy 193.333785 -17.274289)
			(xy 193.32321 -17.276572) (xy 193.286097 -17.285942) (xy 193.210677 -17.299046) (xy 193.134409 -17.305624)
			(xy 193.096134 -17.306036) (xy 193.057818 -17.305656) (xy 192.981465 -17.299127) (xy 192.905958 -17.286046)
			(xy 192.831859 -17.26651) (xy 192.795652 -17.253966) (xy 192.787336 -17.25138) (xy 192.769932 -17.25138)
			(xy 192.761616 -17.253966) (xy 192.725489 -17.266445) (xy 192.651578 -17.285939) (xy 192.576269 -17.299026)
			(xy 192.500115 -17.305611) (xy 192.461896 -17.306036) (xy 192.461134 -17.306036) (xy 192.420027 -17.305555)
			(xy 192.338163 -17.297973) (xy 192.257348 -17.282872) (xy 192.178271 -17.260379) (xy 192.101606 -17.230687)
			(xy 192.028008 -17.194048) (xy 191.958103 -17.150776) (xy 191.892489 -17.10124) (xy 191.831724 -17.045861)
			(xy 191.776328 -16.985113) (xy 191.726772 -16.919513) (xy 191.683479 -16.849621) (xy 191.646819 -16.776033)
			(xy 191.617104 -16.699377) (xy 191.594588 -16.620307) (xy 191.579463 -16.539496) (xy 191.571857 -16.457635)
			(xy 191.571372 -16.416528) (xy 78.722326 -16.416528) (xy 78.729438 -16.465992) (xy 78.733468 -16.5506)
			(xy 78.729438 -16.635208) (xy 78.717383 -16.719049) (xy 78.697413 -16.801365) (xy 78.669709 -16.881409)
			(xy 78.634521 -16.958458) (xy 78.592169 -17.031813) (xy 78.543035 -17.10081) (xy 78.487566 -17.164824)
			(xy 78.426262 -17.223276) (xy 78.35968 -17.275635) (xy 78.288422 -17.321428) (xy 78.213134 -17.36024)
			(xy 78.134498 -17.39172) (xy 78.053225 -17.415582) (xy 77.970052 -17.431611) (xy 77.885732 -17.439661)
			(xy 77.84338 -17.440148) (xy 77.842872 -17.440148) (xy 77.797687 -17.439588) (xy 77.707782 -17.430437)
			(xy 77.61927 -17.412213) (xy 77.533063 -17.385103) (xy 77.491336 -17.367758) (xy 77.482756 -17.36444)
			(xy 77.464393 -17.363542) (xy 77.455522 -17.36598) (xy 77.410853 -17.379982) (xy 77.319321 -17.399623)
			(xy 77.226231 -17.409537) (xy 77.179424 -17.410176) (xy 77.178408 -17.410176) (xy 77.136057 -17.409752)
			(xy 77.051738 -17.401702) (xy 76.968567 -17.385672) (xy 76.887296 -17.361809) (xy 76.808661 -17.330329)
			(xy 76.733375 -17.291517) (xy 76.662118 -17.245724) (xy 76.595538 -17.193365) (xy 76.534236 -17.134915)
			(xy 76.478768 -17.070901) (xy 76.429635 -17.001905) (xy 76.387284 -16.928551) (xy 76.352098 -16.851504)
			(xy 76.324394 -16.77146) (xy 76.304425 -16.689146) (xy 76.29237 -16.605306) (xy 76.28834 -16.5207)
			(xy 0.509016 -16.5207) (xy 0.509016 -17.639611) (xy 15.152858 -17.639611) (xy 15.152858 -17.585109)
			(xy 15.160614 -17.531161) (xy 15.175969 -17.478867) (xy 15.19861 -17.42929) (xy 15.228076 -17.383439)
			(xy 15.263768 -17.342249) (xy 15.304958 -17.306558) (xy 15.350808 -17.277091) (xy 15.400385 -17.25445)
			(xy 15.452679 -17.239095) (xy 15.506627 -17.231338) (xy 15.533878 -17.230852) (xy 16.397478 -17.230852)
			(xy 16.424731 -17.231315) (xy 16.478682 -17.239072) (xy 16.53098 -17.254428) (xy 16.580561 -17.27707)
			(xy 16.626414 -17.306538) (xy 16.667607 -17.342232) (xy 16.703301 -17.383424) (xy 16.732769 -17.429278)
			(xy 16.755412 -17.478858) (xy 16.770768 -17.531156) (xy 16.778525 -17.585107) (xy 16.778525 -17.639611)
			(xy 20.740858 -17.639611) (xy 20.740858 -17.585109) (xy 20.748614 -17.531161) (xy 20.763969 -17.478867)
			(xy 20.78661 -17.42929) (xy 20.816076 -17.383439) (xy 20.851768 -17.342249) (xy 20.892958 -17.306558)
			(xy 20.938808 -17.277091) (xy 20.988385 -17.25445) (xy 21.040679 -17.239095) (xy 21.094627 -17.231338)
			(xy 21.121878 -17.230852) (xy 21.985478 -17.230852) (xy 22.012729 -17.231394) (xy 22.066677 -17.239147)
			(xy 22.118972 -17.2545) (xy 22.168549 -17.277139) (xy 22.2144 -17.306603) (xy 22.255591 -17.342293)
			(xy 22.291284 -17.383482) (xy 22.320751 -17.429331) (xy 22.343392 -17.478908) (xy 22.358748 -17.531202)
			(xy 22.366505 -17.585149) (xy 22.366505 -17.639651) (xy 22.366505 -17.639653) (xy 26.328838 -17.639653)
			(xy 26.328838 -17.585147) (xy 26.336595 -17.531195) (xy 26.35195 -17.478897) (xy 26.374592 -17.429316)
			(xy 26.404059 -17.383462) (xy 26.439752 -17.342268) (xy 26.480944 -17.306573) (xy 26.526797 -17.277103)
			(xy 26.576376 -17.254458) (xy 26.628674 -17.239099) (xy 26.682625 -17.231339) (xy 26.709878 -17.230852)
			(xy 27.573478 -17.230852) (xy 27.600729 -17.231394) (xy 27.654677 -17.239147) (xy 27.706972 -17.2545)
			(xy 27.756549 -17.277139) (xy 27.8024 -17.306603) (xy 27.843591 -17.342293) (xy 27.879284 -17.383482)
			(xy 27.908751 -17.429331) (xy 27.931392 -17.478908) (xy 27.946748 -17.531202) (xy 27.954505 -17.585149)
			(xy 27.954505 -17.639651) (xy 27.954402 -17.640366) (xy 31.915646 -17.640366) (xy 31.915646 -17.585834)
			(xy 31.923406 -17.531857) (xy 31.938769 -17.479533) (xy 31.961421 -17.429928) (xy 31.990902 -17.384052)
			(xy 32.026611 -17.342838) (xy 32.067822 -17.307125) (xy 32.113695 -17.277639) (xy 32.163298 -17.254982)
			(xy 32.21562 -17.239615) (xy 32.269596 -17.231849) (xy 32.296862 -17.23136) (xy 33.160462 -17.23136)
			(xy 33.187736 -17.231777) (xy 33.24173 -17.239535) (xy 33.294071 -17.254899) (xy 33.343691 -17.277556)
			(xy 33.389583 -17.307044) (xy 33.43081 -17.342764) (xy 33.466533 -17.383987) (xy 33.496026 -17.429875)
			(xy 33.518688 -17.479494) (xy 33.534057 -17.531832) (xy 33.54182 -17.585826) (xy 33.54182 -17.640366)
			(xy 37.503646 -17.640366) (xy 37.503646 -17.585834) (xy 37.511406 -17.531857) (xy 37.526769 -17.479533)
			(xy 37.549421 -17.429928) (xy 37.578902 -17.384052) (xy 37.614611 -17.342838) (xy 37.655822 -17.307125)
			(xy 37.701695 -17.277639) (xy 37.751298 -17.254982) (xy 37.80362 -17.239615) (xy 37.857596 -17.231849)
			(xy 37.884862 -17.23136) (xy 38.748462 -17.23136) (xy 38.775736 -17.231777) (xy 38.82973 -17.239535)
			(xy 38.882071 -17.254899) (xy 38.931691 -17.277556) (xy 38.977583 -17.307044) (xy 39.01881 -17.342764)
			(xy 39.054533 -17.383987) (xy 39.084026 -17.429875) (xy 39.106688 -17.479494) (xy 39.122057 -17.531832)
			(xy 39.12982 -17.585826) (xy 39.12982 -17.639654) (xy 43.398638 -17.639654) (xy 43.398638 -17.585146)
			(xy 43.406395 -17.531193) (xy 43.421751 -17.478894) (xy 43.444395 -17.429312) (xy 43.473863 -17.383457)
			(xy 43.509558 -17.342262) (xy 43.550752 -17.306567) (xy 43.596606 -17.277097) (xy 43.646188 -17.254454)
			(xy 43.698487 -17.239096) (xy 43.75244 -17.231338) (xy 43.779694 -17.230852) (xy 44.643294 -17.230852)
			(xy 44.670544 -17.231395) (xy 44.72449 -17.23915) (xy 44.776783 -17.254504) (xy 44.826359 -17.277144)
			(xy 44.872208 -17.306609) (xy 44.913397 -17.342299) (xy 44.949088 -17.383487) (xy 44.978553 -17.429336)
			(xy 45.001194 -17.478911) (xy 45.016548 -17.531204) (xy 45.024305 -17.58515) (xy 45.024305 -17.63965)
			(xy 45.024304 -17.639654) (xy 48.986638 -17.639654) (xy 48.986638 -17.585146) (xy 48.994395 -17.531193)
			(xy 49.009751 -17.478894) (xy 49.032395 -17.429312) (xy 49.061863 -17.383457) (xy 49.097558 -17.342262)
			(xy 49.138752 -17.306567) (xy 49.184606 -17.277097) (xy 49.234188 -17.254454) (xy 49.286487 -17.239096)
			(xy 49.34044 -17.231338) (xy 49.367694 -17.230852) (xy 50.231294 -17.230852) (xy 50.258544 -17.231395)
			(xy 50.31249 -17.23915) (xy 50.364783 -17.254504) (xy 50.414359 -17.277144) (xy 50.460208 -17.306609)
			(xy 50.501397 -17.342299) (xy 50.537088 -17.383487) (xy 50.566553 -17.429336) (xy 50.589194 -17.478911)
			(xy 50.604548 -17.531204) (xy 50.612305 -17.58515) (xy 50.612305 -17.63965) (xy 50.612201 -17.64037)
			(xy 54.607423 -17.64037) (xy 54.607423 -17.58583) (xy 54.615186 -17.531845) (xy 54.630552 -17.479514)
			(xy 54.653209 -17.429903) (xy 54.682696 -17.384021) (xy 54.718413 -17.342803) (xy 54.759632 -17.307088)
			(xy 54.805515 -17.277602) (xy 54.855127 -17.254947) (xy 54.907459 -17.239583) (xy 54.961444 -17.231822)
			(xy 54.988714 -17.23136) (xy 55.852314 -17.23136) (xy 55.879584 -17.231803) (xy 55.933569 -17.239567)
			(xy 55.9859 -17.254935) (xy 56.035512 -17.277593) (xy 56.081393 -17.307081) (xy 56.122612 -17.342798)
			(xy 56.158328 -17.384018) (xy 56.187814 -17.429901) (xy 56.21047 -17.479513) (xy 56.225836 -17.531844)
			(xy 56.233598 -17.58583) (xy 56.233598 -17.64037) (xy 56.225836 -17.694356) (xy 56.21047 -17.746687)
			(xy 56.187814 -17.796299) (xy 56.158328 -17.842182) (xy 56.122612 -17.883402) (xy 56.081393 -17.919119)
			(xy 56.035512 -17.948607) (xy 55.9859 -17.971265) (xy 55.933569 -17.986633) (xy 55.879584 -17.994397)
			(xy 55.852314 -17.994884) (xy 54.988714 -17.994884) (xy 54.961444 -17.994378) (xy 54.907459 -17.986617)
			(xy 54.855127 -17.971253) (xy 54.805515 -17.948598) (xy 54.759632 -17.919112) (xy 54.718413 -17.883397)
			(xy 54.682696 -17.842179) (xy 54.653209 -17.796297) (xy 54.630552 -17.746686) (xy 54.615186 -17.694355)
			(xy 54.607423 -17.64037) (xy 50.612201 -17.64037) (xy 50.604548 -17.693596) (xy 50.589194 -17.745889)
			(xy 50.566553 -17.795464) (xy 50.537088 -17.841313) (xy 50.501397 -17.882501) (xy 50.460208 -17.918191)
			(xy 50.414359 -17.947656) (xy 50.364783 -17.970296) (xy 50.31249 -17.98565) (xy 50.258544 -17.993405)
			(xy 50.231294 -17.993868) (xy 49.367694 -17.993868) (xy 49.34044 -17.993462) (xy 49.286487 -17.985704)
			(xy 49.234188 -17.970346) (xy 49.184606 -17.947703) (xy 49.138752 -17.918233) (xy 49.097558 -17.882538)
			(xy 49.061863 -17.841343) (xy 49.032395 -17.795488) (xy 49.009751 -17.745906) (xy 48.994395 -17.693607)
			(xy 48.986638 -17.639654) (xy 45.024304 -17.639654) (xy 45.016548 -17.693596) (xy 45.001194 -17.745889)
			(xy 44.978553 -17.795464) (xy 44.949088 -17.841313) (xy 44.913397 -17.882501) (xy 44.872208 -17.918191)
			(xy 44.826359 -17.947656) (xy 44.776783 -17.970296) (xy 44.72449 -17.98565) (xy 44.670544 -17.993405)
			(xy 44.643294 -17.993868) (xy 43.779694 -17.993868) (xy 43.75244 -17.993462) (xy 43.698487 -17.985704)
			(xy 43.646188 -17.970346) (xy 43.596606 -17.947703) (xy 43.550752 -17.918233) (xy 43.509558 -17.882538)
			(xy 43.473863 -17.841343) (xy 43.444395 -17.795488) (xy 43.421751 -17.745906) (xy 43.406395 -17.693607)
			(xy 43.398638 -17.639654) (xy 39.12982 -17.639654) (xy 39.12982 -17.640374) (xy 39.122057 -17.694368)
			(xy 39.106688 -17.746706) (xy 39.084026 -17.796325) (xy 39.054533 -17.842213) (xy 39.01881 -17.883436)
			(xy 38.977583 -17.919156) (xy 38.931691 -17.948644) (xy 38.882071 -17.971301) (xy 38.82973 -17.986665)
			(xy 38.775736 -17.994423) (xy 38.748462 -17.994884) (xy 37.884862 -17.994884) (xy 37.857596 -17.994351)
			(xy 37.80362 -17.986585) (xy 37.751298 -17.971218) (xy 37.701695 -17.948561) (xy 37.655822 -17.919075)
			(xy 37.614611 -17.883362) (xy 37.578902 -17.842148) (xy 37.549421 -17.796272) (xy 37.526769 -17.746667)
			(xy 37.511406 -17.694343) (xy 37.503646 -17.640366) (xy 33.54182 -17.640366) (xy 33.54182 -17.640374)
			(xy 33.534057 -17.694368) (xy 33.518688 -17.746706) (xy 33.496026 -17.796325) (xy 33.466533 -17.842213)
			(xy 33.43081 -17.883436) (xy 33.389583 -17.919156) (xy 33.343691 -17.948644) (xy 33.294071 -17.971301)
			(xy 33.24173 -17.986665) (xy 33.187736 -17.994423) (xy 33.160462 -17.994884) (xy 32.296862 -17.994884)
			(xy 32.269596 -17.994351) (xy 32.21562 -17.986585) (xy 32.163298 -17.971218) (xy 32.113695 -17.948561)
			(xy 32.067822 -17.919075) (xy 32.026611 -17.883362) (xy 31.990902 -17.842148) (xy 31.961421 -17.796272)
			(xy 31.938769 -17.746667) (xy 31.923406 -17.694343) (xy 31.915646 -17.640366) (xy 27.954402 -17.640366)
			(xy 27.946748 -17.693598) (xy 27.931392 -17.745892) (xy 27.908751 -17.795469) (xy 27.879284 -17.841318)
			(xy 27.843591 -17.882507) (xy 27.8024 -17.918197) (xy 27.756549 -17.947661) (xy 27.706972 -17.9703)
			(xy 27.654677 -17.985653) (xy 27.600729 -17.993406) (xy 27.573478 -17.993868) (xy 26.709878 -17.993868)
			(xy 26.682625 -17.993461) (xy 26.628674 -17.985701) (xy 26.576376 -17.970342) (xy 26.526797 -17.947697)
			(xy 26.480944 -17.918227) (xy 26.439752 -17.882532) (xy 26.404059 -17.841338) (xy 26.374592 -17.795484)
			(xy 26.35195 -17.745903) (xy 26.336595 -17.693605) (xy 26.328838 -17.639653) (xy 22.366505 -17.639653)
			(xy 22.358748 -17.693598) (xy 22.343392 -17.745892) (xy 22.320751 -17.795469) (xy 22.291284 -17.841318)
			(xy 22.255591 -17.882507) (xy 22.2144 -17.918197) (xy 22.168549 -17.947661) (xy 22.118972 -17.9703)
			(xy 22.066677 -17.985653) (xy 22.012729 -17.993406) (xy 21.985478 -17.993868) (xy 21.121878 -17.993868)
			(xy 21.094627 -17.993382) (xy 21.040679 -17.985625) (xy 20.988385 -17.97027) (xy 20.938808 -17.947629)
			(xy 20.892958 -17.918162) (xy 20.851768 -17.882471) (xy 20.816076 -17.841281) (xy 20.78661 -17.79543)
			(xy 20.763969 -17.745853) (xy 20.748614 -17.693559) (xy 20.740858 -17.639611) (xy 16.778525 -17.639611)
			(xy 16.778525 -17.639613) (xy 16.770768 -17.693564) (xy 16.755412 -17.745862) (xy 16.732769 -17.795442)
			(xy 16.703301 -17.841296) (xy 16.667607 -17.882488) (xy 16.626414 -17.918182) (xy 16.580561 -17.94765)
			(xy 16.53098 -17.970292) (xy 16.478682 -17.985648) (xy 16.424731 -17.993405) (xy 16.397478 -17.993868)
			(xy 15.533878 -17.993868) (xy 15.506627 -17.993382) (xy 15.452679 -17.985625) (xy 15.400385 -17.97027)
			(xy 15.350808 -17.947629) (xy 15.304958 -17.918162) (xy 15.263768 -17.882471) (xy 15.228076 -17.841281)
			(xy 15.19861 -17.79543) (xy 15.175969 -17.745853) (xy 15.160614 -17.693559) (xy 15.152858 -17.639611)
			(xy 0.509016 -17.639611) (xy 0.509016 -19.164391) (xy 17.945563 -19.164391) (xy 17.945563 -19.109849)
			(xy 17.953326 -19.055862) (xy 17.968692 -19.00353) (xy 17.99135 -18.953917) (xy 18.020837 -18.908033)
			(xy 18.056555 -18.866813) (xy 18.097775 -18.831096) (xy 18.143658 -18.801609) (xy 18.193272 -18.778951)
			(xy 18.245604 -18.763585) (xy 18.299591 -18.755823) (xy 18.326862 -18.75536) (xy 19.190462 -18.75536)
			(xy 19.217731 -18.755843) (xy 19.271715 -18.763605) (xy 19.324045 -18.77897) (xy 19.373655 -18.801627)
			(xy 19.419536 -18.831113) (xy 19.460753 -18.866828) (xy 19.496469 -18.908046) (xy 19.525954 -18.953927)
			(xy 19.548611 -19.003537) (xy 19.563976 -19.055867) (xy 19.571738 -19.109851) (xy 19.571738 -19.163653)
			(xy 23.534838 -19.163653) (xy 23.534838 -19.109147) (xy 23.542595 -19.055195) (xy 23.55795 -19.002897)
			(xy 23.580592 -18.953316) (xy 23.610059 -18.907462) (xy 23.645752 -18.866268) (xy 23.686944 -18.830573)
			(xy 23.732797 -18.801103) (xy 23.782376 -18.778458) (xy 23.834674 -18.763099) (xy 23.888625 -18.755339)
			(xy 23.915878 -18.754852) (xy 24.779478 -18.754852) (xy 24.806729 -18.755394) (xy 24.860677 -18.763147)
			(xy 24.912972 -18.7785) (xy 24.962549 -18.801139) (xy 25.0084 -18.830603) (xy 25.049591 -18.866293)
			(xy 25.085284 -18.907482) (xy 25.114751 -18.953331) (xy 25.137392 -19.002908) (xy 25.152748 -19.055202)
			(xy 25.160505 -19.109149) (xy 25.160505 -19.163651) (xy 25.160505 -19.163653) (xy 29.122838 -19.163653)
			(xy 29.122838 -19.109147) (xy 29.130595 -19.055195) (xy 29.14595 -19.002897) (xy 29.168592 -18.953316)
			(xy 29.198059 -18.907462) (xy 29.233752 -18.866268) (xy 29.274944 -18.830573) (xy 29.320797 -18.801103)
			(xy 29.370376 -18.778458) (xy 29.422674 -18.763099) (xy 29.476625 -18.755339) (xy 29.503878 -18.754852)
			(xy 30.367478 -18.754852) (xy 30.394729 -18.755394) (xy 30.448677 -18.763147) (xy 30.500972 -18.7785)
			(xy 30.550549 -18.801139) (xy 30.5964 -18.830603) (xy 30.637591 -18.866293) (xy 30.673284 -18.907482)
			(xy 30.702751 -18.953331) (xy 30.725392 -19.002908) (xy 30.740748 -19.055202) (xy 30.748505 -19.109149)
			(xy 30.748505 -19.163651) (xy 30.748505 -19.163653) (xy 34.710838 -19.163653) (xy 34.710838 -19.109147)
			(xy 34.718595 -19.055195) (xy 34.73395 -19.002897) (xy 34.756592 -18.953316) (xy 34.786059 -18.907462)
			(xy 34.821752 -18.866268) (xy 34.862944 -18.830573) (xy 34.908797 -18.801103) (xy 34.958376 -18.778458)
			(xy 35.010674 -18.763099) (xy 35.064625 -18.755339) (xy 35.091878 -18.754852) (xy 35.955478 -18.754852)
			(xy 35.982729 -18.755394) (xy 36.036677 -18.763147) (xy 36.088972 -18.7785) (xy 36.138549 -18.801139)
			(xy 36.1844 -18.830603) (xy 36.225591 -18.866293) (xy 36.261284 -18.907482) (xy 36.290751 -18.953331)
			(xy 36.313392 -19.002908) (xy 36.328748 -19.055202) (xy 36.336505 -19.109149) (xy 36.336505 -19.163651)
			(xy 36.336505 -19.163654) (xy 40.604638 -19.163654) (xy 40.604638 -19.109146) (xy 40.612395 -19.055193)
			(xy 40.627751 -19.002894) (xy 40.650395 -18.953312) (xy 40.679863 -18.907457) (xy 40.715558 -18.866262)
			(xy 40.756752 -18.830567) (xy 40.802606 -18.801097) (xy 40.852188 -18.778454) (xy 40.904487 -18.763096)
			(xy 40.95844 -18.755338) (xy 40.985694 -18.754852) (xy 41.849294 -18.754852) (xy 41.876544 -18.755395)
			(xy 41.93049 -18.76315) (xy 41.982783 -18.778504) (xy 42.032359 -18.801144) (xy 42.078208 -18.830609)
			(xy 42.119397 -18.866299) (xy 42.155088 -18.907487) (xy 42.184553 -18.953336) (xy 42.207194 -19.002911)
			(xy 42.222548 -19.055204) (xy 42.230305 -19.10915) (xy 42.230305 -19.16365) (xy 42.230202 -19.164367)
			(xy 46.191446 -19.164367) (xy 46.191446 -19.109833) (xy 46.199207 -19.055855) (xy 46.21457 -19.00353)
			(xy 46.237224 -18.953924) (xy 46.266706 -18.908047) (xy 46.302417 -18.866832) (xy 46.343629 -18.831119)
			(xy 46.389505 -18.801634) (xy 46.439109 -18.778978) (xy 46.491433 -18.763612) (xy 46.545411 -18.755848)
			(xy 46.572678 -18.75536) (xy 47.436278 -18.75536) (xy 47.463552 -18.755778) (xy 47.517544 -18.763538)
			(xy 47.569882 -18.778903) (xy 47.619501 -18.801561) (xy 47.66539 -18.83105) (xy 47.706615 -18.866769)
			(xy 47.742337 -18.907992) (xy 47.771828 -18.95388) (xy 47.794489 -19.003497) (xy 47.809857 -19.055835)
			(xy 47.81762 -19.109826) (xy 47.81762 -19.163657) (xy 51.814615 -19.163657) (xy 51.814615 -19.109143)
			(xy 51.822374 -19.055184) (xy 51.837733 -19.002878) (xy 51.86038 -18.95329) (xy 51.889854 -18.907431)
			(xy 51.925554 -18.866233) (xy 51.966755 -18.830536) (xy 52.012617 -18.801065) (xy 52.062206 -18.778422)
			(xy 52.114513 -18.763067) (xy 52.168473 -18.755313) (xy 52.19573 -18.754852) (xy 53.05933 -18.754852)
			(xy 53.086577 -18.75542) (xy 53.140516 -18.763179) (xy 53.192801 -18.778535) (xy 53.24237 -18.801176)
			(xy 53.288211 -18.83064) (xy 53.329394 -18.866328) (xy 53.365078 -18.907513) (xy 53.394538 -18.953357)
			(xy 53.417175 -19.002927) (xy 53.432527 -19.055214) (xy 53.440282 -19.109153) (xy 53.440282 -19.163647)
			(xy 53.440281 -19.163657) (xy 57.402615 -19.163657) (xy 57.402615 -19.109143) (xy 57.410374 -19.055184)
			(xy 57.425733 -19.002878) (xy 57.44838 -18.95329) (xy 57.477854 -18.907431) (xy 57.513554 -18.866233)
			(xy 57.554755 -18.830536) (xy 57.600617 -18.801065) (xy 57.650206 -18.778422) (xy 57.702513 -18.763067)
			(xy 57.756473 -18.755313) (xy 57.78373 -18.754852) (xy 58.64733 -18.754852) (xy 58.674577 -18.75542)
			(xy 58.728516 -18.763179) (xy 58.780801 -18.778535) (xy 58.83037 -18.801176) (xy 58.876211 -18.83064)
			(xy 58.917394 -18.866328) (xy 58.953078 -18.907513) (xy 58.982538 -18.953357) (xy 59.005175 -19.002927)
			(xy 59.020527 -19.055214) (xy 59.028282 -19.109153) (xy 59.028282 -19.163647) (xy 59.020527 -19.217586)
			(xy 59.005175 -19.269873) (xy 58.982538 -19.319443) (xy 58.953078 -19.365287) (xy 58.917394 -19.406472)
			(xy 58.876211 -19.44216) (xy 58.83037 -19.471624) (xy 58.780801 -19.494265) (xy 58.728516 -19.509621)
			(xy 58.674577 -19.51738) (xy 58.64733 -19.517868) (xy 57.78373 -19.517868) (xy 57.756473 -19.517487)
			(xy 57.702513 -19.509733) (xy 57.650206 -19.494378) (xy 57.600617 -19.471735) (xy 57.554755 -19.442264)
			(xy 57.513554 -19.406567) (xy 57.477854 -19.365369) (xy 57.44838 -19.31951) (xy 57.425733 -19.269922)
			(xy 57.410374 -19.217616) (xy 57.402615 -19.163657) (xy 53.440281 -19.163657) (xy 53.432527 -19.217586)
			(xy 53.417175 -19.269873) (xy 53.394538 -19.319443) (xy 53.365078 -19.365287) (xy 53.329394 -19.406472)
			(xy 53.288211 -19.44216) (xy 53.24237 -19.471624) (xy 53.192801 -19.494265) (xy 53.140516 -19.509621)
			(xy 53.086577 -19.51738) (xy 53.05933 -19.517868) (xy 52.19573 -19.517868) (xy 52.168473 -19.517487)
			(xy 52.114513 -19.509733) (xy 52.062206 -19.494378) (xy 52.012617 -19.471735) (xy 51.966755 -19.442264)
			(xy 51.925554 -19.406567) (xy 51.889854 -19.365369) (xy 51.86038 -19.31951) (xy 51.837733 -19.269922)
			(xy 51.822374 -19.217616) (xy 51.814615 -19.163657) (xy 47.81762 -19.163657) (xy 47.81762 -19.164374)
			(xy 47.809857 -19.218365) (xy 47.794489 -19.270703) (xy 47.771828 -19.32032) (xy 47.742337 -19.366208)
			(xy 47.706615 -19.407431) (xy 47.66539 -19.44315) (xy 47.619501 -19.472639) (xy 47.569882 -19.495297)
			(xy 47.517544 -19.510662) (xy 47.463552 -19.518422) (xy 47.436278 -19.518884) (xy 46.572678 -19.518884)
			(xy 46.545411 -19.518352) (xy 46.491433 -19.510588) (xy 46.439109 -19.495222) (xy 46.389505 -19.472566)
			(xy 46.343629 -19.443081) (xy 46.302417 -19.407368) (xy 46.266706 -19.366153) (xy 46.237224 -19.320276)
			(xy 46.21457 -19.27067) (xy 46.199207 -19.218345) (xy 46.191446 -19.164367) (xy 42.230202 -19.164367)
			(xy 42.222548 -19.217596) (xy 42.207194 -19.269889) (xy 42.184553 -19.319464) (xy 42.155088 -19.365313)
			(xy 42.119397 -19.406501) (xy 42.078208 -19.442191) (xy 42.032359 -19.471656) (xy 41.982783 -19.494296)
			(xy 41.93049 -19.50965) (xy 41.876544 -19.517405) (xy 41.849294 -19.517868) (xy 40.985694 -19.517868)
			(xy 40.95844 -19.517462) (xy 40.904487 -19.509704) (xy 40.852188 -19.494346) (xy 40.802606 -19.471703)
			(xy 40.756752 -19.442233) (xy 40.715558 -19.406538) (xy 40.679863 -19.365343) (xy 40.650395 -19.319488)
			(xy 40.627751 -19.269906) (xy 40.612395 -19.217607) (xy 40.604638 -19.163654) (xy 36.336505 -19.163654)
			(xy 36.328748 -19.217598) (xy 36.313392 -19.269892) (xy 36.290751 -19.319469) (xy 36.261284 -19.365318)
			(xy 36.225591 -19.406507) (xy 36.1844 -19.442197) (xy 36.138549 -19.471661) (xy 36.088972 -19.4943)
			(xy 36.036677 -19.509653) (xy 35.982729 -19.517406) (xy 35.955478 -19.517868) (xy 35.091878 -19.517868)
			(xy 35.064625 -19.517461) (xy 35.010674 -19.509701) (xy 34.958376 -19.494342) (xy 34.908797 -19.471697)
			(xy 34.862944 -19.442227) (xy 34.821752 -19.406532) (xy 34.786059 -19.365338) (xy 34.756592 -19.319484)
			(xy 34.73395 -19.269903) (xy 34.718595 -19.217605) (xy 34.710838 -19.163653) (xy 30.748505 -19.163653)
			(xy 30.740748 -19.217598) (xy 30.725392 -19.269892) (xy 30.702751 -19.319469) (xy 30.673284 -19.365318)
			(xy 30.637591 -19.406507) (xy 30.5964 -19.442197) (xy 30.550549 -19.471661) (xy 30.500972 -19.4943)
			(xy 30.448677 -19.509653) (xy 30.394729 -19.517406) (xy 30.367478 -19.517868) (xy 29.503878 -19.517868)
			(xy 29.476625 -19.517461) (xy 29.422674 -19.509701) (xy 29.370376 -19.494342) (xy 29.320797 -19.471697)
			(xy 29.274944 -19.442227) (xy 29.233752 -19.406532) (xy 29.198059 -19.365338) (xy 29.168592 -19.319484)
			(xy 29.14595 -19.269903) (xy 29.130595 -19.217605) (xy 29.122838 -19.163653) (xy 25.160505 -19.163653)
			(xy 25.152748 -19.217598) (xy 25.137392 -19.269892) (xy 25.114751 -19.319469) (xy 25.085284 -19.365318)
			(xy 25.049591 -19.406507) (xy 25.0084 -19.442197) (xy 24.962549 -19.471661) (xy 24.912972 -19.4943)
			(xy 24.860677 -19.509653) (xy 24.806729 -19.517406) (xy 24.779478 -19.517868) (xy 23.915878 -19.517868)
			(xy 23.888625 -19.517461) (xy 23.834674 -19.509701) (xy 23.782376 -19.494342) (xy 23.732797 -19.471697)
			(xy 23.686944 -19.442227) (xy 23.645752 -19.406532) (xy 23.610059 -19.365338) (xy 23.580592 -19.319484)
			(xy 23.55795 -19.269903) (xy 23.542595 -19.217605) (xy 23.534838 -19.163653) (xy 19.571738 -19.163653)
			(xy 19.571738 -19.164389) (xy 19.563976 -19.218373) (xy 19.548611 -19.270703) (xy 19.525954 -19.320313)
			(xy 19.496469 -19.366194) (xy 19.460753 -19.407412) (xy 19.419536 -19.443127) (xy 19.373655 -19.472613)
			(xy 19.324045 -19.49527) (xy 19.271715 -19.510635) (xy 19.217731 -19.518397) (xy 19.190462 -19.518884)
			(xy 18.326862 -19.518884) (xy 18.299591 -19.518417) (xy 18.245604 -19.510655) (xy 18.193272 -19.495289)
			(xy 18.143658 -19.472631) (xy 18.097775 -19.443144) (xy 18.056555 -19.407427) (xy 18.020837 -19.366207)
			(xy 17.99135 -19.320323) (xy 17.968692 -19.27071) (xy 17.953326 -19.218378) (xy 17.945563 -19.164391)
			(xy 0.509016 -19.164391) (xy 0.509016 -20.327366) (xy 65.88506 -20.327366) (xy 65.885484 -20.289077)
			(xy 65.892086 -20.212783) (xy 65.90523 -20.13734) (xy 65.924819 -20.063309) (xy 65.937384 -20.027138)
			(xy 65.940051 -20.018705) (xy 65.94004 -20.001031) (xy 65.937384 -19.992594) (xy 65.924856 -19.956411)
			(xy 65.905279 -19.88238) (xy 65.892127 -19.806942) (xy 65.885498 -19.730654) (xy 65.88506 -19.692366)
			(xy 65.885582 -19.650174) (xy 65.893576 -19.56617) (xy 65.909488 -19.483301) (xy 65.933176 -19.402311)
			(xy 65.964427 -19.323927) (xy 66.00296 -19.248856) (xy 66.048429 -19.17777) (xy 66.074036 -19.144234)
			(xy 66.079883 -19.13601) (xy 66.085128 -19.116537) (xy 66.082515 -19.096539) (xy 66.077846 -19.087592)
			(xy 66.058798 -19.053767) (xy 66.026006 -18.983399) (xy 65.999468 -18.910441) (xy 65.979384 -18.83545)
			(xy 65.965909 -18.758994) (xy 65.959144 -18.681655) (xy 65.95872 -18.642838) (xy 65.95872 -18.642584)
			(xy 65.959137 -18.60148) (xy 65.966724 -18.519622) (xy 65.981831 -18.438814) (xy 66.00433 -18.359744)
			(xy 66.034029 -18.283087) (xy 66.070674 -18.209498) (xy 66.113953 -18.139604) (xy 66.163496 -18.074001)
			(xy 66.218881 -18.01325) (xy 66.279635 -17.957868) (xy 66.34524 -17.908328) (xy 66.415137 -17.865053)
			(xy 66.488728 -17.828411) (xy 66.565386 -17.798716) (xy 66.644456 -17.776221) (xy 66.725266 -17.761118)
			(xy 66.807124 -17.753535) (xy 66.848228 -17.753076) (xy 66.889911 -17.753577) (xy 66.972911 -17.761363)
			(xy 67.054819 -17.776882) (xy 67.134915 -17.799999) (xy 67.212496 -17.830511) (xy 67.286881 -17.868149)
			(xy 67.357417 -17.912584) (xy 67.423485 -17.963425) (xy 67.484504 -18.020226) (xy 67.53994 -18.082488)
			(xy 67.565016 -18.115788) (xy 67.56527 -18.116042) (xy 67.570757 -18.122776) (xy 67.585223 -18.132372)
			(xy 67.602063 -18.136587) (xy 67.610736 -18.136108) (xy 67.697858 -18.127726) (xy 67.706567 -18.126584)
			(xy 67.722478 -18.119178) (xy 67.734922 -18.1068) (xy 67.739006 -18.099024) (xy 67.739006 -18.098516)
			(xy 67.757258 -18.060702) (xy 67.799884 -17.988356) (xy 67.849141 -17.920351) (xy 67.90459 -17.857291)
			(xy 67.965736 -17.79974) (xy 68.032035 -17.748209) (xy 68.102897 -17.703158) (xy 68.17769 -17.664987)
			(xy 68.255748 -17.634037) (xy 68.336377 -17.610583) (xy 68.418857 -17.594835) (xy 68.502455 -17.586933)
			(xy 68.54444 -17.586452) (xy 68.5868 -17.58693) (xy 68.671136 -17.594986) (xy 68.754325 -17.611023)
			(xy 68.835612 -17.634895) (xy 68.914262 -17.666384) (xy 68.989563 -17.705208) (xy 69.060833 -17.751013)
			(xy 69.127426 -17.803385) (xy 69.18874 -17.86185) (xy 69.244218 -17.925878) (xy 69.293359 -17.99489)
			(xy 69.335718 -18.068261) (xy 69.370911 -18.145325) (xy 69.39862 -18.225386) (xy 69.401856 -18.238724)
			(xy 79.0321 -18.238724) (xy 79.032651 -18.193954) (xy 79.041664 -18.104869) (xy 79.059573 -18.017137)
			(xy 79.086195 -17.931647) (xy 79.10322 -17.890236) (xy 79.106772 -17.880641) (xy 79.106781 -17.860202)
			(xy 79.10322 -17.850612) (xy 79.086184 -17.809205) (xy 79.059551 -17.723717) (xy 79.041646 -17.635983)
			(xy 79.032653 -17.546895) (xy 79.0321 -17.502124) (xy 79.032604 -17.459763) (xy 79.040657 -17.375426)
			(xy 79.056691 -17.292236) (xy 79.080559 -17.210946) (xy 79.112047 -17.132294) (xy 79.150869 -17.056991)
			(xy 79.196672 -16.985719) (xy 79.249043 -16.919123) (xy 79.307508 -16.857808) (xy 79.371536 -16.802327)
			(xy 79.440548 -16.753184) (xy 79.513918 -16.710824) (xy 79.590983 -16.675629) (xy 79.671045 -16.64792)
			(xy 79.753378 -16.627946) (xy 79.837237 -16.615889) (xy 79.921862 -16.611858) (xy 80.006487 -16.615889)
			(xy 80.090346 -16.627946) (xy 80.172679 -16.64792) (xy 80.252741 -16.675629) (xy 80.329806 -16.710824)
			(xy 80.403176 -16.753184) (xy 80.472188 -16.802327) (xy 80.536216 -16.857808) (xy 80.594681 -16.919123)
			(xy 80.647052 -16.985719) (xy 80.692855 -17.056991) (xy 80.731677 -17.132294) (xy 80.763165 -17.210946)
			(xy 80.787033 -17.292236) (xy 80.803067 -17.375426) (xy 80.81112 -17.459763) (xy 80.811624 -17.502124)
			(xy 80.811054 -17.546893) (xy 80.802046 -17.635978) (xy 80.784143 -17.723709) (xy 80.757526 -17.809201)
			(xy 80.740504 -17.850612) (xy 80.736924 -17.860198) (xy 80.736933 -17.880645) (xy 80.740504 -17.890236)
			(xy 80.757551 -17.931638) (xy 80.784182 -18.017129) (xy 80.802084 -18.104863) (xy 80.808854 -18.171951)
			(xy 131.633699 -18.171951) (xy 131.633699 -18.117449) (xy 131.641456 -18.063503) (xy 131.656811 -18.011209)
			(xy 131.679453 -17.961633) (xy 131.708919 -17.915784) (xy 131.744611 -17.874596) (xy 131.785802 -17.838906)
			(xy 131.831653 -17.809442) (xy 131.88123 -17.786804) (xy 131.933524 -17.771451) (xy 131.987471 -17.763698)
			(xy 132.014722 -17.763236) (xy 132.878322 -17.763236) (xy 132.905575 -17.763635) (xy 132.959527 -17.771395)
			(xy 133.011825 -17.786754) (xy 133.061405 -17.809399) (xy 133.107258 -17.838869) (xy 133.148451 -17.874565)
			(xy 133.184144 -17.915759) (xy 133.213611 -17.961614) (xy 133.236254 -18.011196) (xy 133.251609 -18.063495)
			(xy 133.259366 -18.117447) (xy 133.259366 -18.171946) (xy 137.033822 -18.171946) (xy 137.033822 -18.117454)
			(xy 137.041577 -18.063516) (xy 137.056928 -18.01123) (xy 137.079564 -17.961661) (xy 137.109023 -17.915818)
			(xy 137.144706 -17.874633) (xy 137.185887 -17.838946) (xy 137.231728 -17.809482) (xy 137.281294 -17.786841)
			(xy 137.333578 -17.771485) (xy 137.387516 -17.763725) (xy 137.414762 -17.763236) (xy 138.278362 -17.763236)
			(xy 138.30562 -17.763608) (xy 138.359581 -17.771362) (xy 138.41189 -17.786716) (xy 138.46148 -17.809359)
			(xy 138.507344 -17.83883) (xy 138.548546 -17.874528) (xy 138.584247 -17.915726) (xy 138.613722 -17.961586)
			(xy 138.63637 -18.011175) (xy 138.65173 -18.063482) (xy 138.659489 -18.117442) (xy 138.659489 -18.17195)
			(xy 140.633699 -18.17195) (xy 140.633699 -18.11745) (xy 140.641455 -18.063505) (xy 140.65681 -18.011213)
			(xy 140.67945 -17.961638) (xy 140.708915 -17.91579) (xy 140.744605 -17.874602) (xy 140.785793 -17.838913)
			(xy 140.831642 -17.809448) (xy 140.881217 -17.786808) (xy 140.933509 -17.771455) (xy 140.987454 -17.763699)
			(xy 141.014704 -17.763236) (xy 141.878304 -17.763236) (xy 141.905558 -17.763634) (xy 141.959512 -17.771392)
			(xy 142.011812 -17.786749) (xy 142.061394 -17.809393) (xy 142.10725 -17.838863) (xy 142.148444 -17.874559)
			(xy 142.184139 -17.915754) (xy 142.213609 -17.961609) (xy 142.236252 -18.011192) (xy 142.251609 -18.063492)
			(xy 142.259366 -18.117446) (xy 142.259366 -18.171954) (xy 142.251609 -18.225908) (xy 142.236252 -18.278208)
			(xy 142.213609 -18.327791) (xy 142.184139 -18.373646) (xy 142.148444 -18.414841) (xy 142.10725 -18.450537)
			(xy 142.061394 -18.480007) (xy 142.011812 -18.502651) (xy 141.959512 -18.518008) (xy 141.905558 -18.525766)
			(xy 141.878304 -18.526252) (xy 141.014704 -18.526252) (xy 140.987454 -18.525701) (xy 140.933509 -18.517945)
			(xy 140.881217 -18.502592) (xy 140.831642 -18.479952) (xy 140.785793 -18.450487) (xy 140.744605 -18.414798)
			(xy 140.708915 -18.37361) (xy 140.67945 -18.327762) (xy 140.65681 -18.278187) (xy 140.641455 -18.225895)
			(xy 140.633699 -18.17195) (xy 138.659489 -18.17195) (xy 138.659489 -18.171958) (xy 138.65173 -18.225918)
			(xy 138.63637 -18.278225) (xy 138.613722 -18.327814) (xy 138.584247 -18.373674) (xy 138.548546 -18.414872)
			(xy 138.507344 -18.45057) (xy 138.46148 -18.480041) (xy 138.41189 -18.502684) (xy 138.359581 -18.518038)
			(xy 138.30562 -18.525792) (xy 138.278362 -18.526252) (xy 137.414762 -18.526252) (xy 137.387516 -18.525675)
			(xy 137.333578 -18.517915) (xy 137.281294 -18.502559) (xy 137.231728 -18.479918) (xy 137.185887 -18.450454)
			(xy 137.144706 -18.414767) (xy 137.109023 -18.373582) (xy 137.079564 -18.327739) (xy 137.056928 -18.27817)
			(xy 137.041577 -18.225884) (xy 137.033822 -18.171946) (xy 133.259366 -18.171946) (xy 133.259366 -18.171953)
			(xy 133.251609 -18.225905) (xy 133.236254 -18.278204) (xy 133.213611 -18.327786) (xy 133.184144 -18.373641)
			(xy 133.148451 -18.414835) (xy 133.107258 -18.450531) (xy 133.061405 -18.480001) (xy 133.011825 -18.502646)
			(xy 132.959527 -18.518005) (xy 132.905575 -18.525765) (xy 132.878322 -18.526252) (xy 132.014722 -18.526252)
			(xy 131.987471 -18.525702) (xy 131.933524 -18.517949) (xy 131.88123 -18.502596) (xy 131.831653 -18.479958)
			(xy 131.785802 -18.450494) (xy 131.744611 -18.414804) (xy 131.708919 -18.373616) (xy 131.679453 -18.327767)
			(xy 131.656811 -18.278191) (xy 131.641456 -18.225897) (xy 131.633699 -18.171951) (xy 80.808854 -18.171951)
			(xy 80.811074 -18.193953) (xy 80.811624 -18.238724) (xy 80.81112 -18.281085) (xy 80.803067 -18.365422)
			(xy 80.787033 -18.448612) (xy 80.763165 -18.529902) (xy 80.731677 -18.608554) (xy 80.692855 -18.683857)
			(xy 80.647052 -18.755129) (xy 80.594681 -18.821725) (xy 80.536216 -18.88304) (xy 80.472188 -18.938521)
			(xy 80.403176 -18.987664) (xy 80.329806 -19.030024) (xy 80.252741 -19.065219) (xy 80.172679 -19.092928)
			(xy 80.090346 -19.112902) (xy 80.006487 -19.124959) (xy 79.921862 -19.128991) (xy 79.837237 -19.124959)
			(xy 79.753378 -19.112902) (xy 79.671045 -19.092928) (xy 79.590983 -19.065219) (xy 79.513918 -19.030024)
			(xy 79.440548 -18.987664) (xy 79.371536 -18.938521) (xy 79.307508 -18.88304) (xy 79.249043 -18.821725)
			(xy 79.196672 -18.755129) (xy 79.150869 -18.683857) (xy 79.112047 -18.608554) (xy 79.080559 -18.529902)
			(xy 79.056691 -18.448612) (xy 79.040657 -18.365422) (xy 79.032604 -18.281085) (xy 79.0321 -18.238724)
			(xy 69.401856 -18.238724) (xy 69.418593 -18.307718) (xy 69.430649 -18.391576) (xy 69.434681 -18.4762)
			(xy 69.430649 -18.560824) (xy 69.418593 -18.644682) (xy 69.39862 -18.727014) (xy 69.370911 -18.807075)
			(xy 69.335718 -18.884139) (xy 69.293359 -18.95751) (xy 69.244218 -19.026522) (xy 69.18874 -19.09055)
			(xy 69.127426 -19.149015) (xy 69.060833 -19.201387) (xy 68.989563 -19.247192) (xy 68.914262 -19.286016)
			(xy 68.835612 -19.317505) (xy 68.754325 -19.341377) (xy 68.671136 -19.357414) (xy 68.5868 -19.36547)
			(xy 68.54444 -19.365976) (xy 68.502753 -19.365468) (xy 68.419745 -19.357644) (xy 68.337834 -19.342089)
			(xy 68.257737 -19.31894) (xy 68.180157 -19.288398) (xy 68.105774 -19.250734) (xy 68.035242 -19.206275)
			(xy 67.969177 -19.155414) (xy 67.90816 -19.098595) (xy 67.852727 -19.036317) (xy 67.827652 -19.00301)
			(xy 67.827398 -19.002756) (xy 67.821873 -18.996058) (xy 67.807425 -18.986454) (xy 67.790601 -18.982223)
			(xy 67.781932 -18.98269) (xy 67.69481 -18.991072) (xy 67.686098 -18.992195) (xy 67.670187 -18.999611)
			(xy 67.657745 -19.011995) (xy 67.653662 -19.019774) (xy 67.653662 -19.020282) (xy 67.63179 -19.065383)
			(xy 67.579339 -19.150805) (xy 67.549014 -19.190716) (xy 67.543272 -19.198996) (xy 67.538026 -19.218428)
			(xy 67.540615 -19.238388) (xy 67.545204 -19.247358) (xy 67.564269 -19.281203) (xy 67.597117 -19.351604)
			(xy 67.623706 -19.424598) (xy 67.643834 -19.499632) (xy 67.657349 -19.576134) (xy 67.664146 -19.653523)
			(xy 67.664584 -19.692366) (xy 67.664167 -19.730656) (xy 67.657563 -19.806949) (xy 67.644416 -19.882392)
			(xy 67.624826 -19.956423) (xy 67.61226 -19.992594) (xy 67.609626 -20.001035) (xy 67.609615 -20.018702)
			(xy 67.61226 -20.027138) (xy 67.624799 -20.063317) (xy 67.644373 -20.13735) (xy 67.653158 -20.187755)
			(xy 138.765443 -20.187755) (xy 138.765443 -20.133245) (xy 138.773201 -20.079289) (xy 138.788559 -20.026987)
			(xy 138.811205 -19.977403) (xy 138.840677 -19.931547) (xy 138.876376 -19.890352) (xy 138.917574 -19.854657)
			(xy 138.963433 -19.825189) (xy 139.013019 -19.802547) (xy 139.065322 -19.787194) (xy 139.119279 -19.779441)
			(xy 139.146534 -19.77898) (xy 140.137134 -19.77898) (xy 140.164383 -19.779493) (xy 140.218325 -19.787253)
			(xy 140.270614 -19.80261) (xy 140.320185 -19.825253) (xy 140.36603 -19.854719) (xy 140.407215 -19.890409)
			(xy 140.442901 -19.931597) (xy 140.449617 -19.942048) (xy 175.988472 -19.942048) (xy 175.988976 -19.899687)
			(xy 175.997029 -19.81535) (xy 176.013063 -19.73216) (xy 176.036931 -19.65087) (xy 176.068419 -19.572218)
			(xy 176.107241 -19.496915) (xy 176.153044 -19.425643) (xy 176.205415 -19.359047) (xy 176.26388 -19.297732)
			(xy 176.327908 -19.242251) (xy 176.39692 -19.193108) (xy 176.47029 -19.150748) (xy 176.547355 -19.115553)
			(xy 176.627417 -19.087844) (xy 176.70975 -19.06787) (xy 176.793609 -19.055813) (xy 176.878234 -19.051782)
			(xy 176.962859 -19.055813) (xy 177.046718 -19.06787) (xy 177.129051 -19.087844) (xy 177.209113 -19.115553)
			(xy 177.286178 -19.150748) (xy 177.359548 -19.193108) (xy 177.42856 -19.242251) (xy 177.492588 -19.297732)
			(xy 177.551053 -19.359047) (xy 177.603424 -19.425643) (xy 177.649227 -19.496915) (xy 177.688049 -19.572218)
			(xy 177.719537 -19.65087) (xy 177.743405 -19.73216) (xy 177.759439 -19.81535) (xy 177.767492 -19.899687)
			(xy 177.767996 -19.942048) (xy 177.767398 -19.98792) (xy 177.757891 -20.079169) (xy 177.739034 -20.168954)
			(xy 177.725578 -20.212812) (xy 177.722752 -20.223379) (xy 177.72523 -20.245087) (xy 177.730404 -20.254722)
			(xy 177.750836 -20.289402) (xy 177.786035 -20.361795) (xy 177.814552 -20.437071) (xy 177.836153 -20.514616)
			(xy 177.850661 -20.593794) (xy 177.857958 -20.67396) (xy 177.85842 -20.714208) (xy 177.85842 -20.715224)
			(xy 177.857839 -20.760561) (xy 177.84856 -20.850758) (xy 177.830152 -20.939544) (xy 177.817018 -20.98294)
			(xy 177.81462 -20.991841) (xy 177.815621 -21.010233) (xy 177.823067 -21.02708) (xy 177.835994 -21.040201)
			(xy 177.844196 -21.044408) (xy 177.8824 -21.062505) (xy 177.955518 -21.104946) (xy 178.024281 -21.15413)
			(xy 178.088069 -21.209614) (xy 178.146306 -21.270898) (xy 178.198469 -21.337429) (xy 178.244087 -21.408608)
			(xy 178.282748 -21.483792) (xy 178.314103 -21.562305) (xy 178.337871 -21.643437) (xy 178.353837 -21.726458)
			(xy 178.361856 -21.810619) (xy 178.362356 -21.85289) (xy 178.361892 -21.894005) (xy 178.354306 -21.975884)
			(xy 178.339197 -22.056714) (xy 178.316694 -22.135805) (xy 178.28699 -22.212482) (xy 178.250337 -22.286091)
			(xy 178.207049 -22.356005) (xy 178.157495 -22.421626) (xy 178.102097 -22.482394) (xy 178.041329 -22.537792)
			(xy 177.975708 -22.587347) (xy 177.905795 -22.630635) (xy 177.832186 -22.667288) (xy 177.755509 -22.696993)
			(xy 177.676418 -22.719496) (xy 177.595588 -22.734605) (xy 177.513709 -22.742192) (xy 177.472594 -22.742652)
			(xy 177.429071 -22.742084) (xy 177.34244 -22.73358) (xy 177.257055 -22.716655) (xy 177.173731 -22.69147)
			(xy 177.093266 -22.658267) (xy 177.016429 -22.617362) (xy 176.943956 -22.569146) (xy 176.876538 -22.514083)
			(xy 176.814822 -22.452697) (xy 176.759398 -22.385575) (xy 176.710795 -22.313361) (xy 176.669479 -22.236745)
			(xy 176.652174 -22.196806) (xy 176.647921 -22.187866) (xy 176.633936 -22.17388) (xy 176.624996 -22.169628)
			(xy 176.585068 -22.152314) (xy 176.508472 -22.110985) (xy 176.436278 -22.062372) (xy 176.369178 -22.006941)
			(xy 176.307813 -21.945221) (xy 176.252769 -21.877802) (xy 176.204574 -21.80533) (xy 176.163687 -21.728496)
			(xy 176.1305 -21.648037) (xy 176.105331 -21.564721) (xy 176.088419 -21.479345) (xy 176.079928 -21.392725)
			(xy 176.079404 -21.349208) (xy 176.079404 -21.348446) (xy 176.079814 -21.310226) (xy 176.086378 -21.234067)
			(xy 176.099462 -21.158755) (xy 176.118968 -21.084845) (xy 176.131474 -21.048726) (xy 176.134055 -21.040409)
			(xy 176.134058 -21.023006) (xy 176.131474 -21.01469) (xy 176.118957 -20.978475) (xy 176.099434 -20.904375)
			(xy 176.086349 -20.828871) (xy 176.079799 -20.752523) (xy 176.079404 -20.714208) (xy 176.07999 -20.668344)
			(xy 176.089425 -20.577104) (xy 176.108186 -20.487316) (xy 176.121568 -20.443444) (xy 176.124428 -20.432883)
			(xy 176.121929 -20.411168) (xy 176.116742 -20.401534) (xy 176.096312 -20.366847) (xy 176.06107 -20.294464)
			(xy 176.032509 -20.219194) (xy 176.010862 -20.141652) (xy 175.996306 -20.062472) (xy 175.988959 -19.982301)
			(xy 175.988472 -19.942048) (xy 140.449617 -19.942048) (xy 140.472364 -19.977445) (xy 140.495002 -20.027018)
			(xy 140.510354 -20.079308) (xy 140.51811 -20.133251) (xy 140.51811 -20.187749) (xy 140.510354 -20.241692)
			(xy 140.495002 -20.293982) (xy 140.472364 -20.343555) (xy 140.442901 -20.389403) (xy 140.407215 -20.430591)
			(xy 140.36603 -20.466281) (xy 140.320185 -20.495747) (xy 140.270614 -20.51839) (xy 140.218325 -20.533747)
			(xy 140.164383 -20.541507) (xy 140.137134 -20.541996) (xy 139.146534 -20.541996) (xy 139.119279 -20.541559)
			(xy 139.065322 -20.533806) (xy 139.013019 -20.518453) (xy 138.963433 -20.495811) (xy 138.917574 -20.466343)
			(xy 138.876376 -20.430648) (xy 138.840677 -20.389453) (xy 138.811205 -20.343597) (xy 138.788559 -20.294013)
			(xy 138.773201 -20.241711) (xy 138.765443 -20.187755) (xy 67.653158 -20.187755) (xy 67.657521 -20.212789)
			(xy 67.664147 -20.289078) (xy 67.664584 -20.327366) (xy 67.66408 -20.369727) (xy 67.656027 -20.454064)
			(xy 67.639993 -20.537254) (xy 67.616125 -20.618544) (xy 67.584637 -20.697196) (xy 67.545815 -20.772499)
			(xy 67.500012 -20.843771) (xy 67.447641 -20.910367) (xy 67.389176 -20.971682) (xy 67.325148 -21.027163)
			(xy 67.256136 -21.076306) (xy 67.182766 -21.118666) (xy 67.105701 -21.153861) (xy 67.025639 -21.18157)
			(xy 66.943306 -21.201544) (xy 66.859447 -21.213601) (xy 66.774822 -21.217633) (xy 66.690197 -21.213601)
			(xy 66.606338 -21.201544) (xy 66.524005 -21.18157) (xy 66.443943 -21.153861) (xy 66.366878 -21.118666)
			(xy 66.293508 -21.076306) (xy 66.224496 -21.027163) (xy 66.160468 -20.971682) (xy 66.102003 -20.910367)
			(xy 66.049632 -20.843771) (xy 66.003829 -20.772499) (xy 65.965007 -20.697196) (xy 65.933519 -20.618544)
			(xy 65.909651 -20.537254) (xy 65.893617 -20.454064) (xy 65.885564 -20.369727) (xy 65.88506 -20.327366)
			(xy 0.509016 -20.327366) (xy 0.509016 -22.309271) (xy 65.993006 -22.309271) (xy 65.993006 -22.224549)
			(xy 66.001059 -22.140212) (xy 66.017093 -22.057022) (xy 66.040961 -21.975732) (xy 66.072449 -21.89708)
			(xy 66.111271 -21.821777) (xy 66.157074 -21.750505) (xy 66.209445 -21.683909) (xy 66.26791 -21.622594)
			(xy 66.331938 -21.567113) (xy 66.40095 -21.51797) (xy 66.47432 -21.47561) (xy 66.551385 -21.440415)
			(xy 66.631447 -21.412706) (xy 66.71378 -21.392732) (xy 66.797639 -21.380675) (xy 66.882264 -21.376644)
			(xy 66.966889 -21.380675) (xy 67.050748 -21.392732) (xy 67.133081 -21.412706) (xy 67.213143 -21.440415)
			(xy 67.290208 -21.47561) (xy 67.363578 -21.51797) (xy 67.43259 -21.567113) (xy 67.496618 -21.622594)
			(xy 67.555083 -21.683909) (xy 67.607454 -21.750505) (xy 67.653257 -21.821777) (xy 67.692079 -21.89708)
			(xy 67.723567 -21.975732) (xy 67.747435 -22.057022) (xy 67.763469 -22.140212) (xy 67.771522 -22.224549)
			(xy 67.772026 -22.26691) (xy 67.771522 -22.309271) (xy 67.763469 -22.393608) (xy 67.747435 -22.476798)
			(xy 67.723567 -22.558088) (xy 67.722853 -22.559872) (xy 114.452596 -22.559872) (xy 114.452596 -22.505328)
			(xy 114.460358 -22.45134) (xy 114.475725 -22.399006) (xy 114.498383 -22.349391) (xy 114.527872 -22.303506)
			(xy 114.563591 -22.262285) (xy 114.604813 -22.226567) (xy 114.650698 -22.19708) (xy 114.700313 -22.174422)
			(xy 114.752648 -22.159056) (xy 114.806636 -22.151295) (xy 114.833908 -22.150832) (xy 115.697508 -22.150832)
			(xy 115.724777 -22.151331) (xy 115.778758 -22.159093) (xy 115.831086 -22.174459) (xy 115.880695 -22.197116)
			(xy 115.926574 -22.226601) (xy 115.96779 -22.262316) (xy 116.003504 -22.303533) (xy 116.032988 -22.349412)
			(xy 116.055644 -22.399021) (xy 116.071008 -22.451349) (xy 116.07877 -22.505331) (xy 116.07877 -22.559869)
			(xy 116.071008 -22.613851) (xy 116.055644 -22.666179) (xy 116.032988 -22.715788) (xy 116.003504 -22.761667)
			(xy 115.96779 -22.802884) (xy 115.926574 -22.838599) (xy 115.880695 -22.868084) (xy 115.831086 -22.890741)
			(xy 115.778758 -22.906107) (xy 115.724777 -22.913869) (xy 115.697508 -22.914356) (xy 114.833908 -22.914356)
			(xy 114.806636 -22.913905) (xy 114.752648 -22.906144) (xy 114.700313 -22.890778) (xy 114.650698 -22.86812)
			(xy 114.604813 -22.838633) (xy 114.563591 -22.802915) (xy 114.527872 -22.761694) (xy 114.498383 -22.715809)
			(xy 114.475725 -22.666194) (xy 114.460358 -22.61386) (xy 114.452596 -22.559872) (xy 67.722853 -22.559872)
			(xy 67.692079 -22.63674) (xy 67.653257 -22.712043) (xy 67.607454 -22.783315) (xy 67.555083 -22.849911)
			(xy 67.496618 -22.911226) (xy 67.43259 -22.966707) (xy 67.363578 -23.01585) (xy 67.361784 -23.016886)
			(xy 136.323137 -23.016886) (xy 136.327046 -22.962479) (xy 136.338661 -22.909183) (xy 136.357746 -22.858084)
			(xy 136.383911 -22.810221) (xy 136.416623 -22.766572) (xy 136.435592 -22.74697) (xy 137.046208 -22.1361)
			(xy 137.06783 -22.115331) (xy 137.116345 -22.080114) (xy 137.169764 -22.052902) (xy 137.226775 -22.034363)
			(xy 137.285982 -22.024951) (xy 137.315956 -22.02434) (xy 137.31621 -22.02434) (xy 137.34348 -22.024815)
			(xy 137.397464 -22.032578) (xy 137.449794 -22.047945) (xy 137.499404 -22.070602) (xy 137.545285 -22.10009)
			(xy 137.586503 -22.135806) (xy 137.622218 -22.177025) (xy 137.651703 -22.222907) (xy 137.674359 -22.272518)
			(xy 137.689724 -22.324848) (xy 137.697486 -22.378832) (xy 137.697972 -22.406102) (xy 137.697972 -22.406356)
			(xy 137.6974 -22.436336) (xy 137.688023 -22.495559) (xy 137.669494 -22.552585) (xy 137.64227 -22.606009)
			(xy 137.60702 -22.654514) (xy 137.586212 -22.676104) (xy 136.975342 -23.28672) (xy 136.955728 -23.305677)
			(xy 136.912079 -23.338389) (xy 136.864216 -23.364554) (xy 136.813117 -23.383639) (xy 136.759821 -23.395254)
			(xy 136.705414 -23.399163) (xy 136.651005 -23.395286) (xy 136.597702 -23.383703) (xy 136.546591 -23.364649)
			(xy 136.498713 -23.338513) (xy 136.455044 -23.305826) (xy 136.416474 -23.267256) (xy 136.383787 -23.223587)
			(xy 136.357651 -23.175709) (xy 136.338597 -23.124598) (xy 136.327014 -23.071295) (xy 136.323137 -23.016886)
			(xy 67.361784 -23.016886) (xy 67.290208 -23.05821) (xy 67.213143 -23.093405) (xy 67.133081 -23.121114)
			(xy 67.050748 -23.141088) (xy 66.966889 -23.153145) (xy 66.882264 -23.157177) (xy 66.797639 -23.153145)
			(xy 66.71378 -23.141088) (xy 66.631447 -23.121114) (xy 66.551385 -23.093405) (xy 66.47432 -23.05821)
			(xy 66.40095 -23.01585) (xy 66.331938 -22.966707) (xy 66.26791 -22.911226) (xy 66.209445 -22.849911)
			(xy 66.157074 -22.783315) (xy 66.111271 -22.712043) (xy 66.072449 -22.63674) (xy 66.040961 -22.558088)
			(xy 66.017093 -22.476798) (xy 66.001059 -22.393608) (xy 65.993006 -22.309271) (xy 0.509016 -22.309271)
			(xy 0.509016 -23.593552) (xy 189.619128 -23.593552) (xy 189.619128 -23.593298) (xy 189.619711 -23.54856)
			(xy 189.628722 -23.459539) (xy 189.646623 -23.371871) (xy 189.673232 -23.286444) (xy 189.690248 -23.245064)
			(xy 189.69384 -23.235481) (xy 189.693822 -23.215031) (xy 189.690248 -23.20544) (xy 189.673222 -23.164064)
			(xy 189.646604 -23.078637) (xy 189.6287 -22.990968) (xy 189.619692 -22.901945) (xy 189.619128 -22.857206)
			(xy 189.619128 -22.856952) (xy 189.619632 -22.814604) (xy 189.627683 -22.73029) (xy 189.643712 -22.647124)
			(xy 189.667573 -22.565857) (xy 189.699052 -22.487227) (xy 189.737863 -22.411946) (xy 189.783653 -22.340694)
			(xy 189.836009 -22.274118) (xy 189.894457 -22.21282) (xy 189.958467 -22.157355) (xy 190.027459 -22.108226)
			(xy 190.100809 -22.065877) (xy 190.177852 -22.030693) (xy 190.257891 -22.002991) (xy 190.3402 -21.983023)
			(xy 190.424035 -21.97097) (xy 190.508636 -21.96694) (xy 190.593237 -21.97097) (xy 190.677072 -21.983023)
			(xy 190.759381 -22.002991) (xy 190.83942 -22.030693) (xy 190.916463 -22.065877) (xy 190.989813 -22.108226)
			(xy 191.058805 -22.157355) (xy 191.122815 -22.21282) (xy 191.181263 -22.274118) (xy 191.233619 -22.340694)
			(xy 191.279409 -22.411946) (xy 191.31822 -22.487227) (xy 191.349699 -22.565857) (xy 191.37356 -22.647124)
			(xy 191.389589 -22.73029) (xy 191.39764 -22.814604) (xy 191.398144 -22.856952) (xy 191.398144 -22.857206)
			(xy 191.397557 -22.901944) (xy 191.388547 -22.990965) (xy 191.370647 -23.078632) (xy 191.344039 -23.16406)
			(xy 191.327024 -23.20544) (xy 191.323489 -23.215039) (xy 191.323471 -23.235473) (xy 191.327024 -23.245064)
			(xy 191.344055 -23.286438) (xy 191.370671 -23.371866) (xy 191.388573 -23.459535) (xy 191.39758 -23.548559)
			(xy 191.398144 -23.593298) (xy 191.398144 -23.593552) (xy 191.39764 -23.6359) (xy 191.389589 -23.720214)
			(xy 191.37356 -23.80338) (xy 191.349699 -23.884647) (xy 191.31822 -23.963277) (xy 191.279409 -24.038558)
			(xy 191.233619 -24.10981) (xy 191.181263 -24.176386) (xy 191.122815 -24.237684) (xy 191.058805 -24.293149)
			(xy 190.989813 -24.342278) (xy 190.916463 -24.384627) (xy 190.83942 -24.419811) (xy 190.759381 -24.447513)
			(xy 190.677072 -24.467481) (xy 190.593237 -24.479534) (xy 190.508636 -24.483565) (xy 190.424035 -24.479534)
			(xy 190.3402 -24.467481) (xy 190.257891 -24.447513) (xy 190.177852 -24.419811) (xy 190.100809 -24.384627)
			(xy 190.027459 -24.342278) (xy 189.958467 -24.293149) (xy 189.894457 -24.237684) (xy 189.836009 -24.176386)
			(xy 189.783653 -24.10981) (xy 189.737863 -24.038558) (xy 189.699052 -23.963277) (xy 189.667573 -23.884647)
			(xy 189.643712 -23.80338) (xy 189.627683 -23.720214) (xy 189.619632 -23.6359) (xy 189.619128 -23.593552)
			(xy 0.509016 -23.593552) (xy 0.509016 -25.56891) (xy 65.510156 -25.56891) (xy 65.510621 -25.527206)
			(xy 65.518403 -25.444163) (xy 65.533928 -25.362214) (xy 65.557059 -25.282079) (xy 65.587593 -25.204462)
			(xy 65.625262 -25.130046) (xy 65.669734 -25.059485) (xy 65.720619 -24.993398) (xy 65.777469 -24.932368)
			(xy 65.839786 -24.876929) (xy 65.873122 -24.851868) (xy 65.88167 -24.844931) (xy 65.892346 -24.825708)
			(xy 65.893696 -24.814784) (xy 65.897332 -24.773398) (xy 65.911399 -24.69151) (xy 65.933041 -24.611291)
			(xy 65.962067 -24.53344) (xy 65.998226 -24.458634) (xy 66.041203 -24.387525) (xy 66.090622 -24.320733)
			(xy 66.146054 -24.25884) (xy 66.207015 -24.202385) (xy 66.272974 -24.15186) (xy 66.343357 -24.107705)
			(xy 66.41755 -24.070304) (xy 66.494907 -24.039985) (xy 66.574755 -24.01701) (xy 66.656396 -24.00158)
			(xy 66.739121 -23.99383) (xy 66.780664 -23.993348) (xy 66.824459 -23.993873) (xy 66.911625 -24.002491)
			(xy 66.997521 -24.019637) (xy 67.081315 -24.045145) (xy 67.162195 -24.078768) (xy 67.201034 -24.099012)
			(xy 67.2125 -24.10443) (xy 67.237828 -24.10443) (xy 67.249294 -24.099012) (xy 67.288138 -24.078781)
			(xy 67.369023 -24.045174) (xy 67.452816 -24.019672) (xy 67.538709 -24.002521) (xy 67.62587 -23.993888)
			(xy 67.669664 -23.993348) (xy 67.713459 -23.993873) (xy 67.800625 -24.002491) (xy 67.886521 -24.019637)
			(xy 67.970315 -24.045145) (xy 68.051195 -24.078768) (xy 68.090034 -24.099012) (xy 68.1015 -24.10443)
			(xy 68.126828 -24.10443) (xy 68.138294 -24.099012) (xy 68.177138 -24.078781) (xy 68.258023 -24.045174)
			(xy 68.341816 -24.019672) (xy 68.427709 -24.002521) (xy 68.51487 -23.993888) (xy 68.558664 -23.993348)
			(xy 68.607651 -23.994055) (xy 68.705028 -24.00487) (xy 68.752974 -24.014938) (xy 68.762324 -24.016604)
			(xy 68.781086 -24.013776) (xy 68.797533 -24.004314) (xy 68.803774 -23.997158) (xy 68.831851 -23.962886)
			(xy 68.893786 -23.899527) (xy 68.961714 -23.842641) (xy 69.034963 -23.792791) (xy 69.112805 -23.750472)
			(xy 69.19447 -23.716104) (xy 69.279148 -23.690027) (xy 69.365999 -23.672499) (xy 69.454163 -23.663695)
			(xy 69.498464 -23.663148) (xy 69.540827 -23.663615) (xy 69.625169 -23.671665) (xy 69.708365 -23.687697)
			(xy 69.789659 -23.711564) (xy 69.868317 -23.743051) (xy 69.943625 -23.781873) (xy 70.014902 -23.827677)
			(xy 70.081502 -23.880049) (xy 70.142823 -23.938516) (xy 70.198307 -24.002546) (xy 70.247454 -24.071561)
			(xy 70.250564 -24.076947) (xy 112.652614 -24.076947) (xy 112.652614 -24.022453) (xy 112.660369 -23.968515)
			(xy 112.67572 -23.916228) (xy 112.698356 -23.866659) (xy 112.727815 -23.820815) (xy 112.763499 -23.77963)
			(xy 112.80468 -23.743942) (xy 112.85052 -23.714477) (xy 112.900087 -23.691836) (xy 112.952372 -23.676478)
			(xy 113.006309 -23.668717) (xy 113.033556 -23.668228) (xy 113.897156 -23.668228) (xy 113.924413 -23.668616)
			(xy 113.978374 -23.676369) (xy 114.030682 -23.691722) (xy 114.080273 -23.714364) (xy 114.126136 -23.743834)
			(xy 114.167338 -23.779531) (xy 114.20304 -23.820729) (xy 114.232514 -23.866588) (xy 114.255162 -23.916176)
			(xy 114.270522 -23.968483) (xy 114.278281 -24.022443) (xy 114.278281 -24.076957) (xy 114.270522 -24.130917)
			(xy 114.255235 -24.182975) (xy 116.218856 -24.182975) (xy 116.218856 -24.128425) (xy 116.226619 -24.074429)
			(xy 116.241989 -24.022088) (xy 116.264651 -23.972468) (xy 116.294144 -23.926577) (xy 116.329868 -23.885352)
			(xy 116.371096 -23.84963) (xy 116.416989 -23.820139) (xy 116.466611 -23.79748) (xy 116.518953 -23.782114)
			(xy 116.572949 -23.774354) (xy 116.600224 -23.773892) (xy 117.463824 -23.773892) (xy 117.491089 -23.774472)
			(xy 117.545063 -23.782235) (xy 117.597384 -23.797601) (xy 117.646985 -23.820256) (xy 117.692857 -23.849739)
			(xy 117.734067 -23.88545) (xy 117.769776 -23.926662) (xy 117.799256 -23.972536) (xy 117.821907 -24.022139)
			(xy 117.83727 -24.07446) (xy 117.84503 -24.128435) (xy 117.84503 -24.182965) (xy 117.83727 -24.23694)
			(xy 117.821907 -24.289261) (xy 117.799256 -24.338864) (xy 117.769776 -24.384738) (xy 117.734067 -24.42595)
			(xy 117.692857 -24.461661) (xy 117.646985 -24.491144) (xy 117.597384 -24.513799) (xy 117.545063 -24.529165)
			(xy 117.491089 -24.536928) (xy 117.463824 -24.537416) (xy 116.600224 -24.537416) (xy 116.572949 -24.537046)
			(xy 116.518953 -24.529286) (xy 116.466611 -24.51392) (xy 116.416989 -24.491261) (xy 116.371096 -24.46177)
			(xy 116.329868 -24.426049) (xy 116.294144 -24.384823) (xy 116.264651 -24.338932) (xy 116.241989 -24.289312)
			(xy 116.226619 -24.236971) (xy 116.218856 -24.182975) (xy 114.255235 -24.182975) (xy 114.255162 -24.183224)
			(xy 114.232514 -24.232812) (xy 114.20304 -24.278671) (xy 114.167338 -24.319869) (xy 114.126136 -24.355566)
			(xy 114.080273 -24.385036) (xy 114.030682 -24.407678) (xy 113.978374 -24.423031) (xy 113.924414 -24.430784)
			(xy 113.897156 -24.431244) (xy 113.033556 -24.431244) (xy 113.006309 -24.430683) (xy 112.952372 -24.422922)
			(xy 112.900087 -24.407564) (xy 112.85052 -24.384923) (xy 112.80468 -24.355458) (xy 112.763499 -24.31977)
			(xy 112.727815 -24.278585) (xy 112.698356 -24.232741) (xy 112.67572 -24.183172) (xy 112.660369 -24.130885)
			(xy 112.652614 -24.076947) (xy 70.250564 -24.076947) (xy 70.289818 -24.144935) (xy 70.325015 -24.222004)
			(xy 70.352727 -24.302069) (xy 70.372702 -24.384407) (xy 70.38476 -24.46827) (xy 70.388792 -24.5529)
			(xy 70.38476 -24.63753) (xy 70.37544 -24.702351) (xy 130.235962 -24.702351) (xy 130.235962 -24.647849)
			(xy 130.243717 -24.593903) (xy 130.259071 -24.541609) (xy 130.28171 -24.492033) (xy 130.311174 -24.446182)
			(xy 130.346863 -24.404991) (xy 130.38805 -24.369298) (xy 130.433897 -24.33983) (xy 130.483472 -24.317185)
			(xy 130.535764 -24.301826) (xy 130.589709 -24.294065) (xy 130.61696 -24.293576) (xy 131.48056 -24.293576)
			(xy 131.507814 -24.294069) (xy 131.561767 -24.301821) (xy 131.614067 -24.317173) (xy 131.66365 -24.339812)
			(xy 131.709506 -24.369277) (xy 131.750702 -24.40497) (xy 131.786399 -24.446162) (xy 131.815869 -24.492015)
			(xy 131.838513 -24.541595) (xy 131.853871 -24.593894) (xy 131.861629 -24.647846) (xy 131.861629 -24.702354)
			(xy 131.853871 -24.756306) (xy 131.838513 -24.808605) (xy 131.815869 -24.858185) (xy 131.786399 -24.904038)
			(xy 131.750702 -24.94523) (xy 131.709506 -24.980923) (xy 131.66365 -25.010388) (xy 131.614067 -25.033027)
			(xy 131.561767 -25.048379) (xy 131.507814 -25.056131) (xy 131.48056 -25.056592) (xy 130.61696 -25.056592)
			(xy 130.589709 -25.056135) (xy 130.535764 -25.048374) (xy 130.483472 -25.033015) (xy 130.433897 -25.01037)
			(xy 130.38805 -24.980902) (xy 130.346863 -24.945209) (xy 130.311174 -24.904018) (xy 130.28171 -24.858167)
			(xy 130.259071 -24.808591) (xy 130.243717 -24.756297) (xy 130.235962 -24.702351) (xy 70.37544 -24.702351)
			(xy 70.372702 -24.721393) (xy 70.352727 -24.803731) (xy 70.325015 -24.883796) (xy 70.289818 -24.960865)
			(xy 70.247454 -25.034239) (xy 70.198307 -25.103254) (xy 70.142823 -25.167284) (xy 70.081502 -25.225751)
			(xy 70.014902 -25.278123) (xy 69.943625 -25.323927) (xy 69.868317 -25.362749) (xy 69.789659 -25.394236)
			(xy 69.708365 -25.418103) (xy 69.625169 -25.434135) (xy 69.540827 -25.442185) (xy 69.498464 -25.442672)
			(xy 69.449476 -25.441976) (xy 69.3521 -25.431154) (xy 69.304154 -25.421082) (xy 69.294812 -25.41935)
			(xy 69.276039 -25.422204) (xy 69.259591 -25.431693) (xy 69.253354 -25.438862) (xy 69.228687 -25.46901)
			(xy 69.174875 -25.52534) (xy 69.116354 -25.57676) (xy 69.085206 -25.600152) (xy 69.076637 -25.607067)
			(xy 69.065975 -25.626306) (xy 69.065849 -25.62733) (xy 133.339332 -25.62733) (xy 133.339332 -24.76373)
			(xy 133.339818 -24.736479) (xy 133.347574 -24.682531) (xy 133.362929 -24.630236) (xy 133.385571 -24.580659)
			(xy 133.415037 -24.534809) (xy 133.450728 -24.493618) (xy 133.491919 -24.457927) (xy 133.537769 -24.428461)
			(xy 133.587346 -24.405819) (xy 133.639641 -24.390464) (xy 133.693589 -24.382708) (xy 133.748091 -24.382708)
			(xy 133.802039 -24.390464) (xy 133.854334 -24.405819) (xy 133.903911 -24.428461) (xy 133.949761 -24.457927)
			(xy 133.990952 -24.493618) (xy 134.026643 -24.534809) (xy 134.056109 -24.580659) (xy 134.078751 -24.630236)
			(xy 134.094106 -24.682531) (xy 134.101862 -24.736479) (xy 134.102348 -24.76373) (xy 134.102348 -25.62733)
			(xy 134.101862 -25.654581) (xy 134.094106 -25.708529) (xy 134.078751 -25.760824) (xy 134.056109 -25.810401)
			(xy 134.026643 -25.856251) (xy 133.990952 -25.897442) (xy 133.949761 -25.933133) (xy 133.903911 -25.962599)
			(xy 133.854334 -25.985241) (xy 133.802039 -26.000596) (xy 133.748091 -26.008352) (xy 133.693589 -26.008352)
			(xy 133.639641 -26.000596) (xy 133.587346 -25.985241) (xy 133.537769 -25.962599) (xy 133.491919 -25.933133)
			(xy 133.450728 -25.897442) (xy 133.415037 -25.856251) (xy 133.385571 -25.810401) (xy 133.362929 -25.760824)
			(xy 133.347574 -25.708529) (xy 133.339818 -25.654581) (xy 133.339332 -25.62733) (xy 69.065849 -25.62733)
			(xy 69.064632 -25.637236) (xy 69.060986 -25.678621) (xy 69.046917 -25.760507) (xy 69.025275 -25.840725)
			(xy 68.996248 -25.918575) (xy 68.960089 -25.99338) (xy 68.917113 -26.064488) (xy 68.867694 -26.131279)
			(xy 68.812263 -26.193171) (xy 68.751303 -26.249626) (xy 68.685345 -26.300151) (xy 68.614964 -26.344307)
			(xy 68.540772 -26.381708) (xy 68.463416 -26.412028) (xy 68.38357 -26.435004) (xy 68.30193 -26.450436)
			(xy 68.219207 -26.458189) (xy 68.177664 -26.458672) (xy 68.133869 -26.458133) (xy 68.046704 -26.449518)
			(xy 67.960808 -26.432375) (xy 67.877014 -26.40687) (xy 67.796134 -26.37325) (xy 67.757294 -26.353008)
			(xy 67.745828 -26.34759) (xy 67.7205 -26.34759) (xy 67.709034 -26.353008) (xy 67.670181 -26.373222)
			(xy 67.589299 -26.406833) (xy 67.505508 -26.43234) (xy 67.419618 -26.449494) (xy 67.332457 -26.458131)
			(xy 67.288664 -26.458672) (xy 67.244869 -26.458133) (xy 67.157704 -26.449518) (xy 67.071808 -26.432375)
			(xy 66.988014 -26.40687) (xy 66.907134 -26.37325) (xy 66.868294 -26.353008) (xy 66.856828 -26.34759)
			(xy 66.8315 -26.34759) (xy 66.820034 -26.353008) (xy 66.781181 -26.373222) (xy 66.700299 -26.406833)
			(xy 66.616508 -26.43234) (xy 66.530618 -26.449494) (xy 66.443457 -26.458131) (xy 66.399664 -26.458672)
			(xy 66.358552 -26.458282) (xy 66.276678 -26.45069) (xy 66.195855 -26.435576) (xy 66.116771 -26.413067)
			(xy 66.040102 -26.383356) (xy 65.966502 -26.346696) (xy 65.8966 -26.3034) (xy 65.830991 -26.253838)
			(xy 65.770236 -26.198433) (xy 65.714853 -26.137658) (xy 65.665316 -26.072031) (xy 65.622046 -26.002113)
			(xy 65.585413 -25.928499) (xy 65.55573 -25.85182) (xy 65.53325 -25.772728) (xy 65.518165 -25.691899)
			(xy 65.510603 -25.610022) (xy 65.510156 -25.56891) (xy 0.509016 -25.56891) (xy 0.509016 -29.026161)
			(xy 11.140205 -29.026161) (xy 11.147539 -28.866724) (xy 11.162812 -28.70785) (xy 11.185984 -28.549934)
			(xy 11.216999 -28.39337) (xy 11.255779 -28.238547) (xy 11.302228 -28.085849) (xy 11.35623 -27.935656)
			(xy 11.417652 -27.788341) (xy 11.48634 -27.644271) (xy 11.562123 -27.503804) (xy 11.644814 -27.367289)
			(xy 11.734207 -27.235065) (xy 11.830079 -27.107461) (xy 11.932193 -26.984794) (xy 12.040293 -26.86737)
			(xy 12.154112 -26.75548) (xy 12.273367 -26.649402) (xy 12.397761 -26.5494) (xy 12.526985 -26.455723)
			(xy 12.660717 -26.368604) (xy 12.798626 -26.288258) (xy 12.940368 -26.214886) (xy 13.085591 -26.148671)
			(xy 13.233934 -26.089776) (xy 13.385028 -26.038349) (xy 13.538498 -25.994517) (xy 13.693962 -25.958388)
			(xy 13.851033 -25.930054) (xy 14.009321 -25.909584) (xy 14.168433 -25.897029) (xy 14.327973 -25.892421)
			(xy 14.487544 -25.895771) (xy 14.64675 -25.90707) (xy 14.805195 -25.92629) (xy 14.962485 -25.953385)
			(xy 15.118229 -25.988285) (xy 15.272039 -26.030905) (xy 15.423535 -26.081139) (xy 15.572338 -26.138862)
			(xy 15.718078 -26.203929) (xy 15.860395 -26.27618) (xy 15.998933 -26.355436) (xy 16.133349 -26.441497)
			(xy 16.263308 -26.534152) (xy 16.388487 -26.633169) (xy 16.508575 -26.738303) (xy 16.623273 -26.849292)
			(xy 16.678148 -26.907236) (xy 17.470427 -27.75458) (xy 130.687572 -27.75458) (xy 130.687572 -26.76398)
			(xy 130.688058 -26.736729) (xy 130.695814 -26.682781) (xy 130.711169 -26.630486) (xy 130.733811 -26.580909)
			(xy 130.763277 -26.535059) (xy 130.798968 -26.493868) (xy 130.840159 -26.458177) (xy 130.886009 -26.428711)
			(xy 130.935586 -26.406069) (xy 130.987881 -26.390714) (xy 131.041829 -26.382958) (xy 131.096331 -26.382958)
			(xy 131.150279 -26.390714) (xy 131.202574 -26.406069) (xy 131.252151 -26.428711) (xy 131.298001 -26.458177)
			(xy 131.339192 -26.493868) (xy 131.374883 -26.535059) (xy 131.404349 -26.580909) (xy 131.426991 -26.630486)
			(xy 131.442346 -26.682781) (xy 131.450102 -26.736729) (xy 131.450588 -26.76398) (xy 131.450588 -26.76779)
			(xy 141.621764 -26.76779) (xy 141.621764 -25.90419) (xy 141.62225 -25.876921) (xy 141.630012 -25.822937)
			(xy 141.645377 -25.770607) (xy 141.668034 -25.720997) (xy 141.69752 -25.675116) (xy 141.733235 -25.633899)
			(xy 141.774452 -25.598184) (xy 141.820333 -25.568698) (xy 141.869943 -25.546041) (xy 141.922273 -25.530676)
			(xy 141.976257 -25.522914) (xy 142.030795 -25.522914) (xy 142.084779 -25.530676) (xy 142.137109 -25.546041)
			(xy 142.186719 -25.568698) (xy 142.2326 -25.598184) (xy 142.273817 -25.633899) (xy 142.309532 -25.675116)
			(xy 142.339018 -25.720997) (xy 142.361675 -25.770607) (xy 142.37704 -25.822937) (xy 142.384802 -25.876921)
			(xy 142.385288 -25.90419) (xy 142.385288 -26.634948) (xy 175.442372 -26.634948) (xy 175.442817 -26.593237)
			(xy 175.450618 -26.510181) (xy 175.466165 -26.428221) (xy 175.489321 -26.348077) (xy 175.519883 -26.270455)
			(xy 175.557582 -26.196038) (xy 175.602086 -26.125479) (xy 175.653004 -26.059399) (xy 175.709888 -25.99838)
			(xy 175.772239 -25.942957) (xy 175.805592 -25.917906) (xy 175.814178 -25.911009) (xy 175.82483 -25.891756)
			(xy 175.826166 -25.880822) (xy 175.829855 -25.839448) (xy 175.843941 -25.757582) (xy 175.865598 -25.677385)
			(xy 175.894637 -25.599556) (xy 175.930804 -25.524774) (xy 175.973785 -25.453688) (xy 176.023205 -25.386918)
			(xy 176.078634 -25.325046) (xy 176.13959 -25.268611) (xy 176.205541 -25.218103) (xy 176.275913 -25.173964)
			(xy 176.350094 -25.136576) (xy 176.427436 -25.106267) (xy 176.507267 -25.083299) (xy 176.588892 -25.067873)
			(xy 176.671599 -25.060123) (xy 176.713134 -25.05964) (xy 176.713642 -25.05964) (xy 176.757406 -25.060139)
			(xy 176.844513 -25.068717) (xy 176.930355 -25.085818) (xy 177.0141 -25.111273) (xy 177.094937 -25.144838)
			(xy 177.133758 -25.16505) (xy 177.145111 -25.170377) (xy 177.170157 -25.170377) (xy 177.18151 -25.16505)
			(xy 177.22038 -25.144826) (xy 177.301322 -25.111257) (xy 177.38517 -25.085803) (xy 177.471113 -25.068709)
			(xy 177.55832 -25.060143) (xy 177.602134 -25.05964) (xy 177.645949 -25.060116) (xy 177.733161 -25.068665)
			(xy 177.819109 -25.085756) (xy 177.902957 -25.111222) (xy 177.983891 -25.144816) (xy 178.022758 -25.16505)
			(xy 178.034111 -25.170377) (xy 178.059157 -25.170377) (xy 178.07051 -25.16505) (xy 178.10938 -25.144826)
			(xy 178.190322 -25.111257) (xy 178.27417 -25.085803) (xy 178.360113 -25.068709) (xy 178.44732 -25.060143)
			(xy 178.491134 -25.05964) (xy 178.541288 -25.060291) (xy 178.640969 -25.071493) (xy 178.690016 -25.081992)
			(xy 178.700529 -25.083816) (xy 178.72144 -25.079687) (xy 178.7389 -25.067462) (xy 178.74488 -25.058624)
			(xy 178.766746 -25.023211) (xy 178.816155 -24.956227) (xy 178.871604 -24.894151) (xy 178.932608 -24.837525)
			(xy 178.998633 -24.786843) (xy 179.069104 -24.742549) (xy 179.143403 -24.705031) (xy 179.220882 -24.674615)
			(xy 179.300862 -24.651569) (xy 179.382645 -24.636093) (xy 179.465517 -24.628322) (xy 179.507134 -24.62784)
			(xy 179.549484 -24.628249) (xy 179.633799 -24.636303) (xy 179.716968 -24.652336) (xy 179.798236 -24.676201)
			(xy 179.876867 -24.707683) (xy 179.95215 -24.746496) (xy 180.023403 -24.79229) (xy 180.08998 -24.844649)
			(xy 180.151278 -24.9031) (xy 180.206744 -24.967112) (xy 180.255873 -25.036107) (xy 180.298222 -25.10946)
			(xy 180.333407 -25.186506) (xy 180.361109 -25.266547) (xy 180.381077 -25.348859) (xy 180.39313 -25.432696)
			(xy 180.397161 -25.5173) (xy 180.39313 -25.601904) (xy 180.381077 -25.685741) (xy 180.361109 -25.768053)
			(xy 180.333407 -25.848094) (xy 180.298222 -25.92514) (xy 180.255873 -25.998493) (xy 180.206744 -26.067488)
			(xy 180.151278 -26.1315) (xy 180.08998 -26.189951) (xy 180.023403 -26.24231) (xy 179.95215 -26.288104)
			(xy 179.876867 -26.326917) (xy 179.798236 -26.358399) (xy 179.716968 -26.382264) (xy 179.633799 -26.398297)
			(xy 179.549484 -26.406351) (xy 179.507134 -26.406856) (xy 179.505864 -26.406856) (xy 179.456029 -26.406131)
			(xy 179.35699 -26.394927) (xy 179.308252 -26.384504) (xy 179.297742 -26.382653) (xy 179.276827 -26.386794)
			(xy 179.259367 -26.39903) (xy 179.253388 -26.407872) (xy 179.230217 -26.445289) (xy 179.177598 -26.515842)
			(xy 179.118275 -26.58086) (xy 179.052827 -26.639708) (xy 179.017676 -26.66619) (xy 179.009104 -26.673102)
			(xy 178.998441 -26.692343) (xy 178.997102 -26.703274) (xy 178.993441 -26.744651) (xy 178.979354 -26.826519)
			(xy 178.957697 -26.906717) (xy 178.928657 -26.984547) (xy 178.892489 -27.059331) (xy 178.849506 -27.130418)
			(xy 178.835198 -27.149749) (xy 180.032656 -27.149749) (xy 180.032656 -27.065027) (xy 180.040709 -26.98069)
			(xy 180.056743 -26.8975) (xy 180.080611 -26.81621) (xy 180.112099 -26.737558) (xy 180.150921 -26.662255)
			(xy 180.196724 -26.590983) (xy 180.249095 -26.524387) (xy 180.30756 -26.463072) (xy 180.371588 -26.407591)
			(xy 180.4406 -26.358448) (xy 180.51397 -26.316088) (xy 180.591035 -26.280893) (xy 180.671097 -26.253184)
			(xy 180.75343 -26.23321) (xy 180.837289 -26.221153) (xy 180.921914 -26.217122) (xy 181.006539 -26.221153)
			(xy 181.090398 -26.23321) (xy 181.172731 -26.253184) (xy 181.252793 -26.280893) (xy 181.329858 -26.316088)
			(xy 181.403228 -26.358448) (xy 181.47224 -26.407591) (xy 181.536268 -26.463072) (xy 181.594733 -26.524387)
			(xy 181.647104 -26.590983) (xy 181.692907 -26.662255) (xy 181.731729 -26.737558) (xy 181.763217 -26.81621)
			(xy 181.787085 -26.8975) (xy 181.803119 -26.98069) (xy 181.811172 -27.065027) (xy 181.811676 -27.107388)
			(xy 181.811172 -27.149749) (xy 181.803119 -27.234086) (xy 181.787085 -27.317276) (xy 181.763217 -27.398566)
			(xy 181.731729 -27.477218) (xy 181.692907 -27.552521) (xy 181.647104 -27.623793) (xy 181.594733 -27.690389)
			(xy 181.536268 -27.751704) (xy 181.47224 -27.807185) (xy 181.403228 -27.856328) (xy 181.329858 -27.898688)
			(xy 181.252793 -27.933883) (xy 181.172731 -27.961592) (xy 181.090398 -27.981566) (xy 181.006539 -27.993623)
			(xy 180.921914 -27.997655) (xy 180.837289 -27.993623) (xy 180.75343 -27.981566) (xy 180.671097 -27.961592)
			(xy 180.591035 -27.933883) (xy 180.51397 -27.898688) (xy 180.4406 -27.856328) (xy 180.371588 -27.807185)
			(xy 180.30756 -27.751704) (xy 180.249095 -27.690389) (xy 180.196724 -27.623793) (xy 180.150921 -27.552521)
			(xy 180.112099 -27.477218) (xy 180.080611 -27.398566) (xy 180.056743 -27.317276) (xy 180.040709 -27.234086)
			(xy 180.032656 -27.149749) (xy 178.835198 -27.149749) (xy 178.800084 -27.197189) (xy 178.744653 -27.259061)
			(xy 178.683695 -27.315497) (xy 178.617742 -27.366004) (xy 178.547367 -27.410143) (xy 178.473184 -27.447529)
			(xy 178.395839 -27.477837) (xy 178.316006 -27.500803) (xy 178.234379 -27.516227) (xy 178.15167 -27.523974)
			(xy 178.110134 -27.524456) (xy 178.109626 -27.524456) (xy 178.065862 -27.523929) (xy 177.978756 -27.515357)
			(xy 177.892915 -27.498263) (xy 177.809169 -27.472814) (xy 177.728331 -27.439255) (xy 177.68951 -27.419046)
			(xy 177.678157 -27.413719) (xy 177.653111 -27.413719) (xy 177.641758 -27.419046) (xy 177.602894 -27.439282)
			(xy 177.521951 -27.472849) (xy 177.438101 -27.498301) (xy 177.352156 -27.515391) (xy 177.264948 -27.523955)
			(xy 177.221134 -27.524456) (xy 177.177318 -27.523994) (xy 177.090106 -27.515442) (xy 177.004158 -27.498348)
			(xy 176.920311 -27.472879) (xy 176.839376 -27.439281) (xy 176.80051 -27.419046) (xy 176.789157 -27.413719)
			(xy 176.764111 -27.413719) (xy 176.752758 -27.419046) (xy 176.713921 -27.439222) (xy 176.633081 -27.472767)
			(xy 176.549339 -27.498216) (xy 176.463504 -27.515325) (xy 176.376404 -27.523927) (xy 176.332642 -27.524456)
			(xy 176.332134 -27.524456) (xy 176.291028 -27.523955) (xy 176.209165 -27.516374) (xy 176.128351 -27.501273)
			(xy 176.049275 -27.47878) (xy 175.972611 -27.449089) (xy 175.899013 -27.412452) (xy 175.829109 -27.369181)
			(xy 175.763495 -27.319646) (xy 175.702731 -27.264268) (xy 175.647335 -27.203522) (xy 175.597779 -27.137923)
			(xy 175.554486 -27.068033) (xy 175.517825 -26.994447) (xy 175.488109 -26.917792) (xy 175.465592 -26.838723)
			(xy 175.450465 -26.757914) (xy 175.442858 -26.676054) (xy 175.442372 -26.634948) (xy 142.385288 -26.634948)
			(xy 142.385288 -26.76779) (xy 142.384802 -26.795059) (xy 142.37704 -26.849043) (xy 142.361675 -26.901373)
			(xy 142.339018 -26.950983) (xy 142.309532 -26.996864) (xy 142.273817 -27.038081) (xy 142.2326 -27.073796)
			(xy 142.186719 -27.103282) (xy 142.137109 -27.125939) (xy 142.084779 -27.141304) (xy 142.030795 -27.149066)
			(xy 141.976257 -27.149066) (xy 141.922273 -27.141304) (xy 141.869943 -27.125939) (xy 141.820333 -27.103282)
			(xy 141.774452 -27.073796) (xy 141.733235 -27.038081) (xy 141.69752 -26.996864) (xy 141.668034 -26.950983)
			(xy 141.645377 -26.901373) (xy 141.630012 -26.849043) (xy 141.62225 -26.795059) (xy 141.621764 -26.76779)
			(xy 131.450588 -26.76779) (xy 131.450588 -27.75458) (xy 131.450102 -27.781831) (xy 131.442346 -27.835779)
			(xy 131.426991 -27.888074) (xy 131.404349 -27.937651) (xy 131.374883 -27.983501) (xy 131.339192 -28.024692)
			(xy 131.298001 -28.060383) (xy 131.252151 -28.089849) (xy 131.202574 -28.112491) (xy 131.150279 -28.127846)
			(xy 131.096331 -28.135602) (xy 131.041829 -28.135602) (xy 130.987881 -28.127846) (xy 130.935586 -28.112491)
			(xy 130.886009 -28.089849) (xy 130.840159 -28.060383) (xy 130.798968 -28.024692) (xy 130.763277 -27.983501)
			(xy 130.733811 -27.937651) (xy 130.711169 -27.888074) (xy 130.695814 -27.835779) (xy 130.688058 -27.781831)
			(xy 130.687572 -27.75458) (xy 17.470427 -27.75458) (xy 17.770856 -28.07589) (xy 17.824996 -28.134528)
			(xy 17.928078 -28.256394) (xy 18.024957 -28.383247) (xy 18.115392 -28.514772) (xy 18.199158 -28.650641)
			(xy 18.276047 -28.790516) (xy 18.345869 -28.934051) (xy 18.408448 -29.080887) (xy 18.463631 -29.230661)
			(xy 18.511279 -29.382999) (xy 18.546379 -29.51861) (xy 101.326696 -29.51861) (xy 101.326696 -28.65501)
			(xy 101.327182 -28.627759) (xy 101.334938 -28.573811) (xy 101.350293 -28.521516) (xy 101.372935 -28.471939)
			(xy 101.402401 -28.426089) (xy 101.438092 -28.384898) (xy 101.479283 -28.349207) (xy 101.525133 -28.319741)
			(xy 101.57471 -28.297099) (xy 101.627005 -28.281744) (xy 101.680953 -28.273988) (xy 101.735455 -28.273988)
			(xy 101.789403 -28.281744) (xy 101.841698 -28.297099) (xy 101.891275 -28.319741) (xy 101.937125 -28.349207)
			(xy 101.978316 -28.384898) (xy 102.014007 -28.426089) (xy 102.043473 -28.471939) (xy 102.066115 -28.521516)
			(xy 102.08147 -28.573811) (xy 102.089226 -28.627759) (xy 102.089712 -28.65501) (xy 102.089712 -29.24302)
			(xy 135.551672 -29.24302) (xy 135.551672 -28.25242) (xy 135.552158 -28.225169) (xy 135.559914 -28.171221)
			(xy 135.575269 -28.118926) (xy 135.597911 -28.069349) (xy 135.627377 -28.023499) (xy 135.663068 -27.982308)
			(xy 135.704259 -27.946617) (xy 135.750109 -27.917151) (xy 135.799686 -27.894509) (xy 135.851981 -27.879154)
			(xy 135.905929 -27.871398) (xy 135.960431 -27.871398) (xy 136.014379 -27.879154) (xy 136.066674 -27.894509)
			(xy 136.116251 -27.917151) (xy 136.162101 -27.946617) (xy 136.203292 -27.982308) (xy 136.238983 -28.023499)
			(xy 136.268449 -28.069349) (xy 136.291091 -28.118926) (xy 136.306446 -28.171221) (xy 136.314202 -28.225169)
			(xy 136.314688 -28.25242) (xy 136.314688 -28.526871) (xy 139.853386 -28.526871) (xy 139.853386 -28.472329)
			(xy 139.861148 -28.418343) (xy 139.876513 -28.366011) (xy 139.89917 -28.316397) (xy 139.928656 -28.270513)
			(xy 139.964371 -28.229293) (xy 140.005589 -28.193574) (xy 140.051471 -28.164084) (xy 140.101082 -28.141424)
			(xy 140.153414 -28.126054) (xy 140.207399 -28.118289) (xy 140.23467 -28.1178) (xy 141.09827 -28.1178)
			(xy 141.12554 -28.118337) (xy 141.179524 -28.126095) (xy 141.231856 -28.141457) (xy 141.281468 -28.164111)
			(xy 141.32735 -28.193595) (xy 141.36857 -28.229309) (xy 141.404287 -28.270526) (xy 141.433775 -28.316406)
			(xy 141.456432 -28.366016) (xy 141.471798 -28.418346) (xy 141.479561 -28.47233) (xy 141.479561 -28.52687)
			(xy 141.471798 -28.580854) (xy 141.456432 -28.633184) (xy 141.433775 -28.682794) (xy 141.404287 -28.728674)
			(xy 141.36857 -28.769891) (xy 141.32735 -28.805605) (xy 141.281468 -28.835089) (xy 141.231856 -28.857743)
			(xy 141.179524 -28.873105) (xy 141.12554 -28.880863) (xy 141.09827 -28.881324) (xy 140.23467 -28.881324)
			(xy 140.207399 -28.880911) (xy 140.153414 -28.873146) (xy 140.101082 -28.857776) (xy 140.051471 -28.835116)
			(xy 140.005589 -28.805626) (xy 139.964371 -28.769907) (xy 139.928656 -28.728687) (xy 139.89917 -28.682803)
			(xy 139.876513 -28.633189) (xy 139.861148 -28.580857) (xy 139.853386 -28.526871) (xy 136.314688 -28.526871)
			(xy 136.314688 -29.24302) (xy 136.314202 -29.270271) (xy 136.306446 -29.324219) (xy 136.291091 -29.376514)
			(xy 136.268449 -29.426091) (xy 136.238983 -29.471941) (xy 136.203292 -29.513132) (xy 136.162101 -29.548823)
			(xy 136.116251 -29.578289) (xy 136.066674 -29.600931) (xy 136.014379 -29.616286) (xy 135.960431 -29.624042)
			(xy 135.905929 -29.624042) (xy 135.851981 -29.616286) (xy 135.799686 -29.600931) (xy 135.750109 -29.578289)
			(xy 135.704259 -29.548823) (xy 135.663068 -29.513132) (xy 135.627377 -29.471941) (xy 135.597911 -29.426091)
			(xy 135.575269 -29.376514) (xy 135.559914 -29.324219) (xy 135.552158 -29.270271) (xy 135.551672 -29.24302)
			(xy 102.089712 -29.24302) (xy 102.089712 -29.51861) (xy 102.089226 -29.545861) (xy 102.08147 -29.599809)
			(xy 102.066115 -29.652104) (xy 102.043473 -29.701681) (xy 102.014007 -29.747531) (xy 101.978316 -29.788722)
			(xy 101.937125 -29.824413) (xy 101.891275 -29.853879) (xy 101.841698 -29.876521) (xy 101.789403 -29.891876)
			(xy 101.735455 -29.899632) (xy 101.680953 -29.899632) (xy 101.627005 -29.891876) (xy 101.57471 -29.876521)
			(xy 101.525133 -29.853879) (xy 101.479283 -29.824413) (xy 101.438092 -29.788722) (xy 101.402401 -29.747531)
			(xy 101.372935 -29.701681) (xy 101.350293 -29.652104) (xy 101.334938 -29.599809) (xy 101.327182 -29.545861)
			(xy 101.326696 -29.51861) (xy 18.546379 -29.51861) (xy 18.551274 -29.537523) (xy 18.583516 -29.693848)
			(xy 18.607926 -29.851586) (xy 18.624443 -30.010345) (xy 18.63109 -30.1338) (xy 197.595716 -30.1338)
			(xy 197.599747 -30.049172) (xy 197.611805 -29.965311) (xy 197.631779 -29.882976) (xy 197.65949 -29.802912)
			(xy 197.694686 -29.725844) (xy 197.737048 -29.652472) (xy 197.786193 -29.583458) (xy 197.841676 -29.519429)
			(xy 197.902994 -29.460963) (xy 197.969592 -29.408591) (xy 198.040866 -29.362787) (xy 198.116172 -29.323965)
			(xy 198.194827 -29.292477) (xy 198.276119 -29.268609) (xy 198.359312 -29.252576) (xy 198.443652 -29.244524)
			(xy 198.486014 -29.244036) (xy 198.524304 -29.244437) (xy 198.600598 -29.251046) (xy 198.676041 -29.264197)
			(xy 198.750071 -29.283791) (xy 198.786242 -29.29636) (xy 198.794679 -29.299011) (xy 198.812349 -29.299011)
			(xy 198.820786 -29.29636) (xy 198.856961 -29.283808) (xy 198.930995 -29.264238) (xy 199.006435 -29.251093)
			(xy 199.082726 -29.244471) (xy 199.121014 -29.244036) (xy 199.159304 -29.244437) (xy 199.235598 -29.251046)
			(xy 199.311041 -29.264197) (xy 199.385071 -29.283791) (xy 199.421242 -29.29636) (xy 199.429679 -29.299011)
			(xy 199.447349 -29.299011) (xy 199.455786 -29.29636) (xy 199.491961 -29.283808) (xy 199.565995 -29.264238)
			(xy 199.641435 -29.251093) (xy 199.717726 -29.244471) (xy 199.756014 -29.244036) (xy 199.794304 -29.244437)
			(xy 199.870598 -29.251046) (xy 199.946041 -29.264197) (xy 200.020071 -29.283791) (xy 200.056242 -29.29636)
			(xy 200.064679 -29.299011) (xy 200.082349 -29.299011) (xy 200.090786 -29.29636) (xy 200.126961 -29.283808)
			(xy 200.200995 -29.264238) (xy 200.276435 -29.251093) (xy 200.352726 -29.244471) (xy 200.391014 -29.244036)
			(xy 200.431702 -29.244422) (xy 200.512738 -29.251848) (xy 200.592757 -29.266645) (xy 200.67109 -29.288689)
			(xy 200.747082 -29.317797) (xy 200.820096 -29.353725) (xy 200.889524 -29.396173) (xy 200.954784 -29.444785)
			(xy 201.015331 -29.499155) (xy 201.070657 -29.558829) (xy 201.120302 -29.623307) (xy 201.163849 -29.69205)
			(xy 201.200934 -29.764484) (xy 201.216514 -29.802074) (xy 201.22098 -29.811942) (xy 201.236608 -29.826918)
			(xy 201.256995 -29.83419) (xy 201.267822 -29.833824) (xy 201.286077 -29.832403) (xy 201.322664 -29.83088)
			(xy 201.340974 -29.830776) (xy 201.383338 -29.831187) (xy 201.467682 -29.839239) (xy 201.550879 -29.855272)
			(xy 201.632176 -29.87914) (xy 201.710835 -29.910629) (xy 201.786145 -29.949452) (xy 201.857423 -29.995258)
			(xy 201.924025 -30.047632) (xy 201.985346 -30.1061) (xy 202.040832 -30.170132) (xy 202.08998 -30.239149)
			(xy 202.132344 -30.312525) (xy 202.167542 -30.389596) (xy 202.195254 -30.469663) (xy 202.21523 -30.552003)
			(xy 202.227288 -30.635868) (xy 202.23132 -30.7205) (xy 202.227288 -30.805132) (xy 202.21523 -30.888997)
			(xy 202.195254 -30.971337) (xy 202.167542 -31.051404) (xy 202.132344 -31.128475) (xy 202.08998 -31.201851)
			(xy 202.040832 -31.270868) (xy 201.985346 -31.3349) (xy 201.924025 -31.393368) (xy 201.857423 -31.445742)
			(xy 201.786145 -31.491548) (xy 201.710835 -31.530371) (xy 201.632176 -31.56186) (xy 201.550879 -31.585728)
			(xy 201.467682 -31.601761) (xy 201.383338 -31.609813) (xy 201.340974 -31.6103) (xy 201.302684 -31.609905)
			(xy 201.226389 -31.603295) (xy 201.150947 -31.590142) (xy 201.076917 -31.570546) (xy 201.040746 -31.557976)
			(xy 201.032309 -31.555325) (xy 201.014639 -31.555325) (xy 201.006202 -31.557976) (xy 200.970027 -31.570528)
			(xy 200.895993 -31.590099) (xy 200.820553 -31.603244) (xy 200.744262 -31.609866) (xy 200.705974 -31.6103)
			(xy 200.667684 -31.609905) (xy 200.591389 -31.603295) (xy 200.515947 -31.590142) (xy 200.441917 -31.570546)
			(xy 200.405746 -31.557976) (xy 200.397309 -31.555325) (xy 200.379639 -31.555325) (xy 200.371202 -31.557976)
			(xy 200.335027 -31.570528) (xy 200.260993 -31.590099) (xy 200.185553 -31.603244) (xy 200.109262 -31.609866)
			(xy 200.070974 -31.6103) (xy 200.032684 -31.609905) (xy 199.956389 -31.603295) (xy 199.880947 -31.590142)
			(xy 199.806917 -31.570546) (xy 199.770746 -31.557976) (xy 199.762309 -31.555325) (xy 199.744639 -31.555325)
			(xy 199.736202 -31.557976) (xy 199.700027 -31.570528) (xy 199.625993 -31.590099) (xy 199.550553 -31.603244)
			(xy 199.474262 -31.609866) (xy 199.435974 -31.6103) (xy 199.395288 -31.609814) (xy 199.314256 -31.602396)
			(xy 199.23424 -31.587608) (xy 199.15591 -31.565572) (xy 199.07992 -31.536472) (xy 199.006906 -31.500553)
			(xy 198.937478 -31.458114) (xy 198.872217 -31.40951) (xy 198.81167 -31.355148) (xy 198.756341 -31.295482)
			(xy 198.706694 -31.231012) (xy 198.663144 -31.162275) (xy 198.626056 -31.089848) (xy 198.610474 -31.052262)
			(xy 198.605924 -31.042441) (xy 198.590335 -31.027459) (xy 198.569982 -31.020164) (xy 198.559166 -31.020512)
			(xy 198.540911 -31.021927) (xy 198.504324 -31.023454) (xy 198.486014 -31.02356) (xy 198.443652 -31.023076)
			(xy 198.359312 -31.015024) (xy 198.276119 -30.998991) (xy 198.194827 -30.975123) (xy 198.116172 -30.943635)
			(xy 198.040866 -30.904813) (xy 197.969592 -30.859009) (xy 197.902994 -30.806637) (xy 197.841676 -30.748171)
			(xy 197.786193 -30.684142) (xy 197.737048 -30.615128) (xy 197.694686 -30.541756) (xy 197.65949 -30.464688)
			(xy 197.631779 -30.384624) (xy 197.611805 -30.302289) (xy 197.599747 -30.218428) (xy 197.595716 -30.1338)
			(xy 18.63109 -30.1338) (xy 18.633025 -30.16973) (xy 18.633652 -30.329344) (xy 18.626321 -30.488792)
			(xy 18.611051 -30.647675) (xy 18.587881 -30.8056) (xy 18.556867 -30.962174) (xy 18.518086 -31.117007)
			(xy 18.471636 -31.269714) (xy 18.417631 -31.419917) (xy 18.356206 -31.56724) (xy 18.287514 -31.711318)
			(xy 18.211725 -31.851793) (xy 18.129028 -31.988316) (xy 18.039629 -32.120546) (xy 17.943749 -32.248156)
			(xy 17.841627 -32.370828) (xy 17.733517 -32.488256) (xy 17.619688 -32.60015) (xy 17.500423 -32.70623)
			(xy 17.376019 -32.806234) (xy 17.246784 -32.899911) (xy 17.173557 -32.94761) (xy 102.642416 -32.94761)
			(xy 102.642416 -31.95701) (xy 102.642902 -31.929759) (xy 102.650658 -31.875811) (xy 102.666013 -31.823516)
			(xy 102.688655 -31.773939) (xy 102.718121 -31.728089) (xy 102.753812 -31.686898) (xy 102.795003 -31.651207)
			(xy 102.840853 -31.621741) (xy 102.89043 -31.599099) (xy 102.942725 -31.583744) (xy 102.996673 -31.575988)
			(xy 103.051175 -31.575988) (xy 103.105123 -31.583744) (xy 103.157418 -31.599099) (xy 103.206995 -31.621741)
			(xy 103.252845 -31.651207) (xy 103.294036 -31.686898) (xy 103.329727 -31.728089) (xy 103.359193 -31.773939)
			(xy 103.381835 -31.823516) (xy 103.39719 -31.875811) (xy 103.404946 -31.929759) (xy 103.405432 -31.95701)
			(xy 103.405432 -32.405066) (xy 105.659936 -32.405066) (xy 105.659936 -31.541466) (xy 105.660422 -31.514215)
			(xy 105.668178 -31.460267) (xy 105.683533 -31.407972) (xy 105.706175 -31.358395) (xy 105.735641 -31.312545)
			(xy 105.771332 -31.271354) (xy 105.812523 -31.235663) (xy 105.858373 -31.206197) (xy 105.90795 -31.183555)
			(xy 105.960245 -31.1682) (xy 106.014193 -31.160444) (xy 106.068695 -31.160444) (xy 106.122643 -31.1682)
			(xy 106.174938 -31.183555) (xy 106.224515 -31.206197) (xy 106.270365 -31.235663) (xy 106.311556 -31.271354)
			(xy 106.347247 -31.312545) (xy 106.376713 -31.358395) (xy 106.399355 -31.407972) (xy 106.41471 -31.460267)
			(xy 106.422466 -31.514215) (xy 106.422952 -31.541466) (xy 106.422952 -31.65856) (xy 140.278612 -31.65856)
			(xy 140.278612 -30.79496) (xy 140.279098 -30.767709) (xy 140.286854 -30.713761) (xy 140.302209 -30.661466)
			(xy 140.324851 -30.611889) (xy 140.354317 -30.566039) (xy 140.390008 -30.524848) (xy 140.431199 -30.489157)
			(xy 140.477049 -30.459691) (xy 140.526626 -30.437049) (xy 140.578921 -30.421694) (xy 140.632869 -30.413938)
			(xy 140.687371 -30.413938) (xy 140.741319 -30.421694) (xy 140.793614 -30.437049) (xy 140.843191 -30.459691)
			(xy 140.889041 -30.489157) (xy 140.930232 -30.524848) (xy 140.965923 -30.566039) (xy 140.995389 -30.611889)
			(xy 141.018031 -30.661466) (xy 141.033386 -30.713761) (xy 141.041142 -30.767709) (xy 141.041628 -30.79496)
			(xy 141.041628 -31.65856) (xy 141.041311 -31.67634) (xy 144.616932 -31.67634) (xy 144.616932 -30.81274)
			(xy 144.617418 -30.785489) (xy 144.625174 -30.731541) (xy 144.640529 -30.679246) (xy 144.663171 -30.629669)
			(xy 144.692637 -30.583819) (xy 144.728328 -30.542628) (xy 144.769519 -30.506937) (xy 144.815369 -30.477471)
			(xy 144.864946 -30.454829) (xy 144.917241 -30.439474) (xy 144.971189 -30.431718) (xy 145.025691 -30.431718)
			(xy 145.079639 -30.439474) (xy 145.131934 -30.454829) (xy 145.181511 -30.477471) (xy 145.227361 -30.506937)
			(xy 145.268552 -30.542628) (xy 145.304243 -30.583819) (xy 145.333709 -30.629669) (xy 145.356351 -30.679246)
			(xy 145.371706 -30.731541) (xy 145.379462 -30.785489) (xy 145.379948 -30.81274) (xy 145.379948 -31.67634)
			(xy 145.379462 -31.703591) (xy 145.371706 -31.757539) (xy 145.356351 -31.809834) (xy 145.333709 -31.859411)
			(xy 145.304243 -31.905261) (xy 145.268552 -31.946452) (xy 145.227361 -31.982143) (xy 145.181511 -32.011609)
			(xy 145.131934 -32.034251) (xy 145.079639 -32.049606) (xy 145.025691 -32.057362) (xy 144.971189 -32.057362)
			(xy 144.917241 -32.049606) (xy 144.864946 -32.034251) (xy 144.815369 -32.011609) (xy 144.769519 -31.982143)
			(xy 144.728328 -31.946452) (xy 144.692637 -31.905261) (xy 144.663171 -31.859411) (xy 144.640529 -31.809834)
			(xy 144.625174 -31.757539) (xy 144.617418 -31.703591) (xy 144.616932 -31.67634) (xy 141.041311 -31.67634)
			(xy 141.041142 -31.685811) (xy 141.033386 -31.739759) (xy 141.018031 -31.792054) (xy 140.995389 -31.841631)
			(xy 140.965923 -31.887481) (xy 140.930232 -31.928672) (xy 140.889041 -31.964363) (xy 140.843191 -31.993829)
			(xy 140.793614 -32.016471) (xy 140.741319 -32.031826) (xy 140.687371 -32.039582) (xy 140.632869 -32.039582)
			(xy 140.578921 -32.031826) (xy 140.526626 -32.016471) (xy 140.477049 -31.993829) (xy 140.431199 -31.964363)
			(xy 140.390008 -31.928672) (xy 140.354317 -31.887481) (xy 140.324851 -31.841631) (xy 140.302209 -31.792054)
			(xy 140.286854 -31.739759) (xy 140.279098 -31.685811) (xy 140.278612 -31.65856) (xy 106.422952 -31.65856)
			(xy 106.422952 -32.405066) (xy 106.422466 -32.432317) (xy 106.41471 -32.486265) (xy 106.399355 -32.53856)
			(xy 106.376713 -32.588137) (xy 106.347247 -32.633987) (xy 106.311556 -32.675178) (xy 106.270365 -32.710869)
			(xy 106.224515 -32.740335) (xy 106.174938 -32.762977) (xy 106.122643 -32.778332) (xy 106.068695 -32.786088)
			(xy 106.014193 -32.786088) (xy 105.960245 -32.778332) (xy 105.90795 -32.762977) (xy 105.858373 -32.740335)
			(xy 105.812523 -32.710869) (xy 105.771332 -32.675178) (xy 105.735641 -32.633987) (xy 105.706175 -32.588137)
			(xy 105.683533 -32.53856) (xy 105.668178 -32.486265) (xy 105.660422 -32.432317) (xy 105.659936 -32.405066)
			(xy 103.405432 -32.405066) (xy 103.405432 -32.94761) (xy 103.404946 -32.974861) (xy 103.39719 -33.028809)
			(xy 103.390276 -33.052356) (xy 119.734235 -33.052356) (xy 119.734235 -32.997844) (xy 119.741993 -32.943888)
			(xy 119.757352 -32.891585) (xy 119.779997 -32.842) (xy 119.80947 -32.796143) (xy 119.845169 -32.754947)
			(xy 119.886367 -32.719252) (xy 119.932226 -32.689783) (xy 119.981813 -32.667141) (xy 120.034117 -32.651787)
			(xy 120.088074 -32.644033) (xy 120.11533 -32.643572) (xy 120.97893 -32.643572) (xy 121.006178 -32.6441)
			(xy 121.06012 -32.65186) (xy 121.112408 -32.667217) (xy 121.161979 -32.689858) (xy 121.207823 -32.719324)
			(xy 121.249008 -32.755014) (xy 121.284694 -32.796201) (xy 121.314156 -32.842047) (xy 121.336794 -32.89162)
			(xy 121.352147 -32.943909) (xy 121.359902 -32.997852) (xy 121.359902 -33.052348) (xy 121.352147 -33.106291)
			(xy 121.336794 -33.15858) (xy 121.314156 -33.208153) (xy 121.284694 -33.253999) (xy 121.249008 -33.295186)
			(xy 121.207823 -33.330876) (xy 121.161979 -33.360342) (xy 121.112408 -33.382983) (xy 121.06012 -33.39834)
			(xy 121.006178 -33.4061) (xy 120.97893 -33.406588) (xy 120.11533 -33.406588) (xy 120.088074 -33.406167)
			(xy 120.034117 -33.398413) (xy 119.981813 -33.383059) (xy 119.932226 -33.360417) (xy 119.886367 -33.330948)
			(xy 119.845169 -33.295253) (xy 119.80947 -33.254057) (xy 119.779997 -33.2082) (xy 119.757352 -33.158615)
			(xy 119.741993 -33.106312) (xy 119.734235 -33.052356) (xy 103.390276 -33.052356) (xy 103.381835 -33.081104)
			(xy 103.359193 -33.130681) (xy 103.329727 -33.176531) (xy 103.294036 -33.217722) (xy 103.252845 -33.253413)
			(xy 103.206995 -33.282879) (xy 103.157418 -33.305521) (xy 103.105123 -33.320876) (xy 103.051175 -33.328632)
			(xy 102.996673 -33.328632) (xy 102.942725 -33.320876) (xy 102.89043 -33.305521) (xy 102.840853 -33.282879)
			(xy 102.795003 -33.253413) (xy 102.753812 -33.217722) (xy 102.718121 -33.176531) (xy 102.688655 -33.130681)
			(xy 102.666013 -33.081104) (xy 102.650658 -33.028809) (xy 102.642902 -32.974861) (xy 102.642416 -32.94761)
			(xy 17.173557 -32.94761) (xy 17.11304 -32.98703) (xy 16.975119 -33.067374) (xy 16.833366 -33.140743)
			(xy 16.688131 -33.206955) (xy 16.539776 -33.265845) (xy 16.38867 -33.317266) (xy 16.235188 -33.361091)
			(xy 16.079713 -33.397211) (xy 15.922631 -33.425536) (xy 15.764332 -33.445995) (xy 15.605209 -33.458538)
			(xy 15.44566 -33.463134) (xy 15.286079 -33.459771) (xy 15.126865 -33.448457) (xy 14.968413 -33.42922)
			(xy 14.811116 -33.402109) (xy 14.655367 -33.367191) (xy 14.501552 -33.324553) (xy 14.350053 -33.2743)
			(xy 14.201248 -33.216557) (xy 14.055506 -33.151469) (xy 13.91319 -33.079197) (xy 13.774653 -32.999921)
			(xy 13.64024 -32.913837) (xy 13.510286 -32.82116) (xy 13.385112 -32.72212) (xy 13.265032 -32.616964)
			(xy 13.150342 -32.505953) (xy 13.095478 -32.447992) (xy 12.00277 -31.279592) (xy 11.948692 -31.220903)
			(xy 11.845626 -31.099035) (xy 11.748763 -30.972182) (xy 11.658343 -30.840658) (xy 11.574591 -30.704792)
			(xy 11.497716 -30.564919) (xy 11.427907 -30.421388) (xy 11.36534 -30.274557) (xy 11.310169 -30.124789)
			(xy 11.262532 -29.972457) (xy 11.222547 -29.81794) (xy 11.190314 -29.661623) (xy 11.165912 -29.503893)
			(xy 11.149402 -29.345143) (xy 11.140826 -29.185767) (xy 11.140205 -29.026161) (xy 0.509016 -29.026161)
			(xy 0.509016 -33.838388) (xy 122.111008 -33.838388) (xy 122.111008 -32.974788) (xy 122.111494 -32.947519)
			(xy 122.119256 -32.893535) (xy 122.134621 -32.841205) (xy 122.157278 -32.791595) (xy 122.186764 -32.745714)
			(xy 122.222479 -32.704497) (xy 122.263696 -32.668782) (xy 122.309577 -32.639296) (xy 122.359187 -32.616639)
			(xy 122.411517 -32.601274) (xy 122.465501 -32.593512) (xy 122.520039 -32.593512) (xy 122.574023 -32.601274)
			(xy 122.626353 -32.616639) (xy 122.675963 -32.639296) (xy 122.721844 -32.668782) (xy 122.763061 -32.704497)
			(xy 122.798776 -32.745714) (xy 122.828262 -32.791595) (xy 122.850919 -32.841205) (xy 122.866284 -32.893535)
			(xy 122.874046 -32.947519) (xy 122.874532 -32.974788) (xy 122.874532 -33.413556) (xy 124.175423 -33.413556)
			(xy 124.175423 -33.359044) (xy 124.183181 -33.305087) (xy 124.198539 -33.252783) (xy 124.221185 -33.203197)
			(xy 124.250658 -33.157339) (xy 124.286357 -33.116142) (xy 124.327555 -33.080446) (xy 124.373415 -33.050976)
			(xy 124.423002 -33.028332) (xy 124.475306 -33.012977) (xy 124.529264 -33.005222) (xy 124.55652 -33.00476)
			(xy 125.42012 -33.00476) (xy 125.447368 -33.005312) (xy 125.501309 -33.01307) (xy 125.553597 -33.028425)
			(xy 125.603167 -33.051066) (xy 125.649011 -33.08053) (xy 125.690196 -33.116218) (xy 125.725882 -33.157405)
			(xy 125.755344 -33.20325) (xy 125.777982 -33.252822) (xy 125.793335 -33.305111) (xy 125.80109 -33.359052)
			(xy 125.80109 -33.413548) (xy 125.793335 -33.467489) (xy 125.777982 -33.519778) (xy 125.755344 -33.56935)
			(xy 125.725882 -33.615195) (xy 125.690196 -33.656382) (xy 125.649011 -33.69207) (xy 125.603167 -33.721534)
			(xy 125.553597 -33.744175) (xy 125.501309 -33.75953) (xy 125.447368 -33.767288) (xy 125.42012 -33.767776)
			(xy 124.55652 -33.767776) (xy 124.529264 -33.767378) (xy 124.475306 -33.759623) (xy 124.423002 -33.744268)
			(xy 124.373415 -33.721624) (xy 124.327555 -33.692154) (xy 124.286357 -33.656458) (xy 124.250658 -33.615261)
			(xy 124.221185 -33.569403) (xy 124.198539 -33.519817) (xy 124.183181 -33.467513) (xy 124.175423 -33.413556)
			(xy 122.874532 -33.413556) (xy 122.874532 -33.838388) (xy 122.874046 -33.865657) (xy 122.866284 -33.919641)
			(xy 122.850919 -33.971971) (xy 122.828262 -34.021581) (xy 122.798776 -34.067462) (xy 122.763061 -34.108679)
			(xy 122.721844 -34.144394) (xy 122.675963 -34.17388) (xy 122.626353 -34.196537) (xy 122.574023 -34.211902)
			(xy 122.520039 -34.219664) (xy 122.465501 -34.219664) (xy 122.411517 -34.211902) (xy 122.359187 -34.196537)
			(xy 122.309577 -34.17388) (xy 122.263696 -34.144394) (xy 122.222479 -34.108679) (xy 122.186764 -34.067462)
			(xy 122.157278 -34.021581) (xy 122.134621 -33.971971) (xy 122.119256 -33.919641) (xy 122.111494 -33.865657)
			(xy 122.111008 -33.838388) (xy 0.509016 -33.838388) (xy 0.509016 -36.080556) (xy 122.143423 -36.080556)
			(xy 122.143423 -36.026044) (xy 122.151181 -35.972087) (xy 122.166539 -35.919783) (xy 122.189185 -35.870197)
			(xy 122.218658 -35.824339) (xy 122.254357 -35.783142) (xy 122.295555 -35.747446) (xy 122.341415 -35.717976)
			(xy 122.391002 -35.695332) (xy 122.443306 -35.679977) (xy 122.497264 -35.672222) (xy 122.52452 -35.67176)
			(xy 123.38812 -35.67176) (xy 123.415368 -35.672312) (xy 123.469309 -35.68007) (xy 123.521597 -35.695425)
			(xy 123.571167 -35.718066) (xy 123.617011 -35.74753) (xy 123.658196 -35.783218) (xy 123.693882 -35.824405)
			(xy 123.723344 -35.87025) (xy 123.745982 -35.919822) (xy 123.761335 -35.972111) (xy 123.76909 -36.026052)
			(xy 123.76909 -36.080548) (xy 123.761335 -36.134489) (xy 123.745982 -36.186778) (xy 123.723344 -36.23635)
			(xy 123.693882 -36.282195) (xy 123.658196 -36.323382) (xy 123.617011 -36.35907) (xy 123.571167 -36.388534)
			(xy 123.521597 -36.411175) (xy 123.469309 -36.42653) (xy 123.415368 -36.434288) (xy 123.38812 -36.434776)
			(xy 122.52452 -36.434776) (xy 122.497264 -36.434378) (xy 122.443306 -36.426623) (xy 122.391002 -36.411268)
			(xy 122.341415 -36.388624) (xy 122.295555 -36.359154) (xy 122.254357 -36.323458) (xy 122.218658 -36.282261)
			(xy 122.189185 -36.236403) (xy 122.166539 -36.186817) (xy 122.151181 -36.134513) (xy 122.143423 -36.080556)
			(xy 0.509016 -36.080556) (xy 0.509016 -39.23137) (xy 9.080235 -39.23137) (xy 9.080235 -39.10223)
			(xy 9.088185 -38.973335) (xy 9.104055 -38.845175) (xy 9.127784 -38.718234) (xy 9.159283 -38.592995)
			(xy 9.198432 -38.469932) (xy 9.245083 -38.349513) (xy 9.299058 -38.232194) (xy 9.360153 -38.11842)
			(xy 9.428136 -38.008623) (xy 9.50275 -37.90322) (xy 9.583711 -37.80261) (xy 9.670711 -37.707175)
			(xy 9.763422 -37.617276) (xy 9.861492 -37.533255) (xy 9.964547 -37.455431) (xy 10.072198 -37.384099)
			(xy 10.184037 -37.319529) (xy 10.299638 -37.261967) (xy 10.418563 -37.21163) (xy 10.540362 -37.16871)
			(xy 10.664572 -37.133369) (xy 10.790721 -37.105742) (xy 10.918333 -37.085933) (xy 11.046922 -37.074017)
			(xy 11.176 -37.070041) (xy 11.305078 -37.074017) (xy 11.433667 -37.085933) (xy 11.521898 -37.099629)
			(xy 170.60087 -37.099629) (xy 170.60087 -37.000299) (xy 170.608862 -36.901292) (xy 170.624796 -36.803249)
			(xy 170.648567 -36.706806) (xy 170.680022 -36.612588) (xy 170.718955 -36.521208) (xy 170.765116 -36.433256)
			(xy 170.818204 -36.349304) (xy 170.877875 -36.269895) (xy 170.943743 -36.195546) (xy 171.01538 -36.126738)
			(xy 171.092321 -36.063918) (xy 171.174067 -36.007493) (xy 171.260089 -35.957828) (xy 171.349828 -35.915246)
			(xy 171.442702 -35.880024) (xy 171.53811 -35.852388) (xy 171.635432 -35.83252) (xy 171.734037 -35.820547)
			(xy 171.833286 -35.816548) (xy 171.932535 -35.820547) (xy 172.03114 -35.83252) (xy 172.128462 -35.852388)
			(xy 172.22387 -35.880024) (xy 172.316744 -35.915246) (xy 172.406483 -35.957828) (xy 172.492505 -36.007493)
			(xy 172.574251 -36.063918) (xy 172.651192 -36.126738) (xy 172.722829 -36.195546) (xy 172.788697 -36.269895)
			(xy 172.848368 -36.349304) (xy 172.901456 -36.433256) (xy 172.947617 -36.521208) (xy 172.98655 -36.612588)
			(xy 173.018005 -36.706806) (xy 173.041776 -36.803249) (xy 173.05771 -36.901292) (xy 173.065702 -37.000299)
			(xy 173.066202 -37.049964) (xy 173.065702 -37.099629) (xy 173.05771 -37.198636) (xy 173.041776 -37.296679)
			(xy 173.034033 -37.328094) (xy 197.270624 -37.328094) (xy 197.271107 -37.28698) (xy 197.278695 -37.205103)
			(xy 197.293804 -37.124275) (xy 197.316307 -37.045187) (xy 197.346011 -36.968512) (xy 197.382664 -36.894904)
			(xy 197.425951 -36.824993) (xy 197.475504 -36.759373) (xy 197.5309 -36.698606) (xy 197.591667 -36.643209)
			(xy 197.657286 -36.593655) (xy 197.727197 -36.550367) (xy 197.800804 -36.513715) (xy 197.877479 -36.48401)
			(xy 197.956568 -36.461506) (xy 198.037395 -36.446396) (xy 198.119272 -36.438808) (xy 198.160386 -36.438332)
			(xy 198.203952 -36.438853) (xy 198.290667 -36.447372) (xy 198.376134 -36.464329) (xy 198.459533 -36.489562)
			(xy 198.540065 -36.522829) (xy 198.616958 -36.563811) (xy 198.689475 -36.612116) (xy 198.756921 -36.66728)
			(xy 198.81865 -36.728775) (xy 198.87407 -36.796011) (xy 198.922649 -36.868345) (xy 198.963923 -36.945081)
			(xy 198.997496 -37.025486) (xy 199.010778 -37.066982) (xy 199.013703 -37.075249) (xy 199.024271 -37.089233)
			(xy 199.038923 -37.098854) (xy 199.047354 -37.101272) (xy 199.088321 -37.111837) (xy 199.168226 -37.13965)
			(xy 199.24513 -37.174922) (xy 199.318339 -37.217334) (xy 199.387193 -37.266504) (xy 199.451068 -37.321986)
			(xy 199.509389 -37.383281) (xy 199.529427 -37.408809) (xy 207.619596 -37.408809) (xy 207.619596 -37.324087)
			(xy 207.627649 -37.23975) (xy 207.643683 -37.15656) (xy 207.667551 -37.07527) (xy 207.699039 -36.996618)
			(xy 207.737861 -36.921315) (xy 207.783664 -36.850043) (xy 207.836035 -36.783447) (xy 207.8945 -36.722132)
			(xy 207.958528 -36.666651) (xy 208.02754 -36.617508) (xy 208.10091 -36.575148) (xy 208.177975 -36.539953)
			(xy 208.258037 -36.512244) (xy 208.34037 -36.49227) (xy 208.424229 -36.480213) (xy 208.508854 -36.476182)
			(xy 208.593479 -36.480213) (xy 208.677338 -36.49227) (xy 208.759671 -36.512244) (xy 208.839733 -36.539953)
			(xy 208.916798 -36.575148) (xy 208.990168 -36.617508) (xy 209.05918 -36.666651) (xy 209.123208 -36.722132)
			(xy 209.181673 -36.783447) (xy 209.234044 -36.850043) (xy 209.279847 -36.921315) (xy 209.318669 -36.996618)
			(xy 209.350157 -37.07527) (xy 209.374025 -37.15656) (xy 209.390059 -37.23975) (xy 209.398112 -37.324087)
			(xy 209.398616 -37.366448) (xy 209.398112 -37.408809) (xy 209.390059 -37.493146) (xy 209.374025 -37.576336)
			(xy 209.350157 -37.657626) (xy 209.318669 -37.736278) (xy 209.279847 -37.811581) (xy 209.234044 -37.882853)
			(xy 209.181673 -37.949449) (xy 209.123208 -38.010764) (xy 209.05918 -38.066245) (xy 208.990168 -38.115388)
			(xy 208.916798 -38.157748) (xy 208.839733 -38.192943) (xy 208.759671 -38.220652) (xy 208.677338 -38.240626)
			(xy 208.593479 -38.252683) (xy 208.508854 -38.256715) (xy 208.424229 -38.252683) (xy 208.34037 -38.240626)
			(xy 208.258037 -38.220652) (xy 208.177975 -38.192943) (xy 208.10091 -38.157748) (xy 208.02754 -38.115388)
			(xy 207.958528 -38.066245) (xy 207.8945 -38.010764) (xy 207.836035 -37.949449) (xy 207.783664 -37.882853)
			(xy 207.737861 -37.811581) (xy 207.699039 -37.736278) (xy 207.667551 -37.657626) (xy 207.643683 -37.576336)
			(xy 207.627649 -37.493146) (xy 207.619596 -37.408809) (xy 199.529427 -37.408809) (xy 199.561629 -37.449835)
			(xy 199.607316 -37.521047) (xy 199.646037 -37.596273) (xy 199.677444 -37.674835) (xy 199.701252 -37.756024)
			(xy 199.717247 -37.839106) (xy 199.725284 -37.92333) (xy 199.725788 -37.965634) (xy 199.72532 -38.006748)
			(xy 199.71773 -38.088625) (xy 199.702618 -38.169453) (xy 199.680113 -38.248541) (xy 199.650407 -38.325216)
			(xy 199.613754 -38.398823) (xy 199.570465 -38.468734) (xy 199.520911 -38.534353) (xy 199.465514 -38.595119)
			(xy 199.404746 -38.650516) (xy 199.339127 -38.70007) (xy 199.269216 -38.743357) (xy 199.195608 -38.78001)
			(xy 199.118933 -38.809716) (xy 199.039845 -38.83222) (xy 198.959017 -38.847331) (xy 198.87714 -38.85492)
			(xy 198.836026 -38.855396) (xy 198.792461 -38.854844) (xy 198.705747 -38.846327) (xy 198.620282 -38.829372)
			(xy 198.536884 -38.804141) (xy 198.456353 -38.770876) (xy 198.379461 -38.729896) (xy 198.306944 -38.681594)
			(xy 198.239498 -38.626432) (xy 198.177769 -38.56494) (xy 198.122348 -38.497707) (xy 198.073767 -38.425377)
			(xy 198.032492 -38.348643) (xy 197.998917 -38.26824) (xy 197.985634 -38.226746) (xy 197.982688 -38.218487)
			(xy 197.97213 -38.204501) (xy 197.957486 -38.194877) (xy 197.949058 -38.192456) (xy 197.908101 -38.181857)
			(xy 197.828197 -38.154046) (xy 197.751293 -38.118776) (xy 197.678085 -38.076367) (xy 197.609232 -38.0272)
			(xy 197.545356 -37.97172) (xy 197.487035 -37.910428) (xy 197.434795 -37.843877) (xy 197.389107 -37.772668)
			(xy 197.350384 -37.697444) (xy 197.318976 -37.618885) (xy 197.295165 -37.537699) (xy 197.279169 -37.454619)
			(xy 197.271129 -37.370397) (xy 197.270624 -37.328094) (xy 173.034033 -37.328094) (xy 173.018005 -37.393122)
			(xy 172.98655 -37.48734) (xy 172.947617 -37.57872) (xy 172.901456 -37.666672) (xy 172.848368 -37.750624)
			(xy 172.788697 -37.830033) (xy 172.722829 -37.904382) (xy 172.651192 -37.97319) (xy 172.574251 -38.03601)
			(xy 172.492505 -38.092435) (xy 172.406483 -38.1421) (xy 172.316744 -38.184682) (xy 172.22387 -38.219904)
			(xy 172.128462 -38.24754) (xy 172.03114 -38.267408) (xy 171.932535 -38.279381) (xy 171.833286 -38.283381)
			(xy 171.734037 -38.279381) (xy 171.635432 -38.267408) (xy 171.53811 -38.24754) (xy 171.442702 -38.219904)
			(xy 171.349828 -38.184682) (xy 171.260089 -38.1421) (xy 171.174067 -38.092435) (xy 171.092321 -38.03601)
			(xy 171.01538 -37.97319) (xy 170.943743 -37.904382) (xy 170.877875 -37.830033) (xy 170.818204 -37.750624)
			(xy 170.765116 -37.666672) (xy 170.718955 -37.57872) (xy 170.680022 -37.48734) (xy 170.648567 -37.393122)
			(xy 170.624796 -37.296679) (xy 170.608862 -37.198636) (xy 170.60087 -37.099629) (xy 11.521898 -37.099629)
			(xy 11.561279 -37.105742) (xy 11.687428 -37.133369) (xy 11.811638 -37.16871) (xy 11.933437 -37.21163)
			(xy 12.052362 -37.261967) (xy 12.167963 -37.319529) (xy 12.279802 -37.384099) (xy 12.387453 -37.455431)
			(xy 12.490508 -37.533255) (xy 12.588578 -37.617276) (xy 12.681289 -37.707175) (xy 12.768289 -37.80261)
			(xy 12.84925 -37.90322) (xy 12.923864 -38.008623) (xy 12.991847 -38.11842) (xy 13.052942 -38.232194)
			(xy 13.106917 -38.349513) (xy 13.153568 -38.469932) (xy 13.192717 -38.592995) (xy 13.224216 -38.718234)
			(xy 13.247945 -38.845175) (xy 13.263815 -38.973335) (xy 13.271765 -39.10223) (xy 13.272262 -39.1668)
			(xy 13.271765 -39.23137) (xy 13.263815 -39.360265) (xy 13.256012 -39.423283) (xy 254.45872 -39.423283)
			(xy 254.45872 -39.338561) (xy 254.466773 -39.254224) (xy 254.482807 -39.171034) (xy 254.506675 -39.089744)
			(xy 254.538163 -39.011092) (xy 254.576985 -38.935789) (xy 254.622788 -38.864517) (xy 254.675159 -38.797921)
			(xy 254.733624 -38.736606) (xy 254.797652 -38.681125) (xy 254.866664 -38.631982) (xy 254.940034 -38.589622)
			(xy 255.017099 -38.554427) (xy 255.097161 -38.526718) (xy 255.179494 -38.506744) (xy 255.263353 -38.494687)
			(xy 255.347978 -38.490656) (xy 255.432603 -38.494687) (xy 255.516462 -38.506744) (xy 255.598795 -38.526718)
			(xy 255.678857 -38.554427) (xy 255.755922 -38.589622) (xy 255.829292 -38.631982) (xy 255.898304 -38.681125)
			(xy 255.962332 -38.736606) (xy 256.020797 -38.797921) (xy 256.073168 -38.864517) (xy 256.118971 -38.935789)
			(xy 256.157793 -39.011092) (xy 256.189281 -39.089744) (xy 256.213149 -39.171034) (xy 256.229183 -39.254224)
			(xy 256.237236 -39.338561) (xy 256.23774 -39.380922) (xy 256.237236 -39.423283) (xy 256.229183 -39.50762)
			(xy 256.213149 -39.59081) (xy 256.189281 -39.6721) (xy 256.157793 -39.750752) (xy 256.118971 -39.826055)
			(xy 256.073168 -39.897327) (xy 256.020797 -39.963923) (xy 255.962332 -40.025238) (xy 255.898304 -40.080719)
			(xy 255.829292 -40.129862) (xy 255.755922 -40.172222) (xy 255.678857 -40.207417) (xy 255.598795 -40.235126)
			(xy 255.516462 -40.2551) (xy 255.432603 -40.267157) (xy 255.347978 -40.271189) (xy 255.263353 -40.267157)
			(xy 255.179494 -40.2551) (xy 255.097161 -40.235126) (xy 255.017099 -40.207417) (xy 254.940034 -40.172222)
			(xy 254.866664 -40.129862) (xy 254.797652 -40.080719) (xy 254.733624 -40.025238) (xy 254.675159 -39.963923)
			(xy 254.622788 -39.897327) (xy 254.576985 -39.826055) (xy 254.538163 -39.750752) (xy 254.506675 -39.6721)
			(xy 254.482807 -39.59081) (xy 254.466773 -39.50762) (xy 254.45872 -39.423283) (xy 13.256012 -39.423283)
			(xy 13.247945 -39.488425) (xy 13.224216 -39.615366) (xy 13.192717 -39.740605) (xy 13.153568 -39.863668)
			(xy 13.106917 -39.984087) (xy 13.052942 -40.101406) (xy 12.991847 -40.21518) (xy 12.923864 -40.324977)
			(xy 12.84925 -40.43038) (xy 12.768289 -40.53099) (xy 12.681289 -40.626425) (xy 12.588578 -40.716324)
			(xy 12.490508 -40.800345) (xy 12.413317 -40.858637) (xy 24.936192 -40.858637) (xy 24.936192 -40.773915)
			(xy 24.944245 -40.689578) (xy 24.960279 -40.606388) (xy 24.984147 -40.525098) (xy 25.015635 -40.446446)
			(xy 25.054457 -40.371143) (xy 25.10026 -40.299871) (xy 25.152631 -40.233275) (xy 25.211096 -40.17196)
			(xy 25.275124 -40.116479) (xy 25.344136 -40.067336) (xy 25.417506 -40.024976) (xy 25.494571 -39.989781)
			(xy 25.574633 -39.962072) (xy 25.656966 -39.942098) (xy 25.740825 -39.930041) (xy 25.82545 -39.92601)
			(xy 25.910075 -39.930041) (xy 25.993934 -39.942098) (xy 26.076267 -39.962072) (xy 26.156329 -39.989781)
			(xy 26.233394 -40.024976) (xy 26.306764 -40.067336) (xy 26.375776 -40.116479) (xy 26.439804 -40.17196)
			(xy 26.498269 -40.233275) (xy 26.55064 -40.299871) (xy 26.596443 -40.371143) (xy 26.635265 -40.446446)
			(xy 26.666753 -40.525098) (xy 26.690621 -40.606388) (xy 26.706655 -40.689578) (xy 26.711938 -40.744902)
			(xy 235.083357 -40.744902) (xy 235.087362 -40.656994) (xy 235.099345 -40.569814) (xy 235.119205 -40.484085)
			(xy 235.14678 -40.400517) (xy 235.181839 -40.319803) (xy 235.224092 -40.242611) (xy 235.27319 -40.169582)
			(xy 235.328726 -40.10132) (xy 235.390238 -40.03839) (xy 235.457219 -39.981316) (xy 235.529112 -39.930568)
			(xy 235.605321 -39.886568) (xy 235.685216 -39.849681) (xy 235.768135 -39.820212) (xy 235.85339 -39.798405)
			(xy 235.940274 -39.784441) (xy 236.028068 -39.778435) (xy 236.116045 -39.780439) (xy 236.203475 -39.790434)
			(xy 236.289634 -39.808338) (xy 236.373808 -39.834002) (xy 236.455299 -39.867215) (xy 236.533433 -39.907701)
			(xy 236.607561 -39.955123) (xy 236.677069 -40.00909) (xy 236.741383 -40.069155) (xy 236.799967 -40.134819)
			(xy 236.852338 -40.205538) (xy 236.898061 -40.280726) (xy 236.936758 -40.359761) (xy 236.968107 -40.441987)
			(xy 236.991849 -40.526723) (xy 237.007787 -40.613267) (xy 237.015789 -40.700902) (xy 237.01629 -40.744902)
			(xy 237.015789 -40.788902) (xy 237.007787 -40.876537) (xy 236.994276 -40.9499) (xy 246.935452 -40.9499)
			(xy 246.939482 -40.865295) (xy 246.951537 -40.781456) (xy 246.971506 -40.699142) (xy 246.999209 -40.619099)
			(xy 247.034396 -40.542053) (xy 247.076747 -40.468699) (xy 247.125879 -40.399704) (xy 247.181347 -40.335692)
			(xy 247.242648 -40.277242) (xy 247.309228 -40.224883) (xy 247.380484 -40.179091) (xy 247.45577 -40.14028)
			(xy 247.534404 -40.1088) (xy 247.615675 -40.084938) (xy 247.698846 -40.06891) (xy 247.783163 -40.060859)
			(xy 247.825514 -40.060372) (xy 247.868043 -40.060872) (xy 247.952713 -40.068982) (xy 248.036223 -40.085137)
			(xy 248.11781 -40.109189) (xy 248.196728 -40.140918) (xy 248.272258 -40.180035) (xy 248.343709 -40.226182)
			(xy 248.41043 -40.278938) (xy 248.441464 -40.308022) (xy 248.441718 -40.308276) (xy 248.44904 -40.314652)
			(xy 248.467069 -40.321822) (xy 248.47677 -40.322246) (xy 248.557288 -40.321992) (xy 248.575576 -40.314626)
			(xy 248.582688 -40.307514) (xy 248.613778 -40.278057) (xy 248.680689 -40.224588) (xy 248.752429 -40.177798)
			(xy 248.828335 -40.13812) (xy 248.907704 -40.105923) (xy 248.9898 -40.081504) (xy 249.073863 -40.065089)
			(xy 249.159115 -40.056831) (xy 249.20194 -40.056308) (xy 249.202448 -40.056308) (xy 249.244796 -40.056782)
			(xy 249.329107 -40.064837) (xy 249.412272 -40.08087) (xy 249.493536 -40.104735) (xy 249.572163 -40.136216)
			(xy 249.647442 -40.175029) (xy 249.718691 -40.220821) (xy 249.785265 -40.273178) (xy 249.84656 -40.331627)
			(xy 249.902022 -40.395637) (xy 249.951149 -40.464629) (xy 249.993496 -40.537978) (xy 250.028678 -40.615021)
			(xy 250.056379 -40.695058) (xy 250.076346 -40.777367) (xy 250.088399 -40.8612) (xy 250.092429 -40.9458)
			(xy 250.088399 -41.0304) (xy 250.076346 -41.114233) (xy 250.056379 -41.196542) (xy 250.028678 -41.276579)
			(xy 249.993496 -41.353622) (xy 249.951149 -41.426971) (xy 249.902022 -41.495963) (xy 249.84656 -41.559973)
			(xy 249.785265 -41.618422) (xy 249.718691 -41.670779) (xy 249.647442 -41.716571) (xy 249.572163 -41.755384)
			(xy 249.493536 -41.786865) (xy 249.412272 -41.81073) (xy 249.329107 -41.826763) (xy 249.244796 -41.834818)
			(xy 249.202448 -41.835324) (xy 249.159919 -41.834822) (xy 249.07525 -41.826709) (xy 248.991741 -41.810552)
			(xy 248.910155 -41.7865) (xy 248.831237 -41.754771) (xy 248.755707 -41.715655) (xy 248.684255 -41.66951)
			(xy 248.617533 -41.616756) (xy 248.586498 -41.587674) (xy 248.586244 -41.58742) (xy 248.578903 -41.58107)
			(xy 248.560888 -41.573885) (xy 248.551192 -41.57345) (xy 248.470674 -41.573704) (xy 248.452386 -41.58107)
			(xy 248.445274 -41.588182) (xy 248.414201 -41.617657) (xy 248.347287 -41.671125) (xy 248.275544 -41.717913)
			(xy 248.199635 -41.757589) (xy 248.120264 -41.789784) (xy 248.038166 -41.8142) (xy 247.954101 -41.830612)
			(xy 247.868848 -41.838866) (xy 247.826022 -41.839388) (xy 247.825514 -41.839388) (xy 247.783163 -41.838941)
			(xy 247.698846 -41.83089) (xy 247.615675 -41.814862) (xy 247.534404 -41.791) (xy 247.45577 -41.75952)
			(xy 247.380484 -41.720709) (xy 247.309228 -41.674917) (xy 247.242648 -41.622558) (xy 247.181347 -41.564108)
			(xy 247.125879 -41.500096) (xy 247.076747 -41.431101) (xy 247.034396 -41.357747) (xy 246.999209 -41.280701)
			(xy 246.971506 -41.200658) (xy 246.951537 -41.118344) (xy 246.939482 -41.034505) (xy 246.935452 -40.9499)
			(xy 236.994276 -40.9499) (xy 236.991849 -40.963081) (xy 236.968107 -41.047817) (xy 236.936758 -41.130043)
			(xy 236.898061 -41.209078) (xy 236.852338 -41.284266) (xy 236.799967 -41.354985) (xy 236.741383 -41.420649)
			(xy 236.677069 -41.480714) (xy 236.607561 -41.534681) (xy 236.533433 -41.582103) (xy 236.455299 -41.622589)
			(xy 236.373808 -41.655802) (xy 236.289634 -41.681466) (xy 236.203475 -41.69937) (xy 236.116045 -41.709365)
			(xy 236.028068 -41.711369) (xy 235.940274 -41.705363) (xy 235.85339 -41.691399) (xy 235.768135 -41.669592)
			(xy 235.685216 -41.640123) (xy 235.605321 -41.603236) (xy 235.529112 -41.559236) (xy 235.457219 -41.508488)
			(xy 235.390238 -41.451414) (xy 235.328726 -41.388484) (xy 235.27319 -41.320222) (xy 235.224092 -41.247193)
			(xy 235.181839 -41.170001) (xy 235.14678 -41.089287) (xy 235.119205 -41.005719) (xy 235.099345 -40.91999)
			(xy 235.087362 -40.83281) (xy 235.083357 -40.744902) (xy 26.711938 -40.744902) (xy 26.714708 -40.773915)
			(xy 26.715212 -40.816276) (xy 26.714708 -40.858637) (xy 26.706655 -40.942974) (xy 26.690621 -41.026164)
			(xy 26.666753 -41.107454) (xy 26.635265 -41.186106) (xy 26.596443 -41.261409) (xy 26.55064 -41.332681)
			(xy 26.498269 -41.399277) (xy 26.439804 -41.460592) (xy 26.375776 -41.516073) (xy 26.306764 -41.565216)
			(xy 26.233394 -41.607576) (xy 26.156329 -41.642771) (xy 26.076267 -41.67048) (xy 25.993934 -41.690454)
			(xy 25.910075 -41.702511) (xy 25.82545 -41.706543) (xy 25.740825 -41.702511) (xy 25.656966 -41.690454)
			(xy 25.574633 -41.67048) (xy 25.494571 -41.642771) (xy 25.417506 -41.607576) (xy 25.344136 -41.565216)
			(xy 25.275124 -41.516073) (xy 25.211096 -41.460592) (xy 25.152631 -41.399277) (xy 25.10026 -41.332681)
			(xy 25.054457 -41.261409) (xy 25.015635 -41.186106) (xy 24.984147 -41.107454) (xy 24.960279 -41.026164)
			(xy 24.944245 -40.942974) (xy 24.936192 -40.858637) (xy 12.413317 -40.858637) (xy 12.387453 -40.878169)
			(xy 12.279802 -40.949501) (xy 12.167963 -41.014071) (xy 12.052362 -41.071633) (xy 11.933437 -41.12197)
			(xy 11.811638 -41.16489) (xy 11.687428 -41.200231) (xy 11.561279 -41.227858) (xy 11.433667 -41.247667)
			(xy 11.305078 -41.259583) (xy 11.176 -41.26356) (xy 11.046922 -41.259583) (xy 10.918333 -41.247667)
			(xy 10.790721 -41.227858) (xy 10.664572 -41.200231) (xy 10.540362 -41.16489) (xy 10.418563 -41.12197)
			(xy 10.299638 -41.071633) (xy 10.184037 -41.014071) (xy 10.072198 -40.949501) (xy 9.964547 -40.878169)
			(xy 9.861492 -40.800345) (xy 9.763422 -40.716324) (xy 9.670711 -40.626425) (xy 9.583711 -40.53099)
			(xy 9.50275 -40.43038) (xy 9.428136 -40.324977) (xy 9.360153 -40.21518) (xy 9.299058 -40.101406)
			(xy 9.245083 -39.984087) (xy 9.198432 -39.863668) (xy 9.159283 -39.740605) (xy 9.127784 -39.615366)
			(xy 9.104055 -39.488425) (xy 9.088185 -39.360265) (xy 9.080235 -39.23137) (xy 0.509016 -39.23137)
			(xy 0.509016 -43.481752) (xy 178.630072 -43.481752) (xy 178.630072 -42.618152) (xy 178.630558 -42.590883)
			(xy 178.63832 -42.536899) (xy 178.653685 -42.484569) (xy 178.676342 -42.434959) (xy 178.705828 -42.389078)
			(xy 178.741543 -42.347861) (xy 178.78276 -42.312146) (xy 178.828641 -42.28266) (xy 178.878251 -42.260003)
			(xy 178.930581 -42.244638) (xy 178.984565 -42.236876) (xy 179.039103 -42.236876) (xy 179.093087 -42.244638)
			(xy 179.145417 -42.260003) (xy 179.195027 -42.28266) (xy 179.240908 -42.312146) (xy 179.282125 -42.347861)
			(xy 179.31784 -42.389078) (xy 179.347326 -42.434959) (xy 179.369983 -42.484569) (xy 179.385348 -42.536899)
			(xy 179.39311 -42.590883) (xy 179.393596 -42.618152) (xy 179.393596 -43.481752) (xy 179.39311 -43.509021)
			(xy 179.385348 -43.563005) (xy 179.369983 -43.615335) (xy 179.347326 -43.664945) (xy 179.31784 -43.710826)
			(xy 179.282125 -43.752043) (xy 179.240908 -43.787758) (xy 179.195027 -43.817244) (xy 179.145417 -43.839901)
			(xy 179.093087 -43.855266) (xy 179.039103 -43.863028) (xy 178.984565 -43.863028) (xy 178.930581 -43.855266)
			(xy 178.878251 -43.839901) (xy 178.828641 -43.817244) (xy 178.78276 -43.787758) (xy 178.741543 -43.752043)
			(xy 178.705828 -43.710826) (xy 178.676342 -43.664945) (xy 178.653685 -43.615335) (xy 178.63832 -43.563005)
			(xy 178.630558 -43.509021) (xy 178.630072 -43.481752) (xy 0.509016 -43.481752) (xy 0.509016 -47.04994)
			(xy 59.582066 -47.04994) (xy 59.586045 -46.890389) (xy 59.597972 -46.731234) (xy 59.617818 -46.572872)
			(xy 59.645532 -46.415696) (xy 59.681047 -46.260096) (xy 59.724273 -46.10646) (xy 59.775104 -45.95517)
			(xy 59.833413 -45.806602) (xy 59.899054 -45.661125) (xy 59.971866 -45.519101) (xy 60.051666 -45.380882)
			(xy 60.138257 -45.246813) (xy 60.231423 -45.117227) (xy 60.330933 -44.992446) (xy 60.436538 -44.87278)
			(xy 60.547978 -44.758527) (xy 60.664973 -44.649971) (xy 60.787235 -44.547381) (xy 60.914458 -44.451014)
			(xy 61.046326 -44.361107) (xy 61.182512 -44.277886) (xy 61.322677 -44.201556) (xy 61.466472 -44.132307)
			(xy 61.613541 -44.070313) (xy 61.763517 -44.015726) (xy 61.916027 -43.968683) (xy 62.070693 -43.9293)
			(xy 62.227129 -43.897676) (xy 62.384947 -43.873888) (xy 62.543755 -43.857997) (xy 62.703158 -43.850041)
			(xy 62.782958 -43.849544) (xy 64.382904 -43.849544) (xy 64.462705 -43.850033) (xy 64.622107 -43.857989)
			(xy 64.780916 -43.87388) (xy 64.938734 -43.897668) (xy 65.095171 -43.929293) (xy 65.249837 -43.968675)
			(xy 65.402347 -44.015719) (xy 65.552323 -44.070306) (xy 65.699392 -44.132301) (xy 65.843188 -44.201549)
			(xy 65.983353 -44.277879) (xy 66.119539 -44.361101) (xy 66.251408 -44.451008) (xy 66.378631 -44.547376)
			(xy 66.500893 -44.649966) (xy 66.617889 -44.758522) (xy 66.729328 -44.872775) (xy 66.834934 -44.992442)
			(xy 66.934444 -45.117223) (xy 67.02761 -45.246809) (xy 67.114201 -45.380878) (xy 67.194001 -45.519097)
			(xy 67.266813 -45.661122) (xy 67.332455 -45.806599) (xy 67.390764 -45.955168) (xy 67.441595 -46.106458)
			(xy 67.484821 -46.260094) (xy 67.520336 -46.415694) (xy 67.54805 -46.572871) (xy 67.567896 -46.731233)
			(xy 67.579823 -46.890388) (xy 67.583802 -47.04994) (xy 89.78165 -47.04994) (xy 89.78563 -46.895439)
			(xy 89.797557 -46.741349) (xy 89.817402 -46.588076) (xy 89.84511 -46.436028) (xy 89.880608 -46.285609)
			(xy 89.923803 -46.137216) (xy 89.97458 -45.991243) (xy 90.032804 -45.848078) (xy 90.098321 -45.708101)
			(xy 90.170957 -45.571681) (xy 90.250519 -45.439181) (xy 90.336796 -45.310953) (xy 90.42956 -45.187337)
			(xy 90.528565 -45.068659) (xy 90.633548 -44.955236) (xy 90.74423 -44.847368) (xy 90.860319 -44.74534)
			(xy 90.981506 -44.649424) (xy 91.10747 -44.559873) (xy 91.237877 -44.476926) (xy 91.372381 -44.400801)
			(xy 91.510626 -44.331702) (xy 91.652244 -44.269811) (xy 91.796861 -44.215293) (xy 91.944092 -44.168291)
			(xy 92.093548 -44.128931) (xy 92.244832 -44.097317) (xy 92.397543 -44.073533) (xy 92.551275 -44.057642)
			(xy 92.705622 -44.049686) (xy 92.782898 -44.049188) (xy 94.383098 -44.049188) (xy 94.460374 -44.049669)
			(xy 94.614722 -44.057625) (xy 94.768456 -44.073516) (xy 94.921168 -44.0973) (xy 95.072452 -44.128914)
			(xy 95.221909 -44.168274) (xy 95.369142 -44.215276) (xy 95.513759 -44.269795) (xy 95.655379 -44.331686)
			(xy 95.793624 -44.400785) (xy 95.928129 -44.47691) (xy 96.058537 -44.559858) (xy 96.184502 -44.649409)
			(xy 96.30569 -44.745326) (xy 96.421779 -44.847354) (xy 96.532463 -44.955223) (xy 96.555487 -44.980098)
			(xy 181.659784 -44.980098) (xy 181.659784 -44.116498) (xy 181.66027 -44.089229) (xy 181.668032 -44.035245)
			(xy 181.683397 -43.982915) (xy 181.706054 -43.933305) (xy 181.73554 -43.887424) (xy 181.771255 -43.846207)
			(xy 181.812472 -43.810492) (xy 181.858353 -43.781006) (xy 181.907963 -43.758349) (xy 181.960293 -43.742984)
			(xy 182.014277 -43.735222) (xy 182.068815 -43.735222) (xy 182.122799 -43.742984) (xy 182.175129 -43.758349)
			(xy 182.224739 -43.781006) (xy 182.27062 -43.810492) (xy 182.311837 -43.846207) (xy 182.347552 -43.887424)
			(xy 182.377038 -43.933305) (xy 182.399695 -43.982915) (xy 182.412218 -44.025566) (xy 236.740192 -44.025566)
			(xy 236.74068 -43.984453) (xy 236.74827 -43.902577) (xy 236.763381 -43.82175) (xy 236.785886 -43.742663)
			(xy 236.815591 -43.665989) (xy 236.852243 -43.592383) (xy 236.895531 -43.522473) (xy 236.945083 -43.456854)
			(xy 237.000479 -43.396088) (xy 237.061245 -43.340691) (xy 237.126863 -43.291137) (xy 237.196773 -43.247849)
			(xy 237.270378 -43.211196) (xy 237.347052 -43.181489) (xy 237.426139 -43.158984) (xy 237.506965 -43.143872)
			(xy 237.588841 -43.136281) (xy 237.629954 -43.135804) (xy 237.672596 -43.136331) (xy 237.757484 -43.144543)
			(xy 237.841197 -43.160838) (xy 237.922968 -43.185068) (xy 237.962694 -43.200574) (xy 237.971356 -43.203655)
			(xy 237.989722 -43.204046) (xy 237.998508 -43.201336) (xy 238.034032 -43.189272) (xy 238.106663 -43.170452)
			(xy 238.18062 -43.157817) (xy 238.25538 -43.151455) (xy 238.292894 -43.151044) (xy 238.332166 -43.151496)
			(xy 238.410399 -43.158477) (xy 238.487712 -43.172332) (xy 238.563501 -43.192954) (xy 238.600488 -43.206162)
			(xy 238.609037 -43.208926) (xy 238.626991 -43.208926) (xy 238.63554 -43.206162) (xy 238.672533 -43.192975)
			(xy 238.748323 -43.172363) (xy 238.825633 -43.158506) (xy 238.903863 -43.151512) (xy 238.943134 -43.151044)
			(xy 238.981423 -43.151469) (xy 239.057717 -43.158071) (xy 239.133159 -43.171215) (xy 239.207191 -43.190803)
			(xy 239.243362 -43.203368) (xy 239.251799 -43.206019) (xy 239.269469 -43.206019) (xy 239.277906 -43.203368)
			(xy 239.314089 -43.190839) (xy 239.38812 -43.171262) (xy 239.463558 -43.158111) (xy 239.539846 -43.151482)
			(xy 239.578134 -43.151044) (xy 239.616423 -43.151469) (xy 239.692717 -43.158071) (xy 239.768159 -43.171215)
			(xy 239.842191 -43.190803) (xy 239.878362 -43.203368) (xy 239.886799 -43.206019) (xy 239.904469 -43.206019)
			(xy 239.912906 -43.203368) (xy 239.949089 -43.190839) (xy 240.02312 -43.171262) (xy 240.098558 -43.158111)
			(xy 240.174846 -43.151482) (xy 240.213134 -43.151044) (xy 240.25606 -43.151581) (xy 240.341511 -43.159862)
			(xy 240.425768 -43.176335) (xy 240.508046 -43.200846) (xy 240.587581 -43.233168) (xy 240.613613 -43.246802)
			(xy 243.62918 -43.246802) (xy 243.629584 -43.208512) (xy 243.636192 -43.132218) (xy 243.649342 -43.056775)
			(xy 243.668936 -42.982745) (xy 243.681504 -42.946574) (xy 243.684156 -42.938137) (xy 243.684156 -42.920466)
			(xy 243.681504 -42.91203) (xy 243.668959 -42.875853) (xy 243.649386 -42.80182) (xy 243.636239 -42.72638)
			(xy 243.629616 -42.65009) (xy 243.62918 -42.611802) (xy 243.629684 -42.569441) (xy 243.637737 -42.485104)
			(xy 243.653771 -42.401914) (xy 243.677639 -42.320624) (xy 243.709127 -42.241972) (xy 243.747949 -42.166669)
			(xy 243.793752 -42.095397) (xy 243.846123 -42.028801) (xy 243.904588 -41.967486) (xy 243.968616 -41.912005)
			(xy 244.037628 -41.862862) (xy 244.110998 -41.820502) (xy 244.188063 -41.785307) (xy 244.268125 -41.757598)
			(xy 244.350458 -41.737624) (xy 244.434317 -41.725567) (xy 244.518942 -41.721536) (xy 244.603567 -41.725567)
			(xy 244.687426 -41.737624) (xy 244.769759 -41.757598) (xy 244.849821 -41.785307) (xy 244.926886 -41.820502)
			(xy 245.000256 -41.862862) (xy 245.069268 -41.912005) (xy 245.133296 -41.967486) (xy 245.191761 -42.028801)
			(xy 245.244132 -42.095397) (xy 245.289935 -42.166669) (xy 245.328757 -42.241972) (xy 245.360245 -42.320624)
			(xy 245.384113 -42.401914) (xy 245.400147 -42.485104) (xy 245.4082 -42.569441) (xy 245.408704 -42.611802)
			(xy 245.408302 -42.650092) (xy 245.401694 -42.726386) (xy 245.388543 -42.801829) (xy 245.368949 -42.875859)
			(xy 245.35638 -42.91203) (xy 245.353727 -42.920466) (xy 245.353728 -42.938137) (xy 245.35638 -42.946574)
			(xy 245.368926 -42.982751) (xy 245.388499 -43.056784) (xy 245.401645 -43.132224) (xy 245.408269 -43.208514)
			(xy 245.408704 -43.246802) (xy 245.4082 -43.289163) (xy 245.400147 -43.3735) (xy 245.384113 -43.45669)
			(xy 245.360245 -43.53798) (xy 245.328757 -43.616632) (xy 245.289935 -43.691935) (xy 245.244132 -43.763207)
			(xy 245.191761 -43.829803) (xy 245.133296 -43.891118) (xy 245.069268 -43.946599) (xy 245.000256 -43.995742)
			(xy 244.926886 -44.038102) (xy 244.849821 -44.073297) (xy 244.769759 -44.101006) (xy 244.687426 -44.12098)
			(xy 244.603567 -44.133037) (xy 244.518942 -44.137069) (xy 244.434317 -44.133037) (xy 244.350458 -44.12098)
			(xy 244.268125 -44.101006) (xy 244.188063 -44.073297) (xy 244.110998 -44.038102) (xy 244.037628 -43.995742)
			(xy 243.968616 -43.946599) (xy 243.904588 -43.891118) (xy 243.846123 -43.829803) (xy 243.793752 -43.763207)
			(xy 243.747949 -43.691935) (xy 243.709127 -43.616632) (xy 243.677639 -43.53798) (xy 243.653771 -43.45669)
			(xy 243.637737 -43.3735) (xy 243.629684 -43.289163) (xy 243.62918 -43.246802) (xy 240.613613 -43.246802)
			(xy 240.663633 -43.272999) (xy 240.735496 -43.31997) (xy 240.802501 -43.373643) (xy 240.864025 -43.433521)
			(xy 240.919496 -43.499046) (xy 240.968398 -43.569608) (xy 241.010277 -43.644552) (xy 241.044744 -43.723182)
			(xy 241.071477 -43.804765) (xy 241.090229 -43.888544) (xy 241.096038 -43.931078) (xy 241.097792 -43.94092)
			(xy 241.107661 -43.958279) (xy 241.123386 -43.970587) (xy 241.132868 -43.97375) (xy 241.172506 -43.985287)
			(xy 241.249638 -44.014728) (xy 241.32371 -44.051189) (xy 241.394086 -44.094356) (xy 241.460159 -44.143858)
			(xy 241.521362 -44.199269) (xy 241.577167 -44.260112) (xy 241.627095 -44.325864) (xy 241.670716 -44.395959)
			(xy 241.707655 -44.469795) (xy 241.737594 -44.546735) (xy 241.760276 -44.626118) (xy 241.775505 -44.707261)
			(xy 241.78315 -44.789466) (xy 241.783616 -44.830746) (xy 241.783231 -44.871862) (xy 241.775639 -44.953744)
			(xy 241.760525 -45.034576) (xy 241.738017 -45.113668) (xy 241.708307 -45.190346) (xy 241.671649 -45.263956)
			(xy 241.628355 -45.333869) (xy 241.578796 -45.39949) (xy 241.523393 -45.460258) (xy 241.462619 -45.515654)
			(xy 241.396993 -45.565207) (xy 241.327075 -45.608494) (xy 241.253462 -45.645144) (xy 241.176781 -45.674846)
			(xy 241.097686 -45.697346) (xy 241.016853 -45.712452) (xy 240.93497 -45.720035) (xy 240.893854 -45.720508)
			(xy 240.848047 -45.719908) (xy 240.756919 -45.710469) (xy 240.667241 -45.691726) (xy 240.579961 -45.663878)
			(xy 240.537746 -45.646086) (xy 240.528923 -45.642621) (xy 240.509997 -45.641842) (xy 240.500916 -45.644562)
			(xy 240.454475 -45.659757) (xy 240.359116 -45.681105) (xy 240.261993 -45.691873) (xy 240.213134 -45.692568)
			(xy 240.174844 -45.692152) (xy 240.09855 -45.685547) (xy 240.023108 -45.672401) (xy 239.949077 -45.652811)
			(xy 239.912906 -45.640244) (xy 239.904469 -45.637593) (xy 239.886799 -45.637593) (xy 239.878362 -45.640244)
			(xy 239.842183 -45.652782) (xy 239.76815 -45.672357) (xy 239.692711 -45.685505) (xy 239.616422 -45.692131)
			(xy 239.578134 -45.692568) (xy 239.539844 -45.692152) (xy 239.46355 -45.685547) (xy 239.388108 -45.672401)
			(xy 239.314077 -45.652811) (xy 239.277906 -45.640244) (xy 239.269469 -45.637593) (xy 239.251799 -45.637593)
			(xy 239.243362 -45.640244) (xy 239.207183 -45.652782) (xy 239.13315 -45.672357) (xy 239.057711 -45.685505)
			(xy 238.981422 -45.692131) (xy 238.943134 -45.692568) (xy 238.903862 -45.692107) (xy 238.825629 -45.685129)
			(xy 238.748316 -45.671276) (xy 238.672527 -45.650657) (xy 238.63554 -45.63745) (xy 238.626991 -45.634686)
			(xy 238.609037 -45.634686) (xy 238.600488 -45.63745) (xy 238.563502 -45.650659) (xy 238.48771 -45.671265)
			(xy 238.410397 -45.685115) (xy 238.332165 -45.692103) (xy 238.292894 -45.692568) (xy 238.24936 -45.692039)
			(xy 238.16271 -45.683524) (xy 238.077306 -45.666586) (xy 237.993965 -45.641387) (xy 237.913484 -45.608168)
			(xy 237.87481 -45.588174) (xy 237.86657 -45.584248) (xy 237.848476 -45.581916) (xy 237.839504 -45.583602)
			(xy 237.790336 -45.594179) (xy 237.690402 -45.605511) (xy 237.640114 -45.606208) (xy 237.599001 -45.605674)
			(xy 237.517127 -45.598088) (xy 237.436301 -45.582981) (xy 237.357214 -45.560481) (xy 237.280541 -45.53078)
			(xy 237.206935 -45.494131) (xy 237.137024 -45.450847) (xy 237.071406 -45.401297) (xy 237.010639 -45.345904)
			(xy 236.955242 -45.285141) (xy 236.905687 -45.219525) (xy 236.862399 -45.149618) (xy 236.825745 -45.076014)
			(xy 236.796038 -44.999343) (xy 236.773533 -44.920257) (xy 236.75842 -44.839433) (xy 236.750829 -44.757559)
			(xy 236.750352 -44.716446) (xy 236.750814 -44.676228) (xy 236.758123 -44.596123) (xy 236.772622 -44.517004)
			(xy 236.794193 -44.439513) (xy 236.80801 -44.40174) (xy 236.811025 -44.392621) (xy 236.810769 -44.373433)
			(xy 236.807502 -44.364402) (xy 236.791394 -44.324025) (xy 236.766206 -44.240819) (xy 236.749266 -44.15555)
			(xy 236.740738 -44.069034) (xy 236.740192 -44.025566) (xy 182.412218 -44.025566) (xy 182.41506 -44.035245)
			(xy 182.422822 -44.089229) (xy 182.423308 -44.116498) (xy 182.423308 -44.980098) (xy 182.422822 -45.007367)
			(xy 182.41506 -45.061351) (xy 182.399695 -45.113681) (xy 182.377038 -45.163291) (xy 182.347552 -45.209172)
			(xy 182.311837 -45.250389) (xy 182.27062 -45.286104) (xy 182.224739 -45.31559) (xy 182.175129 -45.338247)
			(xy 182.122799 -45.353612) (xy 182.068815 -45.361374) (xy 182.014277 -45.361374) (xy 181.960293 -45.353612)
			(xy 181.907963 -45.338247) (xy 181.858353 -45.31559) (xy 181.812472 -45.286104) (xy 181.771255 -45.250389)
			(xy 181.73554 -45.209172) (xy 181.706054 -45.163291) (xy 181.683397 -45.113681) (xy 181.668032 -45.061351)
			(xy 181.66027 -45.007367) (xy 181.659784 -44.980098) (xy 96.555487 -44.980098) (xy 96.637446 -45.068647)
			(xy 96.736452 -45.187325) (xy 96.829216 -45.310943) (xy 96.915495 -45.439171) (xy 96.995057 -45.571672)
			(xy 97.067693 -45.708092) (xy 97.133211 -45.848071) (xy 97.191435 -45.991237) (xy 97.242212 -46.13721)
			(xy 97.285407 -46.285604) (xy 97.320906 -46.436025) (xy 97.329238 -46.481746) (xy 178.630072 -46.481746)
			(xy 178.630072 -45.618146) (xy 178.630558 -45.590877) (xy 178.63832 -45.536893) (xy 178.653685 -45.484563)
			(xy 178.676342 -45.434953) (xy 178.705828 -45.389072) (xy 178.741543 -45.347855) (xy 178.78276 -45.31214)
			(xy 178.828641 -45.282654) (xy 178.878251 -45.259997) (xy 178.930581 -45.244632) (xy 178.984565 -45.23687)
			(xy 179.039103 -45.23687) (xy 179.093087 -45.244632) (xy 179.145417 -45.259997) (xy 179.195027 -45.282654)
			(xy 179.240908 -45.31214) (xy 179.282125 -45.347855) (xy 179.31784 -45.389072) (xy 179.347326 -45.434953)
			(xy 179.369983 -45.484563) (xy 179.385348 -45.536893) (xy 179.39311 -45.590877) (xy 179.393596 -45.618146)
			(xy 179.393596 -46.481746) (xy 179.39311 -46.509015) (xy 179.385348 -46.562999) (xy 179.369983 -46.615329)
			(xy 179.347326 -46.664939) (xy 179.31784 -46.71082) (xy 179.282125 -46.752037) (xy 179.240908 -46.787752)
			(xy 179.195027 -46.817238) (xy 179.145417 -46.839895) (xy 179.093087 -46.85526) (xy 179.039103 -46.863022)
			(xy 178.984565 -46.863022) (xy 178.930581 -46.85526) (xy 178.878251 -46.839895) (xy 178.828641 -46.817238)
			(xy 178.78276 -46.787752) (xy 178.741543 -46.752037) (xy 178.705828 -46.71082) (xy 178.676342 -46.664939)
			(xy 178.653685 -46.615329) (xy 178.63832 -46.562999) (xy 178.630558 -46.509015) (xy 178.630072 -46.481746)
			(xy 97.329238 -46.481746) (xy 97.348615 -46.588073) (xy 97.368459 -46.741347) (xy 97.380387 -46.895438)
			(xy 97.384366 -47.04994) (xy 97.380387 -47.204442) (xy 97.368459 -47.358533) (xy 97.348615 -47.511807)
			(xy 97.320906 -47.663855) (xy 97.285407 -47.814276) (xy 97.242212 -47.96267) (xy 97.219453 -48.028098)
			(xy 181.659784 -48.028098) (xy 181.659784 -47.164498) (xy 181.66027 -47.137229) (xy 181.668032 -47.083245)
			(xy 181.683397 -47.030915) (xy 181.706054 -46.981305) (xy 181.73554 -46.935424) (xy 181.771255 -46.894207)
			(xy 181.812472 -46.858492) (xy 181.858353 -46.829006) (xy 181.907963 -46.806349) (xy 181.960293 -46.790984)
			(xy 182.014277 -46.783222) (xy 182.068815 -46.783222) (xy 182.122799 -46.790984) (xy 182.175129 -46.806349)
			(xy 182.224739 -46.829006) (xy 182.27062 -46.858492) (xy 182.311837 -46.894207) (xy 182.347552 -46.935424)
			(xy 182.377038 -46.981305) (xy 182.399695 -47.030915) (xy 182.41506 -47.083245) (xy 182.422822 -47.137229)
			(xy 182.423308 -47.164498) (xy 182.423308 -48.028098) (xy 182.422822 -48.055367) (xy 182.41506 -48.109351)
			(xy 182.399695 -48.161681) (xy 182.377038 -48.211291) (xy 182.347552 -48.257172) (xy 182.311837 -48.298389)
			(xy 182.27062 -48.334104) (xy 182.224739 -48.36359) (xy 182.175129 -48.386247) (xy 182.122799 -48.401612)
			(xy 182.068815 -48.409374) (xy 182.014277 -48.409374) (xy 181.960293 -48.401612) (xy 181.907963 -48.386247)
			(xy 181.858353 -48.36359) (xy 181.812472 -48.334104) (xy 181.771255 -48.298389) (xy 181.73554 -48.257172)
			(xy 181.706054 -48.211291) (xy 181.683397 -48.161681) (xy 181.668032 -48.109351) (xy 181.66027 -48.055367)
			(xy 181.659784 -48.028098) (xy 97.219453 -48.028098) (xy 97.191435 -48.108643) (xy 97.133211 -48.251809)
			(xy 97.067693 -48.391788) (xy 96.995057 -48.528208) (xy 96.915495 -48.660709) (xy 96.829216 -48.788937)
			(xy 96.736452 -48.912555) (xy 96.637446 -49.031233) (xy 96.532463 -49.144657) (xy 96.421779 -49.252526)
			(xy 96.30569 -49.354554) (xy 96.184502 -49.450471) (xy 96.140518 -49.48174) (xy 178.630072 -49.48174)
			(xy 178.630072 -48.61814) (xy 178.630558 -48.590871) (xy 178.63832 -48.536887) (xy 178.653685 -48.484557)
			(xy 178.676342 -48.434947) (xy 178.705828 -48.389066) (xy 178.741543 -48.347849) (xy 178.78276 -48.312134)
			(xy 178.828641 -48.282648) (xy 178.878251 -48.259991) (xy 178.930581 -48.244626) (xy 178.984565 -48.236864)
			(xy 179.039103 -48.236864) (xy 179.093087 -48.244626) (xy 179.145417 -48.259991) (xy 179.195027 -48.282648)
			(xy 179.240908 -48.312134) (xy 179.282125 -48.347849) (xy 179.31784 -48.389066) (xy 179.347326 -48.434947)
			(xy 179.369983 -48.484557) (xy 179.385348 -48.536887) (xy 179.39311 -48.590871) (xy 179.393596 -48.61814)
			(xy 179.393596 -49.48174) (xy 179.39311 -49.509009) (xy 179.385348 -49.562993) (xy 179.369983 -49.615323)
			(xy 179.347326 -49.664933) (xy 179.31784 -49.710814) (xy 179.282125 -49.752031) (xy 179.240908 -49.787746)
			(xy 179.195027 -49.817232) (xy 179.145417 -49.839889) (xy 179.093087 -49.855254) (xy 179.039103 -49.863016)
			(xy 178.984565 -49.863016) (xy 178.930581 -49.855254) (xy 178.878251 -49.839889) (xy 178.828641 -49.817232)
			(xy 178.78276 -49.787746) (xy 178.741543 -49.752031) (xy 178.705828 -49.710814) (xy 178.676342 -49.664933)
			(xy 178.653685 -49.615323) (xy 178.63832 -49.562993) (xy 178.630558 -49.509009) (xy 178.630072 -49.48174)
			(xy 96.140518 -49.48174) (xy 96.058537 -49.540022) (xy 95.928129 -49.62297) (xy 95.793624 -49.699095)
			(xy 95.655379 -49.768194) (xy 95.513759 -49.830085) (xy 95.369142 -49.884604) (xy 95.221909 -49.931606)
			(xy 95.072452 -49.970966) (xy 94.921168 -50.00258) (xy 94.768456 -50.026364) (xy 94.614722 -50.042255)
			(xy 94.460374 -50.050211) (xy 94.383098 -50.0507) (xy 92.782898 -50.0507) (xy 92.705622 -50.050194)
			(xy 92.551275 -50.042238) (xy 92.397543 -50.026347) (xy 92.244832 -50.002563) (xy 92.093548 -49.970949)
			(xy 91.944092 -49.931589) (xy 91.796861 -49.884587) (xy 91.652244 -49.830069) (xy 91.510626 -49.768178)
			(xy 91.372381 -49.699079) (xy 91.237877 -49.622954) (xy 91.10747 -49.540007) (xy 90.981506 -49.450456)
			(xy 90.860319 -49.35454) (xy 90.74423 -49.252512) (xy 90.633548 -49.144644) (xy 90.528565 -49.031221)
			(xy 90.42956 -48.912543) (xy 90.336796 -48.788927) (xy 90.250519 -48.660699) (xy 90.170957 -48.528199)
			(xy 90.098321 -48.391779) (xy 90.032804 -48.251802) (xy 89.97458 -48.108637) (xy 89.923803 -47.962664)
			(xy 89.880608 -47.814271) (xy 89.84511 -47.663852) (xy 89.817402 -47.511804) (xy 89.797557 -47.358531)
			(xy 89.78563 -47.204441) (xy 89.78165 -47.04994) (xy 67.583802 -47.04994) (xy 67.579823 -47.209492)
			(xy 67.567896 -47.368647) (xy 67.54805 -47.527009) (xy 67.520336 -47.684186) (xy 67.484821 -47.839786)
			(xy 67.441595 -47.993422) (xy 67.390764 -48.144712) (xy 67.332455 -48.293281) (xy 67.266813 -48.438758)
			(xy 67.194001 -48.580783) (xy 67.114201 -48.719002) (xy 67.02761 -48.853071) (xy 66.934444 -48.982657)
			(xy 66.834934 -49.107438) (xy 66.729328 -49.227105) (xy 66.617889 -49.341358) (xy 66.500893 -49.449914)
			(xy 66.378631 -49.552504) (xy 66.251408 -49.648872) (xy 66.119539 -49.738779) (xy 65.983353 -49.822001)
			(xy 65.843188 -49.898331) (xy 65.699392 -49.967579) (xy 65.552323 -50.029574) (xy 65.402347 -50.084161)
			(xy 65.249837 -50.131205) (xy 65.095171 -50.170587) (xy 64.938734 -50.202212) (xy 64.780916 -50.226)
			(xy 64.622107 -50.241891) (xy 64.462705 -50.249847) (xy 64.382904 -50.250344) (xy 62.782958 -50.250344)
			(xy 62.703158 -50.249839) (xy 62.543755 -50.241883) (xy 62.384947 -50.225992) (xy 62.227129 -50.202204)
			(xy 62.070693 -50.17058) (xy 61.916027 -50.131197) (xy 61.763517 -50.084154) (xy 61.613541 -50.029567)
			(xy 61.466472 -49.967573) (xy 61.322677 -49.898324) (xy 61.182512 -49.821994) (xy 61.046326 -49.738773)
			(xy 60.914458 -49.648866) (xy 60.787235 -49.552499) (xy 60.664973 -49.449909) (xy 60.547978 -49.341353)
			(xy 60.436538 -49.2271) (xy 60.330933 -49.107434) (xy 60.231423 -48.982653) (xy 60.138257 -48.853067)
			(xy 60.051666 -48.718998) (xy 59.971866 -48.580779) (xy 59.899054 -48.438755) (xy 59.833413 -48.293278)
			(xy 59.775104 -48.14471) (xy 59.724273 -47.99342) (xy 59.681047 -47.839784) (xy 59.645532 -47.684184)
			(xy 59.617818 -47.527008) (xy 59.597972 -47.368646) (xy 59.586045 -47.209491) (xy 59.582066 -47.04994)
			(xy 0.509016 -47.04994) (xy 0.509016 -50.949098) (xy 181.659784 -50.949098) (xy 181.659784 -50.085498)
			(xy 181.66027 -50.058229) (xy 181.668032 -50.004245) (xy 181.683397 -49.951915) (xy 181.706054 -49.902305)
			(xy 181.73554 -49.856424) (xy 181.771255 -49.815207) (xy 181.812472 -49.779492) (xy 181.858353 -49.750006)
			(xy 181.907963 -49.727349) (xy 181.960293 -49.711984) (xy 182.014277 -49.704222) (xy 182.068815 -49.704222)
			(xy 182.122799 -49.711984) (xy 182.175129 -49.727349) (xy 182.224739 -49.750006) (xy 182.27062 -49.779492)
			(xy 182.311837 -49.815207) (xy 182.347552 -49.856424) (xy 182.377038 -49.902305) (xy 182.399695 -49.951915)
			(xy 182.41506 -50.004245) (xy 182.422822 -50.058229) (xy 182.423308 -50.085498) (xy 182.423308 -50.949098)
			(xy 182.422822 -50.976367) (xy 182.41506 -51.030351) (xy 182.399695 -51.082681) (xy 182.377038 -51.132291)
			(xy 182.347552 -51.178172) (xy 182.311837 -51.219389) (xy 182.27062 -51.255104) (xy 182.224739 -51.28459)
			(xy 182.175129 -51.307247) (xy 182.122799 -51.322612) (xy 182.068815 -51.330374) (xy 182.014277 -51.330374)
			(xy 181.960293 -51.322612) (xy 181.907963 -51.307247) (xy 181.858353 -51.28459) (xy 181.812472 -51.255104)
			(xy 181.771255 -51.219389) (xy 181.73554 -51.178172) (xy 181.706054 -51.132291) (xy 181.683397 -51.082681)
			(xy 181.668032 -51.030351) (xy 181.66027 -50.976367) (xy 181.659784 -50.949098) (xy 0.509016 -50.949098)
			(xy 0.509016 -52.481734) (xy 178.630072 -52.481734) (xy 178.630072 -51.618134) (xy 178.630558 -51.590865)
			(xy 178.63832 -51.536881) (xy 178.653685 -51.484551) (xy 178.676342 -51.434941) (xy 178.705828 -51.38906)
			(xy 178.741543 -51.347843) (xy 178.78276 -51.312128) (xy 178.828641 -51.282642) (xy 178.878251 -51.259985)
			(xy 178.930581 -51.24462) (xy 178.984565 -51.236858) (xy 179.039103 -51.236858) (xy 179.093087 -51.24462)
			(xy 179.145417 -51.259985) (xy 179.195027 -51.282642) (xy 179.240908 -51.312128) (xy 179.282125 -51.347843)
			(xy 179.31784 -51.38906) (xy 179.347326 -51.434941) (xy 179.369983 -51.484551) (xy 179.385348 -51.536881)
			(xy 179.39311 -51.590865) (xy 179.393596 -51.618134) (xy 179.393596 -51.999896) (xy 201.367397 -51.999896)
			(xy 201.371407 -51.837793) (xy 201.38343 -51.676088) (xy 201.403434 -51.515174) (xy 201.431372 -51.355447)
			(xy 201.467175 -51.197297) (xy 201.510755 -51.041111) (xy 201.562006 -50.887271) (xy 201.620802 -50.736154)
			(xy 201.687 -50.58813) (xy 201.760436 -50.44356) (xy 201.840933 -50.302799) (xy 201.928292 -50.166191)
			(xy 202.0223 -50.034071) (xy 202.122727 -49.906761) (xy 202.229327 -49.784573) (xy 202.341839 -49.667807)
			(xy 202.459987 -49.556748) (xy 202.583484 -49.451667) (xy 202.712026 -49.352823) (xy 202.845299 -49.260456)
			(xy 202.982977 -49.174793) (xy 203.124723 -49.096044) (xy 203.27019 -49.024401) (xy 203.419022 -48.960039)
			(xy 203.570854 -48.903117) (xy 203.725316 -48.853773) (xy 203.882029 -48.812128) (xy 204.04061 -48.778283)
			(xy 204.200671 -48.752323) (xy 204.361819 -48.73431) (xy 204.523661 -48.724289) (xy 204.685801 -48.722283)
			(xy 204.847842 -48.728299) (xy 205.009386 -48.74232) (xy 205.17004 -48.764313) (xy 205.32941 -48.794225)
			(xy 205.487105 -48.831981) (xy 205.64274 -48.877489) (xy 205.795934 -48.930639) (xy 205.946312 -48.9913)
			(xy 206.093507 -49.059323) (xy 206.237157 -49.134542) (xy 206.376912 -49.216773) (xy 206.512428 -49.305815)
			(xy 206.643376 -49.40145) (xy 206.769434 -49.503444) (xy 206.890294 -49.611547) (xy 207.00566 -49.725494)
			(xy 207.115249 -49.845008) (xy 207.218794 -49.969795) (xy 207.316041 -50.09955) (xy 207.406753 -50.233955)
			(xy 207.490706 -50.372682) (xy 207.567696 -50.515391) (xy 207.637535 -50.661732) (xy 207.70005 -50.811349)
			(xy 207.755091 -50.963874) (xy 207.802521 -51.118934) (xy 207.842224 -51.27615) (xy 207.874105 -51.435138)
			(xy 207.898083 -51.595507) (xy 207.914102 -51.756866) (xy 207.922121 -51.91882) (xy 207.922622 -51.999896)
			(xy 207.922121 -52.080972) (xy 207.921092 -52.10175) (xy 244.67947 -52.10175) (xy 244.679975 -52.075243)
			(xy 244.687334 -52.022743) (xy 244.701889 -51.971767) (xy 244.723361 -51.923297) (xy 244.751335 -51.878265)
			(xy 244.785274 -51.837539) (xy 244.824523 -51.801903) (xy 244.868327 -51.772043) (xy 244.915843 -51.748534)
			(xy 244.966156 -51.731829) (xy 244.992144 -51.726592) (xy 245.000543 -51.724726) (xy 245.015476 -51.716197)
			(xy 245.026755 -51.703216) (xy 245.030244 -51.69535) (xy 245.045663 -51.657494) (xy 245.082559 -51.584546)
			(xy 245.125992 -51.515291) (xy 245.175596 -51.450313) (xy 245.230952 -51.39016) (xy 245.291595 -51.335341)
			(xy 245.357011 -51.286316) (xy 245.426649 -51.2435) (xy 245.499922 -51.207254) (xy 245.576211 -51.177884)
			(xy 245.654873 -51.155637) (xy 245.735245 -51.140701) (xy 245.816648 -51.133203) (xy 245.857522 -51.13274)
			(xy 245.899843 -51.133258) (xy 245.984099 -51.14133) (xy 246.067208 -51.157371) (xy 246.148416 -51.181236)
			(xy 246.226989 -51.212708) (xy 246.302217 -51.251503) (xy 246.33809 -51.273964) (xy 246.346484 -51.278827)
			(xy 246.365522 -51.28248) (xy 246.38456 -51.278827) (xy 246.392954 -51.273964) (xy 246.42883 -51.25151)
			(xy 246.504063 -51.212731) (xy 246.582638 -51.181268) (xy 246.663845 -51.157405) (xy 246.74695 -51.141356)
			(xy 246.831202 -51.133268) (xy 246.873522 -51.13274) (xy 246.926862 -51.134518) (xy 246.938638 -51.134618)
			(xy 246.960306 -51.125466) (xy 246.975671 -51.107657) (xy 246.979186 -51.096418) (xy 246.990138 -51.056039)
			(xy 247.018713 -50.977397) (xy 247.054545 -50.901785) (xy 247.097317 -50.829872) (xy 247.146653 -50.762292)
			(xy 247.202115 -50.699642) (xy 247.263214 -50.642477) (xy 247.329411 -50.5913) (xy 247.40012 -50.546564)
			(xy 247.474717 -50.508665) (xy 247.552542 -50.477936) (xy 247.632909 -50.45465) (xy 247.715107 -50.439012)
			(xy 247.79841 -50.431161) (xy 247.840246 -50.430684) (xy 247.883752 -50.431235) (xy 247.970347 -50.439729)
			(xy 248.055699 -50.456641) (xy 248.138991 -50.481809) (xy 248.219426 -50.514992) (xy 248.296235 -50.555874)
			(xy 248.332752 -50.579528) (xy 248.341308 -50.584744) (xy 248.360946 -50.588653) (xy 248.380584 -50.584744)
			(xy 248.38914 -50.579528) (xy 248.425663 -50.555885) (xy 248.50248 -50.515022) (xy 248.582916 -50.481847)
			(xy 248.666204 -50.456676) (xy 248.751551 -50.439749) (xy 248.838142 -50.431227) (xy 248.881646 -50.430684)
			(xy 248.926403 -50.431259) (xy 249.015462 -50.440266) (xy 249.103167 -50.458165) (xy 249.188634 -50.484775)
			(xy 249.270999 -50.519828) (xy 249.349431 -50.562968) (xy 249.386598 -50.58791) (xy 249.394939 -50.593062)
			(xy 249.414052 -50.597328) (xy 249.433374 -50.594144) (xy 249.44197 -50.589434) (xy 249.4758 -50.569354)
			(xy 249.546346 -50.534523) (xy 249.619688 -50.506051) (xy 249.695257 -50.484158) (xy 249.772462 -50.469016)
			(xy 249.850701 -50.460742) (xy 249.890026 -50.45964) (xy 249.889772 -50.4444) (xy 249.889772 -50.443892)
			(xy 249.89024 -50.405527) (xy 249.896983 -50.329093) (xy 249.903234 -50.291238) (xy 249.904413 -50.282319)
			(xy 249.901131 -50.26464) (xy 249.891952 -50.249179) (xy 249.8852 -50.243232) (xy 249.851748 -50.215094)
			(xy 249.789907 -50.153305) (xy 249.734424 -50.08575) (xy 249.685833 -50.01308) (xy 249.644603 -49.935995)
			(xy 249.61113 -49.855239) (xy 249.585738 -49.771589) (xy 249.568671 -49.685852) (xy 249.560094 -49.598855)
			(xy 249.559572 -49.555146) (xy 249.560076 -49.512785) (xy 249.568129 -49.428448) (xy 249.584163 -49.345258)
			(xy 249.608031 -49.263968) (xy 249.639519 -49.185316) (xy 249.678341 -49.110013) (xy 249.724144 -49.038741)
			(xy 249.776515 -48.972145) (xy 249.83498 -48.91083) (xy 249.899008 -48.855349) (xy 249.96802 -48.806206)
			(xy 250.04139 -48.763846) (xy 250.118455 -48.728651) (xy 250.198517 -48.700942) (xy 250.28085 -48.680968)
			(xy 250.364709 -48.668911) (xy 250.449334 -48.66488) (xy 250.533959 -48.668911) (xy 250.617818 -48.680968)
			(xy 250.700151 -48.700942) (xy 250.780213 -48.728651) (xy 250.857278 -48.763846) (xy 250.930648 -48.806206)
			(xy 250.99966 -48.855349) (xy 251.063688 -48.91083) (xy 251.122153 -48.972145) (xy 251.174524 -49.038741)
			(xy 251.220327 -49.110013) (xy 251.259149 -49.185316) (xy 251.290637 -49.263968) (xy 251.314505 -49.345258)
			(xy 251.330539 -49.428448) (xy 251.338592 -49.512785) (xy 251.339096 -49.555146) (xy 251.338636 -49.593574)
			(xy 251.331894 -49.670136) (xy 251.325634 -49.708054) (xy 251.324473 -49.716974) (xy 251.32775 -49.73465)
			(xy 251.336921 -49.750111) (xy 251.343668 -49.75606) (xy 251.362142 -49.771471) (xy 251.397596 -49.803999)
			(xy 251.414534 -49.821084) (xy 251.422676 -49.828571) (xy 251.443355 -49.836348) (xy 251.454412 -49.83607)
			(xy 251.469822 -49.835031) (xy 251.50069 -49.833886) (xy 251.516134 -49.833784) (xy 251.557251 -49.834166)
			(xy 251.639133 -49.841757) (xy 251.719966 -49.85687) (xy 251.79906 -49.879378) (xy 251.875739 -49.909087)
			(xy 251.94935 -49.945745) (xy 252.019265 -49.989039) (xy 252.084886 -50.038598) (xy 252.145655 -50.094001)
			(xy 252.201053 -50.154775) (xy 252.250607 -50.220401) (xy 252.293894 -50.29032) (xy 252.330545 -50.363934)
			(xy 252.360248 -50.440616) (xy 252.382748 -50.519712) (xy 252.397854 -50.600546) (xy 252.405438 -50.682429)
			(xy 252.405896 -50.723546) (xy 252.405358 -50.767341) (xy 252.396743 -50.854506) (xy 252.379599 -50.940401)
			(xy 252.354094 -51.024196) (xy 252.320474 -51.105076) (xy 252.300232 -51.143916) (xy 252.29478 -51.15537)
			(xy 252.2948 -51.18071) (xy 252.300232 -51.192176) (xy 252.320452 -51.231026) (xy 252.354062 -51.311909)
			(xy 252.379567 -51.3957) (xy 252.39672 -51.481592) (xy 252.405355 -51.568752) (xy 252.405896 -51.612546)
			(xy 252.405358 -51.656341) (xy 252.396743 -51.743506) (xy 252.379599 -51.829401) (xy 252.354094 -51.913196)
			(xy 252.320474 -51.994076) (xy 252.317441 -51.999896) (xy 265.367523 -51.999896) (xy 265.371533 -51.837793)
			(xy 265.383556 -51.676088) (xy 265.40356 -51.515174) (xy 265.431498 -51.355447) (xy 265.467301 -51.197297)
			(xy 265.510881 -51.041111) (xy 265.562132 -50.887271) (xy 265.620928 -50.736154) (xy 265.687126 -50.58813)
			(xy 265.760562 -50.44356) (xy 265.841059 -50.302799) (xy 265.928418 -50.166191) (xy 266.022426 -50.034071)
			(xy 266.122853 -49.906761) (xy 266.229453 -49.784573) (xy 266.341965 -49.667807) (xy 266.460113 -49.556748)
			(xy 266.58361 -49.451667) (xy 266.712152 -49.352823) (xy 266.845425 -49.260456) (xy 266.983103 -49.174793)
			(xy 267.124849 -49.096044) (xy 267.270316 -49.024401) (xy 267.419148 -48.960039) (xy 267.57098 -48.903117)
			(xy 267.725442 -48.853773) (xy 267.882155 -48.812128) (xy 268.040736 -48.778283) (xy 268.200797 -48.752323)
			(xy 268.361945 -48.73431) (xy 268.523787 -48.724289) (xy 268.685927 -48.722283) (xy 268.847968 -48.728299)
			(xy 269.009512 -48.74232) (xy 269.170166 -48.764313) (xy 269.329536 -48.794225) (xy 269.487231 -48.831981)
			(xy 269.642866 -48.877489) (xy 269.79606 -48.930639) (xy 269.946438 -48.9913) (xy 270.093633 -49.059323)
			(xy 270.237283 -49.134542) (xy 270.377038 -49.216773) (xy 270.512554 -49.305815) (xy 270.643502 -49.40145)
			(xy 270.76956 -49.503444) (xy 270.89042 -49.611547) (xy 271.005786 -49.725494) (xy 271.115375 -49.845008)
			(xy 271.21892 -49.969795) (xy 271.316167 -50.09955) (xy 271.406879 -50.233955) (xy 271.490832 -50.372682)
			(xy 271.567822 -50.515391) (xy 271.637661 -50.661732) (xy 271.700176 -50.811349) (xy 271.755217 -50.963874)
			(xy 271.802647 -51.118934) (xy 271.84235 -51.27615) (xy 271.874231 -51.435138) (xy 271.898209 -51.595507)
			(xy 271.914228 -51.756866) (xy 271.922247 -51.91882) (xy 271.922748 -51.999896) (xy 271.922247 -52.080972)
			(xy 271.914228 -52.242926) (xy 271.898209 -52.404285) (xy 271.874231 -52.564654) (xy 271.84235 -52.723642)
			(xy 271.802647 -52.880858) (xy 271.755217 -53.035918) (xy 271.700176 -53.188443) (xy 271.637661 -53.33806)
			(xy 271.567822 -53.484401) (xy 271.490832 -53.62711) (xy 271.406879 -53.765837) (xy 271.316167 -53.900242)
			(xy 271.21892 -54.029997) (xy 271.115375 -54.154784) (xy 271.005786 -54.274298) (xy 270.89042 -54.388245)
			(xy 270.76956 -54.496348) (xy 270.643502 -54.598342) (xy 270.512554 -54.693977) (xy 270.377038 -54.783019)
			(xy 270.237283 -54.86525) (xy 270.093633 -54.940469) (xy 269.946438 -55.008492) (xy 269.79606 -55.069153)
			(xy 269.642866 -55.122303) (xy 269.487231 -55.167811) (xy 269.329536 -55.205567) (xy 269.170166 -55.235479)
			(xy 269.009512 -55.257472) (xy 268.847968 -55.271493) (xy 268.685927 -55.277509) (xy 268.523787 -55.275503)
			(xy 268.361945 -55.265482) (xy 268.200797 -55.247469) (xy 268.040736 -55.221509) (xy 267.882155 -55.187664)
			(xy 267.725442 -55.146019) (xy 267.57098 -55.096675) (xy 267.419148 -55.039753) (xy 267.270316 -54.975391)
			(xy 267.124849 -54.903748) (xy 266.983103 -54.824999) (xy 266.845425 -54.739336) (xy 266.712152 -54.646969)
			(xy 266.58361 -54.548125) (xy 266.460113 -54.443044) (xy 266.341965 -54.331985) (xy 266.229453 -54.215219)
			(xy 266.122853 -54.093031) (xy 266.022426 -53.965721) (xy 265.928418 -53.833601) (xy 265.841059 -53.696993)
			(xy 265.760562 -53.556232) (xy 265.687126 -53.411662) (xy 265.620928 -53.263638) (xy 265.562132 -53.112521)
			(xy 265.510881 -52.958681) (xy 265.467301 -52.802495) (xy 265.431498 -52.644345) (xy 265.40356 -52.484618)
			(xy 265.383556 -52.323704) (xy 265.371533 -52.161999) (xy 265.367523 -51.999896) (xy 252.317441 -51.999896)
			(xy 252.300232 -52.032916) (xy 252.29478 -52.04437) (xy 252.2948 -52.06971) (xy 252.300232 -52.081176)
			(xy 252.320452 -52.120026) (xy 252.354062 -52.200909) (xy 252.379567 -52.2847) (xy 252.39672 -52.370592)
			(xy 252.405355 -52.457752) (xy 252.405896 -52.501546) (xy 252.405431 -52.54266) (xy 252.39784 -52.624537)
			(xy 252.382728 -52.705364) (xy 252.360222 -52.784452) (xy 252.330515 -52.861127) (xy 252.293861 -52.934733)
			(xy 252.250573 -53.004644) (xy 252.201018 -53.070263) (xy 252.145621 -53.131029) (xy 252.084853 -53.186426)
			(xy 252.019234 -53.235979) (xy 251.949323 -53.279267) (xy 251.875716 -53.31592) (xy 251.799041 -53.345626)
			(xy 251.719952 -53.36813) (xy 251.639125 -53.383242) (xy 251.557248 -53.390832) (xy 251.516134 -53.391308)
			(xy 251.471924 -53.390745) (xy 251.383942 -53.381965) (xy 251.297264 -53.3645) (xy 251.212747 -53.33852)
			(xy 251.131225 -53.304282) (xy 251.053503 -53.262125) (xy 250.980346 -53.212465) (xy 250.912478 -53.15579)
			(xy 250.881134 -53.124608) (xy 250.873005 -53.117104) (xy 250.852316 -53.109337) (xy 250.841256 -53.109622)
			(xy 250.825846 -53.110663) (xy 250.794978 -53.111806) (xy 250.779534 -53.111908) (xy 250.737779 -53.111492)
			(xy 250.654637 -53.103677) (xy 250.572592 -53.088104) (xy 250.492369 -53.064909) (xy 250.414673 -53.034297)
			(xy 250.340188 -52.996537) (xy 250.269571 -52.951961) (xy 250.203442 -52.900963) (xy 250.142385 -52.843991)
			(xy 250.086937 -52.781547) (xy 250.037585 -52.714181) (xy 249.994765 -52.642486) (xy 249.958854 -52.567092)
			(xy 249.930167 -52.488665) (xy 249.908958 -52.407894) (xy 249.895413 -52.32549) (xy 249.892058 -52.283868)
			(xy 249.891061 -52.274773) (xy 249.88348 -52.258135) (xy 249.870549 -52.245209) (xy 249.853908 -52.237634)
			(xy 249.844814 -52.236624) (xy 249.805225 -52.23352) (xy 249.726783 -52.221122) (xy 249.649759 -52.201775)
			(xy 249.574769 -52.175634) (xy 249.50241 -52.142907) (xy 249.433259 -52.103855) (xy 249.400314 -52.081684)
			(xy 249.392012 -52.076461) (xy 249.372875 -52.072218) (xy 249.353539 -52.075433) (xy 249.344942 -52.08016)
			(xy 249.312459 -52.099495) (xy 249.244799 -52.133223) (xy 249.174522 -52.161088) (xy 249.13844 -52.172362)
			(xy 249.128616 -52.175851) (xy 249.112727 -52.189319) (xy 249.103444 -52.207965) (xy 249.102372 -52.218336)
			(xy 249.099675 -52.260463) (xy 249.087279 -52.34397) (xy 249.067027 -52.425926) (xy 249.039099 -52.505595)
			(xy 249.003748 -52.582258) (xy 248.961291 -52.655227) (xy 248.912112 -52.723845) (xy 248.856651 -52.787493)
			(xy 248.795409 -52.8456) (xy 248.728936 -52.897642) (xy 248.657831 -52.943151) (xy 248.582733 -52.981717)
			(xy 248.504319 -53.012994) (xy 248.423294 -53.036699) (xy 248.340387 -53.052621) (xy 248.256345 -53.060614)
			(xy 248.214134 -53.061108) (xy 248.171669 -53.060607) (xy 248.087125 -53.052507) (xy 248.003739 -53.036385)
			(xy 247.922268 -53.01239) (xy 247.843456 -52.98074) (xy 247.768018 -52.941722) (xy 247.696643 -52.895693)
			(xy 247.629979 -52.84307) (xy 247.568634 -52.784334) (xy 247.540526 -52.752498) (xy 247.534176 -52.745132)
			(xy 247.517412 -52.736496) (xy 247.429274 -52.726336) (xy 247.410986 -52.731416) (xy 247.403112 -52.737258)
			(xy 247.370277 -52.761024) (xy 247.301045 -52.803187) (xy 247.228263 -52.838875) (xy 247.152535 -52.867791)
			(xy 247.07449 -52.889697) (xy 246.994775 -52.904409) (xy 246.914052 -52.911805) (xy 246.873522 -52.912264)
			(xy 246.831202 -52.911724) (xy 246.746946 -52.903656) (xy 246.663838 -52.887619) (xy 246.58263 -52.863758)
			(xy 246.504056 -52.83229) (xy 246.428827 -52.793499) (xy 246.392954 -52.77104) (xy 246.38456 -52.766177)
			(xy 246.365522 -52.762524) (xy 246.346484 -52.766177) (xy 246.33809 -52.77104) (xy 246.302222 -52.793507)
			(xy 246.226987 -52.832285) (xy 246.148411 -52.863747) (xy 246.067203 -52.887609) (xy 245.984096 -52.903654)
			(xy 245.899842 -52.911738) (xy 245.857522 -52.912264) (xy 245.813221 -52.911666) (xy 245.725058 -52.90285)
			(xy 245.638208 -52.885314) (xy 245.553531 -52.85923) (xy 245.471867 -52.824858) (xy 245.394025 -52.782538)
			(xy 245.320775 -52.732689) (xy 245.252843 -52.675806) (xy 245.190903 -52.61245) (xy 245.135568 -52.543252)
			(xy 245.111016 -52.506372) (xy 245.106055 -52.499361) (xy 245.092457 -52.488884) (xy 245.076169 -52.483465)
			(xy 245.067582 -52.483258) (xy 245.060978 -52.483258) (xy 245.033722 -52.482865) (xy 244.979766 -52.475104)
			(xy 244.927464 -52.459743) (xy 244.87788 -52.437094) (xy 244.832025 -52.407619) (xy 244.790831 -52.371918)
			(xy 244.755138 -52.330717) (xy 244.725671 -52.284856) (xy 244.703032 -52.235269) (xy 244.68768 -52.182963)
			(xy 244.679929 -52.129006) (xy 244.67947 -52.10175) (xy 207.921092 -52.10175) (xy 207.914102 -52.242926)
			(xy 207.898083 -52.404285) (xy 207.874105 -52.564654) (xy 207.842224 -52.723642) (xy 207.802521 -52.880858)
			(xy 207.755091 -53.035918) (xy 207.70005 -53.188443) (xy 207.637535 -53.33806) (xy 207.567696 -53.484401)
			(xy 207.490706 -53.62711) (xy 207.406753 -53.765837) (xy 207.316041 -53.900242) (xy 207.218794 -54.029997)
			(xy 207.115249 -54.154784) (xy 207.00566 -54.274298) (xy 206.890294 -54.388245) (xy 206.769434 -54.496348)
			(xy 206.643376 -54.598342) (xy 206.512428 -54.693977) (xy 206.376912 -54.783019) (xy 206.237157 -54.86525)
			(xy 206.093507 -54.940469) (xy 205.946312 -55.008492) (xy 205.795934 -55.069153) (xy 205.64274 -55.122303)
			(xy 205.487105 -55.167811) (xy 205.32941 -55.205567) (xy 205.17004 -55.235479) (xy 205.009386 -55.257472)
			(xy 204.847842 -55.271493) (xy 204.685801 -55.277509) (xy 204.523661 -55.275503) (xy 204.361819 -55.265482)
			(xy 204.200671 -55.247469) (xy 204.04061 -55.221509) (xy 203.882029 -55.187664) (xy 203.725316 -55.146019)
			(xy 203.570854 -55.096675) (xy 203.419022 -55.039753) (xy 203.27019 -54.975391) (xy 203.124723 -54.903748)
			(xy 202.982977 -54.824999) (xy 202.845299 -54.739336) (xy 202.712026 -54.646969) (xy 202.583484 -54.548125)
			(xy 202.459987 -54.443044) (xy 202.341839 -54.331985) (xy 202.229327 -54.215219) (xy 202.122727 -54.093031)
			(xy 202.0223 -53.965721) (xy 201.928292 -53.833601) (xy 201.840933 -53.696993) (xy 201.760436 -53.556232)
			(xy 201.687 -53.411662) (xy 201.620802 -53.263638) (xy 201.562006 -53.112521) (xy 201.510755 -52.958681)
			(xy 201.467175 -52.802495) (xy 201.431372 -52.644345) (xy 201.403434 -52.484618) (xy 201.38343 -52.323704)
			(xy 201.371407 -52.161999) (xy 201.367397 -51.999896) (xy 179.393596 -51.999896) (xy 179.393596 -52.481734)
			(xy 179.39311 -52.509003) (xy 179.385348 -52.562987) (xy 179.369983 -52.615317) (xy 179.347326 -52.664927)
			(xy 179.31784 -52.710808) (xy 179.282125 -52.752025) (xy 179.240908 -52.78774) (xy 179.195027 -52.817226)
			(xy 179.145417 -52.839883) (xy 179.093087 -52.855248) (xy 179.039103 -52.86301) (xy 178.984565 -52.86301)
			(xy 178.930581 -52.855248) (xy 178.878251 -52.839883) (xy 178.828641 -52.817226) (xy 178.78276 -52.78774)
			(xy 178.741543 -52.752025) (xy 178.705828 -52.710808) (xy 178.676342 -52.664927) (xy 178.653685 -52.615317)
			(xy 178.63832 -52.562987) (xy 178.630558 -52.509003) (xy 178.630072 -52.481734) (xy 0.509016 -52.481734)
			(xy 0.509016 -53.954934) (xy 181.659784 -53.954934) (xy 181.659784 -53.091334) (xy 181.66027 -53.064065)
			(xy 181.668032 -53.010081) (xy 181.683397 -52.957751) (xy 181.706054 -52.908141) (xy 181.73554 -52.86226)
			(xy 181.771255 -52.821043) (xy 181.812472 -52.785328) (xy 181.858353 -52.755842) (xy 181.907963 -52.733185)
			(xy 181.960293 -52.71782) (xy 182.014277 -52.710058) (xy 182.068815 -52.710058) (xy 182.122799 -52.71782)
			(xy 182.175129 -52.733185) (xy 182.224739 -52.755842) (xy 182.27062 -52.785328) (xy 182.311837 -52.821043)
			(xy 182.347552 -52.86226) (xy 182.377038 -52.908141) (xy 182.399695 -52.957751) (xy 182.41506 -53.010081)
			(xy 182.422822 -53.064065) (xy 182.423308 -53.091334) (xy 182.423308 -53.954934) (xy 182.422822 -53.982203)
			(xy 182.41506 -54.036187) (xy 182.399695 -54.088517) (xy 182.377038 -54.138127) (xy 182.347552 -54.184008)
			(xy 182.311837 -54.225225) (xy 182.27062 -54.26094) (xy 182.224739 -54.290426) (xy 182.175129 -54.313083)
			(xy 182.122799 -54.328448) (xy 182.068815 -54.33621) (xy 182.014277 -54.33621) (xy 181.960293 -54.328448)
			(xy 181.907963 -54.313083) (xy 181.858353 -54.290426) (xy 181.812472 -54.26094) (xy 181.771255 -54.225225)
			(xy 181.73554 -54.184008) (xy 181.706054 -54.138127) (xy 181.683397 -54.088517) (xy 181.668032 -54.036187)
			(xy 181.66027 -53.982203) (xy 181.659784 -53.954934) (xy 0.509016 -53.954934) (xy 0.509016 -55.481728)
			(xy 178.630072 -55.481728) (xy 178.630072 -54.618128) (xy 178.630558 -54.590859) (xy 178.63832 -54.536875)
			(xy 178.653685 -54.484545) (xy 178.676342 -54.434935) (xy 178.705828 -54.389054) (xy 178.741543 -54.347837)
			(xy 178.78276 -54.312122) (xy 178.828641 -54.282636) (xy 178.878251 -54.259979) (xy 178.930581 -54.244614)
			(xy 178.984565 -54.236852) (xy 179.039103 -54.236852) (xy 179.093087 -54.244614) (xy 179.145417 -54.259979)
			(xy 179.195027 -54.282636) (xy 179.240908 -54.312122) (xy 179.282125 -54.347837) (xy 179.31784 -54.389054)
			(xy 179.347326 -54.434935) (xy 179.369983 -54.484545) (xy 179.385348 -54.536875) (xy 179.39311 -54.590859)
			(xy 179.393596 -54.618128) (xy 179.393596 -55.481728) (xy 179.39311 -55.508997) (xy 179.385348 -55.562981)
			(xy 179.369983 -55.615311) (xy 179.347326 -55.664921) (xy 179.31784 -55.710802) (xy 179.282125 -55.752019)
			(xy 179.240908 -55.787734) (xy 179.195027 -55.81722) (xy 179.145417 -55.839877) (xy 179.093087 -55.855242)
			(xy 179.039103 -55.863004) (xy 178.984565 -55.863004) (xy 178.930581 -55.855242) (xy 178.878251 -55.839877)
			(xy 178.828641 -55.81722) (xy 178.78276 -55.787734) (xy 178.741543 -55.752019) (xy 178.705828 -55.710802)
			(xy 178.676342 -55.664921) (xy 178.653685 -55.615311) (xy 178.63832 -55.562981) (xy 178.630558 -55.508997)
			(xy 178.630072 -55.481728) (xy 0.509016 -55.481728) (xy 0.509016 -57.094435) (xy 170.842169 -57.094435)
			(xy 170.842169 -57.005413) (xy 170.850149 -56.916749) (xy 170.866045 -56.829158) (xy 170.889728 -56.743343)
			(xy 170.921008 -56.659998) (xy 170.959634 -56.579792) (xy 171.005293 -56.503371) (xy 171.057619 -56.43135)
			(xy 171.11619 -56.36431) (xy 171.180535 -56.30279) (xy 171.250135 -56.247286) (xy 171.324431 -56.198244)
			(xy 171.402823 -56.156059) (xy 171.484682 -56.121071) (xy 171.569347 -56.093562) (xy 171.656137 -56.073752)
			(xy 171.744353 -56.061802) (xy 171.833286 -56.057809) (xy 171.922219 -56.061802) (xy 172.010435 -56.073752)
			(xy 172.097225 -56.093562) (xy 172.18189 -56.121071) (xy 172.263749 -56.156059) (xy 172.342141 -56.198244)
			(xy 172.416437 -56.247286) (xy 172.486037 -56.30279) (xy 172.550382 -56.36431) (xy 172.608953 -56.43135)
			(xy 172.661279 -56.503371) (xy 172.706938 -56.579792) (xy 172.745564 -56.659998) (xy 172.776844 -56.743343)
			(xy 172.800527 -56.829158) (xy 172.816423 -56.916749) (xy 172.824403 -57.005413) (xy 172.824902 -57.049924)
			(xy 172.824403 -57.094435) (xy 172.816423 -57.183099) (xy 172.800527 -57.27069) (xy 172.776844 -57.356505)
			(xy 172.745564 -57.43985) (xy 172.706938 -57.520056) (xy 172.661279 -57.596477) (xy 172.608953 -57.668498)
			(xy 172.550382 -57.735538) (xy 172.486037 -57.797058) (xy 172.416437 -57.852562) (xy 172.342141 -57.901604)
			(xy 172.263749 -57.943789) (xy 172.18189 -57.978777) (xy 172.097225 -58.006286) (xy 172.010435 -58.026096)
			(xy 171.922219 -58.038046) (xy 171.833286 -58.04204) (xy 171.744353 -58.038046) (xy 171.656137 -58.026096)
			(xy 171.569347 -58.006286) (xy 171.484682 -57.978777) (xy 171.402823 -57.943789) (xy 171.324431 -57.901604)
			(xy 171.250135 -57.852562) (xy 171.180535 -57.797058) (xy 171.11619 -57.735538) (xy 171.057619 -57.668498)
			(xy 171.005293 -57.596477) (xy 170.959634 -57.520056) (xy 170.921008 -57.43985) (xy 170.889728 -57.356505)
			(xy 170.866045 -57.27069) (xy 170.850149 -57.183099) (xy 170.842169 -57.094435) (xy 0.509016 -57.094435)
			(xy 0.509016 -60.375038) (xy 233.333297 -60.375038) (xy 233.337302 -60.28713) (xy 233.349285 -60.19995)
			(xy 233.369145 -60.114221) (xy 233.39672 -60.030653) (xy 233.431779 -59.949939) (xy 233.474032 -59.872747)
			(xy 233.52313 -59.799718) (xy 233.578666 -59.731456) (xy 233.640178 -59.668526) (xy 233.707159 -59.611452)
			(xy 233.779052 -59.560704) (xy 233.855261 -59.516704) (xy 233.935156 -59.479817) (xy 234.018075 -59.450348)
			(xy 234.10333 -59.428541) (xy 234.190214 -59.414577) (xy 234.278008 -59.408571) (xy 234.365985 -59.410575)
			(xy 234.453415 -59.42057) (xy 234.539574 -59.438474) (xy 234.623748 -59.464138) (xy 234.705239 -59.497351)
			(xy 234.783373 -59.537837) (xy 234.857501 -59.585259) (xy 234.927009 -59.639226) (xy 234.991323 -59.699291)
			(xy 235.049907 -59.764955) (xy 235.102278 -59.835674) (xy 235.148001 -59.910862) (xy 235.186698 -59.989897)
			(xy 235.218047 -60.072123) (xy 235.241789 -60.156859) (xy 235.257727 -60.243403) (xy 235.265729 -60.331038)
			(xy 235.26623 -60.375038) (xy 235.265729 -60.419038) (xy 235.257727 -60.506673) (xy 235.241789 -60.593217)
			(xy 235.218047 -60.677953) (xy 235.186698 -60.760179) (xy 235.148001 -60.839214) (xy 235.102278 -60.914402)
			(xy 235.049907 -60.985121) (xy 234.991323 -61.050785) (xy 234.927009 -61.11085) (xy 234.857501 -61.164817)
			(xy 234.783373 -61.212239) (xy 234.705239 -61.252725) (xy 234.623748 -61.285938) (xy 234.539574 -61.311602)
			(xy 234.453415 -61.329506) (xy 234.365985 -61.339501) (xy 234.278008 -61.341505) (xy 234.190214 -61.335499)
			(xy 234.10333 -61.321535) (xy 234.018075 -61.299728) (xy 233.935156 -61.270259) (xy 233.855261 -61.233372)
			(xy 233.779052 -61.189372) (xy 233.707159 -61.138624) (xy 233.640178 -61.08155) (xy 233.578666 -61.01862)
			(xy 233.52313 -60.950358) (xy 233.474032 -60.877329) (xy 233.431779 -60.800137) (xy 233.39672 -60.719423)
			(xy 233.369145 -60.635855) (xy 233.349285 -60.550126) (xy 233.337302 -60.462946) (xy 233.333297 -60.375038)
			(xy 0.509016 -60.375038) (xy 0.509016 -74.760836) (xy 39.554404 -74.760836) (xy 39.554404 -66.060828)
			(xy 39.554909 -65.955304) (xy 39.562993 -65.74441) (xy 39.579149 -65.533981) (xy 39.603352 -65.324324)
			(xy 39.635569 -65.115749) (xy 39.675751 -64.908561) (xy 39.723839 -64.703064) (xy 39.779763 -64.49956)
			(xy 39.84344 -64.298347) (xy 39.914778 -64.09972) (xy 39.993672 -63.903972) (xy 40.080005 -63.71139)
			(xy 40.173652 -63.522255) (xy 40.274474 -63.336846) (xy 40.382324 -63.155435) (xy 40.497043 -62.978288)
			(xy 40.618463 -62.805666) (xy 40.746406 -62.63782) (xy 40.880684 -62.474998) (xy 41.0211 -62.317439)
			(xy 41.167448 -62.165374) (xy 41.319513 -62.019026) (xy 41.477072 -61.87861) (xy 41.639894 -61.744332)
			(xy 41.80774 -61.616389) (xy 41.980362 -61.494969) (xy 42.157509 -61.38025) (xy 42.33892 -61.2724)
			(xy 42.524329 -61.171578) (xy 42.713464 -61.077931) (xy 42.906046 -60.991598) (xy 43.101794 -60.912704)
			(xy 43.300421 -60.841366) (xy 43.501634 -60.777689) (xy 43.705138 -60.721765) (xy 43.910635 -60.673677)
			(xy 44.117823 -60.633495) (xy 44.326398 -60.601278) (xy 44.536055 -60.577075) (xy 44.746484 -60.560919)
			(xy 44.957378 -60.552835) (xy 45.168426 -60.552835) (xy 45.37932 -60.560919) (xy 45.589749 -60.577075)
			(xy 45.799406 -60.601278) (xy 46.007981 -60.633495) (xy 46.215169 -60.673677) (xy 46.420666 -60.721765)
			(xy 46.62417 -60.777689) (xy 46.825383 -60.841366) (xy 47.02401 -60.912704) (xy 47.219758 -60.991598)
			(xy 47.41234 -61.077931) (xy 47.601475 -61.171578) (xy 47.786884 -61.2724) (xy 47.968295 -61.38025)
			(xy 48.145442 -61.494969) (xy 48.318064 -61.616389) (xy 48.48591 -61.744332) (xy 48.648732 -61.87861)
			(xy 48.806291 -62.019026) (xy 48.958356 -62.165374) (xy 49.104704 -62.317439) (xy 49.24512 -62.474998)
			(xy 49.379398 -62.63782) (xy 49.507341 -62.805666) (xy 49.628761 -62.978288) (xy 49.74348 -63.155435)
			(xy 49.85133 -63.336846) (xy 49.952152 -63.522255) (xy 50.045799 -63.71139) (xy 50.132132 -63.903972)
			(xy 50.211026 -64.09972) (xy 50.282364 -64.298347) (xy 50.346041 -64.49956) (xy 50.401965 -64.703064)
			(xy 50.450053 -64.908561) (xy 50.490235 -65.115749) (xy 50.522452 -65.324324) (xy 50.546655 -65.533981)
			(xy 50.562811 -65.74441) (xy 50.570895 -65.955304) (xy 50.5714 -66.060828) (xy 50.5714 -74.760836)
			(xy 50.571366 -74.767948) (xy 173.354492 -74.767948) (xy 173.354492 -66.06794) (xy 173.354997 -65.962416)
			(xy 173.363081 -65.751522) (xy 173.379237 -65.541093) (xy 173.40344 -65.331436) (xy 173.435657 -65.122861)
			(xy 173.475839 -64.915673) (xy 173.523927 -64.710176) (xy 173.579851 -64.506672) (xy 173.643528 -64.305459)
			(xy 173.714866 -64.106832) (xy 173.79376 -63.911084) (xy 173.880093 -63.718502) (xy 173.97374 -63.529367)
			(xy 174.074562 -63.343958) (xy 174.182412 -63.162547) (xy 174.297131 -62.9854) (xy 174.418551 -62.812778)
			(xy 174.546494 -62.644932) (xy 174.680772 -62.48211) (xy 174.821188 -62.324551) (xy 174.967536 -62.172486)
			(xy 175.119601 -62.026138) (xy 175.27716 -61.885722) (xy 175.439982 -61.751444) (xy 175.607828 -61.623501)
			(xy 175.78045 -61.502081) (xy 175.957597 -61.387362) (xy 176.139008 -61.279512) (xy 176.324417 -61.17869)
			(xy 176.513552 -61.085043) (xy 176.706134 -60.99871) (xy 176.901882 -60.919816) (xy 177.100509 -60.848478)
			(xy 177.301722 -60.784801) (xy 177.505226 -60.728877) (xy 177.710723 -60.680789) (xy 177.917911 -60.640607)
			(xy 178.126486 -60.60839) (xy 178.336143 -60.584187) (xy 178.546572 -60.568031) (xy 178.757466 -60.559947)
			(xy 178.968514 -60.559947) (xy 179.179408 -60.568031) (xy 179.389837 -60.584187) (xy 179.599494 -60.60839)
			(xy 179.808069 -60.640607) (xy 180.015257 -60.680789) (xy 180.220754 -60.728877) (xy 180.424258 -60.784801)
			(xy 180.625471 -60.848478) (xy 180.824098 -60.919816) (xy 181.019846 -60.99871) (xy 181.212428 -61.085043)
			(xy 181.401563 -61.17869) (xy 181.586972 -61.279512) (xy 181.768383 -61.387362) (xy 181.94553 -61.502081)
			(xy 182.118152 -61.623501) (xy 182.285998 -61.751444) (xy 182.44882 -61.885722) (xy 182.606379 -62.026138)
			(xy 182.758444 -62.172486) (xy 182.904792 -62.324551) (xy 183.045208 -62.48211) (xy 183.179486 -62.644932)
			(xy 183.307429 -62.812778) (xy 183.428849 -62.9854) (xy 183.543568 -63.162547) (xy 183.651418 -63.343958)
			(xy 183.75224 -63.529367) (xy 183.845887 -63.718502) (xy 183.93222 -63.911084) (xy 184.011114 -64.106832)
			(xy 184.082452 -64.305459) (xy 184.146129 -64.506672) (xy 184.202053 -64.710176) (xy 184.250141 -64.915673)
			(xy 184.290323 -65.122861) (xy 184.32254 -65.331436) (xy 184.346743 -65.541093) (xy 184.362899 -65.751522)
			(xy 184.370983 -65.962416) (xy 184.371488 -66.06794) (xy 184.371488 -74.760836) (xy 287.494472 -74.760836)
			(xy 287.494472 -66.060828) (xy 287.494977 -65.955304) (xy 287.503061 -65.74441) (xy 287.519217 -65.533981)
			(xy 287.54342 -65.324324) (xy 287.575637 -65.115749) (xy 287.615819 -64.908561) (xy 287.663907 -64.703064)
			(xy 287.719831 -64.49956) (xy 287.783508 -64.298347) (xy 287.854846 -64.09972) (xy 287.93374 -63.903972)
			(xy 288.020073 -63.71139) (xy 288.11372 -63.522255) (xy 288.214542 -63.336846) (xy 288.322392 -63.155435)
			(xy 288.437111 -62.978288) (xy 288.558531 -62.805666) (xy 288.686474 -62.63782) (xy 288.820752 -62.474998)
			(xy 288.961168 -62.317439) (xy 289.107516 -62.165374) (xy 289.259581 -62.019026) (xy 289.41714 -61.87861)
			(xy 289.579962 -61.744332) (xy 289.747808 -61.616389) (xy 289.92043 -61.494969) (xy 290.097577 -61.38025)
			(xy 290.278988 -61.2724) (xy 290.464397 -61.171578) (xy 290.653532 -61.077931) (xy 290.846114 -60.991598)
			(xy 291.041862 -60.912704) (xy 291.240489 -60.841366) (xy 291.441702 -60.777689) (xy 291.645206 -60.721765)
			(xy 291.850703 -60.673677) (xy 292.057891 -60.633495) (xy 292.266466 -60.601278) (xy 292.476123 -60.577075)
			(xy 292.686552 -60.560919) (xy 292.897446 -60.552835) (xy 293.108494 -60.552835) (xy 293.319388 -60.560919)
			(xy 293.529817 -60.577075) (xy 293.739474 -60.601278) (xy 293.948049 -60.633495) (xy 294.155237 -60.673677)
			(xy 294.360734 -60.721765) (xy 294.564238 -60.777689) (xy 294.765451 -60.841366) (xy 294.964078 -60.912704)
			(xy 295.159826 -60.991598) (xy 295.352408 -61.077931) (xy 295.541543 -61.171578) (xy 295.726952 -61.2724)
			(xy 295.908363 -61.38025) (xy 296.08551 -61.494969) (xy 296.258132 -61.616389) (xy 296.425978 -61.744332)
			(xy 296.5888 -61.87861) (xy 296.746359 -62.019026) (xy 296.898424 -62.165374) (xy 297.044772 -62.317439)
			(xy 297.185188 -62.474998) (xy 297.319466 -62.63782) (xy 297.447409 -62.805666) (xy 297.568829 -62.978288)
			(xy 297.683548 -63.155435) (xy 297.791398 -63.336846) (xy 297.89222 -63.522255) (xy 297.985867 -63.71139)
			(xy 298.0722 -63.903972) (xy 298.151094 -64.09972) (xy 298.222432 -64.298347) (xy 298.286109 -64.49956)
			(xy 298.342033 -64.703064) (xy 298.390121 -64.908561) (xy 298.430303 -65.115749) (xy 298.46252 -65.324324)
			(xy 298.486723 -65.533981) (xy 298.502879 -65.74441) (xy 298.510963 -65.955304) (xy 298.511468 -66.060828)
			(xy 298.511468 -74.760836) (xy 298.511434 -74.767948) (xy 421.29456 -74.767948) (xy 421.29456 -66.06794)
			(xy 421.295065 -65.962416) (xy 421.303149 -65.751522) (xy 421.319305 -65.541093) (xy 421.343508 -65.331436)
			(xy 421.375725 -65.122861) (xy 421.415907 -64.915673) (xy 421.463995 -64.710176) (xy 421.519919 -64.506672)
			(xy 421.583596 -64.305459) (xy 421.654934 -64.106832) (xy 421.733828 -63.911084) (xy 421.820161 -63.718502)
			(xy 421.913808 -63.529367) (xy 422.01463 -63.343958) (xy 422.12248 -63.162547) (xy 422.237199 -62.9854)
			(xy 422.358619 -62.812778) (xy 422.486562 -62.644932) (xy 422.62084 -62.48211) (xy 422.761256 -62.324551)
			(xy 422.907604 -62.172486) (xy 423.059669 -62.026138) (xy 423.217228 -61.885722) (xy 423.38005 -61.751444)
			(xy 423.547896 -61.623501) (xy 423.720518 -61.502081) (xy 423.897665 -61.387362) (xy 424.079076 -61.279512)
			(xy 424.264485 -61.17869) (xy 424.45362 -61.085043) (xy 424.646202 -60.99871) (xy 424.84195 -60.919816)
			(xy 425.040577 -60.848478) (xy 425.24179 -60.784801) (xy 425.445294 -60.728877) (xy 425.650791 -60.680789)
			(xy 425.857979 -60.640607) (xy 426.066554 -60.60839) (xy 426.276211 -60.584187) (xy 426.48664 -60.568031)
			(xy 426.697534 -60.559947) (xy 426.908582 -60.559947) (xy 427.119476 -60.568031) (xy 427.329905 -60.584187)
			(xy 427.539562 -60.60839) (xy 427.748137 -60.640607) (xy 427.955325 -60.680789) (xy 428.160822 -60.728877)
			(xy 428.364326 -60.784801) (xy 428.565539 -60.848478) (xy 428.764166 -60.919816) (xy 428.959914 -60.99871)
			(xy 429.152496 -61.085043) (xy 429.341631 -61.17869) (xy 429.52704 -61.279512) (xy 429.708451 -61.387362)
			(xy 429.885598 -61.502081) (xy 430.05822 -61.623501) (xy 430.226066 -61.751444) (xy 430.388888 -61.885722)
			(xy 430.546447 -62.026138) (xy 430.698512 -62.172486) (xy 430.84486 -62.324551) (xy 430.985276 -62.48211)
			(xy 431.119554 -62.644932) (xy 431.247497 -62.812778) (xy 431.368917 -62.9854) (xy 431.483636 -63.162547)
			(xy 431.591486 -63.343958) (xy 431.692308 -63.529367) (xy 431.785955 -63.718502) (xy 431.872288 -63.911084)
			(xy 431.951182 -64.106832) (xy 432.02252 -64.305459) (xy 432.086197 -64.506672) (xy 432.142121 -64.710176)
			(xy 432.190209 -64.915673) (xy 432.230391 -65.122861) (xy 432.262608 -65.331436) (xy 432.286811 -65.541093)
			(xy 432.302967 -65.751522) (xy 432.311051 -65.962416) (xy 432.311556 -66.06794) (xy 432.311556 -74.767948)
			(xy 432.311051 -74.873472) (xy 432.302967 -75.084366) (xy 432.286811 -75.294795) (xy 432.262608 -75.504452)
			(xy 432.230391 -75.713027) (xy 432.190209 -75.920215) (xy 432.142121 -76.125712) (xy 432.086197 -76.329216)
			(xy 432.02252 -76.530429) (xy 431.951182 -76.729056) (xy 431.872288 -76.924804) (xy 431.785955 -77.117386)
			(xy 431.692308 -77.306521) (xy 431.591486 -77.49193) (xy 431.483636 -77.673341) (xy 431.368917 -77.850488)
			(xy 431.247497 -78.02311) (xy 431.119554 -78.190956) (xy 430.985276 -78.353778) (xy 430.84486 -78.511337)
			(xy 430.698512 -78.663402) (xy 430.546447 -78.80975) (xy 430.388888 -78.950166) (xy 430.226066 -79.084444)
			(xy 430.05822 -79.212387) (xy 429.885598 -79.333807) (xy 429.708451 -79.448526) (xy 429.52704 -79.556376)
			(xy 429.341631 -79.657198) (xy 429.152496 -79.750845) (xy 428.959914 -79.837178) (xy 428.764166 -79.916072)
			(xy 428.565539 -79.98741) (xy 428.364326 -80.051087) (xy 428.160822 -80.107011) (xy 427.955325 -80.155099)
			(xy 427.748137 -80.195281) (xy 427.539562 -80.227498) (xy 427.329905 -80.251701) (xy 427.119476 -80.267857)
			(xy 426.908582 -80.275941) (xy 426.697534 -80.275941) (xy 426.48664 -80.267857) (xy 426.276211 -80.251701)
			(xy 426.066554 -80.227498) (xy 425.857979 -80.195281) (xy 425.650791 -80.155099) (xy 425.445294 -80.107011)
			(xy 425.24179 -80.051087) (xy 425.040577 -79.98741) (xy 424.84195 -79.916072) (xy 424.646202 -79.837178)
			(xy 424.45362 -79.750845) (xy 424.264485 -79.657198) (xy 424.079076 -79.556376) (xy 423.897665 -79.448526)
			(xy 423.720518 -79.333807) (xy 423.547896 -79.212387) (xy 423.38005 -79.084444) (xy 423.217228 -78.950166)
			(xy 423.059669 -78.80975) (xy 422.907604 -78.663402) (xy 422.761256 -78.511337) (xy 422.62084 -78.353778)
			(xy 422.486562 -78.190956) (xy 422.358619 -78.02311) (xy 422.237199 -77.850488) (xy 422.12248 -77.673341)
			(xy 422.01463 -77.49193) (xy 421.913808 -77.306521) (xy 421.820161 -77.117386) (xy 421.733828 -76.924804)
			(xy 421.654934 -76.729056) (xy 421.583596 -76.530429) (xy 421.519919 -76.329216) (xy 421.463995 -76.125712)
			(xy 421.415907 -75.920215) (xy 421.375725 -75.713027) (xy 421.343508 -75.504452) (xy 421.319305 -75.294795)
			(xy 421.303149 -75.084366) (xy 421.295065 -74.873472) (xy 421.29456 -74.767948) (xy 298.511434 -74.767948)
			(xy 298.510963 -74.86636) (xy 298.502879 -75.077254) (xy 298.486723 -75.287683) (xy 298.46252 -75.49734)
			(xy 298.430303 -75.705915) (xy 298.390121 -75.913103) (xy 298.342033 -76.1186) (xy 298.286109 -76.322104)
			(xy 298.222432 -76.523317) (xy 298.151094 -76.721944) (xy 298.0722 -76.917692) (xy 297.985867 -77.110274)
			(xy 297.89222 -77.299409) (xy 297.791398 -77.484818) (xy 297.683548 -77.666229) (xy 297.568829 -77.843376)
			(xy 297.447409 -78.015998) (xy 297.319466 -78.183844) (xy 297.185188 -78.346666) (xy 297.044772 -78.504225)
			(xy 296.898424 -78.65629) (xy 296.746359 -78.802638) (xy 296.5888 -78.943054) (xy 296.425978 -79.077332)
			(xy 296.258132 -79.205275) (xy 296.08551 -79.326695) (xy 295.908363 -79.441414) (xy 295.726952 -79.549264)
			(xy 295.541543 -79.650086) (xy 295.352408 -79.743733) (xy 295.159826 -79.830066) (xy 294.964078 -79.90896)
			(xy 294.765451 -79.980298) (xy 294.564238 -80.043975) (xy 294.360734 -80.099899) (xy 294.155237 -80.147987)
			(xy 293.948049 -80.188169) (xy 293.739474 -80.220386) (xy 293.529817 -80.244589) (xy 293.319388 -80.260745)
			(xy 293.108494 -80.268829) (xy 292.897446 -80.268829) (xy 292.686552 -80.260745) (xy 292.476123 -80.244589)
			(xy 292.266466 -80.220386) (xy 292.057891 -80.188169) (xy 291.850703 -80.147987) (xy 291.645206 -80.099899)
			(xy 291.441702 -80.043975) (xy 291.240489 -79.980298) (xy 291.041862 -79.90896) (xy 290.846114 -79.830066)
			(xy 290.653532 -79.743733) (xy 290.464397 -79.650086) (xy 290.278988 -79.549264) (xy 290.097577 -79.441414)
			(xy 289.92043 -79.326695) (xy 289.747808 -79.205275) (xy 289.579962 -79.077332) (xy 289.41714 -78.943054)
			(xy 289.259581 -78.802638) (xy 289.107516 -78.65629) (xy 288.961168 -78.504225) (xy 288.820752 -78.346666)
			(xy 288.686474 -78.183844) (xy 288.558531 -78.015998) (xy 288.437111 -77.843376) (xy 288.322392 -77.666229)
			(xy 288.214542 -77.484818) (xy 288.11372 -77.299409) (xy 288.020073 -77.110274) (xy 287.93374 -76.917692)
			(xy 287.854846 -76.721944) (xy 287.783508 -76.523317) (xy 287.719831 -76.322104) (xy 287.663907 -76.1186)
			(xy 287.615819 -75.913103) (xy 287.575637 -75.705915) (xy 287.54342 -75.49734) (xy 287.519217 -75.287683)
			(xy 287.503061 -75.077254) (xy 287.494977 -74.86636) (xy 287.494472 -74.760836) (xy 184.371488 -74.760836)
			(xy 184.371488 -74.767948) (xy 184.370983 -74.873472) (xy 184.362899 -75.084366) (xy 184.346743 -75.294795)
			(xy 184.32254 -75.504452) (xy 184.290323 -75.713027) (xy 184.250141 -75.920215) (xy 184.202053 -76.125712)
			(xy 184.146129 -76.329216) (xy 184.082452 -76.530429) (xy 184.011114 -76.729056) (xy 183.93222 -76.924804)
			(xy 183.845887 -77.117386) (xy 183.75224 -77.306521) (xy 183.651418 -77.49193) (xy 183.543568 -77.673341)
			(xy 183.428849 -77.850488) (xy 183.307429 -78.02311) (xy 183.179486 -78.190956) (xy 183.045208 -78.353778)
			(xy 182.904792 -78.511337) (xy 182.758444 -78.663402) (xy 182.606379 -78.80975) (xy 182.44882 -78.950166)
			(xy 182.285998 -79.084444) (xy 182.118152 -79.212387) (xy 181.94553 -79.333807) (xy 181.768383 -79.448526)
			(xy 181.586972 -79.556376) (xy 181.401563 -79.657198) (xy 181.212428 -79.750845) (xy 181.019846 -79.837178)
			(xy 180.824098 -79.916072) (xy 180.625471 -79.98741) (xy 180.424258 -80.051087) (xy 180.220754 -80.107011)
			(xy 180.015257 -80.155099) (xy 179.808069 -80.195281) (xy 179.599494 -80.227498) (xy 179.389837 -80.251701)
			(xy 179.179408 -80.267857) (xy 178.968514 -80.275941) (xy 178.757466 -80.275941) (xy 178.546572 -80.267857)
			(xy 178.336143 -80.251701) (xy 178.126486 -80.227498) (xy 177.917911 -80.195281) (xy 177.710723 -80.155099)
			(xy 177.505226 -80.107011) (xy 177.301722 -80.051087) (xy 177.100509 -79.98741) (xy 176.901882 -79.916072)
			(xy 176.706134 -79.837178) (xy 176.513552 -79.750845) (xy 176.324417 -79.657198) (xy 176.139008 -79.556376)
			(xy 175.957597 -79.448526) (xy 175.78045 -79.333807) (xy 175.607828 -79.212387) (xy 175.439982 -79.084444)
			(xy 175.27716 -78.950166) (xy 175.119601 -78.80975) (xy 174.967536 -78.663402) (xy 174.821188 -78.511337)
			(xy 174.680772 -78.353778) (xy 174.546494 -78.190956) (xy 174.418551 -78.02311) (xy 174.297131 -77.850488)
			(xy 174.182412 -77.673341) (xy 174.074562 -77.49193) (xy 173.97374 -77.306521) (xy 173.880093 -77.117386)
			(xy 173.79376 -76.924804) (xy 173.714866 -76.729056) (xy 173.643528 -76.530429) (xy 173.579851 -76.329216)
			(xy 173.523927 -76.125712) (xy 173.475839 -75.920215) (xy 173.435657 -75.713027) (xy 173.40344 -75.504452)
			(xy 173.379237 -75.294795) (xy 173.363081 -75.084366) (xy 173.354997 -74.873472) (xy 173.354492 -74.767948)
			(xy 50.571366 -74.767948) (xy 50.570895 -74.86636) (xy 50.562811 -75.077254) (xy 50.546655 -75.287683)
			(xy 50.522452 -75.49734) (xy 50.490235 -75.705915) (xy 50.450053 -75.913103) (xy 50.401965 -76.1186)
			(xy 50.346041 -76.322104) (xy 50.282364 -76.523317) (xy 50.211026 -76.721944) (xy 50.132132 -76.917692)
			(xy 50.045799 -77.110274) (xy 49.952152 -77.299409) (xy 49.85133 -77.484818) (xy 49.74348 -77.666229)
			(xy 49.628761 -77.843376) (xy 49.507341 -78.015998) (xy 49.379398 -78.183844) (xy 49.24512 -78.346666)
			(xy 49.104704 -78.504225) (xy 48.958356 -78.65629) (xy 48.806291 -78.802638) (xy 48.648732 -78.943054)
			(xy 48.48591 -79.077332) (xy 48.318064 -79.205275) (xy 48.145442 -79.326695) (xy 47.968295 -79.441414)
			(xy 47.786884 -79.549264) (xy 47.601475 -79.650086) (xy 47.41234 -79.743733) (xy 47.219758 -79.830066)
			(xy 47.02401 -79.90896) (xy 46.825383 -79.980298) (xy 46.62417 -80.043975) (xy 46.420666 -80.099899)
			(xy 46.215169 -80.147987) (xy 46.007981 -80.188169) (xy 45.799406 -80.220386) (xy 45.589749 -80.244589)
			(xy 45.37932 -80.260745) (xy 45.168426 -80.268829) (xy 44.957378 -80.268829) (xy 44.746484 -80.260745)
			(xy 44.536055 -80.244589) (xy 44.326398 -80.220386) (xy 44.117823 -80.188169) (xy 43.910635 -80.147987)
			(xy 43.705138 -80.099899) (xy 43.501634 -80.043975) (xy 43.300421 -79.980298) (xy 43.101794 -79.90896)
			(xy 42.906046 -79.830066) (xy 42.713464 -79.743733) (xy 42.524329 -79.650086) (xy 42.33892 -79.549264)
			(xy 42.157509 -79.441414) (xy 41.980362 -79.326695) (xy 41.80774 -79.205275) (xy 41.639894 -79.077332)
			(xy 41.477072 -78.943054) (xy 41.319513 -78.802638) (xy 41.167448 -78.65629) (xy 41.0211 -78.504225)
			(xy 40.880684 -78.346666) (xy 40.746406 -78.183844) (xy 40.618463 -78.015998) (xy 40.497043 -77.843376)
			(xy 40.382324 -77.666229) (xy 40.274474 -77.484818) (xy 40.173652 -77.299409) (xy 40.080005 -77.110274)
			(xy 39.993672 -76.917692) (xy 39.914778 -76.721944) (xy 39.84344 -76.523317) (xy 39.779763 -76.322104)
			(xy 39.723839 -76.1186) (xy 39.675751 -75.913103) (xy 39.635569 -75.705915) (xy 39.603352 -75.49734)
			(xy 39.579149 -75.287683) (xy 39.562993 -75.077254) (xy 39.554909 -74.86636) (xy 39.554404 -74.760836)
			(xy 0.509016 -74.760836) (xy 0.509016 -77.67193) (xy 0.5095 -77.725143) (xy 0.517108 -77.831296)
			(xy 0.532269 -77.936637) (xy 0.554904 -78.040627) (xy 0.584899 -78.142739) (xy 0.622101 -78.242451)
			(xy 0.666319 -78.339256) (xy 0.71733 -78.43266) (xy 0.774873 -78.522188) (xy 0.838654 -78.607384)
			(xy 0.90835 -78.687813) (xy 0.945642 -78.725776) (xy 1.77419 -79.554324) (xy 1.823612 -79.604428)
			(xy 1.917404 -79.709374) (xy 2.005163 -79.819414) (xy 2.086614 -79.934202) (xy 2.161501 -80.053377)
			(xy 2.229587 -80.176563) (xy 2.290658 -80.303374) (xy 2.344523 -80.433409) (xy 2.391012 -80.56626)
			(xy 2.429978 -80.701509) (xy 2.461299 -80.83873) (xy 2.484876 -80.977491) (xy 2.500635 -81.117356)
			(xy 2.508527 -81.257885) (xy 2.509012 -81.32826) (xy 2.509012 -81.691972) (xy 232.140715 -81.691972)
			(xy 232.145114 -81.518126) (xy 232.157548 -81.34467) (xy 232.177991 -81.171975) (xy 232.206398 -81.00041)
			(xy 232.242709 -80.830342) (xy 232.286847 -80.662135) (xy 232.338717 -80.49615) (xy 232.398207 -80.332741)
			(xy 232.465191 -80.172258) (xy 232.539525 -80.015044) (xy 232.62105 -79.861437) (xy 232.709592 -79.711764)
			(xy 232.804961 -79.566346) (xy 232.906953 -79.425495) (xy 233.015351 -79.289511) (xy 233.129921 -79.158685)
			(xy 233.250418 -79.033298) (xy 233.376586 -78.913618) (xy 233.508153 -78.799901) (xy 233.644839 -78.69239)
			(xy 233.715306 -78.641448) (xy 238.084614 -78.641448) (xy 238.155081 -78.69239) (xy 238.291767 -78.799901)
			(xy 238.423334 -78.913618) (xy 238.549502 -79.033298) (xy 238.669999 -79.158685) (xy 238.784569 -79.289511)
			(xy 238.892967 -79.425495) (xy 238.994959 -79.566346) (xy 239.090328 -79.711764) (xy 239.17887 -79.861437)
			(xy 239.260395 -80.015044) (xy 239.334729 -80.172258) (xy 239.401713 -80.332741) (xy 239.461203 -80.49615)
			(xy 239.513073 -80.662135) (xy 239.557211 -80.830342) (xy 239.593522 -81.00041) (xy 239.608937 -81.093507)
			(xy 398.275806 -81.093507) (xy 398.275806 -81.008785) (xy 398.283859 -80.924448) (xy 398.299893 -80.841258)
			(xy 398.323761 -80.759968) (xy 398.355249 -80.681316) (xy 398.394071 -80.606013) (xy 398.439874 -80.534741)
			(xy 398.492245 -80.468145) (xy 398.55071 -80.40683) (xy 398.614738 -80.351349) (xy 398.68375 -80.302206)
			(xy 398.75712 -80.259846) (xy 398.834185 -80.224651) (xy 398.914247 -80.196942) (xy 398.99658 -80.176968)
			(xy 399.080439 -80.164911) (xy 399.165064 -80.16088) (xy 399.249689 -80.164911) (xy 399.333548 -80.176968)
			(xy 399.415881 -80.196942) (xy 399.495943 -80.224651) (xy 399.573008 -80.259846) (xy 399.646378 -80.302206)
			(xy 399.71539 -80.351349) (xy 399.779418 -80.40683) (xy 399.837883 -80.468145) (xy 399.890254 -80.534741)
			(xy 399.936057 -80.606013) (xy 399.974879 -80.681316) (xy 400.006367 -80.759968) (xy 400.030235 -80.841258)
			(xy 400.046269 -80.924448) (xy 400.054322 -81.008785) (xy 400.054826 -81.051146) (xy 400.054322 -81.093507)
			(xy 400.046269 -81.177844) (xy 400.030235 -81.261034) (xy 400.006367 -81.342324) (xy 399.974879 -81.420976)
			(xy 399.936057 -81.496279) (xy 399.890254 -81.567551) (xy 399.837883 -81.634147) (xy 399.779418 -81.695462)
			(xy 399.71539 -81.750943) (xy 399.646378 -81.800086) (xy 399.573008 -81.842446) (xy 399.495943 -81.877641)
			(xy 399.415881 -81.90535) (xy 399.333548 -81.925324) (xy 399.249689 -81.937381) (xy 399.165064 -81.941413)
			(xy 399.080439 -81.937381) (xy 398.99658 -81.925324) (xy 398.914247 -81.90535) (xy 398.834185 -81.877641)
			(xy 398.75712 -81.842446) (xy 398.68375 -81.800086) (xy 398.614738 -81.750943) (xy 398.55071 -81.695462)
			(xy 398.492245 -81.634147) (xy 398.439874 -81.567551) (xy 398.394071 -81.496279) (xy 398.355249 -81.420976)
			(xy 398.323761 -81.342324) (xy 398.299893 -81.261034) (xy 398.283859 -81.177844) (xy 398.275806 -81.093507)
			(xy 239.608937 -81.093507) (xy 239.621929 -81.171975) (xy 239.642372 -81.34467) (xy 239.654806 -81.518126)
			(xy 239.659205 -81.691972) (xy 239.655559 -81.865835) (xy 239.643877 -82.039343) (xy 239.624183 -82.212126)
			(xy 239.596519 -82.383812) (xy 239.560945 -82.554036) (xy 239.517536 -82.722432) (xy 239.466387 -82.888641)
			(xy 239.407605 -83.052306) (xy 239.341317 -83.213078) (xy 239.267665 -83.370612) (xy 239.186806 -83.524571)
			(xy 239.098913 -83.674626) (xy 239.004175 -83.820455) (xy 238.902794 -83.961748) (xy 238.794987 -84.0982)
			(xy 238.680985 -84.229521) (xy 238.561032 -84.355429) (xy 238.435384 -84.475655) (xy 238.30431 -84.589941)
			(xy 238.168092 -84.698043) (xy 238.027019 -84.79973) (xy 237.881395 -84.894784) (xy 237.731531 -84.983001)
			(xy 237.577747 -85.064194) (xy 237.420373 -85.138187) (xy 237.259746 -85.204823) (xy 237.096208 -85.263959)
			(xy 236.930111 -85.315469) (xy 236.761809 -85.359242) (xy 236.591663 -85.395185) (xy 236.420037 -85.423221)
			(xy 236.247297 -85.443289) (xy 236.073815 -85.455348) (xy 235.89996 -85.45937) (xy 235.726105 -85.455348)
			(xy 235.552623 -85.443289) (xy 235.379883 -85.423221) (xy 235.208257 -85.395185) (xy 235.038111 -85.359242)
			(xy 234.869809 -85.315469) (xy 234.703712 -85.263959) (xy 234.540174 -85.204823) (xy 234.379547 -85.138187)
			(xy 234.222173 -85.064194) (xy 234.068389 -84.983001) (xy 233.918525 -84.894784) (xy 233.772901 -84.79973)
			(xy 233.631828 -84.698043) (xy 233.49561 -84.589941) (xy 233.364536 -84.475655) (xy 233.238888 -84.355429)
			(xy 233.118935 -84.229521) (xy 233.004933 -84.0982) (xy 232.897126 -83.961748) (xy 232.795745 -83.820455)
			(xy 232.701007 -83.674626) (xy 232.613114 -83.524571) (xy 232.532255 -83.370612) (xy 232.458603 -83.213078)
			(xy 232.392315 -83.052306) (xy 232.333533 -82.888641) (xy 232.282384 -82.722432) (xy 232.238975 -82.554036)
			(xy 232.203401 -82.383812) (xy 232.175737 -82.212126) (xy 232.156043 -82.039343) (xy 232.144361 -81.865835)
			(xy 232.140715 -81.691972) (xy 2.509012 -81.691972) (xy 2.509012 -84.065147) (xy 218.29831 -84.065147)
			(xy 218.29831 -84.010653) (xy 218.306065 -83.956712) (xy 218.321417 -83.904424) (xy 218.344054 -83.854854)
			(xy 218.373515 -83.809009) (xy 218.4092 -83.767823) (xy 218.450383 -83.732134) (xy 218.496225 -83.70267)
			(xy 218.545794 -83.680029) (xy 218.598081 -83.664672) (xy 218.652021 -83.656912) (xy 218.679268 -83.656424)
			(xy 219.542868 -83.656424) (xy 219.570125 -83.656821) (xy 219.624084 -83.664575) (xy 219.67639 -83.679929)
			(xy 219.725978 -83.702572) (xy 219.771839 -83.732041) (xy 219.813039 -83.767738) (xy 219.848739 -83.808935)
			(xy 219.878213 -83.854794) (xy 219.90086 -83.90438) (xy 219.916219 -83.956685) (xy 219.923977 -84.010643)
			(xy 219.923977 -84.065157) (xy 219.916219 -84.119115) (xy 219.90086 -84.17142) (xy 219.878213 -84.221006)
			(xy 219.848739 -84.266865) (xy 219.813039 -84.308062) (xy 219.771839 -84.343759) (xy 219.725978 -84.373228)
			(xy 219.67639 -84.395871) (xy 219.624084 -84.411225) (xy 219.570125 -84.418979) (xy 219.542868 -84.41944)
			(xy 218.679268 -84.41944) (xy 218.652021 -84.418888) (xy 218.598081 -84.411128) (xy 218.545794 -84.395771)
			(xy 218.496225 -84.37313) (xy 218.450383 -84.343666) (xy 218.4092 -84.307977) (xy 218.373515 -84.266791)
			(xy 218.344054 -84.220946) (xy 218.321417 -84.171376) (xy 218.306065 -84.119088) (xy 218.29831 -84.065147)
			(xy 2.509012 -84.065147) (xy 2.509012 -86.948548) (xy 217.344518 -86.948548) (xy 217.344518 -86.894052)
			(xy 217.352274 -86.84011) (xy 217.367627 -86.787821) (xy 217.390266 -86.738249) (xy 217.419729 -86.692404)
			(xy 217.455416 -86.651218) (xy 217.496602 -86.61553) (xy 217.542447 -86.586067) (xy 217.592019 -86.563428)
			(xy 217.644308 -86.548074) (xy 217.69825 -86.540318) (xy 217.725498 -86.539832) (xy 218.589098 -86.539832)
			(xy 218.616354 -86.540215) (xy 218.670311 -86.547972) (xy 218.722614 -86.56333) (xy 218.7722 -86.585975)
			(xy 218.818058 -86.615446) (xy 218.859255 -86.651143) (xy 218.894953 -86.69234) (xy 218.924424 -86.738198)
			(xy 218.947069 -86.787784) (xy 218.962427 -86.840087) (xy 218.970185 -86.894044) (xy 218.970185 -86.948556)
			(xy 218.962427 -87.002513) (xy 218.947069 -87.054816) (xy 218.924424 -87.104402) (xy 218.894953 -87.15026)
			(xy 218.859255 -87.191457) (xy 218.818058 -87.227154) (xy 218.7722 -87.256625) (xy 218.722614 -87.27927)
			(xy 218.670311 -87.294628) (xy 218.616354 -87.302385) (xy 218.589098 -87.302848) (xy 217.725498 -87.302848)
			(xy 217.69825 -87.302282) (xy 217.644308 -87.294526) (xy 217.592019 -87.279172) (xy 217.542447 -87.256533)
			(xy 217.496602 -87.22707) (xy 217.455416 -87.191382) (xy 217.419729 -87.150196) (xy 217.390266 -87.104351)
			(xy 217.367627 -87.054779) (xy 217.352274 -87.00249) (xy 217.344518 -86.948548) (xy 2.509012 -86.948548)
			(xy 2.509012 -106.447336) (xy 11.713464 -106.447336) (xy 11.713464 -105.456736) (xy 11.71395 -105.429467)
			(xy 11.721712 -105.375483) (xy 11.737077 -105.323153) (xy 11.759734 -105.273543) (xy 11.78922 -105.227662)
			(xy 11.824935 -105.186445) (xy 11.866152 -105.15073) (xy 11.912033 -105.121244) (xy 11.961643 -105.098587)
			(xy 12.013973 -105.083222) (xy 12.067957 -105.07546) (xy 12.122495 -105.07546) (xy 12.176479 -105.083222)
			(xy 12.228809 -105.098587) (xy 12.278419 -105.121244) (xy 12.3243 -105.15073) (xy 12.365517 -105.186445)
			(xy 12.401232 -105.227662) (xy 12.430718 -105.273543) (xy 12.453375 -105.323153) (xy 12.46874 -105.375483)
			(xy 12.476502 -105.429467) (xy 12.476988 -105.456736) (xy 12.476988 -105.664) (xy 15.57274 -105.664)
			(xy 15.57274 -104.6734) (xy 15.573226 -104.646131) (xy 15.580988 -104.592147) (xy 15.596353 -104.539817)
			(xy 15.61901 -104.490207) (xy 15.648496 -104.444326) (xy 15.684211 -104.403109) (xy 15.725428 -104.367394)
			(xy 15.771309 -104.337908) (xy 15.820919 -104.315251) (xy 15.873249 -104.299886) (xy 15.927233 -104.292124)
			(xy 15.981771 -104.292124) (xy 16.035755 -104.299886) (xy 16.088085 -104.315251) (xy 16.137695 -104.337908)
			(xy 16.146631 -104.343651) (xy 326.803 -104.343651) (xy 326.803 -104.258929) (xy 326.811053 -104.174592)
			(xy 326.827087 -104.091402) (xy 326.850955 -104.010112) (xy 326.882443 -103.93146) (xy 326.921265 -103.856157)
			(xy 326.967068 -103.784885) (xy 327.019439 -103.718289) (xy 327.077904 -103.656974) (xy 327.141932 -103.601493)
			(xy 327.210944 -103.55235) (xy 327.284314 -103.50999) (xy 327.361379 -103.474795) (xy 327.441441 -103.447086)
			(xy 327.523774 -103.427112) (xy 327.607633 -103.415055) (xy 327.692258 -103.411024) (xy 327.776883 -103.415055)
			(xy 327.860742 -103.427112) (xy 327.943075 -103.447086) (xy 328.023137 -103.474795) (xy 328.100202 -103.50999)
			(xy 328.173572 -103.55235) (xy 328.242584 -103.601493) (xy 328.306612 -103.656974) (xy 328.365077 -103.718289)
			(xy 328.417448 -103.784885) (xy 328.463251 -103.856157) (xy 328.502073 -103.93146) (xy 328.533561 -104.010112)
			(xy 328.557429 -104.091402) (xy 328.573463 -104.174592) (xy 328.581516 -104.258929) (xy 328.58202 -104.30129)
			(xy 328.581516 -104.343651) (xy 328.573463 -104.427988) (xy 328.557429 -104.511178) (xy 328.533561 -104.592468)
			(xy 328.502073 -104.67112) (xy 328.463251 -104.746423) (xy 328.417448 -104.817695) (xy 328.365077 -104.884291)
			(xy 328.306612 -104.945606) (xy 328.242584 -105.001087) (xy 328.173572 -105.05023) (xy 328.100202 -105.09259)
			(xy 328.023137 -105.127785) (xy 327.943075 -105.155494) (xy 327.860742 -105.175468) (xy 327.776883 -105.187525)
			(xy 327.692258 -105.191557) (xy 327.607633 -105.187525) (xy 327.523774 -105.175468) (xy 327.441441 -105.155494)
			(xy 327.361379 -105.127785) (xy 327.284314 -105.09259) (xy 327.210944 -105.05023) (xy 327.141932 -105.001087)
			(xy 327.077904 -104.945606) (xy 327.019439 -104.884291) (xy 326.967068 -104.817695) (xy 326.921265 -104.746423)
			(xy 326.882443 -104.67112) (xy 326.850955 -104.592468) (xy 326.827087 -104.511178) (xy 326.811053 -104.427988)
			(xy 326.803 -104.343651) (xy 16.146631 -104.343651) (xy 16.183576 -104.367394) (xy 16.224793 -104.403109)
			(xy 16.260508 -104.444326) (xy 16.289994 -104.490207) (xy 16.312651 -104.539817) (xy 16.328016 -104.592147)
			(xy 16.335778 -104.646131) (xy 16.336264 -104.6734) (xy 16.336264 -105.664) (xy 16.335778 -105.691269)
			(xy 16.328016 -105.745253) (xy 16.312651 -105.797583) (xy 16.289994 -105.847193) (xy 16.260508 -105.893074)
			(xy 16.224793 -105.934291) (xy 16.183576 -105.970006) (xy 16.137695 -105.999492) (xy 16.088085 -106.022149)
			(xy 16.035755 -106.037514) (xy 15.981771 -106.045276) (xy 15.927233 -106.045276) (xy 15.873249 -106.037514)
			(xy 15.820919 -106.022149) (xy 15.771309 -105.999492) (xy 15.725428 -105.970006) (xy 15.684211 -105.934291)
			(xy 15.648496 -105.893074) (xy 15.61901 -105.847193) (xy 15.596353 -105.797583) (xy 15.580988 -105.745253)
			(xy 15.573226 -105.691269) (xy 15.57274 -105.664) (xy 12.476988 -105.664) (xy 12.476988 -106.447336)
			(xy 12.476502 -106.474605) (xy 12.46874 -106.528589) (xy 12.453375 -106.580919) (xy 12.430718 -106.630529)
			(xy 12.401232 -106.67641) (xy 12.365517 -106.717627) (xy 12.3243 -106.753342) (xy 12.278419 -106.782828)
			(xy 12.228809 -106.805485) (xy 12.176479 -106.82085) (xy 12.122495 -106.828612) (xy 12.067957 -106.828612)
			(xy 12.013973 -106.82085) (xy 11.961643 -106.805485) (xy 11.912033 -106.782828) (xy 11.866152 -106.753342)
			(xy 11.824935 -106.717627) (xy 11.78922 -106.67641) (xy 11.759734 -106.630529) (xy 11.737077 -106.580919)
			(xy 11.721712 -106.528589) (xy 11.71395 -106.474605) (xy 11.713464 -106.447336) (xy 2.509012 -106.447336)
			(xy 2.509012 -108.943971) (xy 11.292822 -108.943971) (xy 11.292822 -108.889469) (xy 11.300578 -108.835522)
			(xy 11.315933 -108.783228) (xy 11.338574 -108.733651) (xy 11.36804 -108.687801) (xy 11.403731 -108.646611)
			(xy 11.444921 -108.61092) (xy 11.490771 -108.581454) (xy 11.540348 -108.558813) (xy 11.592642 -108.543458)
			(xy 11.646589 -108.535702) (xy 11.67384 -108.535216) (xy 12.53744 -108.535216) (xy 12.564692 -108.535694)
			(xy 12.61864 -108.54345) (xy 12.670935 -108.558806) (xy 12.720513 -108.581447) (xy 12.766364 -108.610914)
			(xy 12.807554 -108.646606) (xy 12.843246 -108.687796) (xy 12.872713 -108.733647) (xy 12.895354 -108.783225)
			(xy 12.91071 -108.83552) (xy 12.918466 -108.889468) (xy 12.918466 -108.943972) (xy 12.91071 -108.99792)
			(xy 12.895354 -109.050215) (xy 12.872713 -109.099793) (xy 12.843246 -109.145644) (xy 12.807554 -109.186834)
			(xy 12.766364 -109.222526) (xy 12.720513 -109.251993) (xy 12.670935 -109.274634) (xy 12.61864 -109.28999)
			(xy 12.564692 -109.297746) (xy 12.53744 -109.298232) (xy 11.67384 -109.298232) (xy 11.646589 -109.297738)
			(xy 11.592642 -109.289982) (xy 11.540348 -109.274627) (xy 11.490771 -109.251986) (xy 11.444921 -109.22252)
			(xy 11.403731 -109.186829) (xy 11.36804 -109.145639) (xy 11.338574 -109.099789) (xy 11.315933 -109.050212)
			(xy 11.300578 -108.997918) (xy 11.292822 -108.943971) (xy 2.509012 -108.943971) (xy 2.509012 -109.451973)
			(xy 15.092889 -109.451973) (xy 15.092889 -109.397467) (xy 15.100646 -109.343517) (xy 15.116002 -109.291219)
			(xy 15.138645 -109.241639) (xy 15.168113 -109.195786) (xy 15.203807 -109.154594) (xy 15.244999 -109.118901)
			(xy 15.290853 -109.089433) (xy 15.340433 -109.066791) (xy 15.39273 -109.051435) (xy 15.446681 -109.043679)
			(xy 15.473934 -109.043216) (xy 16.464534 -109.043216) (xy 16.491785 -109.043694) (xy 16.545733 -109.051451)
			(xy 16.598028 -109.066807) (xy 16.647605 -109.089448) (xy 16.693456 -109.118915) (xy 16.734646 -109.154607)
			(xy 16.770337 -109.195798) (xy 16.799804 -109.241648) (xy 16.822445 -109.291226) (xy 16.8378 -109.343521)
			(xy 16.845556 -109.397469) (xy 16.845556 -109.451971) (xy 16.8378 -109.505919) (xy 16.822445 -109.558214)
			(xy 16.799804 -109.607792) (xy 16.770337 -109.653642) (xy 16.734646 -109.694833) (xy 16.693456 -109.730525)
			(xy 16.647605 -109.759992) (xy 16.598028 -109.782633) (xy 16.545733 -109.797989) (xy 16.491785 -109.805746)
			(xy 16.464534 -109.806232) (xy 15.473934 -109.806232) (xy 15.446681 -109.805761) (xy 15.39273 -109.798005)
			(xy 15.340433 -109.782649) (xy 15.290853 -109.760007) (xy 15.244999 -109.730539) (xy 15.203807 -109.694846)
			(xy 15.168113 -109.653654) (xy 15.138645 -109.607801) (xy 15.116002 -109.558221) (xy 15.100646 -109.505923)
			(xy 15.092889 -109.451973) (xy 2.509012 -109.451973) (xy 2.509012 -114.734161) (xy 11.255226 -114.734161)
			(xy 11.255226 -114.679659) (xy 11.262982 -114.625711) (xy 11.278337 -114.573416) (xy 11.300979 -114.523839)
			(xy 11.330445 -114.477988) (xy 11.366136 -114.436798) (xy 11.407326 -114.401106) (xy 11.453177 -114.371639)
			(xy 11.502754 -114.348998) (xy 11.555049 -114.333643) (xy 11.608997 -114.325886) (xy 11.636248 -114.3254)
			(xy 12.499848 -114.3254) (xy 12.527101 -114.325867) (xy 12.581052 -114.333624) (xy 12.633349 -114.34898)
			(xy 12.68293 -114.371622) (xy 12.728783 -114.40109) (xy 12.769975 -114.436783) (xy 12.805669 -114.477976)
			(xy 12.835137 -114.523829) (xy 12.85778 -114.573409) (xy 12.873136 -114.625706) (xy 12.880893 -114.679657)
			(xy 12.880893 -114.734163) (xy 12.873136 -114.788114) (xy 12.85778 -114.840411) (xy 12.835137 -114.889991)
			(xy 12.805669 -114.935844) (xy 12.769975 -114.977037) (xy 12.728783 -115.01273) (xy 12.68293 -115.042198)
			(xy 12.633349 -115.06484) (xy 12.581052 -115.080196) (xy 12.527101 -115.087953) (xy 12.499848 -115.088416)
			(xy 11.636248 -115.088416) (xy 11.608997 -115.087934) (xy 11.555049 -115.080177) (xy 11.502754 -115.064822)
			(xy 11.453177 -115.042181) (xy 11.407326 -115.012714) (xy 11.366136 -114.977022) (xy 11.330445 -114.935832)
			(xy 11.300979 -114.889981) (xy 11.278337 -114.840404) (xy 11.262982 -114.788109) (xy 11.255226 -114.734161)
			(xy 2.509012 -114.734161) (xy 2.509012 -133.480302) (xy 20.179284 -133.480302) (xy 20.179284 -132.489702)
			(xy 20.17977 -132.462451) (xy 20.187526 -132.408503) (xy 20.202881 -132.356208) (xy 20.225523 -132.306631)
			(xy 20.254989 -132.260781) (xy 20.29068 -132.21959) (xy 20.331871 -132.183899) (xy 20.377721 -132.154433)
			(xy 20.427298 -132.131791) (xy 20.479593 -132.116436) (xy 20.533541 -132.10868) (xy 20.588043 -132.10868)
			(xy 20.641991 -132.116436) (xy 20.694286 -132.131791) (xy 20.743863 -132.154433) (xy 20.789713 -132.183899)
			(xy 20.830904 -132.21959) (xy 20.866595 -132.260781) (xy 20.896061 -132.306631) (xy 20.918703 -132.356208)
			(xy 20.934058 -132.408503) (xy 20.941814 -132.462451) (xy 20.9423 -132.489702) (xy 20.9423 -133.480302)
			(xy 20.941814 -133.507553) (xy 20.934058 -133.561501) (xy 20.918703 -133.613796) (xy 20.896061 -133.663373)
			(xy 20.866595 -133.709223) (xy 20.830904 -133.750414) (xy 20.789713 -133.786105) (xy 20.743863 -133.815571)
			(xy 20.694286 -133.838213) (xy 20.641991 -133.853568) (xy 20.588043 -133.861324) (xy 20.533541 -133.861324)
			(xy 20.479593 -133.853568) (xy 20.427298 -133.838213) (xy 20.377721 -133.815571) (xy 20.331871 -133.786105)
			(xy 20.29068 -133.750414) (xy 20.254989 -133.709223) (xy 20.225523 -133.663373) (xy 20.202881 -133.613796)
			(xy 20.187526 -133.561501) (xy 20.17977 -133.507553) (xy 20.179284 -133.480302) (xy 2.509012 -133.480302)
			(xy 2.509012 -138.001502) (xy 20.019264 -138.001502) (xy 20.019264 -137.010902) (xy 20.01975 -136.983651)
			(xy 20.027506 -136.929703) (xy 20.042861 -136.877408) (xy 20.065503 -136.827831) (xy 20.094969 -136.781981)
			(xy 20.13066 -136.74079) (xy 20.171851 -136.705099) (xy 20.217701 -136.675633) (xy 20.267278 -136.652991)
			(xy 20.319573 -136.637636) (xy 20.373521 -136.62988) (xy 20.428023 -136.62988) (xy 20.481971 -136.637636)
			(xy 20.534266 -136.652991) (xy 20.583843 -136.675633) (xy 20.629693 -136.705099) (xy 20.670884 -136.74079)
			(xy 20.706575 -136.781981) (xy 20.736041 -136.827831) (xy 20.758683 -136.877408) (xy 20.774038 -136.929703)
			(xy 20.781794 -136.983651) (xy 20.78228 -137.010902) (xy 20.78228 -138.001502) (xy 20.781794 -138.028753)
			(xy 20.774038 -138.082701) (xy 20.758683 -138.134996) (xy 20.736041 -138.184573) (xy 20.706575 -138.230423)
			(xy 20.670884 -138.271614) (xy 20.629693 -138.307305) (xy 20.583843 -138.336771) (xy 20.534266 -138.359413)
			(xy 20.481971 -138.374768) (xy 20.428023 -138.382524) (xy 20.373521 -138.382524) (xy 20.319573 -138.374768)
			(xy 20.267278 -138.359413) (xy 20.217701 -138.336771) (xy 20.171851 -138.307305) (xy 20.13066 -138.271614)
			(xy 20.094969 -138.230423) (xy 20.065503 -138.184573) (xy 20.042861 -138.134996) (xy 20.027506 -138.082701)
			(xy 20.01975 -138.028753) (xy 20.019264 -138.001502) (xy 2.509012 -138.001502) (xy 2.509012 -145.104166)
			(xy 163.29995 -145.104166) (xy 163.29995 -145.049634) (xy 163.30771 -144.995658) (xy 163.323072 -144.943336)
			(xy 163.345724 -144.893732) (xy 163.375204 -144.847856) (xy 163.410912 -144.806643) (xy 163.452121 -144.77093)
			(xy 163.497993 -144.741445) (xy 163.547595 -144.718788) (xy 163.599915 -144.70342) (xy 163.653891 -144.695653)
			(xy 163.681156 -144.695164) (xy 164.671756 -144.695164) (xy 164.699031 -144.695573) (xy 164.753026 -144.70333)
			(xy 164.805368 -144.718694) (xy 164.85499 -144.74135) (xy 164.900882 -144.770839) (xy 164.94211 -144.806559)
			(xy 164.977835 -144.847783) (xy 165.007329 -144.893672) (xy 165.029991 -144.943291) (xy 165.045361 -144.995631)
			(xy 165.053124 -145.049625) (xy 165.053124 -145.104175) (xy 165.045361 -145.158169) (xy 165.029991 -145.210509)
			(xy 165.007329 -145.260128) (xy 164.977835 -145.306017) (xy 164.94211 -145.347241) (xy 164.900882 -145.382961)
			(xy 164.85499 -145.41245) (xy 164.805368 -145.435106) (xy 164.753026 -145.45047) (xy 164.699031 -145.458227)
			(xy 164.671756 -145.458688) (xy 163.681156 -145.458688) (xy 163.653891 -145.458147) (xy 163.599915 -145.45038)
			(xy 163.547595 -145.435012) (xy 163.497993 -145.412355) (xy 163.452121 -145.38287) (xy 163.410912 -145.347157)
			(xy 163.375204 -145.305944) (xy 163.345724 -145.260068) (xy 163.323072 -145.210464) (xy 163.30771 -145.158142)
			(xy 163.29995 -145.104166) (xy 2.509012 -145.104166) (xy 2.509012 -153.765504) (xy 24.441921 -153.765504)
			(xy 24.445917 -153.555618) (xy 24.457902 -153.346036) (xy 24.477856 -153.137062) (xy 24.505752 -152.929)
			(xy 24.541549 -152.72215) (xy 24.585194 -152.516813) (xy 24.636626 -152.313287) (xy 24.695768 -152.111866)
			(xy 24.762536 -151.912843) (xy 24.836832 -151.716506) (xy 24.91855 -151.52314) (xy 25.007569 -151.333025)
			(xy 25.103762 -151.146437) (xy 25.206989 -150.963646) (xy 25.3171 -150.784918) (xy 25.433935 -150.610511)
			(xy 25.557325 -150.440679) (xy 25.687092 -150.275667) (xy 25.823046 -150.115716) (xy 25.964992 -149.961056)
			(xy 26.112722 -149.811912) (xy 26.266024 -149.668501) (xy 26.424674 -149.53103) (xy 26.588443 -149.399698)
			(xy 26.757093 -149.274697) (xy 26.930379 -149.156206) (xy 27.108051 -149.044399) (xy 27.289851 -148.939437)
			(xy 27.475515 -148.841472) (xy 27.664773 -148.750647) (xy 27.857353 -148.667093) (xy 28.052974 -148.59093)
			(xy 28.251352 -148.522271) (xy 28.452201 -148.461214) (xy 28.655228 -148.407847) (xy 28.860141 -148.362249)
			(xy 29.06664 -148.324484) (xy 29.274427 -148.294609) (xy 29.483202 -148.272666) (xy 29.69266 -148.258687)
			(xy 29.902499 -148.252692) (xy 30.112413 -148.254691) (xy 30.3221 -148.264679) (xy 30.531254 -148.282644)
			(xy 30.739572 -148.308558) (xy 30.946753 -148.342383) (xy 31.152497 -148.384072) (xy 31.356503 -148.433564)
			(xy 31.558478 -148.490786) (xy 31.758128 -148.555656) (xy 31.955163 -148.62808) (xy 32.149299 -148.707953)
			(xy 32.340252 -148.795159) (xy 32.527748 -148.889571) (xy 32.711513 -148.991053) (xy 32.891281 -149.099457)
			(xy 33.066792 -149.214627) (xy 33.237791 -149.336395) (xy 33.404031 -149.464584) (xy 33.56527 -149.59901)
			(xy 33.721274 -149.739477) (xy 33.871817 -149.885781) (xy 34.016681 -150.03771) (xy 34.155656 -150.195044)
			(xy 34.288541 -150.357555) (xy 34.415142 -150.525008) (xy 34.535277 -150.697158) (xy 34.648771 -150.873758)
			(xy 34.688915 -150.941786) (xy 108.742233 -150.941786) (xy 108.746238 -150.836037) (xy 108.758228 -150.730894)
			(xy 108.778137 -150.626959) (xy 108.805848 -150.524827) (xy 108.841205 -150.425083) (xy 108.884003 -150.328299)
			(xy 108.933999 -150.235029) (xy 108.990906 -150.145808) (xy 109.054397 -150.061145) (xy 109.124109 -149.981527)
			(xy 109.199643 -149.907409) (xy 109.280566 -149.839216) (xy 109.366415 -149.777338) (xy 109.456698 -149.722131)
			(xy 109.550897 -149.673909) (xy 109.648474 -149.632949) (xy 109.748869 -149.599487) (xy 109.851507 -149.573713)
			(xy 109.9558 -149.555775) (xy 110.061151 -149.545776) (xy 110.166957 -149.543773) (xy 110.272611 -149.549778)
			(xy 110.377508 -149.563757) (xy 110.481048 -149.585628) (xy 110.582637 -149.615268) (xy 110.681694 -149.652506)
			(xy 110.777651 -149.697128) (xy 110.869958 -149.74888) (xy 110.958087 -149.807465) (xy 111.041533 -149.872547)
			(xy 111.119817 -149.943753) (xy 111.187365 -150.015249) (xy 160.856694 -150.015249) (xy 160.856694 -149.960751)
			(xy 160.86445 -149.906808) (xy 160.879803 -149.854517) (xy 160.902441 -149.804944) (xy 160.931904 -149.759096)
			(xy 160.967592 -149.717909) (xy 161.008777 -149.682219) (xy 161.054623 -149.652753) (xy 161.104195 -149.630111)
			(xy 161.156484 -149.614755) (xy 161.210427 -149.606996) (xy 161.237676 -149.606508) (xy 162.228276 -149.606508)
			(xy 162.255531 -149.606937) (xy 162.309487 -149.614692) (xy 162.36179 -149.630046) (xy 162.411375 -149.652688)
			(xy 162.457233 -149.682157) (xy 162.498431 -149.717852) (xy 162.534128 -149.759047) (xy 162.5636 -149.804904)
			(xy 162.586245 -149.854488) (xy 162.601603 -149.90679) (xy 162.609361 -149.960745) (xy 162.609361 -149.967557)
			(xy 163.793819 -149.967557) (xy 163.793819 -149.913043) (xy 163.801578 -149.859084) (xy 163.816937 -149.806779)
			(xy 163.839584 -149.757192) (xy 163.869057 -149.711333) (xy 163.904758 -149.670135) (xy 163.945958 -149.634438)
			(xy 163.99182 -149.604968) (xy 164.041409 -149.582325) (xy 164.093716 -149.566971) (xy 164.147675 -149.559217)
			(xy 164.174932 -149.558756) (xy 165.165532 -149.558756) (xy 165.192779 -149.559316) (xy 165.246718 -149.567076)
			(xy 165.299004 -149.582432) (xy 165.348573 -149.605073) (xy 165.394415 -149.634537) (xy 165.435597 -149.670226)
			(xy 165.471282 -149.711411) (xy 165.500742 -149.757255) (xy 165.523379 -149.806826) (xy 165.538731 -149.859113)
			(xy 165.546486 -149.913053) (xy 165.546486 -149.967547) (xy 165.538731 -150.021487) (xy 165.523379 -150.073774)
			(xy 165.500742 -150.123345) (xy 165.471282 -150.169189) (xy 165.435597 -150.210374) (xy 165.394415 -150.246063)
			(xy 165.348573 -150.275527) (xy 165.299004 -150.298168) (xy 165.246718 -150.313524) (xy 165.192779 -150.321284)
			(xy 165.165532 -150.321772) (xy 164.174932 -150.321772) (xy 164.147675 -150.321383) (xy 164.093716 -150.313629)
			(xy 164.041409 -150.298275) (xy 163.99182 -150.275632) (xy 163.945958 -150.246162) (xy 163.904758 -150.210465)
			(xy 163.869057 -150.169267) (xy 163.839584 -150.123408) (xy 163.816937 -150.073821) (xy 163.801578 -150.021516)
			(xy 163.793819 -149.967557) (xy 162.609361 -149.967557) (xy 162.609361 -150.015255) (xy 162.601603 -150.06921)
			(xy 162.586245 -150.121512) (xy 162.5636 -150.171096) (xy 162.534128 -150.216953) (xy 162.498431 -150.258148)
			(xy 162.457233 -150.293843) (xy 162.411375 -150.323312) (xy 162.36179 -150.345954) (xy 162.309487 -150.361308)
			(xy 162.255531 -150.369063) (xy 162.228276 -150.369524) (xy 161.237676 -150.369524) (xy 161.210427 -150.369004)
			(xy 161.156484 -150.361245) (xy 161.104195 -150.345889) (xy 161.054623 -150.323247) (xy 161.008777 -150.293781)
			(xy 160.967592 -150.258091) (xy 160.931904 -150.216904) (xy 160.902441 -150.171056) (xy 160.879803 -150.121483)
			(xy 160.86445 -150.069192) (xy 160.856694 -150.015249) (xy 111.187365 -150.015249) (xy 111.192492 -150.020676)
			(xy 111.259142 -150.102876) (xy 111.319384 -150.18988) (xy 111.372873 -150.281191) (xy 111.419304 -150.376286)
			(xy 111.458409 -150.47462) (xy 111.489966 -150.575631) (xy 111.513793 -150.678738) (xy 111.529754 -150.783352)
			(xy 111.537758 -150.888874) (xy 111.538258 -150.941786) (xy 111.537758 -150.994698) (xy 111.529754 -151.10022)
			(xy 111.513793 -151.204834) (xy 111.489966 -151.307941) (xy 111.458409 -151.408952) (xy 111.419304 -151.507286)
			(xy 111.372873 -151.602381) (xy 111.319384 -151.693692) (xy 111.259142 -151.780696) (xy 111.192492 -151.862896)
			(xy 111.119817 -151.939819) (xy 111.041533 -152.011025) (xy 110.958087 -152.076107) (xy 110.869958 -152.134692)
			(xy 110.777651 -152.186444) (xy 110.681694 -152.231066) (xy 110.582637 -152.268304) (xy 110.481048 -152.297944)
			(xy 110.377508 -152.319815) (xy 110.272611 -152.333794) (xy 110.166957 -152.339799) (xy 110.061151 -152.337796)
			(xy 109.9558 -152.327797) (xy 109.851507 -152.309859) (xy 109.748869 -152.284085) (xy 109.648474 -152.250623)
			(xy 109.550897 -152.209663) (xy 109.456698 -152.161441) (xy 109.366415 -152.106234) (xy 109.280566 -152.044356)
			(xy 109.199643 -151.976163) (xy 109.124109 -151.902045) (xy 109.054397 -151.822427) (xy 108.990906 -151.737764)
			(xy 108.933999 -151.648543) (xy 108.884003 -151.555273) (xy 108.841205 -151.458489) (xy 108.805848 -151.358745)
			(xy 108.778137 -151.256613) (xy 108.758228 -151.152678) (xy 108.746238 -151.047535) (xy 108.742233 -150.941786)
			(xy 34.688915 -150.941786) (xy 34.755459 -151.05455) (xy 34.855186 -151.239273) (xy 34.947809 -151.427659)
			(xy 35.033193 -151.619434) (xy 35.111214 -151.814321) (xy 35.181759 -152.012037) (xy 35.244726 -152.212295)
			(xy 35.300023 -152.414805) (xy 35.34757 -152.619274) (xy 35.354948 -152.657556) (xy 115.368832 -152.657556)
			(xy 115.369254 -152.619267) (xy 115.375857 -152.542973) (xy 115.389002 -152.46753) (xy 115.40859 -152.393499)
			(xy 115.421156 -152.357328) (xy 115.423829 -152.348897) (xy 115.423815 -152.331221) (xy 115.421156 -152.322784)
			(xy 115.408624 -152.286603) (xy 115.389048 -152.212571) (xy 115.375898 -152.137132) (xy 115.36927 -152.060844)
			(xy 115.368832 -152.022556) (xy 115.369211 -151.981443) (xy 115.376803 -151.89957) (xy 115.391918 -151.818746)
			(xy 115.414428 -151.739662) (xy 115.44414 -151.662993) (xy 115.480801 -151.589393) (xy 115.524097 -151.51949)
			(xy 115.573659 -151.453881) (xy 115.629065 -151.393126) (xy 115.689841 -151.337743) (xy 115.755469 -151.288206)
			(xy 115.825388 -151.244936) (xy 115.899002 -151.208303) (xy 115.975683 -151.178621) (xy 116.054775 -151.156141)
			(xy 116.135605 -151.141056) (xy 116.217481 -151.133495) (xy 116.258594 -151.133048) (xy 116.29691 -151.133415)
			(xy 116.373264 -151.139947) (xy 116.448771 -151.153032) (xy 116.52287 -151.172572) (xy 116.559076 -151.185118)
			(xy 116.567392 -151.187704) (xy 116.584796 -151.187704) (xy 116.593112 -151.185118) (xy 116.629327 -151.172602)
			(xy 116.703427 -151.153078) (xy 116.778931 -151.139993) (xy 116.855279 -151.133443) (xy 116.893594 -151.133048)
			(xy 116.933808 -151.133478) (xy 117.01391 -151.140701) (xy 117.093031 -151.155132) (xy 117.170525 -151.176654)
			(xy 117.2083 -151.190452) (xy 117.217087 -151.193359) (xy 117.235581 -151.193359) (xy 117.244368 -151.190452)
			(xy 117.282145 -151.176662) (xy 117.359642 -151.155155) (xy 117.438762 -151.140723) (xy 117.518861 -151.133486)
			(xy 117.559074 -151.133048) (xy 117.59739 -151.133421) (xy 117.673744 -151.139951) (xy 117.74925 -151.153034)
			(xy 117.82335 -151.172573) (xy 117.859556 -151.185118) (xy 117.867872 -151.187704) (xy 117.885276 -151.187704)
			(xy 117.893592 -151.185118) (xy 117.929809 -151.172608) (xy 118.003908 -151.153082) (xy 118.079411 -151.139995)
			(xy 118.155759 -151.133444) (xy 118.194074 -151.133048) (xy 118.23239 -151.133421) (xy 118.308744 -151.139951)
			(xy 118.38425 -151.153034) (xy 118.45835 -151.172573) (xy 118.494556 -151.185118) (xy 118.502872 -151.187704)
			(xy 118.520276 -151.187704) (xy 118.528592 -151.185118) (xy 118.564809 -151.172608) (xy 118.638908 -151.153082)
			(xy 118.714411 -151.139995) (xy 118.790759 -151.133444) (xy 118.829074 -151.133048) (xy 118.86739 -151.133421)
			(xy 118.943744 -151.139951) (xy 119.01925 -151.153034) (xy 119.09335 -151.172573) (xy 119.129556 -151.185118)
			(xy 119.137872 -151.187704) (xy 119.155276 -151.187704) (xy 119.163592 -151.185118) (xy 119.199718 -151.172636)
			(xy 119.273629 -151.153143) (xy 119.348939 -151.140056) (xy 119.425093 -151.133472) (xy 119.463312 -151.133048)
			(xy 119.464074 -151.133048) (xy 119.505181 -151.133537) (xy 119.587043 -151.141119) (xy 119.667858 -151.156221)
			(xy 119.746934 -151.178714) (xy 119.823598 -151.208407) (xy 119.897196 -151.245045) (xy 119.9671 -151.288316)
			(xy 120.032714 -151.337852) (xy 120.093479 -151.39323) (xy 120.148875 -151.453978) (xy 120.198431 -151.519577)
			(xy 120.241724 -151.589468) (xy 120.278384 -151.663055) (xy 120.3081 -151.73971) (xy 120.330617 -151.818779)
			(xy 120.345743 -151.899589) (xy 120.35335 -151.98145) (xy 120.353836 -152.022556) (xy 120.353419 -152.060846)
			(xy 120.346814 -152.137139) (xy 120.333668 -152.212582) (xy 120.314078 -152.286613) (xy 120.301512 -152.322784)
			(xy 120.298884 -152.331226) (xy 120.29887 -152.348891) (xy 120.301512 -152.357328) (xy 120.314046 -152.393509)
			(xy 120.333622 -152.467541) (xy 120.346772 -152.542979) (xy 120.353399 -152.619268) (xy 120.353836 -152.657556)
			(xy 120.353306 -152.698665) (xy 120.345722 -152.780533) (xy 120.330616 -152.861351) (xy 120.308115 -152.940431)
			(xy 120.278413 -153.017096) (xy 120.241762 -153.090693) (xy 120.198476 -153.160594) (xy 120.148923 -153.226202)
			(xy 120.093528 -153.286957) (xy 120.032762 -153.34234) (xy 119.967144 -153.391879) (xy 119.897234 -153.435151)
			(xy 119.823629 -153.471786) (xy 119.746958 -153.501473) (xy 119.667874 -153.523957) (xy 119.587052 -153.539047)
			(xy 119.505183 -153.546614) (xy 119.464074 -153.547064) (xy 119.425757 -153.546706) (xy 119.349404 -153.540171)
			(xy 119.273897 -153.527084) (xy 119.199798 -153.507541) (xy 119.163592 -153.494994) (xy 119.155276 -153.492408)
			(xy 119.137872 -153.492408) (xy 119.129556 -153.494994) (xy 119.093344 -153.507519) (xy 119.019243 -153.527041)
			(xy 118.943738 -153.540123) (xy 118.867389 -153.546671) (xy 118.829074 -153.547064) (xy 118.790757 -153.546706)
			(xy 118.714404 -153.540171) (xy 118.638897 -153.527084) (xy 118.564798 -153.507541) (xy 118.528592 -153.494994)
			(xy 118.520276 -153.492408) (xy 118.502872 -153.492408) (xy 118.494556 -153.494994) (xy 118.458344 -153.507519)
			(xy 118.384243 -153.527041) (xy 118.308738 -153.540123) (xy 118.232389 -153.546671) (xy 118.194074 -153.547064)
			(xy 118.155757 -153.546706) (xy 118.079404 -153.540171) (xy 118.003897 -153.527084) (xy 117.929798 -153.507541)
			(xy 117.893592 -153.494994) (xy 117.885276 -153.492408) (xy 117.867872 -153.492408) (xy 117.859556 -153.494994)
			(xy 117.823344 -153.507519) (xy 117.749243 -153.527041) (xy 117.673738 -153.540123) (xy 117.597389 -153.546671)
			(xy 117.559074 -153.547064) (xy 117.51886 -153.546643) (xy 117.438758 -153.539418) (xy 117.359636 -153.524984)
			(xy 117.282143 -153.50346) (xy 117.244368 -153.48966) (xy 117.235581 -153.486753) (xy 117.217087 -153.486753)
			(xy 117.2083 -153.48966) (xy 117.170526 -153.50346) (xy 117.093029 -153.524965) (xy 117.013907 -153.539393)
			(xy 116.933807 -153.546627) (xy 116.893594 -153.547064) (xy 116.855277 -153.5467) (xy 116.778924 -153.540167)
			(xy 116.703417 -153.527082) (xy 116.629318 -153.50754) (xy 116.593112 -153.494994) (xy 116.584796 -153.492408)
			(xy 116.567392 -153.492408) (xy 116.559076 -153.494994) (xy 116.522953 -153.507485) (xy 116.449041 -153.526976)
			(xy 116.37373 -153.54006) (xy 116.297575 -153.546641) (xy 116.259356 -153.547064) (xy 116.258594 -153.547064)
			(xy 116.217487 -153.546593) (xy 116.135624 -153.539008) (xy 116.05481 -153.523904) (xy 115.975734 -153.501409)
			(xy 115.89907 -153.471714) (xy 115.825473 -153.435075) (xy 115.755569 -153.391802) (xy 115.689955 -153.342264)
			(xy 115.629192 -153.286885) (xy 115.573796 -153.226137) (xy 115.52424 -153.160537) (xy 115.480947 -153.090646)
			(xy 115.444287 -153.017059) (xy 115.414571 -152.940403) (xy 115.392053 -152.861333) (xy 115.376926 -152.780524)
			(xy 115.369318 -152.698663) (xy 115.368832 -152.657556) (xy 35.354948 -152.657556) (xy 35.387298 -152.825405)
			(xy 35.41915 -153.032898) (xy 35.44308 -153.241454) (xy 35.459052 -153.45077) (xy 35.467044 -153.660542)
			(xy 35.467544 -153.765504) (xy 35.467044 -153.870466) (xy 35.459052 -154.080238) (xy 35.44308 -154.289554)
			(xy 35.422918 -154.465274) (xy 127.823468 -154.465274) (xy 127.824038 -154.420505) (xy 127.833047 -154.33142)
			(xy 127.850949 -154.243689) (xy 127.877566 -154.158197) (xy 127.894588 -154.116786) (xy 127.89817 -154.1072)
			(xy 127.89816 -154.086753) (xy 127.894588 -154.077162) (xy 127.87754 -154.03576) (xy 127.850909 -153.95027)
			(xy 127.833008 -153.862535) (xy 127.824018 -153.773445) (xy 127.823468 -153.728674) (xy 127.824038 -153.683905)
			(xy 127.833047 -153.59482) (xy 127.850949 -153.507089) (xy 127.877566 -153.421597) (xy 127.894588 -153.380186)
			(xy 127.89817 -153.3706) (xy 127.89816 -153.350153) (xy 127.894588 -153.340562) (xy 127.87754 -153.29916)
			(xy 127.850909 -153.21367) (xy 127.833008 -153.125935) (xy 127.824018 -153.036845) (xy 127.823468 -152.992074)
			(xy 127.823874 -152.950958) (xy 127.831464 -152.869076) (xy 127.846576 -152.788245) (xy 127.869082 -152.709152)
			(xy 127.898791 -152.632473) (xy 127.935447 -152.558863) (xy 127.978739 -152.488949) (xy 128.028297 -152.423328)
			(xy 128.083699 -152.362559) (xy 128.144471 -152.307161) (xy 128.210095 -152.257607) (xy 128.280012 -152.21432)
			(xy 128.353625 -152.177668) (xy 128.430305 -152.147965) (xy 128.509399 -152.125463) (xy 128.590232 -152.110356)
			(xy 128.672114 -152.102771) (xy 128.71323 -152.102312) (xy 128.754841 -152.102773) (xy 128.837698 -152.110553)
			(xy 128.919467 -152.126031) (xy 128.999435 -152.149074) (xy 129.076903 -152.179479) (xy 129.151195 -152.216982)
			(xy 129.186686 -152.23871) (xy 129.195829 -152.243863) (xy 129.216542 -152.24708) (xy 129.236814 -152.241752)
			(xy 129.24536 -152.235662) (xy 129.278989 -152.209671) (xy 129.350383 -152.163546) (xy 129.425854 -152.124445)
			(xy 129.504712 -152.092724) (xy 129.586237 -152.068675) (xy 129.669685 -152.052515) (xy 129.754295 -152.044393)
			(xy 129.796794 -152.043892) (xy 129.837907 -152.044419) (xy 129.919782 -152.052005) (xy 130.000607 -152.067113)
			(xy 130.079694 -152.089613) (xy 130.156368 -152.119315) (xy 130.229974 -152.155965) (xy 130.299884 -152.19925)
			(xy 130.365503 -152.2488) (xy 130.42627 -152.304193) (xy 130.481667 -152.364957) (xy 130.531221 -152.430573)
			(xy 130.57451 -152.500481) (xy 130.611164 -152.574085) (xy 130.64087 -152.650756) (xy 130.663376 -152.729842)
			(xy 130.678488 -152.810667) (xy 130.686079 -152.892541) (xy 130.686556 -152.933654) (xy 130.685993 -152.978424)
			(xy 130.676983 -153.067509) (xy 130.659077 -153.15524) (xy 130.632459 -153.240731) (xy 130.615436 -153.282142)
			(xy 130.611899 -153.291741) (xy 130.611882 -153.312176) (xy 130.615436 -153.321766) (xy 130.63244 -153.363117)
			(xy 130.659051 -153.448479) (xy 130.676958 -153.536082) (xy 130.68598 -153.625039) (xy 130.686556 -153.669746)
			(xy 130.686556 -153.670762) (xy 130.686302 -153.682192) (xy 130.712781 -153.688138) (xy 130.765016 -153.702881)
			(xy 130.790696 -153.711656) (xy 130.798893 -153.71417) (xy 130.816027 -153.71417) (xy 130.824224 -153.711656)
			(xy 130.85944 -153.699695) (xy 130.931444 -153.681041) (xy 131.004765 -153.668532) (xy 131.07888 -153.662259)
			(xy 131.11607 -153.661872) (xy 131.153259 -153.662271) (xy 131.227372 -153.668558) (xy 131.300692 -153.681065)
			(xy 131.372698 -153.699703) (xy 131.407916 -153.711656) (xy 131.416113 -153.71417) (xy 131.433247 -153.71417)
			(xy 131.441444 -153.711656) (xy 131.476659 -153.699689) (xy 131.548662 -153.681037) (xy 131.621984 -153.66853)
			(xy 131.6961 -153.662258) (xy 131.73329 -153.661872) (xy 131.77523 -153.662267) (xy 131.858732 -153.670239)
			(xy 131.941097 -153.686113) (xy 132.02158 -153.709744) (xy 132.099453 -153.740919) (xy 132.165372 -153.774902)
			(xy 188.441847 -153.774902) (xy 188.445843 -153.565016) (xy 188.457828 -153.355434) (xy 188.477782 -153.14646)
			(xy 188.505678 -152.938398) (xy 188.541475 -152.731548) (xy 188.58512 -152.526211) (xy 188.636552 -152.322685)
			(xy 188.695694 -152.121264) (xy 188.762462 -151.922241) (xy 188.836758 -151.725904) (xy 188.918476 -151.532538)
			(xy 189.007495 -151.342423) (xy 189.103688 -151.155835) (xy 189.206915 -150.973044) (xy 189.317026 -150.794316)
			(xy 189.433861 -150.619909) (xy 189.557251 -150.450077) (xy 189.687018 -150.285065) (xy 189.822972 -150.125114)
			(xy 189.964918 -149.970454) (xy 190.112648 -149.82131) (xy 190.26595 -149.677899) (xy 190.4246 -149.540428)
			(xy 190.588369 -149.409096) (xy 190.757019 -149.284095) (xy 190.930305 -149.165604) (xy 191.107977 -149.053797)
			(xy 191.289777 -148.948835) (xy 191.475441 -148.85087) (xy 191.664699 -148.760045) (xy 191.857279 -148.676491)
			(xy 192.0529 -148.600328) (xy 192.251278 -148.531669) (xy 192.452127 -148.470612) (xy 192.655154 -148.417245)
			(xy 192.860067 -148.371647) (xy 193.066566 -148.333882) (xy 193.274353 -148.304007) (xy 193.483128 -148.282064)
			(xy 193.692586 -148.268085) (xy 193.902425 -148.26209) (xy 194.112339 -148.264089) (xy 194.322026 -148.274077)
			(xy 194.53118 -148.292042) (xy 194.739498 -148.317956) (xy 194.946679 -148.351781) (xy 195.152423 -148.39347)
			(xy 195.356429 -148.442962) (xy 195.558404 -148.500184) (xy 195.758054 -148.565054) (xy 195.955089 -148.637478)
			(xy 196.149225 -148.717351) (xy 196.340178 -148.804557) (xy 196.527674 -148.898969) (xy 196.711439 -149.000451)
			(xy 196.891207 -149.108855) (xy 197.066718 -149.224025) (xy 197.237717 -149.345793) (xy 197.403957 -149.473982)
			(xy 197.565196 -149.608408) (xy 197.7212 -149.748875) (xy 197.871743 -149.895179) (xy 198.016607 -150.047108)
			(xy 198.155582 -150.204442) (xy 198.288467 -150.366953) (xy 198.415068 -150.534406) (xy 198.535203 -150.706556)
			(xy 198.648697 -150.883156) (xy 198.755385 -151.063948) (xy 198.855112 -151.248671) (xy 198.947735 -151.437057)
			(xy 199.033119 -151.628832) (xy 199.11114 -151.823719) (xy 199.181685 -152.021435) (xy 199.244652 -152.221693)
			(xy 199.299949 -152.424203) (xy 199.347496 -152.628672) (xy 199.387224 -152.834803) (xy 199.419076 -153.042296)
			(xy 199.443006 -153.250852) (xy 199.458978 -153.460168) (xy 199.46697 -153.66994) (xy 199.467428 -153.766012)
			(xy 272.382243 -153.766012) (xy 272.386239 -153.556126) (xy 272.398224 -153.346544) (xy 272.418178 -153.13757)
			(xy 272.446074 -152.929508) (xy 272.481871 -152.722658) (xy 272.525516 -152.517321) (xy 272.576948 -152.313795)
			(xy 272.63609 -152.112374) (xy 272.702858 -151.913351) (xy 272.777154 -151.717014) (xy 272.858872 -151.523648)
			(xy 272.947891 -151.333533) (xy 273.044084 -151.146945) (xy 273.147311 -150.964154) (xy 273.257422 -150.785426)
			(xy 273.374257 -150.611019) (xy 273.497647 -150.441187) (xy 273.627414 -150.276175) (xy 273.763368 -150.116224)
			(xy 273.905314 -149.961564) (xy 274.053044 -149.81242) (xy 274.206346 -149.669009) (xy 274.364996 -149.531538)
			(xy 274.528765 -149.400206) (xy 274.697415 -149.275205) (xy 274.870701 -149.156714) (xy 275.048373 -149.044907)
			(xy 275.230173 -148.939945) (xy 275.415837 -148.84198) (xy 275.605095 -148.751155) (xy 275.797675 -148.667601)
			(xy 275.993296 -148.591438) (xy 276.191674 -148.522779) (xy 276.392523 -148.461722) (xy 276.59555 -148.408355)
			(xy 276.800463 -148.362757) (xy 277.006962 -148.324992) (xy 277.214749 -148.295117) (xy 277.423524 -148.273174)
			(xy 277.632982 -148.259195) (xy 277.842821 -148.2532) (xy 278.052735 -148.255199) (xy 278.262422 -148.265187)
			(xy 278.471576 -148.283152) (xy 278.679894 -148.309066) (xy 278.887075 -148.342891) (xy 279.092819 -148.38458)
			(xy 279.296825 -148.434072) (xy 279.4988 -148.491294) (xy 279.69845 -148.556164) (xy 279.895485 -148.628588)
			(xy 280.089621 -148.708461) (xy 280.280574 -148.795667) (xy 280.46807 -148.890079) (xy 280.651835 -148.991561)
			(xy 280.831603 -149.099965) (xy 281.007114 -149.215135) (xy 281.178113 -149.336903) (xy 281.344353 -149.465092)
			(xy 281.505592 -149.599518) (xy 281.661596 -149.739985) (xy 281.812139 -149.886289) (xy 281.957003 -150.038218)
			(xy 282.095978 -150.195552) (xy 282.228863 -150.358063) (xy 282.355464 -150.525516) (xy 282.475599 -150.697666)
			(xy 282.589093 -150.874266) (xy 282.695781 -151.055058) (xy 282.795508 -151.239781) (xy 282.888131 -151.428167)
			(xy 282.973515 -151.619942) (xy 283.051536 -151.814829) (xy 283.122081 -152.012545) (xy 283.185048 -152.212803)
			(xy 283.240345 -152.415313) (xy 283.287892 -152.619782) (xy 283.305746 -152.71242) (xy 358.186997 -152.71242)
			(xy 358.191002 -152.606671) (xy 358.202992 -152.501528) (xy 358.222901 -152.397593) (xy 358.250612 -152.295461)
			(xy 358.285969 -152.195717) (xy 358.328767 -152.098933) (xy 358.378763 -152.005663) (xy 358.43567 -151.916442)
			(xy 358.499161 -151.831779) (xy 358.568873 -151.752161) (xy 358.644407 -151.678043) (xy 358.72533 -151.60985)
			(xy 358.811179 -151.547972) (xy 358.901462 -151.492765) (xy 358.995661 -151.444543) (xy 359.093238 -151.403583)
			(xy 359.193633 -151.370121) (xy 359.296271 -151.344347) (xy 359.400564 -151.326409) (xy 359.505915 -151.31641)
			(xy 359.611721 -151.314407) (xy 359.717375 -151.320412) (xy 359.822272 -151.334391) (xy 359.925812 -151.356262)
			(xy 360.027401 -151.385902) (xy 360.126458 -151.42314) (xy 360.222415 -151.467762) (xy 360.314722 -151.519514)
			(xy 360.402851 -151.578099) (xy 360.486297 -151.643181) (xy 360.564581 -151.714387) (xy 360.637256 -151.79131)
			(xy 360.703906 -151.87351) (xy 360.764148 -151.960514) (xy 360.817637 -152.051825) (xy 360.864068 -152.14692)
			(xy 360.903173 -152.245254) (xy 360.93473 -152.346265) (xy 360.958557 -152.449372) (xy 360.974518 -152.553986)
			(xy 360.982522 -152.659508) (xy 360.983022 -152.71242) (xy 360.982522 -152.765332) (xy 360.974518 -152.870854)
			(xy 360.958557 -152.975468) (xy 360.93473 -153.078575) (xy 360.903173 -153.179586) (xy 360.864068 -153.27792)
			(xy 360.817637 -153.373015) (xy 360.764148 -153.464326) (xy 360.703906 -153.55133) (xy 360.637256 -153.63353)
			(xy 360.564581 -153.710453) (xy 360.486297 -153.781659) (xy 360.402851 -153.846741) (xy 360.314722 -153.905326)
			(xy 360.222415 -153.957078) (xy 360.126458 -154.0017) (xy 360.027401 -154.038938) (xy 359.925812 -154.068578)
			(xy 359.822272 -154.090449) (xy 359.717375 -154.104428) (xy 359.611721 -154.110433) (xy 359.505915 -154.10843)
			(xy 359.400564 -154.098431) (xy 359.296271 -154.080493) (xy 359.193633 -154.054719) (xy 359.093238 -154.021257)
			(xy 358.995661 -153.980297) (xy 358.901462 -153.932075) (xy 358.811179 -153.876868) (xy 358.72533 -153.81499)
			(xy 358.644407 -153.746797) (xy 358.568873 -153.672679) (xy 358.499161 -153.593061) (xy 358.43567 -153.508398)
			(xy 358.378763 -153.419177) (xy 358.328767 -153.325907) (xy 358.285969 -153.229123) (xy 358.250612 -153.129379)
			(xy 358.222901 -153.027247) (xy 358.202992 -152.923312) (xy 358.191002 -152.818169) (xy 358.186997 -152.71242)
			(xy 283.305746 -152.71242) (xy 283.32762 -152.825913) (xy 283.359472 -153.033406) (xy 283.383402 -153.241962)
			(xy 283.399374 -153.451278) (xy 283.407366 -153.66105) (xy 283.407866 -153.766012) (xy 283.407366 -153.870974)
			(xy 283.399374 -154.080746) (xy 283.383402 -154.290062) (xy 283.359472 -154.498618) (xy 283.32762 -154.706111)
			(xy 283.287892 -154.912242) (xy 283.240345 -155.116711) (xy 283.185048 -155.319221) (xy 283.122081 -155.519479)
			(xy 283.051536 -155.717195) (xy 282.973515 -155.912082) (xy 282.888131 -156.103857) (xy 282.795508 -156.292243)
			(xy 282.695781 -156.476966) (xy 282.589093 -156.657758) (xy 282.475599 -156.834358) (xy 282.355464 -157.006508)
			(xy 282.228863 -157.173961) (xy 282.095978 -157.336472) (xy 281.957003 -157.493806) (xy 281.812139 -157.645735)
			(xy 281.661596 -157.792039) (xy 281.505592 -157.932506) (xy 281.344353 -158.066932) (xy 281.178113 -158.195121)
			(xy 281.007114 -158.316889) (xy 280.831603 -158.432059) (xy 280.651835 -158.540463) (xy 280.46807 -158.641945)
			(xy 280.280574 -158.736357) (xy 280.089621 -158.823563) (xy 279.895485 -158.903436) (xy 279.69845 -158.97586)
			(xy 279.4988 -159.04073) (xy 279.382794 -159.073596) (xy 343.127076 -159.073596) (xy 343.127653 -159.028827)
			(xy 343.136659 -158.939742) (xy 343.15456 -158.852011) (xy 343.181175 -158.766519) (xy 343.198196 -158.725108)
			(xy 343.201765 -158.715518) (xy 343.201764 -158.695074) (xy 343.198196 -158.685484) (xy 343.181156 -158.644079)
			(xy 343.154522 -158.55859) (xy 343.136619 -158.470856) (xy 343.127627 -158.381767) (xy 343.127076 -158.336996)
			(xy 343.127653 -158.292227) (xy 343.136659 -158.203142) (xy 343.15456 -158.115411) (xy 343.181175 -158.029919)
			(xy 343.198196 -157.988508) (xy 343.201765 -157.978918) (xy 343.201764 -157.958474) (xy 343.198196 -157.948884)
			(xy 343.181156 -157.907479) (xy 343.154522 -157.82199) (xy 343.136619 -157.734256) (xy 343.127627 -157.645167)
			(xy 343.127076 -157.600396) (xy 343.127549 -157.559286) (xy 343.135137 -157.477416) (xy 343.150247 -157.396596)
			(xy 343.172752 -157.317516) (xy 343.202459 -157.240849) (xy 343.239114 -157.167252) (xy 343.282404 -157.097351)
			(xy 343.33196 -157.031743) (xy 343.387359 -156.970988) (xy 343.448129 -156.915605) (xy 343.51375 -156.866067)
			(xy 343.583663 -156.822796) (xy 343.657271 -156.786161) (xy 343.733945 -156.756475) (xy 343.813032 -156.733992)
			(xy 343.893856 -156.718903) (xy 343.975728 -156.711337) (xy 344.016838 -156.710888) (xy 344.058442 -156.711362)
			(xy 344.14129 -156.719094) (xy 344.223055 -156.734524) (xy 344.303022 -156.757517) (xy 344.380495 -156.787874)
			(xy 344.454797 -156.825328) (xy 344.490294 -156.847032) (xy 344.499434 -156.852189) (xy 344.520149 -156.855402)
			(xy 344.540422 -156.850073) (xy 344.548968 -156.843984) (xy 344.582592 -156.818029) (xy 344.653971 -156.771973)
			(xy 344.729414 -156.73293) (xy 344.808235 -156.701255) (xy 344.889716 -156.677237) (xy 344.973116 -156.661094)
			(xy 345.057674 -156.652974) (xy 345.100148 -156.652468) (xy 345.100402 -156.652468) (xy 345.14151 -156.652911)
			(xy 345.223374 -156.660496) (xy 345.30419 -156.6756) (xy 345.383268 -156.698096) (xy 345.459933 -156.727791)
			(xy 345.533532 -156.764433) (xy 345.603437 -156.807707) (xy 345.669051 -156.857246) (xy 345.729816 -156.912627)
			(xy 345.785212 -156.973378) (xy 345.806812 -157.001972) (xy 386.403596 -157.001972) (xy 386.40399 -156.963682)
			(xy 386.410601 -156.887387) (xy 386.423753 -156.811945) (xy 386.44335 -156.737915) (xy 386.45592 -156.701744)
			(xy 386.458586 -156.693311) (xy 386.458577 -156.675637) (xy 386.45592 -156.6672) (xy 386.443367 -156.631026)
			(xy 386.423796 -156.556991) (xy 386.410652 -156.481551) (xy 386.40403 -156.40526) (xy 386.403596 -156.366972)
			(xy 386.404015 -156.328179) (xy 386.410791 -156.25089) (xy 386.424264 -156.174482) (xy 386.44433 -156.099536)
			(xy 386.45719 -156.062934) (xy 386.459858 -156.054502) (xy 386.459846 -156.036827) (xy 386.45719 -156.02839)
			(xy 386.444324 -155.991789) (xy 386.424239 -155.916847) (xy 386.410766 -155.840438) (xy 386.404005 -155.763146)
			(xy 386.403596 -155.724352) (xy 386.404014 -155.686062) (xy 386.410618 -155.609769) (xy 386.423763 -155.534326)
			(xy 386.443354 -155.460295) (xy 386.45592 -155.424124) (xy 386.458596 -155.415693) (xy 386.45858 -155.398017)
			(xy 386.45592 -155.38958) (xy 386.443389 -155.353398) (xy 386.423812 -155.279367) (xy 386.410662 -155.203928)
			(xy 386.404034 -155.12764) (xy 386.403596 -155.089352) (xy 386.40407 -155.049438) (xy 386.411294 -154.969935)
			(xy 386.425601 -154.891398) (xy 386.446874 -154.814455) (xy 386.460492 -154.776932) (xy 386.463345 -154.768269)
			(xy 386.463329 -154.750041) (xy 386.460492 -154.741372) (xy 386.44684 -154.70386) (xy 386.425547 -154.626919)
			(xy 386.411244 -154.548377) (xy 386.404048 -154.468869) (xy 386.403596 -154.428952) (xy 386.404014 -154.390662)
			(xy 386.410618 -154.314369) (xy 386.423763 -154.238926) (xy 386.443354 -154.164895) (xy 386.45592 -154.128724)
			(xy 386.458596 -154.120293) (xy 386.45858 -154.102617) (xy 386.45592 -154.09418) (xy 386.443389 -154.057998)
			(xy 386.423812 -153.983967) (xy 386.410662 -153.908528) (xy 386.404034 -153.83224) (xy 386.403596 -153.793952)
			(xy 386.404007 -153.75284) (xy 386.411599 -153.670969) (xy 386.426714 -153.590147) (xy 386.449223 -153.511065)
			(xy 386.478934 -153.434397) (xy 386.515593 -153.360799) (xy 386.558887 -153.290897) (xy 386.608448 -153.225289)
			(xy 386.663851 -153.164535) (xy 386.724625 -153.109152) (xy 386.79025 -153.059614) (xy 386.860166 -153.016344)
			(xy 386.933777 -152.97971) (xy 387.010455 -152.950026) (xy 387.089545 -152.927544) (xy 387.170372 -152.912457)
			(xy 387.252246 -152.904893) (xy 387.293358 -152.904444) (xy 387.331674 -152.904822) (xy 387.408027 -152.91135)
			(xy 387.483534 -152.924432) (xy 387.557634 -152.94397) (xy 387.59384 -152.956514) (xy 387.602156 -152.9591)
			(xy 387.61956 -152.9591) (xy 387.627876 -152.956514) (xy 387.663994 -152.944008) (xy 387.737908 -152.924522)
			(xy 387.81322 -152.911442) (xy 387.889376 -152.904865) (xy 387.927596 -152.904444) (xy 387.928358 -152.904444)
			(xy 387.969464 -152.904953) (xy 388.051326 -152.912533) (xy 388.13214 -152.927634) (xy 388.211216 -152.950125)
			(xy 388.28788 -152.979816) (xy 388.361478 -153.016453) (xy 388.431382 -153.059723) (xy 388.496996 -153.109258)
			(xy 388.55776 -153.164634) (xy 388.613157 -153.225381) (xy 388.662713 -153.290979) (xy 388.706006 -153.360869)
			(xy 388.742667 -153.434454) (xy 388.772383 -153.511109) (xy 388.7949 -153.590177) (xy 388.810027 -153.670986)
			(xy 388.817634 -153.752846) (xy 388.817889 -153.774394) (xy 436.382169 -153.774394) (xy 436.386165 -153.564508)
			(xy 436.39815 -153.354926) (xy 436.418104 -153.145952) (xy 436.446 -152.93789) (xy 436.481797 -152.73104)
			(xy 436.525442 -152.525703) (xy 436.576874 -152.322177) (xy 436.636016 -152.120756) (xy 436.702784 -151.921733)
			(xy 436.77708 -151.725396) (xy 436.858798 -151.53203) (xy 436.947817 -151.341915) (xy 437.04401 -151.155327)
			(xy 437.147237 -150.972536) (xy 437.257348 -150.793808) (xy 437.374183 -150.619401) (xy 437.497573 -150.449569)
			(xy 437.62734 -150.284557) (xy 437.763294 -150.124606) (xy 437.90524 -149.969946) (xy 438.05297 -149.820802)
			(xy 438.206272 -149.677391) (xy 438.364922 -149.53992) (xy 438.528691 -149.408588) (xy 438.697341 -149.283587)
			(xy 438.870627 -149.165096) (xy 439.048299 -149.053289) (xy 439.230099 -148.948327) (xy 439.415763 -148.850362)
			(xy 439.605021 -148.759537) (xy 439.797601 -148.675983) (xy 439.993222 -148.59982) (xy 440.1916 -148.531161)
			(xy 440.392449 -148.470104) (xy 440.595476 -148.416737) (xy 440.800389 -148.371139) (xy 441.006888 -148.333374)
			(xy 441.214675 -148.303499) (xy 441.42345 -148.281556) (xy 441.632908 -148.267577) (xy 441.842747 -148.261582)
			(xy 442.052661 -148.263581) (xy 442.262348 -148.273569) (xy 442.471502 -148.291534) (xy 442.67982 -148.317448)
			(xy 442.887001 -148.351273) (xy 443.092745 -148.392962) (xy 443.296751 -148.442454) (xy 443.498726 -148.499676)
			(xy 443.698376 -148.564546) (xy 443.895411 -148.63697) (xy 444.089547 -148.716843) (xy 444.2805 -148.804049)
			(xy 444.467996 -148.898461) (xy 444.651761 -148.999943) (xy 444.831529 -149.108347) (xy 445.00704 -149.223517)
			(xy 445.178039 -149.345285) (xy 445.344279 -149.473474) (xy 445.505518 -149.6079) (xy 445.661522 -149.748367)
			(xy 445.812065 -149.894671) (xy 445.956929 -150.0466) (xy 446.095904 -150.203934) (xy 446.228789 -150.366445)
			(xy 446.35539 -150.533898) (xy 446.475525 -150.706048) (xy 446.589019 -150.882648) (xy 446.695707 -151.06344)
			(xy 446.795434 -151.248163) (xy 446.888057 -151.436549) (xy 446.973441 -151.628324) (xy 447.051462 -151.823211)
			(xy 447.122007 -152.020927) (xy 447.184974 -152.221185) (xy 447.240271 -152.423695) (xy 447.287818 -152.628164)
			(xy 447.327546 -152.834295) (xy 447.359398 -153.041788) (xy 447.383328 -153.250344) (xy 447.3993 -153.45966)
			(xy 447.407292 -153.669432) (xy 447.407792 -153.774394) (xy 447.407292 -153.879356) (xy 447.3993 -154.089128)
			(xy 447.383328 -154.298444) (xy 447.359398 -154.507) (xy 447.327546 -154.714493) (xy 447.287818 -154.920624)
			(xy 447.240271 -155.125093) (xy 447.184974 -155.327603) (xy 447.122007 -155.527861) (xy 447.051462 -155.725577)
			(xy 446.973441 -155.920464) (xy 446.888057 -156.112239) (xy 446.795434 -156.300625) (xy 446.695707 -156.485348)
			(xy 446.589019 -156.66614) (xy 446.475525 -156.84274) (xy 446.35539 -157.01489) (xy 446.228789 -157.182343)
			(xy 446.095904 -157.344854) (xy 445.956929 -157.502188) (xy 445.812065 -157.654117) (xy 445.661522 -157.800421)
			(xy 445.505518 -157.940888) (xy 445.344279 -158.075314) (xy 445.178039 -158.203503) (xy 445.00704 -158.325271)
			(xy 444.831529 -158.440441) (xy 444.651761 -158.548845) (xy 444.467996 -158.650327) (xy 444.2805 -158.744739)
			(xy 444.089547 -158.831945) (xy 443.895411 -158.911818) (xy 443.698376 -158.984242) (xy 443.498726 -159.049112)
			(xy 443.296751 -159.106334) (xy 443.092745 -159.155826) (xy 442.887001 -159.197515) (xy 442.67982 -159.23134)
			(xy 442.471502 -159.257254) (xy 442.262348 -159.275219) (xy 442.052661 -159.285207) (xy 441.842747 -159.287206)
			(xy 441.632908 -159.281211) (xy 441.42345 -159.267232) (xy 441.214675 -159.245289) (xy 441.006888 -159.215414)
			(xy 440.800389 -159.177649) (xy 440.595476 -159.132051) (xy 440.392449 -159.078684) (xy 440.1916 -159.017627)
			(xy 439.993222 -158.948968) (xy 439.797601 -158.872805) (xy 439.605021 -158.789251) (xy 439.415763 -158.698426)
			(xy 439.230099 -158.600461) (xy 439.048299 -158.495499) (xy 438.870627 -158.383692) (xy 438.697341 -158.265201)
			(xy 438.528691 -158.1402) (xy 438.364922 -158.008868) (xy 438.206272 -157.871397) (xy 438.05297 -157.727986)
			(xy 437.90524 -157.578842) (xy 437.763294 -157.424182) (xy 437.62734 -157.264231) (xy 437.497573 -157.099219)
			(xy 437.374183 -156.929387) (xy 437.257348 -156.75498) (xy 437.147237 -156.576252) (xy 437.04401 -156.393461)
			(xy 436.947817 -156.206873) (xy 436.858798 -156.016758) (xy 436.77708 -155.823392) (xy 436.702784 -155.627055)
			(xy 436.636016 -155.428032) (xy 436.576874 -155.226611) (xy 436.525442 -155.023085) (xy 436.481797 -154.817748)
			(xy 436.446 -154.610898) (xy 436.418104 -154.402836) (xy 436.39815 -154.193862) (xy 436.386165 -153.98428)
			(xy 436.382169 -153.774394) (xy 388.817889 -153.774394) (xy 388.81812 -153.793952) (xy 388.817702 -153.832242)
			(xy 388.811098 -153.908535) (xy 388.797953 -153.983978) (xy 388.778362 -154.058009) (xy 388.765796 -154.09418)
			(xy 388.763168 -154.102623) (xy 388.763152 -154.120288) (xy 388.765796 -154.128724) (xy 388.778328 -154.164905)
			(xy 388.797905 -154.238937) (xy 388.811055 -154.314375) (xy 388.817683 -154.390664) (xy 388.81812 -154.428952)
			(xy 388.817646 -154.468866) (xy 388.810422 -154.548369) (xy 388.796115 -154.626906) (xy 388.774842 -154.703849)
			(xy 388.761224 -154.741372) (xy 388.758419 -154.750047) (xy 388.758403 -154.768264) (xy 388.761224 -154.776932)
			(xy 388.774878 -154.814443) (xy 388.79617 -154.891385) (xy 388.810472 -154.969927) (xy 388.817668 -155.049435)
			(xy 388.81812 -155.089352) (xy 388.817702 -155.127642) (xy 388.811098 -155.203935) (xy 388.797953 -155.279378)
			(xy 388.778362 -155.353409) (xy 388.765796 -155.38958) (xy 388.763168 -155.398023) (xy 388.763152 -155.415688)
			(xy 388.765796 -155.424124) (xy 388.778328 -155.460305) (xy 388.797905 -155.534337) (xy 388.811055 -155.609775)
			(xy 388.817683 -155.686064) (xy 388.81812 -155.724352) (xy 388.817677 -155.763144) (xy 388.810908 -155.840433)
			(xy 388.797442 -155.916841) (xy 388.777382 -155.991787) (xy 388.764526 -156.02839) (xy 388.761895 -156.036832)
			(xy 388.761883 -156.054497) (xy 388.764526 -156.062934) (xy 388.7774 -156.099532) (xy 388.797482 -156.174476)
			(xy 388.810953 -156.250885) (xy 388.817712 -156.328178) (xy 388.81812 -156.366972) (xy 388.817708 -156.405262)
			(xy 388.811103 -156.481556) (xy 388.797955 -156.556998) (xy 388.778363 -156.631029) (xy 388.765796 -156.6672)
			(xy 388.763157 -156.67564) (xy 388.763148 -156.693308) (xy 388.765796 -156.701744) (xy 388.778334 -156.737923)
			(xy 388.797909 -156.811956) (xy 388.811058 -156.887395) (xy 388.817683 -156.963684) (xy 388.81812 -157.001972)
			(xy 388.817621 -157.043082) (xy 388.810036 -157.124951) (xy 388.794928 -157.20577) (xy 388.772425 -157.284851)
			(xy 388.742721 -157.361517) (xy 388.706068 -157.435115) (xy 388.66278 -157.505016) (xy 388.613226 -157.570624)
			(xy 388.557828 -157.631379) (xy 388.49706 -157.686762) (xy 388.43144 -157.736301) (xy 388.361528 -157.779573)
			(xy 388.287921 -157.816208) (xy 388.211248 -157.845893) (xy 388.132162 -157.868377) (xy 388.051339 -157.883465)
			(xy 387.969468 -157.891031) (xy 387.928358 -157.89148) (xy 387.890041 -157.891126) (xy 387.813688 -157.88459)
			(xy 387.738181 -157.871501) (xy 387.664082 -157.851957) (xy 387.627876 -157.83941) (xy 387.61956 -157.836824)
			(xy 387.602156 -157.836824) (xy 387.59384 -157.83941) (xy 387.557721 -157.851912) (xy 387.483807 -157.871399)
			(xy 387.408495 -157.88448) (xy 387.33234 -157.891059) (xy 387.29412 -157.89148) (xy 387.293358 -157.89148)
			(xy 387.252251 -157.891028) (xy 387.170388 -157.88344) (xy 387.089574 -157.868332) (xy 387.010498 -157.845835)
			(xy 386.933835 -157.816138) (xy 386.860238 -157.779497) (xy 386.790335 -157.736222) (xy 386.724722 -157.686684)
			(xy 386.663959 -157.631304) (xy 386.608563 -157.570555) (xy 386.559008 -157.504955) (xy 386.515715 -157.435063)
			(xy 386.479055 -157.361475) (xy 386.449338 -157.28482) (xy 386.42682 -157.20575) (xy 386.411692 -157.12494)
			(xy 386.404083 -157.043079) (xy 386.403596 -157.001972) (xy 345.806812 -157.001972) (xy 345.834767 -157.03898)
			(xy 345.878059 -157.108874) (xy 345.914719 -157.182463) (xy 345.944433 -157.259121) (xy 345.966949 -157.338193)
			(xy 345.982074 -157.419006) (xy 345.989679 -157.500868) (xy 345.990164 -157.541976) (xy 345.989609 -157.586746)
			(xy 345.980596 -157.675831) (xy 345.962689 -157.763562) (xy 345.936068 -157.849053) (xy 345.919044 -157.890464)
			(xy 345.915494 -157.900059) (xy 345.915485 -157.920497) (xy 345.919044 -157.930088) (xy 345.936056 -157.971436)
			(xy 345.962665 -158.056799) (xy 345.980569 -158.144403) (xy 345.989589 -158.233361) (xy 345.990164 -158.278068)
			(xy 345.990164 -158.279084) (xy 345.98991 -158.290514) (xy 346.016389 -158.296459) (xy 346.068624 -158.311202)
			(xy 346.094304 -158.319978) (xy 346.102501 -158.322492) (xy 346.119635 -158.322492) (xy 346.127832 -158.319978)
			(xy 346.163048 -158.308033) (xy 346.235059 -158.289446) (xy 346.308381 -158.277006) (xy 346.382492 -158.2708)
			(xy 346.419678 -158.270448) (xy 346.456862 -158.27082) (xy 346.53097 -158.277041) (xy 346.60429 -158.289483)
			(xy 346.676301 -158.308056) (xy 346.711524 -158.319978) (xy 346.719721 -158.322492) (xy 346.736855 -158.322492)
			(xy 346.745052 -158.319978) (xy 346.780146 -158.308069) (xy 346.851906 -158.289524) (xy 346.924971 -158.277084)
			(xy 346.998824 -158.270837) (xy 347.035882 -158.270448) (xy 347.036898 -158.270448) (xy 347.078822 -158.270999)
			(xy 347.162292 -158.278969) (xy 347.244625 -158.294837) (xy 347.325078 -158.31846) (xy 347.40292 -158.349624)
			(xy 347.477448 -158.388045) (xy 347.547987 -158.433377) (xy 347.613896 -158.485209) (xy 347.674581 -158.543071)
			(xy 347.72949 -158.60644) (xy 347.778127 -158.674741) (xy 347.820052 -158.747357) (xy 347.854884 -158.823628)
			(xy 347.882308 -158.902865) (xy 347.902076 -158.984351) (xy 347.914009 -159.067346) (xy 347.917999 -159.1511)
			(xy 347.914009 -159.234854) (xy 347.902076 -159.317849) (xy 347.882308 -159.399335) (xy 347.854884 -159.478572)
			(xy 347.820052 -159.554843) (xy 347.778127 -159.627459) (xy 347.72949 -159.69576) (xy 347.674581 -159.759129)
			(xy 347.613896 -159.816991) (xy 347.547987 -159.868823) (xy 347.477448 -159.914155) (xy 347.40292 -159.952576)
			(xy 347.325078 -159.98374) (xy 347.244625 -160.007363) (xy 347.162292 -160.023231) (xy 347.078822 -160.031201)
			(xy 347.036898 -160.031684) (xy 347.035882 -160.031684) (xy 346.998825 -160.031285) (xy 346.924976 -160.025019)
			(xy 346.851913 -160.012575) (xy 346.780153 -159.994041) (xy 346.745052 -159.982154) (xy 346.736855 -159.97964)
			(xy 346.719721 -159.97964) (xy 346.711524 -159.982154) (xy 346.684116 -159.991499) (xy 346.628318 -160.007008)
			(xy 346.600018 -160.013142) (xy 346.590235 -160.015622) (xy 346.573598 -160.027019) (xy 346.562626 -160.04394)
			(xy 346.560394 -160.053782) (xy 346.550929 -160.102889) (xy 346.522417 -160.19875) (xy 346.503498 -160.245044)
			(xy 346.499892 -160.254619) (xy 346.499745 -160.275056) (xy 346.503244 -160.284668) (xy 346.520278 -160.326041)
			(xy 346.546893 -160.41147) (xy 346.564794 -160.499139) (xy 346.5738 -160.588163) (xy 346.574364 -160.632902)
			(xy 346.574364 -160.633156) (xy 346.57386 -160.675504) (xy 346.565809 -160.759818) (xy 346.54978 -160.842984)
			(xy 346.525919 -160.924251) (xy 346.49444 -161.002881) (xy 346.455629 -161.078162) (xy 346.409839 -161.149414)
			(xy 346.357483 -161.21599) (xy 346.299035 -161.277288) (xy 346.235025 -161.332753) (xy 346.166033 -161.381882)
			(xy 346.092683 -161.424231) (xy 346.01564 -161.459415) (xy 345.935601 -161.487117) (xy 345.853292 -161.507085)
			(xy 345.769457 -161.519138) (xy 345.684856 -161.523169) (xy 345.600255 -161.519138) (xy 345.51642 -161.507085)
			(xy 345.434111 -161.487117) (xy 345.354072 -161.459415) (xy 345.277029 -161.424231) (xy 345.203679 -161.381882)
			(xy 345.134687 -161.332753) (xy 345.070677 -161.277288) (xy 345.012229 -161.21599) (xy 344.959873 -161.149414)
			(xy 344.914083 -161.078162) (xy 344.875272 -161.002881) (xy 344.843793 -160.924251) (xy 344.819932 -160.842984)
			(xy 344.803903 -160.759818) (xy 344.795852 -160.675504) (xy 344.795348 -160.633156) (xy 344.795348 -160.632902)
			(xy 344.795938 -160.588164) (xy 344.804948 -160.499143) (xy 344.822847 -160.411476) (xy 344.849453 -160.326048)
			(xy 344.866468 -160.284668) (xy 344.870056 -160.275084) (xy 344.87004 -160.254635) (xy 344.866468 -160.245044)
			(xy 344.849433 -160.203637) (xy 344.822801 -160.118148) (xy 344.804897 -160.030415) (xy 344.795901 -159.941327)
			(xy 344.795348 -159.896556) (xy 344.795678 -159.859467) (xy 344.801776 -159.78554) (xy 344.814009 -159.712377)
			(xy 344.82278 -159.676338) (xy 344.824538 -159.668008) (xy 344.823098 -159.651057) (xy 344.816174 -159.635517)
			(xy 344.810588 -159.629094) (xy 344.770202 -159.586168) (xy 344.758264 -159.588708) (xy 344.749364 -159.591023)
			(xy 344.733871 -159.600904) (xy 344.728038 -159.608012) (xy 344.702891 -159.640664) (xy 344.647483 -159.701681)
			(xy 344.586669 -159.757312) (xy 344.520971 -159.807081) (xy 344.450952 -159.850561) (xy 344.377213 -159.887379)
			(xy 344.300384 -159.917221) (xy 344.221125 -159.93983) (xy 344.140115 -159.955012) (xy 344.058048 -159.962637)
			(xy 344.016838 -159.963104) (xy 343.975733 -159.962551) (xy 343.893874 -159.954971) (xy 343.813062 -159.939871)
			(xy 343.733989 -159.917381) (xy 343.657327 -159.887692) (xy 343.583731 -159.851057) (xy 343.513829 -159.807789)
			(xy 343.448216 -159.758257) (xy 343.387452 -159.702884) (xy 343.332056 -159.642141) (xy 343.2825 -159.576547)
			(xy 343.239206 -159.506661) (xy 343.202543 -159.433078) (xy 343.172826 -159.356428) (xy 343.150306 -159.277363)
			(xy 343.135175 -159.196557) (xy 343.127564 -159.114701) (xy 343.127076 -159.073596) (xy 279.382794 -159.073596)
			(xy 279.296825 -159.097952) (xy 279.092819 -159.147444) (xy 278.887075 -159.189133) (xy 278.679894 -159.222958)
			(xy 278.471576 -159.248872) (xy 278.262422 -159.266837) (xy 278.052735 -159.276825) (xy 277.842821 -159.278824)
			(xy 277.632982 -159.272829) (xy 277.423524 -159.25885) (xy 277.214749 -159.236907) (xy 277.006962 -159.207032)
			(xy 276.800463 -159.169267) (xy 276.59555 -159.123669) (xy 276.392523 -159.070302) (xy 276.191674 -159.009245)
			(xy 275.993296 -158.940586) (xy 275.797675 -158.864423) (xy 275.605095 -158.780869) (xy 275.415837 -158.690044)
			(xy 275.230173 -158.592079) (xy 275.048373 -158.487117) (xy 274.870701 -158.37531) (xy 274.697415 -158.256819)
			(xy 274.528765 -158.131818) (xy 274.364996 -158.000486) (xy 274.206346 -157.863015) (xy 274.053044 -157.719604)
			(xy 273.905314 -157.57046) (xy 273.763368 -157.4158) (xy 273.627414 -157.255849) (xy 273.497647 -157.090837)
			(xy 273.374257 -156.921005) (xy 273.257422 -156.746598) (xy 273.147311 -156.56787) (xy 273.044084 -156.385079)
			(xy 272.947891 -156.198491) (xy 272.858872 -156.008376) (xy 272.777154 -155.81501) (xy 272.702858 -155.618673)
			(xy 272.63609 -155.41965) (xy 272.576948 -155.218229) (xy 272.525516 -155.014703) (xy 272.481871 -154.809366)
			(xy 272.446074 -154.602516) (xy 272.418178 -154.394454) (xy 272.398224 -154.18548) (xy 272.386239 -153.975898)
			(xy 272.382243 -153.766012) (xy 199.467428 -153.766012) (xy 199.46747 -153.774902) (xy 199.46697 -153.879864)
			(xy 199.458978 -154.089636) (xy 199.443006 -154.298952) (xy 199.419076 -154.507508) (xy 199.387224 -154.715001)
			(xy 199.347496 -154.921132) (xy 199.299949 -155.125601) (xy 199.244652 -155.328111) (xy 199.181685 -155.528369)
			(xy 199.11114 -155.726085) (xy 199.033119 -155.920972) (xy 198.947735 -156.112747) (xy 198.855112 -156.301133)
			(xy 198.755385 -156.485856) (xy 198.648697 -156.666648) (xy 198.535203 -156.843248) (xy 198.415068 -157.015398)
			(xy 198.288467 -157.182851) (xy 198.155582 -157.345362) (xy 198.016607 -157.502696) (xy 197.871743 -157.654625)
			(xy 197.7212 -157.800929) (xy 197.565196 -157.941396) (xy 197.403957 -158.075822) (xy 197.237717 -158.204011)
			(xy 197.066718 -158.325779) (xy 196.891207 -158.440949) (xy 196.711439 -158.549353) (xy 196.527674 -158.650835)
			(xy 196.340178 -158.745247) (xy 196.149225 -158.832453) (xy 195.955089 -158.912326) (xy 195.758054 -158.98475)
			(xy 195.558404 -159.04962) (xy 195.356429 -159.106842) (xy 195.152423 -159.156334) (xy 194.946679 -159.198023)
			(xy 194.739498 -159.231848) (xy 194.53118 -159.257762) (xy 194.322026 -159.275727) (xy 194.112339 -159.285715)
			(xy 193.902425 -159.287714) (xy 193.692586 -159.281719) (xy 193.483128 -159.26774) (xy 193.274353 -159.245797)
			(xy 193.066566 -159.215922) (xy 192.860067 -159.178157) (xy 192.655154 -159.132559) (xy 192.452127 -159.079192)
			(xy 192.251278 -159.018135) (xy 192.0529 -158.949476) (xy 191.857279 -158.873313) (xy 191.664699 -158.789759)
			(xy 191.475441 -158.698934) (xy 191.289777 -158.600969) (xy 191.107977 -158.496007) (xy 190.930305 -158.3842)
			(xy 190.757019 -158.265709) (xy 190.588369 -158.140708) (xy 190.4246 -158.009376) (xy 190.26595 -157.871905)
			(xy 190.112648 -157.728494) (xy 189.964918 -157.57935) (xy 189.822972 -157.42469) (xy 189.687018 -157.264739)
			(xy 189.557251 -157.099727) (xy 189.433861 -156.929895) (xy 189.317026 -156.755488) (xy 189.206915 -156.57676)
			(xy 189.103688 -156.393969) (xy 189.007495 -156.207381) (xy 188.918476 -156.017266) (xy 188.836758 -155.8239)
			(xy 188.762462 -155.627563) (xy 188.695694 -155.42854) (xy 188.636552 -155.227119) (xy 188.58512 -155.023593)
			(xy 188.541475 -154.818256) (xy 188.505678 -154.611406) (xy 188.477782 -154.403344) (xy 188.457828 -154.19437)
			(xy 188.445843 -153.984788) (xy 188.441847 -153.774902) (xy 132.165372 -153.774902) (xy 132.17401 -153.779355)
			(xy 132.244575 -153.824704) (xy 132.31051 -153.876555) (xy 132.371218 -153.934439) (xy 132.426149 -153.997832)
			(xy 132.474805 -154.066159) (xy 132.516746 -154.138802) (xy 132.551591 -154.215103) (xy 132.579026 -154.29437)
			(xy 132.598802 -154.375887) (xy 132.61074 -154.458914) (xy 132.614731 -154.5427) (xy 132.61074 -154.626486)
			(xy 132.598802 -154.709513) (xy 132.579026 -154.79103) (xy 132.551591 -154.870297) (xy 132.516746 -154.946598)
			(xy 132.474805 -155.019241) (xy 132.426149 -155.087568) (xy 132.371218 -155.150961) (xy 132.31051 -155.208845)
			(xy 132.244575 -155.260696) (xy 132.17401 -155.306045) (xy 132.099453 -155.344481) (xy 132.02158 -155.375656)
			(xy 131.941097 -155.399287) (xy 131.858732 -155.415161) (xy 131.77523 -155.423133) (xy 131.73329 -155.423616)
			(xy 131.6961 -155.423229) (xy 131.621987 -155.416939) (xy 131.548668 -155.404428) (xy 131.476662 -155.385787)
			(xy 131.441444 -155.373832) (xy 131.433247 -155.371318) (xy 131.416113 -155.371318) (xy 131.407916 -155.373832)
			(xy 131.374578 -155.385154) (xy 131.306486 -155.403082) (xy 131.237181 -155.41552) (xy 131.202176 -155.419298)
			(xy 131.192163 -155.420682) (xy 131.174401 -155.43031) (xy 131.161723 -155.446041) (xy 131.158488 -155.45562)
			(xy 131.151035 -155.480306) (xy 131.133624 -155.528851) (xy 131.12369 -155.552648) (xy 131.120082 -155.562222)
			(xy 131.119936 -155.58266) (xy 131.123436 -155.592272) (xy 131.140471 -155.633645) (xy 131.167086 -155.719073)
			(xy 131.184987 -155.806743) (xy 131.193992 -155.895767) (xy 131.194556 -155.940506) (xy 131.194556 -155.94076)
			(xy 131.194052 -155.983108) (xy 131.186001 -156.067422) (xy 131.169972 -156.150588) (xy 131.146111 -156.231855)
			(xy 131.114632 -156.310485) (xy 131.075821 -156.385766) (xy 131.030031 -156.457018) (xy 130.977675 -156.523594)
			(xy 130.919227 -156.584892) (xy 130.855217 -156.640357) (xy 130.786225 -156.689486) (xy 130.712875 -156.731835)
			(xy 130.635832 -156.767019) (xy 130.555793 -156.794721) (xy 130.473484 -156.814689) (xy 130.389649 -156.826742)
			(xy 130.305048 -156.830773) (xy 130.220447 -156.826742) (xy 130.136612 -156.814689) (xy 130.054303 -156.794721)
			(xy 129.974264 -156.767019) (xy 129.897221 -156.731835) (xy 129.823871 -156.689486) (xy 129.754879 -156.640357)
			(xy 129.690869 -156.584892) (xy 129.632421 -156.523594) (xy 129.580065 -156.457018) (xy 129.534275 -156.385766)
			(xy 129.495464 -156.310485) (xy 129.463985 -156.231855) (xy 129.440124 -156.150588) (xy 129.424095 -156.067422)
			(xy 129.416044 -155.983108) (xy 129.41554 -155.94076) (xy 129.41554 -155.940506) (xy 129.416091 -155.895767)
			(xy 129.425111 -155.806745) (xy 129.443021 -155.719078) (xy 129.46964 -155.633651) (xy 129.48666 -155.592272)
			(xy 129.490247 -155.582688) (xy 129.490232 -155.562239) (xy 129.48666 -155.552648) (xy 129.471663 -155.516314)
			(xy 129.447353 -155.441557) (xy 129.429731 -155.364948) (xy 129.418932 -155.287083) (xy 129.416556 -155.247848)
			(xy 129.415794 -155.233878) (xy 129.400046 -155.21051) (xy 129.29235 -155.160472) (xy 129.264664 -155.16352)
			(xy 129.253234 -155.172156) (xy 129.220015 -155.196974) (xy 129.149739 -155.241) (xy 129.075668 -155.27829)
			(xy 128.998447 -155.308521) (xy 128.918747 -155.33143) (xy 128.83726 -155.346818) (xy 128.754694 -155.354552)
			(xy 128.71323 -155.355036) (xy 128.672115 -155.354573) (xy 128.590235 -155.346988) (xy 128.509404 -155.33188)
			(xy 128.430313 -155.309379) (xy 128.353635 -155.279675) (xy 128.280025 -155.243023) (xy 128.210111 -155.199735)
			(xy 128.144489 -155.150181) (xy 128.08372 -155.094783) (xy 128.028322 -155.034014) (xy 127.978767 -154.968393)
			(xy 127.935479 -154.898479) (xy 127.898826 -154.824869) (xy 127.869122 -154.748191) (xy 127.84662 -154.669099)
			(xy 127.831512 -154.588269) (xy 127.823927 -154.506389) (xy 127.823468 -154.465274) (xy 35.422918 -154.465274)
			(xy 35.41915 -154.49811) (xy 35.387298 -154.705603) (xy 35.34757 -154.911734) (xy 35.300023 -155.116203)
			(xy 35.244726 -155.318713) (xy 35.181759 -155.518971) (xy 35.111214 -155.716687) (xy 35.033193 -155.911574)
			(xy 34.947809 -156.103349) (xy 34.855186 -156.291735) (xy 34.755459 -156.476458) (xy 34.648771 -156.65725)
			(xy 34.535277 -156.83385) (xy 34.415142 -157.006) (xy 34.288541 -157.173453) (xy 34.155656 -157.335964)
			(xy 34.016681 -157.493298) (xy 33.871817 -157.645227) (xy 33.721274 -157.791531) (xy 33.56527 -157.931998)
			(xy 33.404031 -158.066424) (xy 33.237791 -158.194613) (xy 33.066792 -158.316381) (xy 32.891281 -158.431551)
			(xy 32.711513 -158.539955) (xy 32.527748 -158.641437) (xy 32.340252 -158.735849) (xy 32.149299 -158.823055)
			(xy 31.955163 -158.902928) (xy 31.758128 -158.975352) (xy 31.558478 -159.040222) (xy 31.356503 -159.097444)
			(xy 31.152497 -159.146936) (xy 30.946753 -159.188625) (xy 30.739572 -159.22245) (xy 30.531254 -159.248364)
			(xy 30.3221 -159.266329) (xy 30.112413 -159.276317) (xy 29.902499 -159.278316) (xy 29.69266 -159.272321)
			(xy 29.483202 -159.258342) (xy 29.274427 -159.236399) (xy 29.06664 -159.206524) (xy 28.860141 -159.168759)
			(xy 28.655228 -159.123161) (xy 28.452201 -159.069794) (xy 28.251352 -159.008737) (xy 28.052974 -158.940078)
			(xy 27.857353 -158.863915) (xy 27.664773 -158.780361) (xy 27.475515 -158.689536) (xy 27.289851 -158.591571)
			(xy 27.108051 -158.486609) (xy 26.930379 -158.374802) (xy 26.757093 -158.256311) (xy 26.588443 -158.13131)
			(xy 26.424674 -157.999978) (xy 26.266024 -157.862507) (xy 26.112722 -157.719096) (xy 25.964992 -157.569952)
			(xy 25.823046 -157.415292) (xy 25.687092 -157.255341) (xy 25.557325 -157.090329) (xy 25.433935 -156.920497)
			(xy 25.3171 -156.74609) (xy 25.206989 -156.567362) (xy 25.103762 -156.384571) (xy 25.007569 -156.197983)
			(xy 24.91855 -156.007868) (xy 24.836832 -155.814502) (xy 24.762536 -155.618165) (xy 24.695768 -155.419142)
			(xy 24.636626 -155.217721) (xy 24.585194 -155.014195) (xy 24.541549 -154.808858) (xy 24.505752 -154.602008)
			(xy 24.477856 -154.393946) (xy 24.457902 -154.184972) (xy 24.445917 -153.97539) (xy 24.441921 -153.765504)
			(xy 2.509012 -153.765504) (xy 2.509012 -164.097716) (xy 86.129368 -164.097716) (xy 86.129877 -164.05494)
			(xy 86.138089 -163.969783) (xy 86.154448 -163.88581) (xy 86.178803 -163.803797) (xy 86.194392 -163.76396)
			(xy 86.19746 -163.755511) (xy 86.19811 -163.737557) (xy 86.195662 -163.728908) (xy 86.181097 -163.683434)
			(xy 86.160666 -163.590154) (xy 86.150355 -163.495221) (xy 86.149688 -163.447476) (xy 86.150084 -163.409186)
			(xy 86.156694 -163.332892) (xy 86.169846 -163.257449) (xy 86.189443 -163.183419) (xy 86.202012 -163.147248)
			(xy 86.204676 -163.138815) (xy 86.204669 -163.121141) (xy 86.202012 -163.112704) (xy 86.18946 -163.076529)
			(xy 86.169889 -163.002495) (xy 86.156744 -162.927055) (xy 86.150122 -162.850764) (xy 86.149688 -162.812476)
			(xy 86.15013 -162.771365) (xy 86.157719 -162.689494) (xy 86.172832 -162.608673) (xy 86.195339 -162.529592)
			(xy 86.225048 -162.452925) (xy 86.261705 -162.379327) (xy 86.304997 -162.309425) (xy 86.354555 -162.243817)
			(xy 86.409957 -162.183063) (xy 86.470728 -162.12768) (xy 86.536351 -162.078142) (xy 86.606266 -162.034871)
			(xy 86.679876 -161.998237) (xy 86.756552 -161.968552) (xy 86.83564 -161.94607) (xy 86.916466 -161.930982)
			(xy 86.998339 -161.923417) (xy 87.03945 -161.922968) (xy 87.077766 -161.923352) (xy 87.154119 -161.92988)
			(xy 87.229626 -161.94296) (xy 87.303725 -161.962495) (xy 87.339932 -161.975038) (xy 87.348248 -161.977624)
			(xy 87.365652 -161.977624) (xy 87.373968 -161.975038) (xy 87.410177 -161.962503) (xy 87.484279 -161.942985)
			(xy 87.559785 -161.929905) (xy 87.636135 -161.92336) (xy 87.67445 -161.922968) (xy 87.712766 -161.923352)
			(xy 87.789119 -161.92988) (xy 87.864626 -161.94296) (xy 87.938725 -161.962495) (xy 87.974932 -161.975038)
			(xy 87.983248 -161.977624) (xy 88.000652 -161.977624) (xy 88.008968 -161.975038) (xy 88.045177 -161.962503)
			(xy 88.119279 -161.942985) (xy 88.194785 -161.929905) (xy 88.271135 -161.92336) (xy 88.30945 -161.922968)
			(xy 88.347766 -161.923352) (xy 88.424119 -161.92988) (xy 88.499626 -161.94296) (xy 88.573725 -161.962495)
			(xy 88.609932 -161.975038) (xy 88.618248 -161.977624) (xy 88.635652 -161.977624) (xy 88.643968 -161.975038)
			(xy 88.680177 -161.962503) (xy 88.754279 -161.942985) (xy 88.829785 -161.929905) (xy 88.906135 -161.92336)
			(xy 88.94445 -161.922968) (xy 88.982766 -161.923352) (xy 89.059119 -161.92988) (xy 89.134626 -161.94296)
			(xy 89.208725 -161.962495) (xy 89.244932 -161.975038) (xy 89.253248 -161.977624) (xy 89.270652 -161.977624)
			(xy 89.278968 -161.975038) (xy 89.315177 -161.962503) (xy 89.389279 -161.942985) (xy 89.464785 -161.929905)
			(xy 89.541135 -161.92336) (xy 89.57945 -161.922968) (xy 89.62106 -161.923438) (xy 89.703917 -161.931201)
			(xy 89.785687 -161.946663) (xy 89.865658 -161.96969) (xy 89.90457 -161.984436) (xy 89.913248 -161.987466)
			(xy 89.931617 -161.98771) (xy 89.940384 -161.984944) (xy 89.976385 -161.972506) (xy 90.050053 -161.953122)
			(xy 90.125108 -161.940106) (xy 90.201001 -161.933552) (xy 90.239088 -161.933128) (xy 90.23985 -161.933128)
			(xy 90.280956 -161.93366) (xy 90.362817 -161.94124) (xy 90.443629 -161.956339) (xy 90.522705 -161.97883)
			(xy 90.599368 -162.008519) (xy 90.672965 -162.045155) (xy 90.742868 -162.088423) (xy 90.808482 -162.137957)
			(xy 90.869246 -162.193332) (xy 90.924643 -162.254076) (xy 90.974199 -162.319673) (xy 91.017492 -162.389561)
			(xy 91.054154 -162.463145) (xy 91.08387 -162.539798) (xy 91.106389 -162.618865) (xy 91.121517 -162.699672)
			(xy 91.129125 -162.781531) (xy 91.129612 -162.822636) (xy 91.12919 -162.860925) (xy 91.122588 -162.937219)
			(xy 91.109443 -163.012662) (xy 91.089854 -163.086693) (xy 91.077288 -163.122864) (xy 91.076082 -163.126674)
			(xy 119.365268 -163.126674) (xy 119.365838 -163.081905) (xy 119.374847 -162.99282) (xy 119.392749 -162.905089)
			(xy 119.419366 -162.819597) (xy 119.436388 -162.778186) (xy 119.43997 -162.7686) (xy 119.43996 -162.748153)
			(xy 119.436388 -162.738562) (xy 119.41934 -162.69716) (xy 119.392709 -162.61167) (xy 119.374808 -162.523935)
			(xy 119.365818 -162.434845) (xy 119.365268 -162.390074) (xy 119.365838 -162.345305) (xy 119.374847 -162.25622)
			(xy 119.392749 -162.168489) (xy 119.419366 -162.082997) (xy 119.436388 -162.041586) (xy 119.43997 -162.032)
			(xy 119.43996 -162.011553) (xy 119.436388 -162.001962) (xy 119.41934 -161.96056) (xy 119.392709 -161.87507)
			(xy 119.374808 -161.787335) (xy 119.365818 -161.698245) (xy 119.365268 -161.653474) (xy 119.365674 -161.612358)
			(xy 119.373264 -161.530476) (xy 119.388376 -161.449645) (xy 119.410882 -161.370552) (xy 119.440591 -161.293873)
			(xy 119.477247 -161.220263) (xy 119.520539 -161.150349) (xy 119.570097 -161.084728) (xy 119.625499 -161.023959)
			(xy 119.686271 -160.968561) (xy 119.751895 -160.919007) (xy 119.821812 -160.87572) (xy 119.895425 -160.839068)
			(xy 119.972105 -160.809365) (xy 120.051199 -160.786863) (xy 120.132032 -160.771756) (xy 120.213914 -160.764171)
			(xy 120.25503 -160.763712) (xy 120.296641 -160.764173) (xy 120.379498 -160.771953) (xy 120.461267 -160.787431)
			(xy 120.541235 -160.810474) (xy 120.618703 -160.840879) (xy 120.692995 -160.878382) (xy 120.728486 -160.90011)
			(xy 120.737629 -160.905263) (xy 120.758342 -160.90848) (xy 120.778614 -160.903152) (xy 120.78716 -160.897062)
			(xy 120.820789 -160.871071) (xy 120.892183 -160.824946) (xy 120.967654 -160.785845) (xy 121.046512 -160.754124)
			(xy 121.128037 -160.730075) (xy 121.211485 -160.713915) (xy 121.296095 -160.705793) (xy 121.338594 -160.705292)
			(xy 121.379707 -160.705819) (xy 121.461582 -160.713405) (xy 121.542407 -160.728513) (xy 121.621494 -160.751013)
			(xy 121.698168 -160.780715) (xy 121.771774 -160.817365) (xy 121.841684 -160.86065) (xy 121.907303 -160.9102)
			(xy 121.96807 -160.965593) (xy 122.023467 -161.026357) (xy 122.073021 -161.091973) (xy 122.11631 -161.161881)
			(xy 122.152964 -161.235485) (xy 122.18267 -161.312156) (xy 122.205176 -161.391242) (xy 122.220288 -161.472067)
			(xy 122.227879 -161.553941) (xy 122.228356 -161.595054) (xy 122.227793 -161.639824) (xy 122.218783 -161.728909)
			(xy 122.200877 -161.81664) (xy 122.174259 -161.902131) (xy 122.157236 -161.943542) (xy 122.153699 -161.953141)
			(xy 122.153682 -161.973576) (xy 122.157236 -161.983166) (xy 122.17424 -162.024517) (xy 122.200851 -162.109879)
			(xy 122.218758 -162.197482) (xy 122.22778 -162.286439) (xy 122.228356 -162.331146) (xy 122.228356 -162.332162)
			(xy 122.228102 -162.343592) (xy 122.254581 -162.349538) (xy 122.306816 -162.364281) (xy 122.332496 -162.373056)
			(xy 122.340693 -162.37557) (xy 122.357827 -162.37557) (xy 122.366024 -162.373056) (xy 122.40124 -162.361095)
			(xy 122.473244 -162.342441) (xy 122.546565 -162.329932) (xy 122.62068 -162.323659) (xy 122.65787 -162.323272)
			(xy 122.695059 -162.323671) (xy 122.769172 -162.329958) (xy 122.842492 -162.342465) (xy 122.914498 -162.361103)
			(xy 122.949716 -162.373056) (xy 122.957913 -162.37557) (xy 122.975047 -162.37557) (xy 122.983244 -162.373056)
			(xy 123.018459 -162.361089) (xy 123.090462 -162.342437) (xy 123.163784 -162.32993) (xy 123.2379 -162.323658)
			(xy 123.27509 -162.323272) (xy 123.31703 -162.323667) (xy 123.400532 -162.331639) (xy 123.482897 -162.347513)
			(xy 123.56338 -162.371144) (xy 123.641253 -162.402319) (xy 123.71581 -162.440755) (xy 123.786375 -162.486104)
			(xy 123.85231 -162.537955) (xy 123.913018 -162.595839) (xy 123.913877 -162.59683) (xy 376.471695 -162.59683)
			(xy 376.4757 -162.491081) (xy 376.48769 -162.385938) (xy 376.507599 -162.282003) (xy 376.53531 -162.179871)
			(xy 376.570667 -162.080127) (xy 376.613465 -161.983343) (xy 376.663461 -161.890073) (xy 376.720368 -161.800852)
			(xy 376.783859 -161.716189) (xy 376.853571 -161.636571) (xy 376.929105 -161.562453) (xy 377.010028 -161.49426)
			(xy 377.095877 -161.432382) (xy 377.18616 -161.377175) (xy 377.280359 -161.328953) (xy 377.377936 -161.287993)
			(xy 377.478331 -161.254531) (xy 377.580969 -161.228757) (xy 377.685262 -161.210819) (xy 377.790613 -161.20082)
			(xy 377.896419 -161.198817) (xy 378.002073 -161.204822) (xy 378.10697 -161.218801) (xy 378.21051 -161.240672)
			(xy 378.312099 -161.270312) (xy 378.411156 -161.30755) (xy 378.507113 -161.352172) (xy 378.59942 -161.403924)
			(xy 378.687549 -161.462509) (xy 378.770995 -161.527591) (xy 378.849279 -161.598797) (xy 378.921954 -161.67572)
			(xy 378.988604 -161.75792) (xy 379.048846 -161.844924) (xy 379.102335 -161.936235) (xy 379.148766 -162.03133)
			(xy 379.187871 -162.129664) (xy 379.219428 -162.230675) (xy 379.243255 -162.333782) (xy 379.259216 -162.438396)
			(xy 379.26722 -162.543918) (xy 379.26772 -162.59683) (xy 379.26722 -162.649742) (xy 379.266995 -162.65271)
			(xy 385.808735 -162.65271) (xy 385.81274 -162.546961) (xy 385.82473 -162.441818) (xy 385.844639 -162.337883)
			(xy 385.87235 -162.235751) (xy 385.907707 -162.136007) (xy 385.950505 -162.039223) (xy 386.000501 -161.945953)
			(xy 386.057408 -161.856732) (xy 386.120899 -161.772069) (xy 386.190611 -161.692451) (xy 386.266145 -161.618333)
			(xy 386.347068 -161.55014) (xy 386.432917 -161.488262) (xy 386.5232 -161.433055) (xy 386.617399 -161.384833)
			(xy 386.714976 -161.343873) (xy 386.815371 -161.310411) (xy 386.918009 -161.284637) (xy 387.022302 -161.266699)
			(xy 387.127653 -161.2567) (xy 387.233459 -161.254697) (xy 387.339113 -161.260702) (xy 387.44401 -161.274681)
			(xy 387.54755 -161.296552) (xy 387.649139 -161.326192) (xy 387.748196 -161.36343) (xy 387.844153 -161.408052)
			(xy 387.93646 -161.459804) (xy 388.024589 -161.518389) (xy 388.108035 -161.583471) (xy 388.186319 -161.654677)
			(xy 388.231017 -161.701988) (xy 409.929076 -161.701988) (xy 409.92965 -161.657219) (xy 409.938657 -161.568134)
			(xy 409.956559 -161.480403) (xy 409.983175 -161.394911) (xy 410.000196 -161.3535) (xy 410.00377 -161.343912)
			(xy 410.003765 -161.323466) (xy 410.000196 -161.313876) (xy 409.983153 -161.272472) (xy 409.956521 -161.186983)
			(xy 409.938618 -161.099248) (xy 409.929627 -161.010159) (xy 409.929076 -160.965388) (xy 409.92965 -160.920619)
			(xy 409.938657 -160.831534) (xy 409.956559 -160.743803) (xy 409.983175 -160.658311) (xy 410.000196 -160.6169)
			(xy 410.00377 -160.607312) (xy 410.003765 -160.586866) (xy 410.000196 -160.577276) (xy 409.983153 -160.535872)
			(xy 409.956521 -160.450383) (xy 409.938618 -160.362648) (xy 409.929627 -160.273559) (xy 409.929076 -160.228788)
			(xy 409.929541 -160.187678) (xy 409.93713 -160.105808) (xy 409.952241 -160.024988) (xy 409.974747 -159.945907)
			(xy 410.004454 -159.869241) (xy 410.041109 -159.795643) (xy 410.0844 -159.725742) (xy 410.133957 -159.660134)
			(xy 410.189357 -159.59938) (xy 410.250127 -159.543997) (xy 410.315748 -159.494459) (xy 410.385662 -159.451187)
			(xy 410.45927 -159.414553) (xy 410.535944 -159.384867) (xy 410.615031 -159.362384) (xy 410.695856 -159.347295)
			(xy 410.777728 -159.339729) (xy 410.818838 -159.33928) (xy 410.860442 -159.339755) (xy 410.94329 -159.347487)
			(xy 411.025054 -159.362917) (xy 411.105022 -159.38591) (xy 411.182495 -159.416266) (xy 411.256796 -159.45372)
			(xy 411.292294 -159.475424) (xy 411.301434 -159.480582) (xy 411.322149 -159.483796) (xy 411.342422 -159.478466)
			(xy 411.350968 -159.472376) (xy 411.384591 -159.44642) (xy 411.45597 -159.400364) (xy 411.531414 -159.361321)
			(xy 411.610235 -159.329647) (xy 411.691716 -159.305629) (xy 411.775116 -159.289486) (xy 411.859674 -159.281366)
			(xy 411.902148 -159.28086) (xy 411.902402 -159.28086) (xy 411.943509 -159.281311) (xy 412.025374 -159.288895)
			(xy 412.106189 -159.304) (xy 412.185267 -159.326496) (xy 412.261931 -159.356191) (xy 412.33553 -159.392831)
			(xy 412.405434 -159.436106) (xy 412.471048 -159.485644) (xy 412.531813 -159.541025) (xy 412.587209 -159.601775)
			(xy 412.636764 -159.667376) (xy 412.680057 -159.737269) (xy 412.716716 -159.810858) (xy 412.746431 -159.887515)
			(xy 412.768947 -159.966587) (xy 412.784073 -160.047398) (xy 412.791679 -160.129261) (xy 412.792164 -160.170368)
			(xy 412.791606 -160.215138) (xy 412.782594 -160.304223) (xy 412.764688 -160.391954) (xy 412.738068 -160.477445)
			(xy 412.721044 -160.518856) (xy 412.717498 -160.528452) (xy 412.717487 -160.548889) (xy 412.721044 -160.55848)
			(xy 412.738053 -160.599829) (xy 412.764663 -160.685192) (xy 412.782568 -160.772795) (xy 412.791589 -160.861753)
			(xy 412.792164 -160.90646) (xy 412.792164 -160.907476) (xy 412.79191 -160.918906) (xy 412.818389 -160.924851)
			(xy 412.870624 -160.939594) (xy 412.896304 -160.94837) (xy 412.904501 -160.950884) (xy 412.921635 -160.950884)
			(xy 412.929832 -160.94837) (xy 412.96505 -160.936429) (xy 413.037059 -160.91784) (xy 413.110382 -160.905398)
			(xy 413.184492 -160.899192) (xy 413.221678 -160.89884) (xy 413.258862 -160.899213) (xy 413.33297 -160.905434)
			(xy 413.40629 -160.917875) (xy 413.478301 -160.936448) (xy 413.513524 -160.94837) (xy 413.521721 -160.950884)
			(xy 413.538855 -160.950884) (xy 413.547052 -160.94837) (xy 413.582146 -160.93646) (xy 413.653906 -160.917916)
			(xy 413.726971 -160.905476) (xy 413.800824 -160.899229) (xy 413.837882 -160.89884) (xy 413.838898 -160.89884)
			(xy 413.880822 -160.899407) (xy 413.964291 -160.907377) (xy 414.046623 -160.923245) (xy 414.127075 -160.946868)
			(xy 414.204917 -160.978031) (xy 414.279444 -161.016452) (xy 414.349982 -161.061784) (xy 414.415891 -161.113615)
			(xy 414.476575 -161.171477) (xy 414.531484 -161.234845) (xy 414.580121 -161.303146) (xy 414.622045 -161.37576)
			(xy 414.656876 -161.452031) (xy 414.684301 -161.531268) (xy 414.704068 -161.612752) (xy 414.716001 -161.695747)
			(xy 414.719991 -161.7795) (xy 414.716001 -161.863253) (xy 414.704068 -161.946248) (xy 414.684301 -162.027732)
			(xy 414.656876 -162.106969) (xy 414.622045 -162.18324) (xy 414.580121 -162.255854) (xy 414.531484 -162.324155)
			(xy 414.476575 -162.387523) (xy 414.415891 -162.445385) (xy 414.349982 -162.497216) (xy 414.279444 -162.542548)
			(xy 414.204917 -162.580969) (xy 414.127075 -162.612132) (xy 414.046623 -162.635755) (xy 413.964291 -162.651623)
			(xy 413.880822 -162.659593) (xy 413.838898 -162.660076) (xy 413.837882 -162.660076) (xy 413.800825 -162.659672)
			(xy 413.726976 -162.653407) (xy 413.653913 -162.640964) (xy 413.582153 -162.622432) (xy 413.547052 -162.610546)
			(xy 413.538855 -162.608032) (xy 413.521721 -162.608032) (xy 413.513524 -162.610546) (xy 413.484638 -162.620383)
			(xy 413.425785 -162.636529) (xy 413.395922 -162.642804) (xy 413.386334 -162.645159) (xy 413.369889 -162.656054)
			(xy 413.358796 -162.672367) (xy 413.356298 -162.68192) (xy 413.34617 -162.726275) (xy 413.318046 -162.812805)
			(xy 413.300164 -162.85464) (xy 413.296347 -162.864579) (xy 413.296353 -162.885846) (xy 413.300164 -162.895788)
			(xy 413.318394 -162.938388) (xy 413.346909 -163.026556) (xy 413.366099 -163.117213) (xy 413.375757 -163.209373)
			(xy 413.376364 -163.255706) (xy 413.376364 -163.256214) (xy 413.37586 -163.298562) (xy 413.367809 -163.382876)
			(xy 413.35178 -163.466042) (xy 413.327919 -163.547309) (xy 413.29644 -163.625939) (xy 413.257629 -163.70122)
			(xy 413.230169 -163.74395) (xy 431.840894 -163.74395) (xy 431.840894 -163.68945) (xy 431.84865 -163.635505)
			(xy 431.864004 -163.583213) (xy 431.886644 -163.533639) (xy 431.916109 -163.48779) (xy 431.951798 -163.446602)
			(xy 431.992986 -163.410912) (xy 432.038833 -163.381447) (xy 432.088408 -163.358807) (xy 432.140699 -163.343452)
			(xy 432.194644 -163.335695) (xy 432.221894 -163.335208) (xy 433.212494 -163.335208) (xy 433.239748 -163.335638)
			(xy 433.293702 -163.343395) (xy 433.346003 -163.358751) (xy 433.395586 -163.381394) (xy 433.441442 -163.410863)
			(xy 433.482637 -163.446559) (xy 433.518333 -163.487753) (xy 433.547803 -163.533609) (xy 433.570447 -163.583191)
			(xy 433.585804 -163.635492) (xy 433.593561 -163.689446) (xy 433.593561 -163.743954) (xy 433.585804 -163.797908)
			(xy 433.570447 -163.850209) (xy 433.547803 -163.899791) (xy 433.518333 -163.945647) (xy 433.482637 -163.986841)
			(xy 433.441442 -164.022537) (xy 433.395586 -164.052006) (xy 433.346003 -164.074649) (xy 433.293702 -164.090005)
			(xy 433.239748 -164.097762) (xy 433.212494 -164.098224) (xy 432.221894 -164.098224) (xy 432.194644 -164.097705)
			(xy 432.140699 -164.089948) (xy 432.088408 -164.074593) (xy 432.038833 -164.051953) (xy 431.992986 -164.022488)
			(xy 431.951798 -163.986798) (xy 431.916109 -163.94561) (xy 431.886644 -163.899761) (xy 431.864004 -163.850187)
			(xy 431.84865 -163.797895) (xy 431.840894 -163.74395) (xy 413.230169 -163.74395) (xy 413.211839 -163.772472)
			(xy 413.159483 -163.839048) (xy 413.101035 -163.900346) (xy 413.037025 -163.955811) (xy 412.968033 -164.00494)
			(xy 412.894683 -164.047289) (xy 412.81764 -164.082473) (xy 412.737601 -164.110175) (xy 412.655292 -164.130143)
			(xy 412.571457 -164.142196) (xy 412.486856 -164.146227) (xy 412.402255 -164.142196) (xy 412.31842 -164.130143)
			(xy 412.236111 -164.110175) (xy 412.156072 -164.082473) (xy 412.079029 -164.047289) (xy 412.005679 -164.00494)
			(xy 411.936687 -163.955811) (xy 411.872677 -163.900346) (xy 411.814229 -163.839048) (xy 411.761873 -163.772472)
			(xy 411.716083 -163.70122) (xy 411.677272 -163.625939) (xy 411.645793 -163.547309) (xy 411.621932 -163.466042)
			(xy 411.605903 -163.382876) (xy 411.597852 -163.298562) (xy 411.597348 -163.256214) (xy 411.597348 -163.255706)
			(xy 411.597963 -163.209374) (xy 411.607632 -163.117217) (xy 411.626825 -163.026563) (xy 411.655334 -162.938394)
			(xy 411.673548 -162.895788) (xy 411.677348 -162.885844) (xy 411.677353 -162.864582) (xy 411.673548 -162.85464)
			(xy 411.655311 -162.811974) (xy 411.626764 -162.723684) (xy 411.607569 -162.632899) (xy 411.597934 -162.54061)
			(xy 411.597348 -162.494214) (xy 411.597953 -162.446404) (xy 411.608131 -162.351329) (xy 411.617668 -162.304476)
			(xy 411.61964 -162.292071) (xy 411.612727 -162.267957) (xy 411.60446 -162.258502) (xy 411.56382 -162.216338)
			(xy 411.560264 -162.2171) (xy 411.551416 -162.219411) (xy 411.536053 -162.229303) (xy 411.530292 -162.236404)
			(xy 411.505137 -162.269067) (xy 411.449717 -162.33011) (xy 411.388886 -162.385763) (xy 411.323166 -162.435548)
			(xy 411.253121 -162.479037) (xy 411.179352 -162.515858) (xy 411.102492 -162.545694) (xy 411.023201 -162.56829)
			(xy 410.942159 -162.583451) (xy 410.860062 -162.591047) (xy 410.818838 -162.591496) (xy 410.777733 -162.590951)
			(xy 410.695873 -162.583371) (xy 410.615061 -162.568271) (xy 410.535987 -162.54578) (xy 410.459325 -162.516091)
			(xy 410.385729 -162.479456) (xy 410.315826 -162.436187) (xy 410.250213 -162.386655) (xy 410.18945 -162.331281)
			(xy 410.134053 -162.270538) (xy 410.084497 -162.204943) (xy 410.041203 -162.135056) (xy 410.004541 -162.061473)
			(xy 409.974824 -161.984822) (xy 409.952304 -161.905756) (xy 409.937174 -161.82495) (xy 409.929564 -161.743093)
			(xy 409.929076 -161.701988) (xy 388.231017 -161.701988) (xy 388.258994 -161.7316) (xy 388.325644 -161.8138)
			(xy 388.385886 -161.900804) (xy 388.439375 -161.992115) (xy 388.485806 -162.08721) (xy 388.524911 -162.185544)
			(xy 388.556468 -162.286555) (xy 388.580295 -162.389662) (xy 388.596256 -162.494276) (xy 388.60426 -162.599798)
			(xy 388.60476 -162.65271) (xy 388.60426 -162.705622) (xy 388.596256 -162.811144) (xy 388.580295 -162.915758)
			(xy 388.556468 -163.018865) (xy 388.524911 -163.119876) (xy 388.485806 -163.21821) (xy 388.439375 -163.313305)
			(xy 388.385886 -163.404616) (xy 388.325644 -163.49162) (xy 388.258994 -163.57382) (xy 388.186319 -163.650743)
			(xy 388.108035 -163.721949) (xy 388.024589 -163.787031) (xy 387.93646 -163.845616) (xy 387.844153 -163.897368)
			(xy 387.748196 -163.94199) (xy 387.649139 -163.979228) (xy 387.54755 -164.008868) (xy 387.44401 -164.030739)
			(xy 387.339113 -164.044718) (xy 387.233459 -164.050723) (xy 387.127653 -164.04872) (xy 387.022302 -164.038721)
			(xy 386.918009 -164.020783) (xy 386.815371 -163.995009) (xy 386.714976 -163.961547) (xy 386.617399 -163.920587)
			(xy 386.5232 -163.872365) (xy 386.432917 -163.817158) (xy 386.347068 -163.75528) (xy 386.266145 -163.687087)
			(xy 386.190611 -163.612969) (xy 386.120899 -163.533351) (xy 386.057408 -163.448688) (xy 386.000501 -163.359467)
			(xy 385.950505 -163.266197) (xy 385.907707 -163.169413) (xy 385.87235 -163.069669) (xy 385.844639 -162.967537)
			(xy 385.82473 -162.863602) (xy 385.81274 -162.758459) (xy 385.808735 -162.65271) (xy 379.266995 -162.65271)
			(xy 379.259216 -162.755264) (xy 379.243255 -162.859878) (xy 379.219428 -162.962985) (xy 379.187871 -163.063996)
			(xy 379.148766 -163.16233) (xy 379.102335 -163.257425) (xy 379.048846 -163.348736) (xy 378.988604 -163.43574)
			(xy 378.921954 -163.51794) (xy 378.849279 -163.594863) (xy 378.770995 -163.666069) (xy 378.687549 -163.731151)
			(xy 378.59942 -163.789736) (xy 378.507113 -163.841488) (xy 378.411156 -163.88611) (xy 378.312099 -163.923348)
			(xy 378.21051 -163.952988) (xy 378.10697 -163.974859) (xy 378.002073 -163.988838) (xy 377.896419 -163.994843)
			(xy 377.790613 -163.99284) (xy 377.685262 -163.982841) (xy 377.580969 -163.964903) (xy 377.478331 -163.939129)
			(xy 377.377936 -163.905667) (xy 377.280359 -163.864707) (xy 377.18616 -163.816485) (xy 377.095877 -163.761278)
			(xy 377.010028 -163.6994) (xy 376.929105 -163.631207) (xy 376.853571 -163.557089) (xy 376.783859 -163.477471)
			(xy 376.720368 -163.392808) (xy 376.663461 -163.303587) (xy 376.613465 -163.210317) (xy 376.570667 -163.113533)
			(xy 376.53531 -163.013789) (xy 376.507599 -162.911657) (xy 376.48769 -162.807722) (xy 376.4757 -162.702579)
			(xy 376.471695 -162.59683) (xy 123.913877 -162.59683) (xy 123.967949 -162.659232) (xy 124.016605 -162.727559)
			(xy 124.058546 -162.800202) (xy 124.093391 -162.876503) (xy 124.120826 -162.95577) (xy 124.140602 -163.037287)
			(xy 124.15254 -163.120314) (xy 124.156531 -163.2041) (xy 124.15254 -163.287886) (xy 124.140602 -163.370913)
			(xy 124.120826 -163.45243) (xy 124.093391 -163.531697) (xy 124.058546 -163.607998) (xy 124.016605 -163.680641)
			(xy 123.967949 -163.748968) (xy 123.913018 -163.812361) (xy 123.85231 -163.870245) (xy 123.786375 -163.922096)
			(xy 123.71581 -163.967445) (xy 123.641253 -164.005881) (xy 123.56338 -164.037056) (xy 123.482897 -164.060687)
			(xy 123.400532 -164.076561) (xy 123.31703 -164.084533) (xy 123.27509 -164.085016) (xy 123.2379 -164.084629)
			(xy 123.163787 -164.078339) (xy 123.090468 -164.065828) (xy 123.018462 -164.047187) (xy 122.983244 -164.035232)
			(xy 122.975047 -164.032718) (xy 122.957913 -164.032718) (xy 122.949716 -164.035232) (xy 122.907233 -164.049509)
			(xy 122.820068 -164.070379) (xy 122.775726 -164.076888) (xy 122.765804 -164.078672) (xy 122.748385 -164.088778)
			(xy 122.736231 -164.104835) (xy 122.733308 -164.11448) (xy 122.724748 -164.14638) (xy 122.70352 -164.20893)
			(xy 122.69089 -164.239448) (xy 122.687282 -164.249022) (xy 122.687136 -164.26946) (xy 122.690636 -164.279072)
			(xy 122.707671 -164.320445) (xy 122.734286 -164.405873) (xy 122.752187 -164.493543) (xy 122.756237 -164.53358)
			(xy 365.854996 -164.53358) (xy 365.855358 -164.495263) (xy 365.861892 -164.41891) (xy 365.874978 -164.343403)
			(xy 365.89452 -164.269304) (xy 365.907066 -164.233098) (xy 365.909662 -164.224784) (xy 365.909655 -164.207378)
			(xy 365.907066 -164.199062) (xy 365.894569 -164.162941) (xy 365.875081 -164.089028) (xy 365.861998 -164.013717)
			(xy 365.855418 -163.937561) (xy 365.854996 -163.899342) (xy 365.854996 -163.89858) (xy 365.855448 -163.857477)
			(xy 365.863034 -163.775622) (xy 365.878141 -163.694816) (xy 365.900639 -163.615749) (xy 365.930337 -163.539095)
			(xy 365.966981 -163.465508) (xy 366.010258 -163.395615) (xy 366.059799 -163.330014) (xy 366.115181 -163.269264)
			(xy 366.175933 -163.213883) (xy 366.241535 -163.164344) (xy 366.311429 -163.121069) (xy 366.385017 -163.084427)
			(xy 366.461672 -163.054732) (xy 366.54074 -163.032236) (xy 366.621546 -163.017131) (xy 366.703401 -163.009546)
			(xy 366.744504 -163.009072) (xy 366.745266 -163.009072) (xy 366.783487 -163.009474) (xy 366.859645 -163.01604)
			(xy 366.934958 -163.029126) (xy 367.008868 -163.048635) (xy 367.044986 -163.061142) (xy 367.053302 -163.063728)
			(xy 367.070706 -163.063728) (xy 367.079022 -163.061142) (xy 367.115235 -163.04862) (xy 367.189336 -163.029098)
			(xy 367.26484 -163.016015) (xy 367.341189 -163.009466) (xy 367.379504 -163.009072) (xy 367.419718 -163.009498)
			(xy 367.49982 -163.016721) (xy 367.578942 -163.031153) (xy 367.656435 -163.052677) (xy 367.69421 -163.066476)
			(xy 367.702997 -163.069383) (xy 367.721491 -163.069383) (xy 367.730278 -163.066476) (xy 367.768054 -163.052684)
			(xy 367.845551 -163.031177) (xy 367.924672 -163.016746) (xy 368.004771 -163.00951) (xy 368.044984 -163.009072)
			(xy 368.0833 -163.009446) (xy 368.159653 -163.015977) (xy 368.23516 -163.029059) (xy 368.309259 -163.048598)
			(xy 368.345466 -163.061142) (xy 368.353782 -163.063728) (xy 368.371186 -163.063728) (xy 368.379502 -163.061142)
			(xy 368.415717 -163.048626) (xy 368.489817 -163.029103) (xy 368.565321 -163.016017) (xy 368.641669 -163.009467)
			(xy 368.679984 -163.009072) (xy 368.7183 -163.009446) (xy 368.794653 -163.015977) (xy 368.87016 -163.029059)
			(xy 368.944259 -163.048598) (xy 368.980466 -163.061142) (xy 368.988782 -163.063728) (xy 369.006186 -163.063728)
			(xy 369.014502 -163.061142) (xy 369.050717 -163.048626) (xy 369.124817 -163.029103) (xy 369.200321 -163.016017)
			(xy 369.276669 -163.009467) (xy 369.314984 -163.009072) (xy 369.3533 -163.009446) (xy 369.429653 -163.015977)
			(xy 369.50516 -163.029059) (xy 369.579259 -163.048598) (xy 369.615466 -163.061142) (xy 369.623782 -163.063728)
			(xy 369.641186 -163.063728) (xy 369.649502 -163.061142) (xy 369.685717 -163.048626) (xy 369.759817 -163.029103)
			(xy 369.835321 -163.016017) (xy 369.911669 -163.009467) (xy 369.949984 -163.009072) (xy 369.994754 -163.009635)
			(xy 370.083841 -163.018637) (xy 370.171573 -163.03654) (xy 370.257063 -163.063164) (xy 370.298472 -163.080192)
			(xy 370.308063 -163.083757) (xy 370.328505 -163.083757) (xy 370.338096 -163.080192) (xy 370.379479 -163.063183)
			(xy 370.464904 -163.036561) (xy 370.55257 -163.018653) (xy 370.641592 -163.00964) (xy 370.68633 -163.009072)
			(xy 370.686584 -163.009072) (xy 370.727686 -163.009582) (xy 370.809538 -163.017165) (xy 370.890342 -163.032268)
			(xy 370.969408 -163.054763) (xy 371.046061 -163.084457) (xy 371.119647 -163.121096) (xy 371.189538 -163.16437)
			(xy 371.255139 -163.213907) (xy 371.315889 -163.269286) (xy 371.37127 -163.330033) (xy 371.42081 -163.395632)
			(xy 371.464086 -163.465522) (xy 371.500729 -163.539106) (xy 371.530426 -163.615758) (xy 371.552923 -163.694823)
			(xy 371.56803 -163.775626) (xy 371.575616 -163.857478) (xy 371.576092 -163.89858) (xy 371.576092 -163.899342)
			(xy 371.575679 -163.937562) (xy 371.569116 -164.013721) (xy 371.556033 -164.089033) (xy 371.536527 -164.162943)
			(xy 371.524022 -164.199062) (xy 371.521447 -164.207381) (xy 371.52144 -164.224782) (xy 371.524022 -164.233098)
			(xy 371.536535 -164.269314) (xy 371.55606 -164.343414) (xy 371.569146 -164.418917) (xy 371.575697 -164.495265)
			(xy 371.576092 -164.53358) (xy 371.575734 -164.571323) (xy 371.569392 -164.646543) (xy 371.556692 -164.720953)
			(xy 371.537726 -164.794018) (xy 371.525546 -164.829744) (xy 371.522818 -164.838516) (xy 371.52307 -164.85687)
			(xy 371.526054 -164.865558) (xy 371.541045 -164.904681) (xy 371.564495 -164.985121) (xy 371.58028 -165.067409)
			(xy 371.588259 -165.150817) (xy 371.588792 -165.19271) (xy 371.588792 -165.19398) (xy 371.588329 -165.235083)
			(xy 371.580745 -165.316939) (xy 371.565641 -165.397747) (xy 371.543146 -165.476815) (xy 371.51345 -165.553471)
			(xy 371.476808 -165.62706) (xy 371.433533 -165.696954) (xy 371.383993 -165.762556) (xy 371.328611 -165.823308)
			(xy 371.267859 -165.87869) (xy 371.202257 -165.92823) (xy 371.132363 -165.971506) (xy 371.058775 -166.008149)
			(xy 370.982119 -166.037844) (xy 370.90305 -166.06034) (xy 370.822243 -166.075445) (xy 370.740387 -166.083029)
			(xy 370.699284 -166.083488) (xy 370.69903 -166.083488) (xy 370.654291 -166.082927) (xy 370.56527 -166.07391)
			(xy 370.477602 -166.056003) (xy 370.392175 -166.029387) (xy 370.350796 -166.012368) (xy 370.341205 -166.008803)
			(xy 370.320763 -166.008803) (xy 370.311172 -166.012368) (xy 370.269762 -166.029396) (xy 370.184274 -166.056029)
			(xy 370.096542 -166.073935) (xy 370.007454 -166.082933) (xy 369.962684 -166.083488) (xy 369.924367 -166.083126)
			(xy 369.848014 -166.076592) (xy 369.772507 -166.063506) (xy 369.698408 -166.043964) (xy 369.662202 -166.031418)
			(xy 369.653886 -166.028832) (xy 369.636482 -166.028832) (xy 369.628166 -166.031418) (xy 369.591953 -166.043941)
			(xy 369.517852 -166.063463) (xy 369.442348 -166.076546) (xy 369.365999 -166.083094) (xy 369.327684 -166.083488)
			(xy 369.289367 -166.083126) (xy 369.213014 -166.076592) (xy 369.137507 -166.063506) (xy 369.063408 -166.043964)
			(xy 369.027202 -166.031418) (xy 369.018886 -166.028832) (xy 369.001482 -166.028832) (xy 368.993166 -166.031418)
			(xy 368.956953 -166.043941) (xy 368.882852 -166.063463) (xy 368.807348 -166.076546) (xy 368.730999 -166.083094)
			(xy 368.692684 -166.083488) (xy 368.654367 -166.083126) (xy 368.578014 -166.076592) (xy 368.502507 -166.063506)
			(xy 368.428408 -166.043964) (xy 368.392202 -166.031418) (xy 368.383886 -166.028832) (xy 368.366482 -166.028832)
			(xy 368.358166 -166.031418) (xy 368.321953 -166.043941) (xy 368.247852 -166.063463) (xy 368.172348 -166.076546)
			(xy 368.095999 -166.083094) (xy 368.057684 -166.083488) (xy 368.01747 -166.083062) (xy 367.937368 -166.075838)
			(xy 367.858246 -166.061406) (xy 367.780753 -166.039883) (xy 367.742978 -166.026084) (xy 367.734191 -166.023177)
			(xy 367.715697 -166.023177) (xy 367.70691 -166.026084) (xy 367.669134 -166.039877) (xy 367.591637 -166.061385)
			(xy 367.512517 -166.075815) (xy 367.432417 -166.083051) (xy 367.392204 -166.083488) (xy 367.353888 -166.08312)
			(xy 367.277534 -166.076588) (xy 367.202027 -166.063503) (xy 367.127928 -166.043963) (xy 367.091722 -166.031418)
			(xy 367.083406 -166.028832) (xy 367.066002 -166.028832) (xy 367.057686 -166.031418) (xy 367.021563 -166.043908)
			(xy 366.947651 -166.063398) (xy 366.87234 -166.076483) (xy 366.796185 -166.083065) (xy 366.757966 -166.083488)
			(xy 366.757204 -166.083488) (xy 366.7161 -166.083044) (xy 366.634244 -166.075459) (xy 366.553436 -166.060354)
			(xy 366.474367 -166.037857) (xy 366.397711 -166.00816) (xy 366.324122 -165.971516) (xy 366.254228 -165.928239)
			(xy 366.188625 -165.878698) (xy 366.127874 -165.823315) (xy 366.072492 -165.762562) (xy 366.022951 -165.696959)
			(xy 365.979676 -165.627064) (xy 365.943034 -165.553475) (xy 365.913338 -165.476818) (xy 365.890843 -165.397748)
			(xy 365.875739 -165.316941) (xy 365.868155 -165.235084) (xy 365.867696 -165.19398) (xy 365.867696 -165.192964)
			(xy 365.868115 -165.155349) (xy 365.874496 -165.080389) (xy 365.887191 -165.006237) (xy 365.906111 -164.933424)
			(xy 365.918242 -164.897816) (xy 365.920992 -164.889049) (xy 365.920727 -164.87069) (xy 365.917734 -164.862002)
			(xy 365.902679 -164.822733) (xy 365.879172 -164.741978) (xy 365.863391 -164.659366) (xy 365.855475 -164.575633)
			(xy 365.854996 -164.53358) (xy 122.756237 -164.53358) (xy 122.761192 -164.582567) (xy 122.761756 -164.627306)
			(xy 122.761756 -164.62756) (xy 122.761252 -164.669908) (xy 122.753201 -164.754222) (xy 122.737172 -164.837388)
			(xy 122.713311 -164.918655) (xy 122.681832 -164.997285) (xy 122.643021 -165.072566) (xy 122.597231 -165.143818)
			(xy 122.544875 -165.210394) (xy 122.486427 -165.271692) (xy 122.422417 -165.327157) (xy 122.353425 -165.376286)
			(xy 122.280075 -165.418635) (xy 122.203032 -165.453819) (xy 122.122993 -165.481521) (xy 122.040684 -165.501489)
			(xy 121.956849 -165.513542) (xy 121.872248 -165.517573) (xy 121.787647 -165.513542) (xy 121.703812 -165.501489)
			(xy 121.621503 -165.481521) (xy 121.541464 -165.453819) (xy 121.464421 -165.418635) (xy 121.391071 -165.376286)
			(xy 121.322079 -165.327157) (xy 121.258069 -165.271692) (xy 121.199621 -165.210394) (xy 121.147265 -165.143818)
			(xy 121.101475 -165.072566) (xy 121.062664 -164.997285) (xy 121.031185 -164.918655) (xy 121.007324 -164.837388)
			(xy 120.991295 -164.754222) (xy 120.983244 -164.669908) (xy 120.98274 -164.62756) (xy 120.98274 -164.627306)
			(xy 120.983291 -164.582567) (xy 120.992311 -164.493545) (xy 121.010221 -164.405878) (xy 121.03684 -164.320451)
			(xy 121.05386 -164.279072) (xy 121.057447 -164.269488) (xy 121.057432 -164.249039) (xy 121.05386 -164.239448)
			(xy 121.037012 -164.19848) (xy 121.010567 -164.113931) (xy 120.992664 -164.027171) (xy 120.983478 -163.939061)
			(xy 120.98274 -163.89477) (xy 120.982373 -163.885212) (xy 120.975335 -163.867438) (xy 120.962255 -163.853496)
			(xy 120.953784 -163.84905) (xy 120.870726 -163.809934) (xy 120.861899 -163.806187) (xy 120.842781 -163.804911)
			(xy 120.824539 -163.810771) (xy 120.816878 -163.816538) (xy 120.782853 -163.843559) (xy 120.710459 -163.891613)
			(xy 120.633724 -163.93238) (xy 120.55338 -163.965469) (xy 120.470192 -163.990568) (xy 120.384953 -164.007435)
			(xy 120.298476 -164.01591) (xy 120.25503 -164.016436) (xy 120.213915 -164.015973) (xy 120.132035 -164.008388)
			(xy 120.051204 -163.99328) (xy 119.972113 -163.970779) (xy 119.895435 -163.941075) (xy 119.821825 -163.904423)
			(xy 119.751911 -163.861135) (xy 119.686289 -163.811581) (xy 119.62552 -163.756183) (xy 119.570122 -163.695414)
			(xy 119.520567 -163.629793) (xy 119.477279 -163.559879) (xy 119.440626 -163.486269) (xy 119.410922 -163.409591)
			(xy 119.38842 -163.330499) (xy 119.373312 -163.249669) (xy 119.365727 -163.167789) (xy 119.365268 -163.126674)
			(xy 91.076082 -163.126674) (xy 91.074618 -163.131296) (xy 91.074629 -163.148971) (xy 91.077288 -163.157408)
			(xy 91.089816 -163.193591) (xy 91.109393 -163.267622) (xy 91.122545 -163.34306) (xy 91.129174 -163.419348)
			(xy 91.129612 -163.457636) (xy 91.129114 -163.500412) (xy 91.120898 -163.585569) (xy 91.104536 -163.669543)
			(xy 91.080178 -163.751555) (xy 91.064588 -163.791392) (xy 91.061544 -163.799848) (xy 91.060879 -163.817795)
			(xy 91.063318 -163.826444) (xy 91.07787 -163.871922) (xy 91.098306 -163.9652) (xy 91.108623 -164.060131)
			(xy 91.109292 -164.107876) (xy 91.108825 -164.148987) (xy 91.101239 -164.230857) (xy 91.08613 -164.311679)
			(xy 91.063626 -164.390761) (xy 91.033921 -164.467428) (xy 90.997266 -164.541027) (xy 90.953976 -164.610929)
			(xy 90.904419 -164.676538) (xy 90.849019 -164.737293) (xy 90.788249 -164.792677) (xy 90.722626 -164.842215)
			(xy 90.652712 -164.885486) (xy 90.579103 -164.92212) (xy 90.502427 -164.951804) (xy 90.423339 -164.974286)
			(xy 90.342514 -164.989373) (xy 90.260641 -164.996936) (xy 90.21953 -164.997384) (xy 90.177921 -164.996892)
			(xy 90.095064 -164.989136) (xy 90.013294 -164.97368) (xy 89.933323 -164.950659) (xy 89.89441 -164.935916)
			(xy 89.88572 -164.932926) (xy 89.867362 -164.932654) (xy 89.858596 -164.935408) (xy 89.822497 -164.947854)
			(xy 89.748643 -164.967275) (xy 89.673397 -164.980297) (xy 89.597312 -164.986825) (xy 89.55913 -164.987224)
			(xy 89.520814 -164.986846) (xy 89.444461 -164.980317) (xy 89.368954 -164.967235) (xy 89.294855 -164.947698)
			(xy 89.258648 -164.935154) (xy 89.250332 -164.932568) (xy 89.232928 -164.932568) (xy 89.224612 -164.935154)
			(xy 89.188396 -164.947666) (xy 89.114296 -164.96719) (xy 89.038793 -164.980277) (xy 88.962445 -164.986828)
			(xy 88.92413 -164.987224) (xy 88.885814 -164.986846) (xy 88.809461 -164.980317) (xy 88.733954 -164.967235)
			(xy 88.659855 -164.947698) (xy 88.623648 -164.935154) (xy 88.615332 -164.932568) (xy 88.597928 -164.932568)
			(xy 88.589612 -164.935154) (xy 88.553396 -164.947666) (xy 88.479296 -164.96719) (xy 88.403793 -164.980277)
			(xy 88.327445 -164.986828) (xy 88.28913 -164.987224) (xy 88.250814 -164.986846) (xy 88.174461 -164.980317)
			(xy 88.098954 -164.967235) (xy 88.024855 -164.947698) (xy 87.988648 -164.935154) (xy 87.980332 -164.932568)
			(xy 87.962928 -164.932568) (xy 87.954612 -164.935154) (xy 87.918396 -164.947666) (xy 87.844296 -164.96719)
			(xy 87.768793 -164.980277) (xy 87.692445 -164.986828) (xy 87.65413 -164.987224) (xy 87.615814 -164.986846)
			(xy 87.539461 -164.980317) (xy 87.463954 -164.967235) (xy 87.389855 -164.947698) (xy 87.353648 -164.935154)
			(xy 87.345332 -164.932568) (xy 87.327928 -164.932568) (xy 87.319612 -164.935154) (xy 87.283487 -164.947638)
			(xy 87.209575 -164.96713) (xy 87.134265 -164.980216) (xy 87.058111 -164.9868) (xy 87.019892 -164.987224)
			(xy 87.01913 -164.987224) (xy 86.978023 -164.986759) (xy 86.896158 -164.979177) (xy 86.815342 -164.964075)
			(xy 86.736265 -164.941581) (xy 86.659599 -164.911888) (xy 86.586 -164.875249) (xy 86.516095 -164.831976)
			(xy 86.45048 -164.782438) (xy 86.389716 -164.727058) (xy 86.334319 -164.666309) (xy 86.284763 -164.600708)
			(xy 86.241471 -164.530815) (xy 86.204811 -164.457226) (xy 86.175097 -164.380569) (xy 86.152582 -164.301497)
			(xy 86.137457 -164.220686) (xy 86.129853 -164.138823) (xy 86.129368 -164.097716) (xy 2.509012 -164.097716)
			(xy 2.509012 -166.86276) (xy 61.046868 -166.86276) (xy 61.047433 -166.81799) (xy 61.056443 -166.728905)
			(xy 61.074347 -166.641174) (xy 61.100966 -166.555683) (xy 61.117988 -166.514272) (xy 61.121578 -166.504688)
			(xy 61.121563 -166.484239) (xy 61.117988 -166.474648) (xy 61.100968 -166.433235) (xy 61.074329 -166.347749)
			(xy 61.05642 -166.260018) (xy 61.047422 -166.17093) (xy 61.046868 -166.12616) (xy 61.047433 -166.08139)
			(xy 61.056443 -165.992305) (xy 61.074347 -165.904574) (xy 61.100966 -165.819083) (xy 61.117988 -165.777672)
			(xy 61.121578 -165.768088) (xy 61.121563 -165.747639) (xy 61.117988 -165.738048) (xy 61.100968 -165.696635)
			(xy 61.074329 -165.611149) (xy 61.05642 -165.523418) (xy 61.047422 -165.43433) (xy 61.046868 -165.38956)
			(xy 61.047314 -165.348449) (xy 61.054905 -165.266579) (xy 61.070019 -165.185759) (xy 61.092527 -165.106679)
			(xy 61.122236 -165.030013) (xy 61.158893 -164.956415) (xy 61.202185 -164.886514) (xy 61.251743 -164.820907)
			(xy 61.307144 -164.760153) (xy 61.367915 -164.70477) (xy 61.433537 -164.655232) (xy 61.503451 -164.611961)
			(xy 61.57706 -164.575327) (xy 61.653735 -164.545641) (xy 61.732822 -164.523157) (xy 61.813647 -164.508068)
			(xy 61.895519 -164.500502) (xy 61.93663 -164.500052) (xy 61.978234 -164.500535) (xy 62.061081 -164.508266)
			(xy 62.142846 -164.523695) (xy 62.222813 -164.546687) (xy 62.300286 -164.577041) (xy 62.374588 -164.614493)
			(xy 62.410086 -164.636196) (xy 62.419228 -164.641351) (xy 62.439942 -164.644569) (xy 62.460215 -164.639239)
			(xy 62.46876 -164.633148) (xy 62.502383 -164.607191) (xy 62.573762 -164.561136) (xy 62.649206 -164.522094)
			(xy 62.728027 -164.49042) (xy 62.809509 -164.466402) (xy 62.892908 -164.450259) (xy 62.977466 -164.442138)
			(xy 63.01994 -164.441632) (xy 63.020194 -164.441632) (xy 63.0613 -164.442118) (xy 63.143163 -164.449702)
			(xy 63.223977 -164.464805) (xy 63.303052 -164.487299) (xy 63.379716 -164.516993) (xy 63.453313 -164.553631)
			(xy 63.523217 -164.596903) (xy 63.58883 -164.64644) (xy 63.649594 -164.701818) (xy 63.70499 -164.762565)
			(xy 63.754546 -164.828164) (xy 63.797839 -164.898054) (xy 63.8345 -164.971641) (xy 63.864216 -165.048295)
			(xy 63.886734 -165.127364) (xy 63.901861 -165.208173) (xy 63.909469 -165.290034) (xy 63.909956 -165.33114)
			(xy 63.909389 -165.375909) (xy 63.900379 -165.464994) (xy 63.882475 -165.552725) (xy 63.855858 -165.638217)
			(xy 63.838836 -165.679628) (xy 63.83525 -165.689212) (xy 63.835264 -165.709661) (xy 63.838836 -165.719252)
			(xy 63.855836 -165.760605) (xy 63.882448 -165.845966) (xy 63.900356 -165.933568) (xy 63.903248 -165.962076)
			(xy 81.591411 -165.962076) (xy 81.595416 -165.856327) (xy 81.607406 -165.751184) (xy 81.627315 -165.647249)
			(xy 81.655026 -165.545117) (xy 81.690383 -165.445373) (xy 81.733181 -165.348589) (xy 81.783177 -165.255319)
			(xy 81.840084 -165.166098) (xy 81.903575 -165.081435) (xy 81.973287 -165.001817) (xy 82.048821 -164.927699)
			(xy 82.129744 -164.859506) (xy 82.215593 -164.797628) (xy 82.305876 -164.742421) (xy 82.400075 -164.694199)
			(xy 82.497652 -164.653239) (xy 82.598047 -164.619777) (xy 82.700685 -164.594003) (xy 82.804978 -164.576065)
			(xy 82.910329 -164.566066) (xy 83.016135 -164.564063) (xy 83.121789 -164.570068) (xy 83.226686 -164.584047)
			(xy 83.330226 -164.605918) (xy 83.431815 -164.635558) (xy 83.530872 -164.672796) (xy 83.626829 -164.717418)
			(xy 83.719136 -164.76917) (xy 83.807265 -164.827755) (xy 83.890711 -164.892837) (xy 83.968995 -164.964043)
			(xy 84.04167 -165.040966) (xy 84.10832 -165.123166) (xy 84.168562 -165.21017) (xy 84.222051 -165.301481)
			(xy 84.268482 -165.396576) (xy 84.307587 -165.49491) (xy 84.339144 -165.595921) (xy 84.362971 -165.699028)
			(xy 84.378932 -165.803642) (xy 84.386936 -165.909164) (xy 84.387436 -165.962076) (xy 90.989411 -165.962076)
			(xy 90.993416 -165.856327) (xy 91.005406 -165.751184) (xy 91.025315 -165.647249) (xy 91.053026 -165.545117)
			(xy 91.088383 -165.445373) (xy 91.131181 -165.348589) (xy 91.181177 -165.255319) (xy 91.238084 -165.166098)
			(xy 91.301575 -165.081435) (xy 91.371287 -165.001817) (xy 91.446821 -164.927699) (xy 91.527744 -164.859506)
			(xy 91.613593 -164.797628) (xy 91.703876 -164.742421) (xy 91.798075 -164.694199) (xy 91.895652 -164.653239)
			(xy 91.996047 -164.619777) (xy 92.098685 -164.594003) (xy 92.202978 -164.576065) (xy 92.308329 -164.566066)
			(xy 92.414135 -164.564063) (xy 92.519789 -164.570068) (xy 92.624686 -164.584047) (xy 92.728226 -164.605918)
			(xy 92.829815 -164.635558) (xy 92.928872 -164.672796) (xy 93.024829 -164.717418) (xy 93.117136 -164.76917)
			(xy 93.205265 -164.827755) (xy 93.288711 -164.892837) (xy 93.366995 -164.964043) (xy 93.43967 -165.040966)
			(xy 93.50632 -165.123166) (xy 93.566562 -165.21017) (xy 93.620051 -165.301481) (xy 93.666482 -165.396576)
			(xy 93.705587 -165.49491) (xy 93.737144 -165.595921) (xy 93.760971 -165.699028) (xy 93.776932 -165.803642)
			(xy 93.784936 -165.909164) (xy 93.785436 -165.962076) (xy 93.784936 -166.014988) (xy 93.776932 -166.12051)
			(xy 93.760971 -166.225124) (xy 93.737144 -166.328231) (xy 93.705587 -166.429242) (xy 93.666482 -166.527576)
			(xy 93.620051 -166.622671) (xy 93.566562 -166.713982) (xy 93.50632 -166.800986) (xy 93.43967 -166.883186)
			(xy 93.366995 -166.960109) (xy 93.288711 -167.031315) (xy 93.205265 -167.096397) (xy 93.117136 -167.154982)
			(xy 93.024829 -167.206734) (xy 92.928872 -167.251356) (xy 92.829815 -167.288594) (xy 92.728226 -167.318234)
			(xy 92.624686 -167.340105) (xy 92.519789 -167.354084) (xy 92.414135 -167.360089) (xy 92.308329 -167.358086)
			(xy 92.202978 -167.348087) (xy 92.098685 -167.330149) (xy 91.996047 -167.304375) (xy 91.895652 -167.270913)
			(xy 91.798075 -167.229953) (xy 91.703876 -167.181731) (xy 91.613593 -167.126524) (xy 91.527744 -167.064646)
			(xy 91.446821 -166.996453) (xy 91.371287 -166.922335) (xy 91.301575 -166.842717) (xy 91.238084 -166.758054)
			(xy 91.181177 -166.668833) (xy 91.131181 -166.575563) (xy 91.088383 -166.478779) (xy 91.053026 -166.379035)
			(xy 91.025315 -166.276903) (xy 91.005406 -166.172968) (xy 90.993416 -166.067825) (xy 90.989411 -165.962076)
			(xy 84.387436 -165.962076) (xy 84.386936 -166.014988) (xy 84.378932 -166.12051) (xy 84.362971 -166.225124)
			(xy 84.339144 -166.328231) (xy 84.307587 -166.429242) (xy 84.268482 -166.527576) (xy 84.222051 -166.622671)
			(xy 84.168562 -166.713982) (xy 84.10832 -166.800986) (xy 84.04167 -166.883186) (xy 83.968995 -166.960109)
			(xy 83.890711 -167.031315) (xy 83.807265 -167.096397) (xy 83.719136 -167.154982) (xy 83.626829 -167.206734)
			(xy 83.530872 -167.251356) (xy 83.431815 -167.288594) (xy 83.330226 -167.318234) (xy 83.226686 -167.340105)
			(xy 83.121789 -167.354084) (xy 83.016135 -167.360089) (xy 82.910329 -167.358086) (xy 82.804978 -167.348087)
			(xy 82.700685 -167.330149) (xy 82.598047 -167.304375) (xy 82.497652 -167.270913) (xy 82.400075 -167.229953)
			(xy 82.305876 -167.181731) (xy 82.215593 -167.126524) (xy 82.129744 -167.064646) (xy 82.048821 -166.996453)
			(xy 81.973287 -166.922335) (xy 81.903575 -166.842717) (xy 81.840084 -166.758054) (xy 81.783177 -166.668833)
			(xy 81.733181 -166.575563) (xy 81.690383 -166.478779) (xy 81.655026 -166.379035) (xy 81.627315 -166.276903)
			(xy 81.607406 -166.172968) (xy 81.595416 -166.067825) (xy 81.591411 -165.962076) (xy 63.903248 -165.962076)
			(xy 63.909379 -166.022525) (xy 63.909956 -166.067232) (xy 63.909956 -166.068248) (xy 63.909702 -166.079678)
			(xy 63.936181 -166.085625) (xy 63.988416 -166.100367) (xy 64.014096 -166.109142) (xy 64.022293 -166.111656)
			(xy 64.039427 -166.111656) (xy 64.047624 -166.109142) (xy 64.082842 -166.097202) (xy 64.154852 -166.078613)
			(xy 64.228174 -166.066171) (xy 64.302285 -166.059965) (xy 64.33947 -166.059612) (xy 64.376654 -166.059989)
			(xy 64.450761 -166.066209) (xy 64.524081 -166.078649) (xy 64.596093 -166.097221) (xy 64.631316 -166.109142)
			(xy 64.639513 -166.111656) (xy 64.656647 -166.111656) (xy 64.664844 -166.109142) (xy 64.699939 -166.097233)
			(xy 64.771698 -166.078689) (xy 64.844763 -166.066249) (xy 64.918616 -166.060001) (xy 64.955674 -166.059612)
			(xy 64.95669 -166.059612) (xy 64.998618 -166.060035) (xy 65.082094 -166.068005) (xy 65.164434 -166.083874)
			(xy 65.244893 -166.107498) (xy 65.322742 -166.138663) (xy 65.397276 -166.177087) (xy 65.46782 -166.222422)
			(xy 65.533735 -166.274258) (xy 65.594424 -166.332124) (xy 65.649338 -166.395498) (xy 65.69798 -166.463804)
			(xy 65.739908 -166.536425) (xy 65.774743 -166.612703) (xy 65.802169 -166.691946) (xy 65.821939 -166.773438)
			(xy 65.833873 -166.85644) (xy 65.837863 -166.9402) (xy 65.833873 -167.02396) (xy 65.821939 -167.106962)
			(xy 65.802169 -167.188454) (xy 65.774743 -167.267697) (xy 65.739908 -167.343975) (xy 65.69798 -167.416596)
			(xy 65.688295 -167.430196) (xy 351.432876 -167.430196) (xy 351.433453 -167.385427) (xy 351.442459 -167.296342)
			(xy 351.46036 -167.208611) (xy 351.486975 -167.123119) (xy 351.503996 -167.081708) (xy 351.507565 -167.072118)
			(xy 351.507564 -167.051674) (xy 351.503996 -167.042084) (xy 351.486956 -167.000679) (xy 351.460322 -166.91519)
			(xy 351.442419 -166.827456) (xy 351.433427 -166.738367) (xy 351.432876 -166.693596) (xy 351.433453 -166.648827)
			(xy 351.442459 -166.559742) (xy 351.46036 -166.472011) (xy 351.486975 -166.386519) (xy 351.503996 -166.345108)
			(xy 351.507565 -166.335518) (xy 351.507564 -166.315074) (xy 351.503996 -166.305484) (xy 351.486956 -166.264079)
			(xy 351.460322 -166.17859) (xy 351.442419 -166.090856) (xy 351.433427 -166.001767) (xy 351.432876 -165.956996)
			(xy 351.433349 -165.915886) (xy 351.440937 -165.834016) (xy 351.456047 -165.753196) (xy 351.478552 -165.674116)
			(xy 351.508259 -165.597449) (xy 351.544914 -165.523852) (xy 351.588204 -165.453951) (xy 351.63776 -165.388343)
			(xy 351.693159 -165.327588) (xy 351.753929 -165.272205) (xy 351.81955 -165.222667) (xy 351.889463 -165.179396)
			(xy 351.963071 -165.142761) (xy 352.039745 -165.113075) (xy 352.118832 -165.090592) (xy 352.199656 -165.075503)
			(xy 352.281528 -165.067937) (xy 352.322638 -165.067488) (xy 352.364242 -165.067962) (xy 352.44709 -165.075694)
			(xy 352.528855 -165.091124) (xy 352.608822 -165.114117) (xy 352.686295 -165.144474) (xy 352.760597 -165.181928)
			(xy 352.796094 -165.203632) (xy 352.805234 -165.208789) (xy 352.825949 -165.212002) (xy 352.846222 -165.206673)
			(xy 352.854768 -165.200584) (xy 352.888392 -165.174629) (xy 352.959771 -165.128573) (xy 353.035214 -165.08953)
			(xy 353.114035 -165.057855) (xy 353.195516 -165.033837) (xy 353.278916 -165.017694) (xy 353.363474 -165.009574)
			(xy 353.405948 -165.009068) (xy 353.406202 -165.009068) (xy 353.44731 -165.009511) (xy 353.529174 -165.017096)
			(xy 353.60999 -165.0322) (xy 353.689068 -165.054696) (xy 353.765733 -165.084391) (xy 353.839332 -165.121033)
			(xy 353.909237 -165.164307) (xy 353.974851 -165.213846) (xy 354.035616 -165.269227) (xy 354.091012 -165.329978)
			(xy 354.140567 -165.39558) (xy 354.183859 -165.465474) (xy 354.220519 -165.539063) (xy 354.250233 -165.615721)
			(xy 354.272749 -165.694793) (xy 354.287874 -165.775606) (xy 354.295479 -165.857468) (xy 354.295964 -165.898576)
			(xy 354.295409 -165.943346) (xy 354.286396 -166.032431) (xy 354.268489 -166.120162) (xy 354.241868 -166.205653)
			(xy 354.224844 -166.247064) (xy 354.221294 -166.256659) (xy 354.221285 -166.277097) (xy 354.224844 -166.286688)
			(xy 354.241856 -166.328036) (xy 354.268465 -166.413399) (xy 354.286369 -166.501003) (xy 354.289105 -166.527988)
			(xy 401.547076 -166.527988) (xy 401.54765 -166.483219) (xy 401.556657 -166.394134) (xy 401.574559 -166.306403)
			(xy 401.601175 -166.220911) (xy 401.618196 -166.1795) (xy 401.62177 -166.169912) (xy 401.621765 -166.149466)
			(xy 401.618196 -166.139876) (xy 401.601153 -166.098472) (xy 401.574521 -166.012983) (xy 401.556618 -165.925248)
			(xy 401.547627 -165.836159) (xy 401.547076 -165.791388) (xy 401.54765 -165.746619) (xy 401.556657 -165.657534)
			(xy 401.574559 -165.569803) (xy 401.601175 -165.484311) (xy 401.618196 -165.4429) (xy 401.62177 -165.433312)
			(xy 401.621765 -165.412866) (xy 401.618196 -165.403276) (xy 401.601153 -165.361872) (xy 401.574521 -165.276383)
			(xy 401.556618 -165.188648) (xy 401.547627 -165.099559) (xy 401.547076 -165.054788) (xy 401.547541 -165.013678)
			(xy 401.55513 -164.931808) (xy 401.570241 -164.850988) (xy 401.592747 -164.771907) (xy 401.622454 -164.695241)
			(xy 401.659109 -164.621643) (xy 401.7024 -164.551742) (xy 401.751957 -164.486134) (xy 401.807357 -164.42538)
			(xy 401.868127 -164.369997) (xy 401.933748 -164.320459) (xy 402.003662 -164.277187) (xy 402.07727 -164.240553)
			(xy 402.153944 -164.210867) (xy 402.233031 -164.188384) (xy 402.313856 -164.173295) (xy 402.395728 -164.165729)
			(xy 402.436838 -164.16528) (xy 402.478442 -164.165755) (xy 402.56129 -164.173487) (xy 402.643054 -164.188917)
			(xy 402.723022 -164.21191) (xy 402.800495 -164.242266) (xy 402.874796 -164.27972) (xy 402.910294 -164.301424)
			(xy 402.919434 -164.306582) (xy 402.940149 -164.309796) (xy 402.960422 -164.304466) (xy 402.968968 -164.298376)
			(xy 403.002591 -164.27242) (xy 403.07397 -164.226364) (xy 403.149414 -164.187321) (xy 403.228235 -164.155647)
			(xy 403.309716 -164.131629) (xy 403.393116 -164.115486) (xy 403.477674 -164.107366) (xy 403.520148 -164.10686)
			(xy 403.520402 -164.10686) (xy 403.561509 -164.107311) (xy 403.643374 -164.114895) (xy 403.724189 -164.13)
			(xy 403.803267 -164.152496) (xy 403.879931 -164.182191) (xy 403.95353 -164.218831) (xy 404.023434 -164.262106)
			(xy 404.089048 -164.311644) (xy 404.149813 -164.367025) (xy 404.205209 -164.427775) (xy 404.254764 -164.493376)
			(xy 404.298057 -164.563269) (xy 404.334716 -164.636858) (xy 404.364431 -164.713515) (xy 404.386947 -164.792587)
			(xy 404.402073 -164.873398) (xy 404.409679 -164.955261) (xy 404.410164 -164.996368) (xy 404.409606 -165.041138)
			(xy 404.400594 -165.130223) (xy 404.382688 -165.217954) (xy 404.356068 -165.303445) (xy 404.339044 -165.344856)
			(xy 404.335498 -165.354452) (xy 404.335487 -165.374889) (xy 404.339044 -165.38448) (xy 404.356053 -165.425829)
			(xy 404.382663 -165.511192) (xy 404.400568 -165.598795) (xy 404.409589 -165.687753) (xy 404.410164 -165.73246)
			(xy 404.410164 -165.733476) (xy 404.40991 -165.744906) (xy 404.436389 -165.750851) (xy 404.488624 -165.765594)
			(xy 404.514304 -165.77437) (xy 404.522501 -165.776884) (xy 404.539635 -165.776884) (xy 404.547832 -165.77437)
			(xy 404.58305 -165.762429) (xy 404.655059 -165.74384) (xy 404.728382 -165.731398) (xy 404.802492 -165.725192)
			(xy 404.839678 -165.72484) (xy 404.876862 -165.725213) (xy 404.95097 -165.731434) (xy 405.02429 -165.743875)
			(xy 405.096301 -165.762448) (xy 405.131524 -165.77437) (xy 405.139721 -165.776884) (xy 405.156855 -165.776884)
			(xy 405.165052 -165.77437) (xy 405.200146 -165.76246) (xy 405.271906 -165.743916) (xy 405.344971 -165.731476)
			(xy 405.418824 -165.725229) (xy 405.455882 -165.72484) (xy 405.456898 -165.72484) (xy 405.498822 -165.725407)
			(xy 405.582291 -165.733377) (xy 405.664623 -165.749245) (xy 405.745075 -165.772868) (xy 405.822917 -165.804031)
			(xy 405.897444 -165.842452) (xy 405.967982 -165.887784) (xy 406.033891 -165.939615) (xy 406.094575 -165.997477)
			(xy 406.149484 -166.060845) (xy 406.198121 -166.129146) (xy 406.240045 -166.20176) (xy 406.274876 -166.278031)
			(xy 406.302301 -166.357268) (xy 406.322068 -166.438752) (xy 406.334001 -166.521747) (xy 406.337991 -166.6055)
			(xy 406.334001 -166.689253) (xy 406.322068 -166.772248) (xy 406.302301 -166.853732) (xy 406.274876 -166.932969)
			(xy 406.240045 -167.00924) (xy 406.198121 -167.081854) (xy 406.149484 -167.150155) (xy 406.094575 -167.213523)
			(xy 406.033891 -167.271385) (xy 405.967982 -167.323216) (xy 405.897444 -167.368548) (xy 405.822917 -167.406969)
			(xy 405.745075 -167.438132) (xy 405.664623 -167.461755) (xy 405.582291 -167.477623) (xy 405.498822 -167.485593)
			(xy 405.456898 -167.486076) (xy 405.455882 -167.486076) (xy 405.418825 -167.485672) (xy 405.344976 -167.479407)
			(xy 405.271913 -167.466964) (xy 405.200153 -167.448432) (xy 405.165052 -167.436546) (xy 405.156855 -167.434032)
			(xy 405.139721 -167.434032) (xy 405.131524 -167.436546) (xy 405.102638 -167.446383) (xy 405.043785 -167.462529)
			(xy 405.013922 -167.468804) (xy 405.004334 -167.471159) (xy 404.987889 -167.482054) (xy 404.976796 -167.498367)
			(xy 404.974298 -167.50792) (xy 404.96417 -167.552275) (xy 404.936046 -167.638805) (xy 404.918164 -167.68064)
			(xy 404.914347 -167.690579) (xy 404.914353 -167.711846) (xy 404.918164 -167.721788) (xy 404.936394 -167.764388)
			(xy 404.964909 -167.852556) (xy 404.984099 -167.943213) (xy 404.993757 -168.035373) (xy 404.994364 -168.081706)
			(xy 404.994364 -168.082214) (xy 404.99386 -168.124562) (xy 404.985809 -168.208876) (xy 404.96978 -168.292042)
			(xy 404.945919 -168.373309) (xy 404.91444 -168.451939) (xy 404.875629 -168.52722) (xy 404.829839 -168.598472)
			(xy 404.777483 -168.665048) (xy 404.719035 -168.726346) (xy 404.655025 -168.781811) (xy 404.586033 -168.83094)
			(xy 404.512683 -168.873289) (xy 404.43564 -168.908473) (xy 404.355601 -168.936175) (xy 404.273292 -168.956143)
			(xy 404.189457 -168.968196) (xy 404.104856 -168.972227) (xy 404.020255 -168.968196) (xy 403.93642 -168.956143)
			(xy 403.854111 -168.936175) (xy 403.774072 -168.908473) (xy 403.697029 -168.873289) (xy 403.623679 -168.83094)
			(xy 403.554687 -168.781811) (xy 403.490677 -168.726346) (xy 403.432229 -168.665048) (xy 403.379873 -168.598472)
			(xy 403.334083 -168.52722) (xy 403.295272 -168.451939) (xy 403.263793 -168.373309) (xy 403.239932 -168.292042)
			(xy 403.223903 -168.208876) (xy 403.215852 -168.124562) (xy 403.215348 -168.082214) (xy 403.215348 -168.081706)
			(xy 403.215963 -168.035374) (xy 403.225632 -167.943217) (xy 403.244825 -167.852563) (xy 403.273334 -167.764394)
			(xy 403.291548 -167.721788) (xy 403.295348 -167.711844) (xy 403.295353 -167.690582) (xy 403.291548 -167.68064)
			(xy 403.273311 -167.637974) (xy 403.244764 -167.549684) (xy 403.225569 -167.458899) (xy 403.215934 -167.36661)
			(xy 403.215348 -167.320214) (xy 403.215953 -167.272404) (xy 403.226131 -167.177329) (xy 403.235668 -167.130476)
			(xy 403.23764 -167.118071) (xy 403.230727 -167.093957) (xy 403.22246 -167.084502) (xy 403.18182 -167.042338)
			(xy 403.178264 -167.0431) (xy 403.169416 -167.045411) (xy 403.154053 -167.055303) (xy 403.148292 -167.062404)
			(xy 403.123137 -167.095067) (xy 403.067717 -167.15611) (xy 403.006886 -167.211763) (xy 402.941166 -167.261548)
			(xy 402.871121 -167.305037) (xy 402.797352 -167.341858) (xy 402.720492 -167.371694) (xy 402.641201 -167.39429)
			(xy 402.560159 -167.409451) (xy 402.478062 -167.417047) (xy 402.436838 -167.417496) (xy 402.395733 -167.416951)
			(xy 402.313873 -167.409371) (xy 402.233061 -167.394271) (xy 402.153987 -167.37178) (xy 402.077325 -167.342091)
			(xy 402.003729 -167.305456) (xy 401.933826 -167.262187) (xy 401.868213 -167.212655) (xy 401.80745 -167.157281)
			(xy 401.752053 -167.096538) (xy 401.702497 -167.030943) (xy 401.659203 -166.961056) (xy 401.622541 -166.887473)
			(xy 401.592824 -166.810822) (xy 401.570304 -166.731756) (xy 401.555174 -166.65095) (xy 401.547564 -166.569093)
			(xy 401.547076 -166.527988) (xy 354.289105 -166.527988) (xy 354.295389 -166.589961) (xy 354.295964 -166.634668)
			(xy 354.295964 -166.635684) (xy 354.29571 -166.647114) (xy 354.322189 -166.653059) (xy 354.374424 -166.667802)
			(xy 354.400104 -166.676578) (xy 354.408301 -166.679092) (xy 354.425435 -166.679092) (xy 354.433632 -166.676578)
			(xy 354.468848 -166.664633) (xy 354.540859 -166.646046) (xy 354.614181 -166.633606) (xy 354.688292 -166.6274)
			(xy 354.725478 -166.627048) (xy 354.762662 -166.62742) (xy 354.83677 -166.633641) (xy 354.91009 -166.646083)
			(xy 354.982101 -166.664656) (xy 355.017324 -166.676578) (xy 355.025521 -166.679092) (xy 355.042655 -166.679092)
			(xy 355.050852 -166.676578) (xy 355.085946 -166.664669) (xy 355.157706 -166.646124) (xy 355.230771 -166.633684)
			(xy 355.304624 -166.627437) (xy 355.341682 -166.627048) (xy 355.342698 -166.627048) (xy 355.384622 -166.627599)
			(xy 355.468092 -166.635569) (xy 355.550425 -166.651437) (xy 355.630878 -166.67506) (xy 355.70872 -166.706224)
			(xy 355.783248 -166.744645) (xy 355.853787 -166.789977) (xy 355.919696 -166.841809) (xy 355.980381 -166.899671)
			(xy 356.03529 -166.96304) (xy 356.083927 -167.031341) (xy 356.125852 -167.103957) (xy 356.160684 -167.180228)
			(xy 356.188108 -167.259465) (xy 356.207876 -167.340951) (xy 356.219809 -167.423946) (xy 356.223799 -167.5077)
			(xy 356.219809 -167.591454) (xy 356.207876 -167.674449) (xy 356.188108 -167.755935) (xy 356.160684 -167.835172)
			(xy 356.125852 -167.911443) (xy 356.083927 -167.984059) (xy 356.03529 -168.05236) (xy 355.980381 -168.115729)
			(xy 355.919696 -168.173591) (xy 355.853787 -168.225423) (xy 355.783248 -168.270755) (xy 355.70872 -168.309176)
			(xy 355.630878 -168.34034) (xy 355.550425 -168.363963) (xy 355.468092 -168.379831) (xy 355.384622 -168.387801)
			(xy 355.342698 -168.388284) (xy 355.341682 -168.388284) (xy 355.304625 -168.387885) (xy 355.230776 -168.381619)
			(xy 355.157713 -168.369175) (xy 355.085953 -168.350641) (xy 355.050852 -168.338754) (xy 355.042655 -168.33624)
			(xy 355.025521 -168.33624) (xy 355.017324 -168.338754) (xy 354.989546 -168.348208) (xy 354.932984 -168.363843)
			(xy 354.904294 -168.369996) (xy 354.894532 -168.372423) (xy 354.877923 -168.383747) (xy 354.866932 -168.400579)
			(xy 354.86467 -168.410382) (xy 354.855142 -168.457509) (xy 354.827269 -168.549532) (xy 354.809044 -168.594024)
			(xy 354.805459 -168.603609) (xy 354.805473 -168.624057) (xy 354.809044 -168.633648) (xy 354.826071 -168.675024)
			(xy 354.852688 -168.760451) (xy 354.870591 -168.84812) (xy 354.879599 -168.937143) (xy 354.880164 -168.981882)
			(xy 354.880164 -168.982136) (xy 354.87966 -169.024484) (xy 354.871609 -169.108798) (xy 354.85558 -169.191964)
			(xy 354.831719 -169.273231) (xy 354.80024 -169.351861) (xy 354.761429 -169.427142) (xy 354.715639 -169.498394)
			(xy 354.663283 -169.56497) (xy 354.604835 -169.626268) (xy 354.540825 -169.681733) (xy 354.471833 -169.730862)
			(xy 354.398483 -169.773211) (xy 354.32144 -169.808395) (xy 354.241401 -169.836097) (xy 354.159092 -169.856065)
			(xy 354.075257 -169.868118) (xy 353.990656 -169.872149) (xy 353.906055 -169.868118) (xy 353.82222 -169.856065)
			(xy 353.739911 -169.836097) (xy 353.659872 -169.808395) (xy 353.582829 -169.773211) (xy 353.509479 -169.730862)
			(xy 353.440487 -169.681733) (xy 353.376477 -169.626268) (xy 353.318029 -169.56497) (xy 353.265673 -169.498394)
			(xy 353.219883 -169.427142) (xy 353.181072 -169.351861) (xy 353.149593 -169.273231) (xy 353.125732 -169.191964)
			(xy 353.109703 -169.108798) (xy 353.101652 -169.024484) (xy 353.101148 -168.982136) (xy 353.101148 -168.981882)
			(xy 353.101731 -168.937144) (xy 353.110743 -168.848123) (xy 353.128644 -168.760456) (xy 353.155252 -168.675028)
			(xy 353.172268 -168.633648) (xy 353.175811 -168.624051) (xy 353.175824 -168.603615) (xy 353.172268 -168.594024)
			(xy 353.155227 -168.55262) (xy 353.128597 -168.46713) (xy 353.110694 -168.379396) (xy 353.1017 -168.290307)
			(xy 353.101148 -168.245536) (xy 353.10149 -168.209754) (xy 353.107197 -168.138419) (xy 353.118619 -168.067773)
			(xy 353.126802 -168.032938) (xy 353.128529 -168.024629) (xy 353.126997 -168.007741) (xy 353.119979 -167.992303)
			(xy 353.114356 -167.985948) (xy 353.07397 -167.943276) (xy 353.064064 -167.945308) (xy 353.055164 -167.947623)
			(xy 353.039671 -167.957504) (xy 353.033838 -167.964612) (xy 353.008691 -167.997264) (xy 352.953283 -168.058281)
			(xy 352.892469 -168.113912) (xy 352.826771 -168.163681) (xy 352.756752 -168.207161) (xy 352.683013 -168.243979)
			(xy 352.606184 -168.273821) (xy 352.526925 -168.29643) (xy 352.445915 -168.311612) (xy 352.363848 -168.319237)
			(xy 352.322638 -168.319704) (xy 352.281533 -168.319151) (xy 352.199674 -168.311571) (xy 352.118862 -168.296471)
			(xy 352.039789 -168.273981) (xy 351.963127 -168.244292) (xy 351.889531 -168.207657) (xy 351.819629 -168.164389)
			(xy 351.754016 -168.114857) (xy 351.693252 -168.059484) (xy 351.637856 -167.998741) (xy 351.5883 -167.933147)
			(xy 351.545006 -167.863261) (xy 351.508343 -167.789678) (xy 351.478626 -167.713028) (xy 351.456106 -167.633963)
			(xy 351.440975 -167.553157) (xy 351.433364 -167.471301) (xy 351.432876 -167.430196) (xy 65.688295 -167.430196)
			(xy 65.649338 -167.484902) (xy 65.594424 -167.548276) (xy 65.533735 -167.606142) (xy 65.46782 -167.657978)
			(xy 65.397276 -167.703313) (xy 65.322742 -167.741737) (xy 65.244893 -167.772902) (xy 65.164434 -167.796526)
			(xy 65.082094 -167.812395) (xy 64.998618 -167.820365) (xy 64.95669 -167.820848) (xy 64.955674 -167.820848)
			(xy 64.918617 -167.820448) (xy 64.844768 -167.814181) (xy 64.771705 -167.801738) (xy 64.699945 -167.783204)
			(xy 64.664844 -167.771318) (xy 64.656647 -167.768804) (xy 64.639513 -167.768804) (xy 64.631316 -167.771318)
			(xy 64.597889 -167.782662) (xy 64.529607 -167.80059) (xy 64.494918 -167.807132) (xy 64.484907 -167.809437)
			(xy 64.467748 -167.820693) (xy 64.456372 -167.837772) (xy 64.454024 -167.847772) (xy 64.44452 -167.895628)
			(xy 64.416383 -167.989057) (xy 64.39789 -168.034208) (xy 64.394248 -168.043772) (xy 64.394124 -168.064219)
			(xy 64.397636 -168.073832) (xy 64.414658 -168.11521) (xy 64.441276 -168.200636) (xy 64.459181 -168.288304)
			(xy 64.46819 -168.377327) (xy 64.468756 -168.422066) (xy 64.468756 -168.42232) (xy 64.468252 -168.464668)
			(xy 64.460201 -168.548982) (xy 64.444172 -168.632148) (xy 64.420311 -168.713415) (xy 64.388832 -168.792045)
			(xy 64.350021 -168.867326) (xy 64.304231 -168.938578) (xy 64.251875 -169.005154) (xy 64.193427 -169.066452)
			(xy 64.129417 -169.121917) (xy 64.060425 -169.171046) (xy 63.987075 -169.213395) (xy 63.910032 -169.248579)
			(xy 63.829993 -169.276281) (xy 63.747684 -169.296249) (xy 63.663849 -169.308302) (xy 63.579248 -169.312333)
			(xy 63.494647 -169.308302) (xy 63.410812 -169.296249) (xy 63.328503 -169.276281) (xy 63.248464 -169.248579)
			(xy 63.171421 -169.213395) (xy 63.098071 -169.171046) (xy 63.029079 -169.121917) (xy 62.965069 -169.066452)
			(xy 62.906621 -169.005154) (xy 62.854265 -168.938578) (xy 62.808475 -168.867326) (xy 62.769664 -168.792045)
			(xy 62.738185 -168.713415) (xy 62.714324 -168.632148) (xy 62.698295 -168.548982) (xy 62.690244 -168.464668)
			(xy 62.68974 -168.42232) (xy 62.68974 -168.422066) (xy 62.690311 -168.377328) (xy 62.699325 -168.288306)
			(xy 62.71723 -168.200639) (xy 62.743842 -168.115211) (xy 62.76086 -168.073832) (xy 62.764412 -168.064238)
			(xy 62.76442 -168.043799) (xy 62.76086 -168.034208) (xy 62.743813 -167.992806) (xy 62.717185 -167.907315)
			(xy 62.699284 -167.81958) (xy 62.690292 -167.730491) (xy 62.68974 -167.68572) (xy 62.689828 -167.668048)
			(xy 62.691224 -167.632732) (xy 62.692534 -167.615108) (xy 62.692907 -167.605036) (xy 62.68662 -167.585904)
			(xy 62.673425 -167.57069) (xy 62.664594 -167.565832) (xy 62.566296 -167.516556) (xy 62.535816 -167.520366)
			(xy 62.524132 -167.53078) (xy 62.493735 -167.556935) (xy 62.428993 -167.604263) (xy 62.360251 -167.645567)
			(xy 62.288069 -167.680512) (xy 62.213032 -167.708812) (xy 62.135751 -167.730238) (xy 62.056854 -167.744617)
			(xy 61.976982 -167.75183) (xy 61.936884 -167.752268) (xy 61.93663 -167.752268) (xy 61.895524 -167.751759)
			(xy 61.813662 -167.744177) (xy 61.732849 -167.729076) (xy 61.653773 -167.706584) (xy 61.57711 -167.676893)
			(xy 61.503513 -167.640256) (xy 61.433609 -167.596985) (xy 61.367995 -167.547451) (xy 61.307231 -167.492074)
			(xy 61.251835 -167.431328) (xy 61.202279 -167.36573) (xy 61.158986 -167.295841) (xy 61.122325 -167.222256)
			(xy 61.092608 -167.145602) (xy 61.07009 -167.066534) (xy 61.054963 -166.985725) (xy 61.047355 -166.903866)
			(xy 61.046868 -166.86276) (xy 2.509012 -166.86276) (xy 2.509012 -170.29303) (xy 8.7249 -170.29303)
			(xy 8.7249 -169.42943) (xy 8.725386 -169.402179) (xy 8.733142 -169.348231) (xy 8.748497 -169.295936)
			(xy 8.771139 -169.246359) (xy 8.800605 -169.200509) (xy 8.836296 -169.159318) (xy 8.877487 -169.123627)
			(xy 8.923337 -169.094161) (xy 8.972914 -169.071519) (xy 9.025209 -169.056164) (xy 9.079157 -169.048408)
			(xy 9.133659 -169.048408) (xy 9.187607 -169.056164) (xy 9.239902 -169.071519) (xy 9.289479 -169.094161)
			(xy 9.335329 -169.123627) (xy 9.37652 -169.159318) (xy 9.412211 -169.200509) (xy 9.441677 -169.246359)
			(xy 9.464319 -169.295936) (xy 9.479674 -169.348231) (xy 9.48743 -169.402179) (xy 9.487916 -169.42943)
			(xy 9.487916 -169.857674) (xy 111.084868 -169.857674) (xy 111.085438 -169.812905) (xy 111.094447 -169.72382)
			(xy 111.112349 -169.636089) (xy 111.138966 -169.550597) (xy 111.155988 -169.509186) (xy 111.15957 -169.4996)
			(xy 111.15956 -169.479153) (xy 111.155988 -169.469562) (xy 111.13894 -169.42816) (xy 111.112309 -169.34267)
			(xy 111.094408 -169.254935) (xy 111.085418 -169.165845) (xy 111.084868 -169.121074) (xy 111.085438 -169.076305)
			(xy 111.094447 -168.98722) (xy 111.112349 -168.899489) (xy 111.138966 -168.813997) (xy 111.155988 -168.772586)
			(xy 111.15957 -168.763) (xy 111.15956 -168.742553) (xy 111.155988 -168.732962) (xy 111.13894 -168.69156)
			(xy 111.112309 -168.60607) (xy 111.094408 -168.518335) (xy 111.085418 -168.429245) (xy 111.084868 -168.384474)
			(xy 111.085274 -168.343358) (xy 111.092864 -168.261476) (xy 111.107976 -168.180645) (xy 111.130482 -168.101552)
			(xy 111.160191 -168.024873) (xy 111.196847 -167.951263) (xy 111.240139 -167.881349) (xy 111.289697 -167.815728)
			(xy 111.345099 -167.754959) (xy 111.405871 -167.699561) (xy 111.471495 -167.650007) (xy 111.541412 -167.60672)
			(xy 111.615025 -167.570068) (xy 111.691705 -167.540365) (xy 111.770799 -167.517863) (xy 111.851632 -167.502756)
			(xy 111.933514 -167.495171) (xy 111.97463 -167.494712) (xy 112.016241 -167.495173) (xy 112.099098 -167.502953)
			(xy 112.180867 -167.518431) (xy 112.260835 -167.541474) (xy 112.338303 -167.571879) (xy 112.412595 -167.609382)
			(xy 112.448086 -167.63111) (xy 112.457229 -167.636263) (xy 112.477942 -167.63948) (xy 112.498214 -167.634152)
			(xy 112.50676 -167.628062) (xy 112.540389 -167.602071) (xy 112.611783 -167.555946) (xy 112.687254 -167.516845)
			(xy 112.766112 -167.485124) (xy 112.847637 -167.461075) (xy 112.931085 -167.444915) (xy 113.015695 -167.436793)
			(xy 113.058194 -167.436292) (xy 113.099307 -167.436819) (xy 113.181182 -167.444405) (xy 113.262007 -167.459513)
			(xy 113.341094 -167.482013) (xy 113.417768 -167.511715) (xy 113.491374 -167.548365) (xy 113.561284 -167.59165)
			(xy 113.626903 -167.6412) (xy 113.68767 -167.696593) (xy 113.743067 -167.757357) (xy 113.792621 -167.822973)
			(xy 113.83591 -167.892881) (xy 113.872564 -167.966485) (xy 113.90227 -168.043156) (xy 113.924776 -168.122242)
			(xy 113.939888 -168.203067) (xy 113.947479 -168.284941) (xy 113.947956 -168.326054) (xy 113.947393 -168.370824)
			(xy 113.938383 -168.459909) (xy 113.920477 -168.54764) (xy 113.893859 -168.633131) (xy 113.876836 -168.674542)
			(xy 113.873299 -168.684141) (xy 113.873282 -168.704576) (xy 113.876836 -168.714166) (xy 113.89384 -168.755517)
			(xy 113.920451 -168.840879) (xy 113.938358 -168.928482) (xy 113.94738 -169.017439) (xy 113.947956 -169.062146)
			(xy 113.947956 -169.063162) (xy 113.947702 -169.074592) (xy 113.974181 -169.080538) (xy 114.026416 -169.095281)
			(xy 114.052096 -169.104056) (xy 114.060293 -169.10657) (xy 114.077427 -169.10657) (xy 114.085624 -169.104056)
			(xy 114.12084 -169.092095) (xy 114.192844 -169.073441) (xy 114.266165 -169.060932) (xy 114.34028 -169.054659)
			(xy 114.37747 -169.054272) (xy 114.414659 -169.054671) (xy 114.488772 -169.060958) (xy 114.562092 -169.073465)
			(xy 114.634098 -169.092103) (xy 114.669316 -169.104056) (xy 114.677513 -169.10657) (xy 114.694647 -169.10657)
			(xy 114.702844 -169.104056) (xy 114.738059 -169.092089) (xy 114.810062 -169.073437) (xy 114.883384 -169.06093)
			(xy 114.9575 -169.054658) (xy 114.99469 -169.054272) (xy 115.03663 -169.054667) (xy 115.120132 -169.062639)
			(xy 115.202497 -169.078513) (xy 115.28298 -169.102144) (xy 115.360853 -169.133319) (xy 115.43541 -169.171755)
			(xy 115.505975 -169.217104) (xy 115.57191 -169.268955) (xy 115.632618 -169.326839) (xy 115.687549 -169.390232)
			(xy 115.736205 -169.458559) (xy 115.778146 -169.531202) (xy 115.812991 -169.607503) (xy 115.840426 -169.68677)
			(xy 115.860202 -169.768287) (xy 115.87214 -169.851314) (xy 115.876131 -169.9351) (xy 115.87214 -170.018886)
			(xy 115.860202 -170.101913) (xy 115.840426 -170.18343) (xy 115.812991 -170.262697) (xy 115.778146 -170.338998)
			(xy 115.736205 -170.411641) (xy 115.687549 -170.479968) (xy 115.632618 -170.543361) (xy 115.57191 -170.601245)
			(xy 115.505975 -170.653096) (xy 115.498571 -170.657854) (xy 161.052951 -170.657854) (xy 161.052951 -170.603346)
			(xy 161.060709 -170.549393) (xy 161.076066 -170.497093) (xy 161.09871 -170.447511) (xy 161.12818 -170.401657)
			(xy 161.163876 -170.360463) (xy 161.205071 -170.324769) (xy 161.250927 -170.295301) (xy 161.30051 -170.27266)
			(xy 161.352811 -170.257305) (xy 161.406764 -170.24955) (xy 161.434018 -170.249088) (xy 162.297618 -170.249088)
			(xy 162.324868 -170.249583) (xy 162.378813 -170.257342) (xy 162.431105 -170.272698) (xy 162.48068 -170.29534)
			(xy 162.526528 -170.324806) (xy 162.567715 -170.360498) (xy 162.603404 -170.401687) (xy 162.632869 -170.447536)
			(xy 162.655508 -170.497111) (xy 162.670862 -170.549404) (xy 162.678618 -170.60335) (xy 162.678618 -170.65785)
			(xy 162.670862 -170.711796) (xy 162.655508 -170.764089) (xy 162.632869 -170.813664) (xy 162.603404 -170.859513)
			(xy 162.567715 -170.900702) (xy 162.526528 -170.936394) (xy 162.48068 -170.96586) (xy 162.431105 -170.988502)
			(xy 162.378813 -171.003858) (xy 162.324868 -171.011617) (xy 162.297618 -171.012104) (xy 161.434018 -171.012104)
			(xy 161.406764 -171.01165) (xy 161.352811 -171.003895) (xy 161.30051 -170.98854) (xy 161.250927 -170.965899)
			(xy 161.205071 -170.936431) (xy 161.163876 -170.900737) (xy 161.12818 -170.859543) (xy 161.09871 -170.813689)
			(xy 161.076066 -170.764107) (xy 161.060709 -170.711807) (xy 161.052951 -170.657854) (xy 115.498571 -170.657854)
			(xy 115.43541 -170.698445) (xy 115.360853 -170.736881) (xy 115.28298 -170.768056) (xy 115.202497 -170.791687)
			(xy 115.120132 -170.807561) (xy 115.03663 -170.815533) (xy 114.99469 -170.816016) (xy 114.9575 -170.815629)
			(xy 114.883387 -170.809339) (xy 114.810068 -170.796828) (xy 114.738062 -170.778187) (xy 114.702844 -170.766232)
			(xy 114.694647 -170.763718) (xy 114.677513 -170.763718) (xy 114.669316 -170.766232) (xy 114.625188 -170.781068)
			(xy 114.534574 -170.80245) (xy 114.488468 -170.808904) (xy 114.478735 -170.810567) (xy 114.461516 -170.820188)
			(xy 114.449244 -170.83563) (xy 114.44605 -170.844972) (xy 114.43848 -170.870441) (xy 114.420685 -170.920512)
			(xy 114.41049 -170.945048) (xy 114.406882 -170.954622) (xy 114.406736 -170.97506) (xy 114.410236 -170.984672)
			(xy 114.427271 -171.026045) (xy 114.453886 -171.111473) (xy 114.471787 -171.199143) (xy 114.480792 -171.288167)
			(xy 114.481356 -171.332906) (xy 114.481356 -171.33316) (xy 114.480852 -171.375508) (xy 114.472801 -171.459822)
			(xy 114.456772 -171.542988) (xy 114.432911 -171.624255) (xy 114.401432 -171.702885) (xy 114.362621 -171.778166)
			(xy 114.316831 -171.849418) (xy 114.264475 -171.915994) (xy 114.206027 -171.977292) (xy 114.142017 -172.032757)
			(xy 114.073025 -172.081886) (xy 113.999675 -172.124235) (xy 113.922632 -172.159419) (xy 113.842593 -172.187121)
			(xy 113.760284 -172.207089) (xy 113.676449 -172.219142) (xy 113.591848 -172.223173) (xy 113.507247 -172.219142)
			(xy 113.423412 -172.207089) (xy 113.341103 -172.187121) (xy 113.261064 -172.159419) (xy 113.184021 -172.124235)
			(xy 113.110671 -172.081886) (xy 113.041679 -172.032757) (xy 112.977669 -171.977292) (xy 112.919221 -171.915994)
			(xy 112.866865 -171.849418) (xy 112.821075 -171.778166) (xy 112.782264 -171.702885) (xy 112.750785 -171.624255)
			(xy 112.726924 -171.542988) (xy 112.710895 -171.459822) (xy 112.702844 -171.375508) (xy 112.70234 -171.33316)
			(xy 112.70234 -171.332906) (xy 112.702891 -171.288167) (xy 112.711911 -171.199145) (xy 112.729821 -171.111478)
			(xy 112.75644 -171.026051) (xy 112.77346 -170.984672) (xy 112.777047 -170.975088) (xy 112.777032 -170.954639)
			(xy 112.77346 -170.945048) (xy 112.757652 -170.906707) (xy 112.732373 -170.827716) (xy 112.714548 -170.746717)
			(xy 112.70433 -170.664411) (xy 112.702594 -170.622976) (xy 112.702594 -170.622722) (xy 112.701955 -170.613271)
			(xy 112.694549 -170.595846) (xy 112.681333 -170.582289) (xy 112.672876 -170.578018) (xy 112.589818 -170.540172)
			(xy 112.581121 -170.536666) (xy 112.562416 -170.535564) (xy 112.544562 -170.541248) (xy 112.536986 -170.546776)
			(xy 112.536986 -170.54703) (xy 112.536478 -170.54703) (xy 112.502475 -170.574102) (xy 112.430107 -170.622247)
			(xy 112.353386 -170.663099) (xy 112.273043 -170.696267) (xy 112.189846 -170.721435) (xy 112.104591 -170.738363)
			(xy 112.01809 -170.746889) (xy 111.97463 -170.747436) (xy 111.933515 -170.746973) (xy 111.851635 -170.739388)
			(xy 111.770804 -170.72428) (xy 111.691713 -170.701779) (xy 111.615035 -170.672075) (xy 111.541425 -170.635423)
			(xy 111.471511 -170.592135) (xy 111.405889 -170.542581) (xy 111.34512 -170.487183) (xy 111.289722 -170.426414)
			(xy 111.240167 -170.360793) (xy 111.196879 -170.290879) (xy 111.160226 -170.217269) (xy 111.130522 -170.140591)
			(xy 111.10802 -170.061499) (xy 111.092912 -169.980669) (xy 111.085327 -169.898789) (xy 111.084868 -169.857674)
			(xy 9.487916 -169.857674) (xy 9.487916 -170.29303) (xy 9.48743 -170.320281) (xy 9.479674 -170.374229)
			(xy 9.464319 -170.426524) (xy 9.441677 -170.476101) (xy 9.412211 -170.521951) (xy 9.37652 -170.563142)
			(xy 9.335329 -170.598833) (xy 9.289479 -170.628299) (xy 9.239902 -170.650941) (xy 9.187607 -170.666296)
			(xy 9.133659 -170.674052) (xy 9.079157 -170.674052) (xy 9.025209 -170.666296) (xy 8.972914 -170.650941)
			(xy 8.923337 -170.628299) (xy 8.877487 -170.598833) (xy 8.836296 -170.563142) (xy 8.800605 -170.521951)
			(xy 8.771139 -170.476101) (xy 8.748497 -170.426524) (xy 8.733142 -170.374229) (xy 8.725386 -170.320281)
			(xy 8.7249 -170.29303) (xy 2.509012 -170.29303) (xy 2.509012 -173.07814) (xy 8.7249 -173.07814) (xy 8.7249 -172.21454)
			(xy 8.725386 -172.187289) (xy 8.733142 -172.133341) (xy 8.748497 -172.081046) (xy 8.771139 -172.031469)
			(xy 8.800605 -171.985619) (xy 8.836296 -171.944428) (xy 8.877487 -171.908737) (xy 8.923337 -171.879271)
			(xy 8.972914 -171.856629) (xy 9.025209 -171.841274) (xy 9.079157 -171.833518) (xy 9.133659 -171.833518)
			(xy 9.187607 -171.841274) (xy 9.239902 -171.856629) (xy 9.289479 -171.879271) (xy 9.335329 -171.908737)
			(xy 9.37652 -171.944428) (xy 9.412211 -171.985619) (xy 9.441677 -172.031469) (xy 9.464319 -172.081046)
			(xy 9.479674 -172.133341) (xy 9.48743 -172.187289) (xy 9.487916 -172.21454) (xy 9.487916 -173.07814)
			(xy 9.48743 -173.105391) (xy 9.479674 -173.159339) (xy 9.464319 -173.211634) (xy 9.441677 -173.261211)
			(xy 9.412211 -173.307061) (xy 9.37652 -173.348252) (xy 9.335329 -173.383943) (xy 9.289479 -173.413409)
			(xy 9.239902 -173.436051) (xy 9.187607 -173.451406) (xy 9.133659 -173.459162) (xy 9.079157 -173.459162)
			(xy 9.025209 -173.451406) (xy 8.972914 -173.436051) (xy 8.923337 -173.413409) (xy 8.877487 -173.383943)
			(xy 8.836296 -173.348252) (xy 8.800605 -173.307061) (xy 8.771139 -173.261211) (xy 8.748497 -173.211634)
			(xy 8.733142 -173.159339) (xy 8.725386 -173.105391) (xy 8.7249 -173.07814) (xy 2.509012 -173.07814)
			(xy 2.509012 -175.848264) (xy 8.7249 -175.848264) (xy 8.7249 -174.984664) (xy 8.725386 -174.957413)
			(xy 8.733142 -174.903465) (xy 8.748497 -174.85117) (xy 8.771139 -174.801593) (xy 8.800605 -174.755743)
			(xy 8.836296 -174.714552) (xy 8.877487 -174.678861) (xy 8.923337 -174.649395) (xy 8.972914 -174.626753)
			(xy 9.025209 -174.611398) (xy 9.079157 -174.603642) (xy 9.133659 -174.603642) (xy 9.187607 -174.611398)
			(xy 9.239902 -174.626753) (xy 9.289479 -174.649395) (xy 9.335329 -174.678861) (xy 9.37652 -174.714552)
			(xy 9.412211 -174.755743) (xy 9.441677 -174.801593) (xy 9.464319 -174.85117) (xy 9.479674 -174.903465)
			(xy 9.48743 -174.957413) (xy 9.487916 -174.984664) (xy 9.487916 -175.559974) (xy 69.360288 -175.559974)
			(xy 69.360857 -175.515205) (xy 69.369865 -175.42612) (xy 69.387768 -175.338388) (xy 69.414386 -175.252897)
			(xy 69.431408 -175.211486) (xy 69.434989 -175.2019) (xy 69.43498 -175.181453) (xy 69.431408 -175.171862)
			(xy 69.414355 -175.130462) (xy 69.387726 -175.044971) (xy 69.369827 -174.957236) (xy 69.360838 -174.868145)
			(xy 69.360288 -174.823374) (xy 69.360857 -174.778605) (xy 69.369865 -174.68952) (xy 69.387768 -174.601788)
			(xy 69.414386 -174.516297) (xy 69.431408 -174.474886) (xy 69.434989 -174.4653) (xy 69.43498 -174.444853)
			(xy 69.431408 -174.435262) (xy 69.414355 -174.393862) (xy 69.387726 -174.308371) (xy 69.369827 -174.220636)
			(xy 69.360838 -174.131545) (xy 69.360288 -174.086774) (xy 69.360674 -174.045657) (xy 69.368264 -173.963775)
			(xy 69.383377 -173.882942) (xy 69.405884 -173.803848) (xy 69.435593 -173.727169) (xy 69.47225 -173.653557)
			(xy 69.515543 -173.583643) (xy 69.565103 -173.518021) (xy 69.620506 -173.457252) (xy 69.681279 -173.401854)
			(xy 69.746905 -173.3523) (xy 69.816824 -173.309013) (xy 69.890438 -173.272362) (xy 69.96712 -173.24266)
			(xy 70.046216 -173.220159) (xy 70.12705 -173.205053) (xy 70.208933 -173.19747) (xy 70.25005 -173.197012)
			(xy 70.29166 -173.197513) (xy 70.374516 -173.205285) (xy 70.456284 -173.220756) (xy 70.536252 -173.243791)
			(xy 70.613721 -173.274189) (xy 70.688014 -173.311686) (xy 70.723506 -173.33341) (xy 70.73264 -173.338581)
			(xy 70.753359 -173.341792) (xy 70.773635 -173.336456) (xy 70.78218 -173.330362) (xy 70.815836 -173.304408)
			(xy 70.887226 -173.258279) (xy 70.962691 -173.219173) (xy 71.041544 -173.187448) (xy 71.123065 -173.163392)
			(xy 71.20651 -173.147226) (xy 71.291116 -173.139097) (xy 71.333614 -173.138592) (xy 71.374727 -173.139099)
			(xy 71.456602 -173.146687) (xy 71.537428 -173.161797) (xy 71.616516 -173.1843) (xy 71.693189 -173.214003)
			(xy 71.703445 -173.21911) (xy 393.739116 -173.21911) (xy 393.739743 -173.172708) (xy 393.749432 -173.08041)
			(xy 393.768686 -172.989625) (xy 393.797294 -172.90134) (xy 393.81557 -172.858684) (xy 393.819371 -172.84874)
			(xy 393.819374 -172.827478) (xy 393.81557 -172.817536) (xy 393.797307 -172.774875) (xy 393.768715 -172.686587)
			(xy 393.749458 -172.595804) (xy 393.739745 -172.503511) (xy 393.739116 -172.45711) (xy 393.739622 -172.415997)
			(xy 393.747208 -172.33412) (xy 393.762316 -172.253293) (xy 393.784818 -172.174205) (xy 393.81452 -172.097531)
			(xy 393.851171 -172.023924) (xy 393.894457 -171.954012) (xy 393.944008 -171.888393) (xy 393.999403 -171.827626)
			(xy 394.060168 -171.772229) (xy 394.125786 -171.722675) (xy 394.195696 -171.679387) (xy 394.269301 -171.642733)
			(xy 394.345975 -171.613028) (xy 394.425062 -171.590524) (xy 394.505889 -171.575413) (xy 394.587765 -171.567824)
			(xy 394.628878 -171.567348) (xy 394.670013 -171.567796) (xy 394.75193 -171.575416) (xy 394.832794 -171.590566)
			(xy 394.911913 -171.613115) (xy 394.988614 -171.642872) (xy 395.06224 -171.679583) (xy 395.132163 -171.722933)
			(xy 395.197785 -171.772553) (xy 395.258547 -171.828019) (xy 395.313929 -171.888856) (xy 395.339062 -171.921424)
			(xy 395.345281 -171.928954) (xy 395.36201 -171.939002) (xy 395.371574 -171.940982) (xy 395.41286 -171.948033)
			(xy 395.493962 -171.968978) (xy 395.572736 -171.997455) (xy 395.648484 -172.033212) (xy 395.720535 -172.075931)
			(xy 395.78825 -172.125234) (xy 395.851031 -172.180685) (xy 395.908321 -172.241793) (xy 395.959613 -172.308015)
			(xy 396.004452 -172.378766) (xy 396.042441 -172.453419) (xy 396.073244 -172.531313) (xy 396.096588 -172.611757)
			(xy 396.112266 -172.69404) (xy 396.120139 -172.777432) (xy 396.12062 -172.819314) (xy 396.120152 -172.860082)
			(xy 396.112652 -172.941273) (xy 396.097752 -173.021436) (xy 396.075577 -173.099899) (xy 396.046313 -173.176003)
			(xy 396.028672 -173.21276) (xy 396.024359 -173.222451) (xy 396.023438 -173.243625) (xy 396.026894 -173.253654)
			(xy 396.041217 -173.292003) (xy 396.063564 -173.370761) (xy 396.07857 -173.451241) (xy 396.086111 -173.53276)
			(xy 396.086584 -173.573694) (xy 396.086007 -173.618463) (xy 396.077001 -173.707548) (xy 396.0591 -173.795279)
			(xy 396.032485 -173.880771) (xy 396.015464 -173.922182) (xy 396.011903 -173.931774) (xy 396.0119 -173.952215)
			(xy 396.015464 -173.961806) (xy 396.032477 -174.003153) (xy 396.059087 -174.088517) (xy 396.076991 -174.17612)
			(xy 396.08601 -174.265079) (xy 396.086584 -174.309786) (xy 396.086584 -174.310802) (xy 396.08633 -174.322232)
			(xy 396.112809 -174.328178) (xy 396.165044 -174.342921) (xy 396.190724 -174.351696) (xy 396.198921 -174.35421)
			(xy 396.216055 -174.35421) (xy 396.224252 -174.351696) (xy 396.259466 -174.339729) (xy 396.33147 -174.321076)
			(xy 396.404792 -174.308569) (xy 396.478908 -174.302297) (xy 396.516098 -174.301912) (xy 396.553288 -174.302301)
			(xy 396.627401 -174.30859) (xy 396.70072 -174.3211) (xy 396.772726 -174.339741) (xy 396.807944 -174.351696)
			(xy 396.816141 -174.35421) (xy 396.833275 -174.35421) (xy 396.841472 -174.351696) (xy 396.876685 -174.339723)
			(xy 396.948689 -174.321072) (xy 397.022011 -174.308567) (xy 397.096127 -174.302297) (xy 397.133318 -174.301912)
			(xy 397.175254 -174.302444) (xy 397.258746 -174.310418) (xy 397.341102 -174.326292) (xy 397.421577 -174.349923)
			(xy 397.49944 -174.381096) (xy 397.573988 -174.41953) (xy 397.644545 -174.464875) (xy 397.710473 -174.516722)
			(xy 397.771173 -174.574601) (xy 397.826097 -174.637988) (xy 397.874747 -174.706309) (xy 397.916683 -174.778944)
			(xy 397.951524 -174.855237) (xy 397.978955 -174.934497) (xy 397.998729 -175.016005) (xy 398.010665 -175.099023)
			(xy 398.014656 -175.1828) (xy 398.010665 -175.266577) (xy 397.998729 -175.349595) (xy 397.978955 -175.431103)
			(xy 397.951524 -175.510363) (xy 397.916683 -175.586656) (xy 397.874747 -175.659291) (xy 397.826097 -175.727612)
			(xy 397.771173 -175.790999) (xy 397.710473 -175.848878) (xy 397.644545 -175.900725) (xy 397.573988 -175.94607)
			(xy 397.49944 -175.984504) (xy 397.421577 -176.015677) (xy 397.341102 -176.039308) (xy 397.258746 -176.055182)
			(xy 397.175254 -176.063156) (xy 397.133318 -176.063656) (xy 397.096129 -176.063259) (xy 397.022016 -176.056971)
			(xy 396.948696 -176.044464) (xy 396.87669 -176.025825) (xy 396.841472 -176.013872) (xy 396.833275 -176.011358)
			(xy 396.816141 -176.011358) (xy 396.807944 -176.013872) (xy 396.778999 -176.023726) (xy 396.720017 -176.039869)
			(xy 396.690088 -176.04613) (xy 396.680511 -176.048515) (xy 396.664071 -176.059402) (xy 396.652972 -176.0757)
			(xy 396.650464 -176.085246) (xy 396.640294 -176.12901) (xy 396.612299 -176.21439) (xy 396.594584 -176.25568)
			(xy 396.590807 -176.265631) (xy 396.590789 -176.286886) (xy 396.594584 -176.296828) (xy 396.612789 -176.339438)
			(xy 396.641312 -176.427603) (xy 396.660509 -176.518256) (xy 396.670174 -176.610414) (xy 396.670784 -176.656746)
			(xy 396.670784 -176.657254) (xy 396.67028 -176.699602) (xy 396.662229 -176.783916) (xy 396.6462 -176.867082)
			(xy 396.622339 -176.948349) (xy 396.59086 -177.026979) (xy 396.552049 -177.10226) (xy 396.506259 -177.173512)
			(xy 396.453903 -177.240088) (xy 396.395455 -177.301386) (xy 396.331445 -177.356851) (xy 396.262453 -177.40598)
			(xy 396.189103 -177.448329) (xy 396.11206 -177.483513) (xy 396.032021 -177.511215) (xy 395.949712 -177.531183)
			(xy 395.865877 -177.543236) (xy 395.781276 -177.547267) (xy 395.696675 -177.543236) (xy 395.61284 -177.531183)
			(xy 395.530531 -177.511215) (xy 395.450492 -177.483513) (xy 395.373449 -177.448329) (xy 395.300099 -177.40598)
			(xy 395.231107 -177.356851) (xy 395.167097 -177.301386) (xy 395.108649 -177.240088) (xy 395.056293 -177.173512)
			(xy 395.010503 -177.10226) (xy 394.971692 -177.026979) (xy 394.940213 -176.948349) (xy 394.916352 -176.867082)
			(xy 394.900323 -176.783916) (xy 394.892272 -176.699602) (xy 394.891768 -176.657254) (xy 394.891768 -176.656746)
			(xy 394.892395 -176.610415) (xy 394.902061 -176.518257) (xy 394.92125 -176.427603) (xy 394.949756 -176.339434)
			(xy 394.967968 -176.296828) (xy 394.971802 -176.286894) (xy 394.971784 -176.265622) (xy 394.967968 -176.25568)
			(xy 394.949707 -176.213025) (xy 394.921167 -176.12473) (xy 394.901979 -176.033943) (xy 394.89235 -175.941651)
			(xy 394.891768 -175.895254) (xy 394.89209 -175.858508) (xy 394.898067 -175.785262) (xy 394.903706 -175.74895)
			(xy 394.905149 -175.737024) (xy 394.898112 -175.714088) (xy 394.890244 -175.705008) (xy 394.824966 -175.637698)
			(xy 394.80236 -175.629824) (xy 394.790168 -175.631602) (xy 394.748357 -175.636737) (xy 394.664175 -175.639973)
			(xy 394.580064 -175.635239) (xy 394.496776 -175.622575) (xy 394.415059 -175.602096) (xy 394.335643 -175.573985)
			(xy 394.259239 -175.538493) (xy 394.186532 -175.495939) (xy 394.118173 -175.446704) (xy 394.054773 -175.391227)
			(xy 393.996901 -175.330007) (xy 393.945075 -175.26359) (xy 393.899757 -175.192573) (xy 393.861356 -175.11759)
			(xy 393.830213 -175.039313) (xy 393.806608 -174.958443) (xy 393.790753 -174.875704) (xy 393.782789 -174.791836)
			(xy 393.782296 -174.749714) (xy 393.782793 -174.706976) (xy 393.790968 -174.621894) (xy 393.807264 -174.537986)
			(xy 393.831529 -174.456028) (xy 393.847066 -174.416212) (xy 393.850705 -174.406179) (xy 393.85003 -174.384863)
			(xy 393.845796 -174.375064) (xy 393.828734 -174.338786) (xy 393.800425 -174.263775) (xy 393.778984 -174.18652)
			(xy 393.764586 -174.107649) (xy 393.757348 -174.027801) (xy 393.756896 -173.987714) (xy 393.757452 -173.943459)
			(xy 393.766275 -173.855391) (xy 393.783795 -173.768633) (xy 393.809839 -173.684042) (xy 393.826492 -173.643036)
			(xy 393.830085 -173.632871) (xy 393.829579 -173.611348) (xy 393.825476 -173.60138) (xy 393.808875 -173.565511)
			(xy 393.781358 -173.491412) (xy 393.760529 -173.415162) (xy 393.746554 -173.337364) (xy 393.739543 -173.258632)
			(xy 393.739116 -173.21911) (xy 71.703445 -173.21911) (xy 71.766795 -173.250654) (xy 71.836706 -173.29394)
			(xy 71.902324 -173.343492) (xy 71.963091 -173.398886) (xy 72.018488 -173.459651) (xy 72.068042 -173.525268)
			(xy 72.11133 -173.595177) (xy 72.147984 -173.668781) (xy 72.17769 -173.745454) (xy 72.200196 -173.82454)
			(xy 72.215308 -173.905366) (xy 72.222899 -173.987241) (xy 72.223376 -174.028354) (xy 72.22282 -174.073124)
			(xy 72.213808 -174.162209) (xy 72.195901 -174.24994) (xy 72.16928 -174.335431) (xy 72.152256 -174.376842)
			(xy 72.148718 -174.38644) (xy 72.148701 -174.406876) (xy 72.152256 -174.416466) (xy 72.169272 -174.457846)
			(xy 72.195896 -174.543271) (xy 72.213802 -174.630939) (xy 72.222811 -174.719961) (xy 72.223376 -174.7647)
			(xy 72.223376 -174.765208) (xy 72.223122 -174.77867) (xy 72.249601 -174.784615) (xy 72.301836 -174.799358)
			(xy 72.327516 -174.808134) (xy 72.335713 -174.810648) (xy 72.352847 -174.810648) (xy 72.361044 -174.808134)
			(xy 72.39626 -174.796188) (xy 72.46827 -174.777601) (xy 72.541593 -174.765161) (xy 72.615704 -174.758956)
			(xy 72.65289 -174.758604) (xy 72.690074 -174.75897) (xy 72.764182 -174.765192) (xy 72.837502 -174.777635)
			(xy 72.909513 -174.796211) (xy 72.944736 -174.808134) (xy 72.952933 -174.810648) (xy 72.970067 -174.810648)
			(xy 72.978264 -174.808134) (xy 73.013366 -174.796247) (xy 73.085122 -174.777697) (xy 73.158185 -174.765251)
			(xy 73.232036 -174.758997) (xy 73.269094 -174.758604) (xy 73.27011 -174.758604) (xy 73.312036 -174.759059)
			(xy 73.395508 -174.767031) (xy 73.477845 -174.7829) (xy 73.5583 -174.806525) (xy 73.636145 -174.83769)
			(xy 73.710676 -174.876114) (xy 73.781216 -174.921448) (xy 73.847128 -174.973283) (xy 73.907814 -175.031148)
			(xy 73.962725 -175.094519) (xy 74.011364 -175.162823) (xy 74.053289 -175.235441) (xy 74.088123 -175.311716)
			(xy 74.115548 -175.390956) (xy 74.135316 -175.472444) (xy 74.14725 -175.555443) (xy 74.15124 -175.6392)
			(xy 74.14725 -175.722957) (xy 74.135316 -175.805956) (xy 74.115548 -175.887444) (xy 74.088123 -175.966684)
			(xy 74.053289 -176.042959) (xy 74.01685 -176.106074) (xy 102.855268 -176.106074) (xy 102.855838 -176.061305)
			(xy 102.864847 -175.97222) (xy 102.882749 -175.884489) (xy 102.909366 -175.798997) (xy 102.926388 -175.757586)
			(xy 102.92997 -175.748) (xy 102.92996 -175.727553) (xy 102.926388 -175.717962) (xy 102.90934 -175.67656)
			(xy 102.882709 -175.59107) (xy 102.864808 -175.503335) (xy 102.855818 -175.414245) (xy 102.855268 -175.369474)
			(xy 102.855838 -175.324705) (xy 102.864847 -175.23562) (xy 102.882749 -175.147889) (xy 102.909366 -175.062397)
			(xy 102.926388 -175.020986) (xy 102.92997 -175.0114) (xy 102.92996 -174.990953) (xy 102.926388 -174.981362)
			(xy 102.90934 -174.93996) (xy 102.882709 -174.85447) (xy 102.864808 -174.766735) (xy 102.855818 -174.677645)
			(xy 102.855268 -174.632874) (xy 102.855674 -174.591758) (xy 102.863264 -174.509876) (xy 102.878376 -174.429045)
			(xy 102.900882 -174.349952) (xy 102.930591 -174.273273) (xy 102.967247 -174.199663) (xy 103.010539 -174.129749)
			(xy 103.060097 -174.064128) (xy 103.115499 -174.003359) (xy 103.176271 -173.947961) (xy 103.241895 -173.898407)
			(xy 103.311812 -173.85512) (xy 103.385425 -173.818468) (xy 103.462105 -173.788765) (xy 103.541199 -173.766263)
			(xy 103.622032 -173.751156) (xy 103.703914 -173.743571) (xy 103.74503 -173.743112) (xy 103.786641 -173.743573)
			(xy 103.869498 -173.751353) (xy 103.951267 -173.766831) (xy 104.031235 -173.789874) (xy 104.108703 -173.820279)
			(xy 104.182995 -173.857782) (xy 104.218486 -173.87951) (xy 104.227629 -173.884663) (xy 104.248342 -173.88788)
			(xy 104.268614 -173.882552) (xy 104.27716 -173.876462) (xy 104.310789 -173.850471) (xy 104.382183 -173.804346)
			(xy 104.457654 -173.765245) (xy 104.536512 -173.733524) (xy 104.618037 -173.709475) (xy 104.701485 -173.693315)
			(xy 104.786095 -173.685193) (xy 104.828594 -173.684692) (xy 104.869707 -173.685219) (xy 104.951582 -173.692805)
			(xy 105.032407 -173.707913) (xy 105.111494 -173.730413) (xy 105.188168 -173.760115) (xy 105.261774 -173.796765)
			(xy 105.331684 -173.84005) (xy 105.397303 -173.8896) (xy 105.45807 -173.944993) (xy 105.513467 -174.005757)
			(xy 105.563021 -174.071373) (xy 105.60631 -174.141281) (xy 105.642964 -174.214885) (xy 105.67267 -174.291556)
			(xy 105.695176 -174.370642) (xy 105.710288 -174.451467) (xy 105.717879 -174.533341) (xy 105.718356 -174.574454)
			(xy 105.717793 -174.619224) (xy 105.708783 -174.708309) (xy 105.690877 -174.79604) (xy 105.664259 -174.881531)
			(xy 105.647236 -174.922942) (xy 105.643699 -174.932541) (xy 105.643682 -174.952976) (xy 105.647236 -174.962566)
			(xy 105.66424 -175.003917) (xy 105.690851 -175.089279) (xy 105.708758 -175.176882) (xy 105.71778 -175.265839)
			(xy 105.718356 -175.310546) (xy 105.718356 -175.311562) (xy 105.718102 -175.322992) (xy 105.744581 -175.328938)
			(xy 105.796816 -175.343681) (xy 105.822496 -175.352456) (xy 105.830693 -175.35497) (xy 105.847827 -175.35497)
			(xy 105.856024 -175.352456) (xy 105.89124 -175.340495) (xy 105.963244 -175.321841) (xy 106.036565 -175.309332)
			(xy 106.11068 -175.303059) (xy 106.14787 -175.302672) (xy 106.185059 -175.303071) (xy 106.259172 -175.309358)
			(xy 106.332492 -175.321865) (xy 106.404498 -175.340503) (xy 106.439716 -175.352456) (xy 106.447913 -175.35497)
			(xy 106.465047 -175.35497) (xy 106.473244 -175.352456) (xy 106.508459 -175.340489) (xy 106.580462 -175.321837)
			(xy 106.653784 -175.30933) (xy 106.7279 -175.303058) (xy 106.76509 -175.302672) (xy 106.80703 -175.303067)
			(xy 106.890532 -175.311039) (xy 106.972897 -175.326913) (xy 107.05338 -175.350544) (xy 107.131253 -175.381719)
			(xy 107.20581 -175.420155) (xy 107.276375 -175.465504) (xy 107.34231 -175.517355) (xy 107.403018 -175.575239)
			(xy 107.457949 -175.638632) (xy 107.505577 -175.705516) (xy 359.713276 -175.705516) (xy 359.713826 -175.660746)
			(xy 359.72284 -175.571661) (xy 359.740749 -175.48393) (xy 359.767371 -175.398439) (xy 359.784396 -175.357028)
			(xy 359.787954 -175.347435) (xy 359.78796 -175.326994) (xy 359.784396 -175.317404) (xy 359.767362 -175.275997)
			(xy 359.740727 -175.190508) (xy 359.722822 -175.102775) (xy 359.713828 -175.013687) (xy 359.713276 -174.968916)
			(xy 359.713826 -174.924146) (xy 359.72284 -174.835061) (xy 359.740749 -174.74733) (xy 359.767371 -174.661839)
			(xy 359.784396 -174.620428) (xy 359.787954 -174.610835) (xy 359.78796 -174.590394) (xy 359.784396 -174.580804)
			(xy 359.767362 -174.539397) (xy 359.740727 -174.453908) (xy 359.722822 -174.366175) (xy 359.713828 -174.277087)
			(xy 359.713276 -174.232316) (xy 359.713768 -174.191206) (xy 359.721354 -174.109337) (xy 359.736463 -174.028517)
			(xy 359.758966 -173.949437) (xy 359.788671 -173.872771) (xy 359.825324 -173.799173) (xy 359.868613 -173.729272)
			(xy 359.918168 -173.663664) (xy 359.973567 -173.602909) (xy 360.034335 -173.547526) (xy 360.099955 -173.497988)
			(xy 360.169867 -173.454716) (xy 360.243474 -173.418081) (xy 360.320148 -173.388396) (xy 360.399234 -173.365912)
			(xy 360.480057 -173.350823) (xy 360.561928 -173.343257) (xy 360.603038 -173.342808) (xy 360.644642 -173.343279)
			(xy 360.72749 -173.351011) (xy 360.809255 -173.366441) (xy 360.889223 -173.389435) (xy 360.966695 -173.419793)
			(xy 361.040997 -173.457248) (xy 361.076494 -173.478952) (xy 361.08563 -173.48412) (xy 361.106349 -173.487339)
			(xy 361.126625 -173.482001) (xy 361.135168 -173.475904) (xy 361.168794 -173.449952) (xy 361.240172 -173.403895)
			(xy 361.315615 -173.364851) (xy 361.394436 -173.333176) (xy 361.475917 -173.309157) (xy 361.559316 -173.293014)
			(xy 361.643874 -173.284894) (xy 361.686348 -173.284388) (xy 361.686602 -173.284388) (xy 361.72771 -173.284811)
			(xy 361.809576 -173.292396) (xy 361.890393 -173.307501) (xy 361.969472 -173.329998) (xy 362.046138 -173.359694)
			(xy 362.119738 -173.396336) (xy 362.189643 -173.439612) (xy 362.255258 -173.489152) (xy 362.316023 -173.544534)
			(xy 362.371419 -173.605287) (xy 362.420974 -173.67089) (xy 362.464266 -173.740786) (xy 362.500925 -173.814377)
			(xy 362.530638 -173.891036) (xy 362.553153 -173.97011) (xy 362.568276 -174.050924) (xy 362.57588 -174.132788)
			(xy 362.576364 -174.173896) (xy 362.575781 -174.218665) (xy 362.566776 -174.307749) (xy 362.548877 -174.395481)
			(xy 362.522264 -174.480972) (xy 362.505244 -174.522384) (xy 362.501683 -174.531976) (xy 362.501681 -174.552417)
			(xy 362.505244 -174.562008) (xy 362.522284 -174.603413) (xy 362.548917 -174.688902) (xy 362.56682 -174.776636)
			(xy 362.575812 -174.865725) (xy 362.576364 -174.910496) (xy 362.575094 -174.953676) (xy 362.575044 -174.965402)
			(xy 362.584373 -174.986895) (xy 362.602231 -175.002063) (xy 362.613448 -175.005492) (xy 362.632331 -175.010413)
			(xy 362.669682 -175.021721) (xy 362.688124 -175.028098) (xy 362.696321 -175.030612) (xy 362.713455 -175.030612)
			(xy 362.721652 -175.028098) (xy 362.756876 -175.016176) (xy 362.828883 -174.997583) (xy 362.902204 -174.985136)
			(xy 362.976313 -174.978924) (xy 363.013498 -174.978568) (xy 363.050682 -174.978934) (xy 363.12479 -174.985156)
			(xy 363.19811 -174.997599) (xy 363.270121 -175.016175) (xy 363.305344 -175.028098) (xy 363.313541 -175.030612)
			(xy 363.330675 -175.030612) (xy 363.338872 -175.028098) (xy 363.373974 -175.016212) (xy 363.44573 -174.997661)
			(xy 363.518793 -174.985214) (xy 363.592644 -174.978961) (xy 363.629702 -174.978568) (xy 363.630718 -174.978568)
			(xy 363.672642 -174.979095) (xy 363.75611 -174.987067) (xy 363.838443 -175.002937) (xy 363.918894 -175.026561)
			(xy 363.996736 -175.057726) (xy 364.071262 -175.096148) (xy 364.141799 -175.141481) (xy 364.207708 -175.193313)
			(xy 364.268391 -175.251175) (xy 364.323299 -175.314544) (xy 364.371935 -175.382845) (xy 364.413859 -175.45546)
			(xy 364.44869 -175.531731) (xy 364.476114 -175.610968) (xy 364.495881 -175.692452) (xy 364.507814 -175.775447)
			(xy 364.511804 -175.8592) (xy 364.507814 -175.942953) (xy 364.495881 -176.025948) (xy 364.476114 -176.107432)
			(xy 364.44869 -176.186669) (xy 364.413859 -176.26294) (xy 364.371935 -176.335555) (xy 364.323299 -176.403856)
			(xy 364.268391 -176.467225) (xy 364.207708 -176.525087) (xy 364.141799 -176.576919) (xy 364.071262 -176.622252)
			(xy 363.996736 -176.660674) (xy 363.918894 -176.691839) (xy 363.838443 -176.715463) (xy 363.75611 -176.731333)
			(xy 363.672642 -176.739305) (xy 363.630718 -176.739804) (xy 363.629702 -176.739804) (xy 363.592645 -176.739398)
			(xy 363.518796 -176.733134) (xy 363.445733 -176.720692) (xy 363.373973 -176.70216) (xy 363.338872 -176.690274)
			(xy 363.330675 -176.68776) (xy 363.313541 -176.68776) (xy 363.305344 -176.690274) (xy 363.271298 -176.701763)
			(xy 363.201741 -176.719817) (xy 363.166406 -176.726342) (xy 363.157048 -176.728326) (xy 363.140733 -176.738296)
			(xy 363.129218 -176.75356) (xy 363.126274 -176.762664) (xy 363.118487 -176.78918) (xy 363.100057 -176.841287)
			(xy 363.089444 -176.866804) (xy 363.085871 -176.876392) (xy 363.085877 -176.896837) (xy 363.089444 -176.906428)
			(xy 363.106465 -176.947806) (xy 363.133084 -177.033233) (xy 363.150988 -177.120901) (xy 363.159998 -177.209923)
			(xy 363.160564 -177.254662) (xy 363.160564 -177.254916) (xy 363.16006 -177.297264) (xy 363.152009 -177.381578)
			(xy 363.13598 -177.464744) (xy 363.112119 -177.546011) (xy 363.08064 -177.624641) (xy 363.041829 -177.699922)
			(xy 362.996039 -177.771174) (xy 362.943683 -177.83775) (xy 362.885235 -177.899048) (xy 362.821225 -177.954513)
			(xy 362.752233 -178.003642) (xy 362.678883 -178.045991) (xy 362.60184 -178.081175) (xy 362.521801 -178.108877)
			(xy 362.439492 -178.128845) (xy 362.355657 -178.140898) (xy 362.271056 -178.144929) (xy 362.186455 -178.140898)
			(xy 362.10262 -178.128845) (xy 362.020311 -178.108877) (xy 361.940272 -178.081175) (xy 361.863229 -178.045991)
			(xy 361.789879 -178.003642) (xy 361.720887 -177.954513) (xy 361.656877 -177.899048) (xy 361.598429 -177.83775)
			(xy 361.546073 -177.771174) (xy 361.500283 -177.699922) (xy 361.461472 -177.624641) (xy 361.429993 -177.546011)
			(xy 361.406132 -177.464744) (xy 361.390103 -177.381578) (xy 361.382052 -177.297264) (xy 361.381548 -177.254916)
			(xy 361.381548 -177.254662) (xy 361.382124 -177.209924) (xy 361.391138 -177.120903) (xy 361.409041 -177.033235)
			(xy 361.435651 -176.947807) (xy 361.452668 -176.906428) (xy 361.456222 -176.896834) (xy 361.456228 -176.876395)
			(xy 361.452668 -176.866804) (xy 361.435658 -176.825422) (xy 361.409036 -176.739997) (xy 361.391129 -176.65233)
			(xy 361.382115 -176.563308) (xy 361.381548 -176.51857) (xy 361.381548 -176.518316) (xy 361.38189 -176.482968)
			(xy 361.387504 -176.412495) (xy 361.39869 -176.34269) (xy 361.406694 -176.308258) (xy 361.409002 -176.295757)
			(xy 361.402463 -176.271224) (xy 361.394248 -176.261522) (xy 361.353608 -176.218596) (xy 361.34421 -176.220628)
			(xy 361.335443 -176.222892) (xy 361.32021 -176.232657) (xy 361.314492 -176.239678) (xy 361.289344 -176.272353)
			(xy 361.233931 -176.333418) (xy 361.173106 -176.389094) (xy 361.10739 -176.438902) (xy 361.037347 -176.482416)
			(xy 360.963578 -176.519263) (xy 360.886716 -176.549126) (xy 360.807421 -176.571748) (xy 360.726373 -176.586937)
			(xy 360.644268 -176.594561) (xy 360.603038 -176.595024) (xy 360.561931 -176.594551) (xy 360.480067 -176.58697)
			(xy 360.399251 -176.571868) (xy 360.320173 -176.549375) (xy 360.243508 -176.519683) (xy 360.169909 -176.483044)
			(xy 360.100004 -176.439772) (xy 360.034389 -176.390235) (xy 359.973624 -176.334856) (xy 359.918228 -176.274107)
			(xy 359.868672 -176.208506) (xy 359.825379 -176.138613) (xy 359.78872 -176.065025) (xy 359.759005 -175.988368)
			(xy 359.73649 -175.909296) (xy 359.721365 -175.828485) (xy 359.713761 -175.746623) (xy 359.713276 -175.705516)
			(xy 107.505577 -175.705516) (xy 107.506605 -175.706959) (xy 107.548546 -175.779602) (xy 107.583391 -175.855903)
			(xy 107.610826 -175.93517) (xy 107.630602 -176.016687) (xy 107.64254 -176.099714) (xy 107.646531 -176.1835)
			(xy 107.64254 -176.267286) (xy 107.630602 -176.350313) (xy 107.610826 -176.43183) (xy 107.583391 -176.511097)
			(xy 107.548546 -176.587398) (xy 107.506605 -176.660041) (xy 107.457949 -176.728368) (xy 107.403018 -176.791761)
			(xy 107.34231 -176.849645) (xy 107.276375 -176.901496) (xy 107.20581 -176.946845) (xy 107.131253 -176.985281)
			(xy 107.05338 -177.016456) (xy 106.972897 -177.040087) (xy 106.890532 -177.055961) (xy 106.80703 -177.063933)
			(xy 106.76509 -177.064416) (xy 106.7279 -177.064029) (xy 106.653787 -177.057739) (xy 106.580468 -177.045228)
			(xy 106.508462 -177.026587) (xy 106.473244 -177.014632) (xy 106.465047 -177.012118) (xy 106.447913 -177.012118)
			(xy 106.439716 -177.014632) (xy 106.394061 -177.029945) (xy 106.300252 -177.051713) (xy 106.252518 -177.058066)
			(xy 106.242041 -177.059824) (xy 106.223772 -177.070618) (xy 106.211473 -177.087908) (xy 106.20883 -177.098198)
			(xy 106.199325 -177.142161) (xy 106.1726 -177.22805) (xy 106.15549 -177.269648) (xy 106.151882 -177.279222)
			(xy 106.151736 -177.29966) (xy 106.155236 -177.309272) (xy 106.172271 -177.350645) (xy 106.198886 -177.436073)
			(xy 106.216787 -177.523743) (xy 106.225792 -177.612767) (xy 106.226356 -177.657506) (xy 106.226356 -177.65776)
			(xy 106.225852 -177.700108) (xy 106.217801 -177.784422) (xy 106.201772 -177.867588) (xy 106.177911 -177.948855)
			(xy 106.146432 -178.027485) (xy 106.107621 -178.102766) (xy 106.061831 -178.174018) (xy 106.009475 -178.240594)
			(xy 105.951027 -178.301892) (xy 105.887017 -178.357357) (xy 105.818025 -178.406486) (xy 105.744675 -178.448835)
			(xy 105.667632 -178.484019) (xy 105.587593 -178.511721) (xy 105.505284 -178.531689) (xy 105.421449 -178.543742)
			(xy 105.336848 -178.547773) (xy 105.252247 -178.543742) (xy 105.168412 -178.531689) (xy 105.086103 -178.511721)
			(xy 105.006064 -178.484019) (xy 104.929021 -178.448835) (xy 104.855671 -178.406486) (xy 104.786679 -178.357357)
			(xy 104.722669 -178.301892) (xy 104.664221 -178.240594) (xy 104.611865 -178.174018) (xy 104.566075 -178.102766)
			(xy 104.527264 -178.027485) (xy 104.495785 -177.948855) (xy 104.471924 -177.867588) (xy 104.455895 -177.784422)
			(xy 104.447844 -177.700108) (xy 104.44734 -177.65776) (xy 104.44734 -177.657506) (xy 104.447891 -177.612767)
			(xy 104.456911 -177.523745) (xy 104.474821 -177.436078) (xy 104.50144 -177.350651) (xy 104.51846 -177.309272)
			(xy 104.522047 -177.299688) (xy 104.522032 -177.279239) (xy 104.51846 -177.269648) (xy 104.501426 -177.228241)
			(xy 104.474794 -177.142752) (xy 104.456889 -177.055019) (xy 104.447894 -176.965931) (xy 104.44734 -176.92116)
			(xy 104.447594 -176.89703) (xy 104.44745 -176.887477) (xy 104.440882 -176.869548) (xy 104.428227 -176.855249)
			(xy 104.419908 -176.850548) (xy 104.33812 -176.808638) (xy 104.329507 -176.804642) (xy 104.310627 -176.802733)
			(xy 104.292347 -176.807824) (xy 104.284526 -176.81321) (xy 104.284526 -176.813464) (xy 104.284018 -176.813464)
			(xy 104.250823 -176.838169) (xy 104.180649 -176.882028) (xy 104.106709 -176.919187) (xy 104.029639 -176.949324)
			(xy 103.950105 -176.97218) (xy 103.868793 -176.987556) (xy 103.786406 -176.995321) (xy 103.74503 -176.995836)
			(xy 103.703915 -176.995373) (xy 103.622035 -176.987788) (xy 103.541204 -176.97268) (xy 103.462113 -176.950179)
			(xy 103.385435 -176.920475) (xy 103.311825 -176.883823) (xy 103.241911 -176.840535) (xy 103.176289 -176.790981)
			(xy 103.11552 -176.735583) (xy 103.060122 -176.674814) (xy 103.010567 -176.609193) (xy 102.967279 -176.539279)
			(xy 102.930626 -176.465669) (xy 102.900922 -176.388991) (xy 102.87842 -176.309899) (xy 102.863312 -176.229069)
			(xy 102.855727 -176.147189) (xy 102.855268 -176.106074) (xy 74.01685 -176.106074) (xy 74.011364 -176.115577)
			(xy 73.962725 -176.183881) (xy 73.907814 -176.247252) (xy 73.847128 -176.305117) (xy 73.781216 -176.356952)
			(xy 73.710676 -176.402286) (xy 73.636145 -176.44071) (xy 73.5583 -176.471875) (xy 73.477845 -176.4955)
			(xy 73.395508 -176.511369) (xy 73.312036 -176.519341) (xy 73.27011 -176.51984) (xy 73.269094 -176.51984)
			(xy 73.232037 -176.519434) (xy 73.158188 -176.51317) (xy 73.085125 -176.500728) (xy 73.013365 -176.482196)
			(xy 72.978264 -176.47031) (xy 72.970067 -176.467796) (xy 72.952933 -176.467796) (xy 72.944736 -176.47031)
			(xy 72.910756 -176.481853) (xy 72.841327 -176.500034) (xy 72.806052 -176.506632) (xy 72.796116 -176.508916)
			(xy 72.779041 -176.520017) (xy 72.767603 -176.536869) (xy 72.765158 -176.546764) (xy 72.755578 -176.591455)
			(xy 72.728473 -176.67875) (xy 72.711056 -176.721008) (xy 72.70748 -176.730595) (xy 72.707488 -176.751041)
			(xy 72.711056 -176.760632) (xy 72.728073 -176.802012) (xy 72.754694 -176.887437) (xy 72.7726 -176.975105)
			(xy 72.78161 -177.064127) (xy 72.782176 -177.108866) (xy 72.782176 -177.10912) (xy 72.781672 -177.151468)
			(xy 72.773621 -177.235782) (xy 72.757592 -177.318948) (xy 72.733731 -177.400215) (xy 72.702252 -177.478845)
			(xy 72.663441 -177.554126) (xy 72.617651 -177.625378) (xy 72.565295 -177.691954) (xy 72.506847 -177.753252)
			(xy 72.442837 -177.808717) (xy 72.373845 -177.857846) (xy 72.300495 -177.900195) (xy 72.223452 -177.935379)
			(xy 72.143413 -177.963081) (xy 72.061104 -177.983049) (xy 71.977269 -177.995102) (xy 71.892668 -177.999133)
			(xy 71.808067 -177.995102) (xy 71.724232 -177.983049) (xy 71.641923 -177.963081) (xy 71.561884 -177.935379)
			(xy 71.484841 -177.900195) (xy 71.411491 -177.857846) (xy 71.342499 -177.808717) (xy 71.278489 -177.753252)
			(xy 71.220041 -177.691954) (xy 71.167685 -177.625378) (xy 71.121895 -177.554126) (xy 71.083084 -177.478845)
			(xy 71.051605 -177.400215) (xy 71.027744 -177.318948) (xy 71.011715 -177.235782) (xy 71.003664 -177.151468)
			(xy 71.00316 -177.10912) (xy 71.00316 -177.108866) (xy 71.003737 -177.064128) (xy 71.01275 -176.975107)
			(xy 71.030653 -176.887439) (xy 71.057263 -176.802011) (xy 71.07428 -176.760632) (xy 71.077831 -176.751038)
			(xy 71.077839 -176.730599) (xy 71.07428 -176.721008) (xy 71.057235 -176.679605) (xy 71.030605 -176.594115)
			(xy 71.012704 -176.50638) (xy 71.003712 -176.417291) (xy 71.00316 -176.37252) (xy 71.003216 -176.357395)
			(xy 71.004231 -176.327162) (xy 71.005192 -176.312068) (xy 71.005427 -176.302019) (xy 70.999034 -176.282984)
			(xy 70.985815 -176.267867) (xy 70.976998 -176.263046) (xy 70.8787 -176.214532) (xy 70.84822 -176.218596)
			(xy 70.83679 -176.228756) (xy 70.806403 -176.254854) (xy 70.741691 -176.302073) (xy 70.672994 -176.343279)
			(xy 70.60087 -176.378141) (xy 70.525902 -176.406374) (xy 70.4487 -176.427751) (xy 70.369887 -176.442098)
			(xy 70.290104 -176.449298) (xy 70.25005 -176.449736) (xy 70.208935 -176.449254) (xy 70.127056 -176.441671)
			(xy 70.046226 -176.426565) (xy 69.967134 -176.404065) (xy 69.890456 -176.374363) (xy 69.816846 -176.337712)
			(xy 69.746932 -176.294426) (xy 69.68131 -176.244873) (xy 69.620541 -176.189476) (xy 69.565143 -176.128708)
			(xy 69.515588 -176.063088) (xy 69.472299 -175.993175) (xy 69.435647 -175.919566) (xy 69.405943 -175.842889)
			(xy 69.383441 -175.763798) (xy 69.368332 -175.682968) (xy 69.360747 -175.601089) (xy 69.360288 -175.559974)
			(xy 9.487916 -175.559974) (xy 9.487916 -175.848264) (xy 9.48743 -175.875515) (xy 9.479674 -175.929463)
			(xy 9.464319 -175.981758) (xy 9.441677 -176.031335) (xy 9.412211 -176.077185) (xy 9.37652 -176.118376)
			(xy 9.335329 -176.154067) (xy 9.289479 -176.183533) (xy 9.239902 -176.206175) (xy 9.187607 -176.22153)
			(xy 9.133659 -176.229286) (xy 9.079157 -176.229286) (xy 9.025209 -176.22153) (xy 8.972914 -176.206175)
			(xy 8.923337 -176.183533) (xy 8.877487 -176.154067) (xy 8.836296 -176.118376) (xy 8.800605 -176.077185)
			(xy 8.771139 -176.031335) (xy 8.748497 -175.981758) (xy 8.733142 -175.929463) (xy 8.725386 -175.875515)
			(xy 8.7249 -175.848264) (xy 2.509012 -175.848264) (xy 2.509012 -178.618388) (xy 8.7249 -178.618388)
			(xy 8.7249 -177.754788) (xy 8.725386 -177.727537) (xy 8.733142 -177.673589) (xy 8.748497 -177.621294)
			(xy 8.771139 -177.571717) (xy 8.800605 -177.525867) (xy 8.836296 -177.484676) (xy 8.877487 -177.448985)
			(xy 8.923337 -177.419519) (xy 8.972914 -177.396877) (xy 9.025209 -177.381522) (xy 9.079157 -177.373766)
			(xy 9.133659 -177.373766) (xy 9.187607 -177.381522) (xy 9.239902 -177.396877) (xy 9.289479 -177.419519)
			(xy 9.335329 -177.448985) (xy 9.37652 -177.484676) (xy 9.412211 -177.525867) (xy 9.441677 -177.571717)
			(xy 9.464319 -177.621294) (xy 9.479674 -177.673589) (xy 9.48743 -177.727537) (xy 9.487916 -177.754788)
			(xy 9.487916 -178.618388) (xy 9.48743 -178.645639) (xy 9.479674 -178.699587) (xy 9.464319 -178.751882)
			(xy 9.44304 -178.798474) (xy 77.963268 -178.798474) (xy 77.963886 -178.752072) (xy 77.973579 -178.659774)
			(xy 77.992835 -178.568989) (xy 78.021445 -178.480704) (xy 78.039722 -178.438048) (xy 78.043541 -178.42811)
			(xy 78.043531 -178.406843) (xy 78.039722 -178.3969) (xy 78.021451 -178.354243) (xy 77.99286 -178.265953)
			(xy 77.973605 -178.175169) (xy 77.963896 -178.082875) (xy 77.963268 -178.036474) (xy 77.963674 -177.995358)
			(xy 77.971264 -177.913476) (xy 77.986376 -177.832645) (xy 78.008882 -177.753552) (xy 78.038591 -177.676873)
			(xy 78.075247 -177.603263) (xy 78.118539 -177.533349) (xy 78.168097 -177.467728) (xy 78.223499 -177.406959)
			(xy 78.284271 -177.351561) (xy 78.349895 -177.302007) (xy 78.419812 -177.25872) (xy 78.493425 -177.222068)
			(xy 78.570105 -177.192365) (xy 78.649199 -177.169863) (xy 78.730032 -177.154756) (xy 78.811914 -177.147171)
			(xy 78.85303 -177.146712) (xy 78.893848 -177.147168) (xy 78.975141 -177.154659) (xy 79.055405 -177.169568)
			(xy 79.133966 -177.191768) (xy 79.210162 -177.221072) (xy 79.283352 -177.257234) (xy 79.352922 -177.29995)
			(xy 79.418285 -177.348861) (xy 79.478892 -177.403555) (xy 79.534233 -177.463571) (xy 79.559404 -177.495708)
			(xy 79.565179 -177.502627) (xy 79.580393 -177.512264) (xy 79.589122 -177.514504) (xy 79.631283 -177.524073)
			(xy 79.713687 -177.550242) (xy 79.793163 -177.584282) (xy 79.868962 -177.625872) (xy 79.940368 -177.67462)
			(xy 80.006708 -177.730066) (xy 80.067355 -177.791686) (xy 80.121738 -177.8589) (xy 80.169343 -177.931073)
			(xy 80.209721 -178.007525) (xy 80.242492 -178.087533) (xy 80.267345 -178.170343) (xy 80.284047 -178.255173)
			(xy 80.29244 -178.341224) (xy 80.292956 -178.384454) (xy 80.292766 -178.411062) (xy 80.289588 -178.464184)
			(xy 80.286606 -178.490626) (xy 80.285833 -178.501873) (xy 80.292962 -178.523233) (xy 80.300322 -178.531774)
			(xy 80.329261 -178.562798) (xy 80.381784 -178.629432) (xy 80.427728 -178.700761) (xy 80.466676 -178.776139)
			(xy 80.498274 -178.854881) (xy 80.522235 -178.936272) (xy 80.538342 -179.019574) (xy 80.546449 -179.104032)
			(xy 80.546956 -179.146454) (xy 80.546393 -179.191224) (xy 80.537383 -179.280309) (xy 80.519477 -179.36804)
			(xy 80.492859 -179.453531) (xy 80.475836 -179.494942) (xy 80.472299 -179.504541) (xy 80.472282 -179.524976)
			(xy 80.475836 -179.534566) (xy 80.49284 -179.575917) (xy 80.519451 -179.661279) (xy 80.537358 -179.748882)
			(xy 80.54638 -179.837839) (xy 80.546956 -179.882546) (xy 80.546956 -179.883562) (xy 80.546702 -179.894992)
			(xy 80.573181 -179.900938) (xy 80.625416 -179.915681) (xy 80.651096 -179.924456) (xy 80.659293 -179.92697)
			(xy 80.676427 -179.92697) (xy 80.684624 -179.924456) (xy 80.71984 -179.912495) (xy 80.791844 -179.893841)
			(xy 80.865165 -179.881332) (xy 80.93928 -179.875059) (xy 80.97647 -179.874672) (xy 81.013659 -179.875071)
			(xy 81.087772 -179.881358) (xy 81.161092 -179.893865) (xy 81.233098 -179.912503) (xy 81.268316 -179.924456)
			(xy 81.276513 -179.92697) (xy 81.293647 -179.92697) (xy 81.301844 -179.924456) (xy 81.337059 -179.912489)
			(xy 81.409062 -179.893837) (xy 81.482384 -179.88133) (xy 81.5565 -179.875058) (xy 81.59369 -179.874672)
			(xy 81.63563 -179.875067) (xy 81.719132 -179.883039) (xy 81.801497 -179.898913) (xy 81.88198 -179.922544)
			(xy 81.959853 -179.953719) (xy 82.03441 -179.992155) (xy 82.104975 -180.037504) (xy 82.17091 -180.089355)
			(xy 82.231618 -180.147239) (xy 82.286549 -180.210632) (xy 82.335205 -180.278959) (xy 82.377146 -180.351602)
			(xy 82.411991 -180.427903) (xy 82.439426 -180.50717) (xy 82.459202 -180.588687) (xy 82.462267 -180.610002)
			(xy 86.081108 -180.610002) (xy 86.081685 -180.565233) (xy 86.090691 -180.476148) (xy 86.108592 -180.388417)
			(xy 86.135207 -180.302925) (xy 86.152228 -180.261514) (xy 86.155792 -180.251923) (xy 86.155793 -180.231481)
			(xy 86.152228 -180.22189) (xy 86.135186 -180.180486) (xy 86.108554 -180.094996) (xy 86.090651 -180.007262)
			(xy 86.081659 -179.918173) (xy 86.081108 -179.873402) (xy 86.081685 -179.828633) (xy 86.090691 -179.739548)
			(xy 86.108592 -179.651817) (xy 86.135207 -179.566325) (xy 86.152228 -179.524914) (xy 86.155792 -179.515323)
			(xy 86.155793 -179.494881) (xy 86.152228 -179.48529) (xy 86.135186 -179.443886) (xy 86.108554 -179.358396)
			(xy 86.090651 -179.270662) (xy 86.081659 -179.181573) (xy 86.081108 -179.136802) (xy 86.081615 -179.095689)
			(xy 86.089201 -179.013813) (xy 86.10431 -178.932986) (xy 86.126812 -178.853898) (xy 86.156515 -178.777224)
			(xy 86.193165 -178.703617) (xy 86.236451 -178.633706) (xy 86.286003 -178.568087) (xy 86.341397 -178.50732)
			(xy 86.402163 -178.451923) (xy 86.46778 -178.402369) (xy 86.537689 -178.359081) (xy 86.611295 -178.322428)
			(xy 86.687968 -178.292722) (xy 86.767055 -178.270217) (xy 86.847881 -178.255106) (xy 86.929757 -178.247516)
			(xy 86.97087 -178.24704) (xy 87.01248 -178.247527) (xy 87.095336 -178.255301) (xy 87.177105 -178.270774)
			(xy 87.257073 -178.293812) (xy 87.334542 -178.324213) (xy 87.408835 -178.361712) (xy 87.444326 -178.383438)
			(xy 87.453453 -178.388623) (xy 87.474176 -178.391826) (xy 87.494454 -178.386485) (xy 87.503 -178.38039)
			(xy 87.536641 -178.354416) (xy 87.608034 -178.30829) (xy 87.683503 -178.269188) (xy 87.762359 -178.237466)
			(xy 87.843882 -178.213414) (xy 87.927328 -178.19725) (xy 88.011936 -178.189124) (xy 88.054434 -178.18862)
			(xy 88.095548 -178.18908) (xy 88.177426 -178.19667) (xy 88.258254 -178.211782) (xy 88.337343 -178.234287)
			(xy 88.414018 -178.263994) (xy 88.487625 -178.300648) (xy 88.557536 -178.343937) (xy 88.623155 -178.393491)
			(xy 88.683922 -178.448889) (xy 88.739319 -178.509657) (xy 88.788872 -178.575277) (xy 88.83216 -178.645189)
			(xy 88.868813 -178.718797) (xy 88.898518 -178.795473) (xy 88.921021 -178.874562) (xy 88.936132 -178.95539)
			(xy 88.94372 -179.037268) (xy 88.944196 -179.078382) (xy 88.943648 -179.123152) (xy 88.934633 -179.212238)
			(xy 88.916724 -179.299969) (xy 88.890101 -179.38546) (xy 88.873076 -179.42687) (xy 88.869521 -179.436464)
			(xy 88.869514 -179.456904) (xy 88.873076 -179.466494) (xy 88.890086 -179.507843) (xy 88.916696 -179.593206)
			(xy 88.934602 -179.680809) (xy 88.943621 -179.769767) (xy 88.944196 -179.814474) (xy 88.944196 -179.81549)
			(xy 88.943942 -179.82692) (xy 88.970422 -179.832862) (xy 89.022656 -179.847607) (xy 89.048336 -179.856384)
			(xy 89.056533 -179.858898) (xy 89.073667 -179.858898) (xy 89.081864 -179.856384) (xy 89.117077 -179.844413)
			(xy 89.189082 -179.825761) (xy 89.262404 -179.813256) (xy 89.33652 -179.806985) (xy 89.37371 -179.8066)
			(xy 89.4109 -179.806986) (xy 89.485013 -179.813277) (xy 89.558333 -179.825787) (xy 89.630338 -179.844429)
			(xy 89.665556 -179.856384) (xy 89.673753 -179.858898) (xy 89.690887 -179.858898) (xy 89.699084 -179.856384)
			(xy 89.734295 -179.844408) (xy 89.8063 -179.825757) (xy 89.879623 -179.813253) (xy 89.953739 -179.806984)
			(xy 89.99093 -179.8066) (xy 90.032865 -179.807156) (xy 90.116355 -179.815131) (xy 90.198709 -179.831006)
			(xy 90.279182 -179.854637) (xy 90.357043 -179.885811) (xy 90.431589 -179.924244) (xy 90.502144 -179.969589)
			(xy 90.56807 -180.021436) (xy 90.628768 -180.079314) (xy 90.683691 -180.1427) (xy 90.732339 -180.211019)
			(xy 90.774274 -180.283653) (xy 90.809114 -180.359944) (xy 90.836544 -180.439202) (xy 90.856317 -180.520708)
			(xy 90.868253 -180.603725) (xy 90.869375 -180.627274) (xy 94.473268 -180.627274) (xy 94.473838 -180.582505)
			(xy 94.482847 -180.49342) (xy 94.500749 -180.405689) (xy 94.527366 -180.320197) (xy 94.544388 -180.278786)
			(xy 94.54797 -180.2692) (xy 94.54796 -180.248753) (xy 94.544388 -180.239162) (xy 94.52734 -180.19776)
			(xy 94.500709 -180.11227) (xy 94.482808 -180.024535) (xy 94.473818 -179.935445) (xy 94.473268 -179.890674)
			(xy 94.473838 -179.845905) (xy 94.482847 -179.75682) (xy 94.500749 -179.669089) (xy 94.527366 -179.583597)
			(xy 94.544388 -179.542186) (xy 94.54797 -179.5326) (xy 94.54796 -179.512153) (xy 94.544388 -179.502562)
			(xy 94.52734 -179.46116) (xy 94.500709 -179.37567) (xy 94.482808 -179.287935) (xy 94.473818 -179.198845)
			(xy 94.473268 -179.154074) (xy 94.473674 -179.112958) (xy 94.481264 -179.031076) (xy 94.496376 -178.950245)
			(xy 94.518882 -178.871152) (xy 94.548591 -178.794473) (xy 94.585247 -178.720863) (xy 94.628539 -178.650949)
			(xy 94.678097 -178.585328) (xy 94.733499 -178.524559) (xy 94.794271 -178.469161) (xy 94.859895 -178.419607)
			(xy 94.929812 -178.37632) (xy 95.003425 -178.339668) (xy 95.080105 -178.309965) (xy 95.159199 -178.287463)
			(xy 95.240032 -178.272356) (xy 95.321914 -178.264771) (xy 95.36303 -178.264312) (xy 95.404641 -178.264773)
			(xy 95.487498 -178.272553) (xy 95.569267 -178.288031) (xy 95.649235 -178.311074) (xy 95.726703 -178.341479)
			(xy 95.800995 -178.378982) (xy 95.836486 -178.40071) (xy 95.845629 -178.405863) (xy 95.866342 -178.40908)
			(xy 95.886614 -178.403752) (xy 95.89516 -178.397662) (xy 95.928789 -178.371671) (xy 96.000183 -178.325546)
			(xy 96.075654 -178.286445) (xy 96.154512 -178.254724) (xy 96.236037 -178.230675) (xy 96.319485 -178.214515)
			(xy 96.404095 -178.206393) (xy 96.446594 -178.205892) (xy 96.487707 -178.206419) (xy 96.569582 -178.214005)
			(xy 96.650407 -178.229113) (xy 96.729494 -178.251613) (xy 96.806168 -178.281315) (xy 96.879774 -178.317965)
			(xy 96.949684 -178.36125) (xy 97.015303 -178.4108) (xy 97.07607 -178.466193) (xy 97.131467 -178.526957)
			(xy 97.181021 -178.592573) (xy 97.22431 -178.662481) (xy 97.260964 -178.736085) (xy 97.29067 -178.812756)
			(xy 97.313176 -178.891842) (xy 97.328288 -178.972667) (xy 97.335879 -179.054541) (xy 97.336356 -179.095654)
			(xy 97.335793 -179.140424) (xy 97.329275 -179.204874) (xy 368.074448 -179.204874) (xy 368.075006 -179.161932)
			(xy 368.083288 -179.076448) (xy 368.099773 -178.99216) (xy 368.124306 -178.909855) (xy 368.15666 -178.830297)
			(xy 368.196533 -178.75423) (xy 368.243554 -178.682361) (xy 368.297284 -178.615359) (xy 368.357224 -178.55385)
			(xy 368.422813 -178.498405) (xy 368.493443 -178.449542) (xy 368.568454 -178.407716) (xy 368.607594 -178.390042)
			(xy 368.615999 -178.385919) (xy 368.629281 -178.372745) (xy 368.633502 -178.364388) (xy 368.645948 -178.33721)
			(xy 368.64947 -178.328554) (xy 368.650638 -178.309919) (xy 368.648234 -178.300888) (xy 368.635415 -178.257999)
			(xy 368.617464 -178.170297) (xy 368.608423 -178.081234) (xy 368.607848 -178.036474) (xy 368.608352 -177.994113)
			(xy 368.616405 -177.909776) (xy 368.632439 -177.826586) (xy 368.656307 -177.745296) (xy 368.687795 -177.666644)
			(xy 368.726617 -177.591341) (xy 368.77242 -177.520069) (xy 368.824791 -177.453473) (xy 368.883256 -177.392158)
			(xy 368.947284 -177.336677) (xy 369.016296 -177.287534) (xy 369.089666 -177.245174) (xy 369.166731 -177.209979)
			(xy 369.246793 -177.18227) (xy 369.329126 -177.162296) (xy 369.412985 -177.150239) (xy 369.49761 -177.146208)
			(xy 369.582235 -177.150239) (xy 369.666094 -177.162296) (xy 369.748427 -177.18227) (xy 369.828489 -177.209979)
			(xy 369.905554 -177.245174) (xy 369.978924 -177.287534) (xy 370.047936 -177.336677) (xy 370.111964 -177.392158)
			(xy 370.170429 -177.453473) (xy 370.2228 -177.520069) (xy 370.268603 -177.591341) (xy 370.307425 -177.666644)
			(xy 370.338913 -177.745296) (xy 370.362781 -177.826586) (xy 370.378815 -177.909776) (xy 370.386868 -177.994113)
			(xy 370.387372 -178.036474) (xy 370.387372 -178.036728) (xy 370.386948 -178.075094) (xy 370.380306 -178.151538)
			(xy 370.367099 -178.227125) (xy 370.357654 -178.264312) (xy 370.35562 -178.273261) (xy 370.357441 -178.291512)
			(xy 370.365595 -178.307941) (xy 370.37903 -178.320427) (xy 370.387372 -178.324256) (xy 370.427603 -178.341379)
			(xy 370.50477 -178.382506) (xy 370.577528 -178.431007) (xy 370.645175 -178.486413) (xy 370.707059 -178.548191)
			(xy 370.762582 -178.615743) (xy 370.811207 -178.688417) (xy 370.852467 -178.765513) (xy 370.885962 -178.846285)
			(xy 370.911369 -178.929954) (xy 370.928442 -179.015713) (xy 370.937018 -179.102733) (xy 370.937536 -179.146454)
			(xy 370.936975 -179.191224) (xy 370.927964 -179.280309) (xy 370.910058 -179.36804) (xy 370.883439 -179.453531)
			(xy 370.866416 -179.494942) (xy 370.86288 -179.504541) (xy 370.862862 -179.524975) (xy 370.866416 -179.534566)
			(xy 370.883441 -179.575977) (xy 370.910078 -179.661464) (xy 370.927986 -179.749196) (xy 370.936982 -179.838284)
			(xy 370.937536 -179.883054) (xy 370.937282 -179.903882) (xy 370.937631 -179.91519) (xy 370.946776 -179.935848)
			(xy 370.963889 -179.950596) (xy 370.97462 -179.954174) (xy 370.989618 -179.95835) (xy 371.019344 -179.967623)
			(xy 371.034056 -179.972716) (xy 371.042253 -179.97523) (xy 371.059387 -179.97523) (xy 371.067584 -179.972716)
			(xy 371.102796 -179.960741) (xy 371.174801 -179.94209) (xy 371.248123 -179.929585) (xy 371.322239 -179.923316)
			(xy 371.35943 -179.922932) (xy 371.396619 -179.923339) (xy 371.470732 -179.929623) (xy 371.544052 -179.942128)
			(xy 371.616058 -179.960764) (xy 371.651276 -179.972716) (xy 371.659473 -179.97523) (xy 371.676607 -179.97523)
			(xy 371.684804 -179.972716) (xy 371.720023 -179.960763) (xy 371.792025 -179.942106) (xy 371.865345 -179.929595)
			(xy 371.93946 -179.923319) (xy 371.97665 -179.922932) (xy 372.01859 -179.923405) (xy 372.10209 -179.931374)
			(xy 372.184455 -179.947244) (xy 372.264938 -179.970872) (xy 372.34281 -180.002043) (xy 372.417367 -180.040476)
			(xy 372.487932 -180.085822) (xy 372.553868 -180.137671) (xy 372.614576 -180.195553) (xy 372.669507 -180.258944)
			(xy 372.718163 -180.327269) (xy 372.760105 -180.39991) (xy 372.794951 -180.476209) (xy 372.822386 -180.555475)
			(xy 372.842162 -180.63699) (xy 372.848069 -180.678074) (xy 376.477276 -180.678074) (xy 376.477846 -180.633305)
			(xy 376.486854 -180.54422) (xy 376.504757 -180.456489) (xy 376.531374 -180.370997) (xy 376.548396 -180.329586)
			(xy 376.551978 -180.32) (xy 376.551968 -180.299553) (xy 376.548396 -180.289962) (xy 376.531349 -180.24856)
			(xy 376.504717 -180.16307) (xy 376.486816 -180.075335) (xy 376.477826 -179.986245) (xy 376.477276 -179.941474)
			(xy 376.477846 -179.896705) (xy 376.486854 -179.80762) (xy 376.504757 -179.719889) (xy 376.531374 -179.634397)
			(xy 376.548396 -179.592986) (xy 376.551978 -179.5834) (xy 376.551968 -179.562953) (xy 376.548396 -179.553362)
			(xy 376.531349 -179.51196) (xy 376.504717 -179.42647) (xy 376.486816 -179.338735) (xy 376.477826 -179.249645)
			(xy 376.477276 -179.204874) (xy 376.477674 -179.163758) (xy 376.485264 -179.081876) (xy 376.500376 -179.001043)
			(xy 376.522883 -178.92195) (xy 376.552591 -178.845272) (xy 376.589248 -178.771661) (xy 376.632541 -178.701747)
			(xy 376.682099 -178.636125) (xy 376.737501 -178.575356) (xy 376.798274 -178.519958) (xy 376.863899 -178.470404)
			(xy 376.933817 -178.427117) (xy 377.00743 -178.390466) (xy 377.084111 -178.360763) (xy 377.163206 -178.338262)
			(xy 377.244039 -178.323155) (xy 377.325922 -178.315571) (xy 377.367038 -178.315112) (xy 377.408648 -178.315619)
			(xy 377.491503 -178.323389) (xy 377.573272 -178.338859) (xy 377.65324 -178.361894) (xy 377.730709 -178.392291)
			(xy 377.805002 -178.429786) (xy 377.840494 -178.45151) (xy 377.849633 -178.45667) (xy 377.870349 -178.459885)
			(xy 377.890623 -178.454554) (xy 377.899168 -178.448462) (xy 377.932829 -178.422514) (xy 378.004217 -178.376384)
			(xy 378.079682 -178.337278) (xy 378.158534 -178.305551) (xy 378.240054 -178.281495) (xy 378.323498 -178.265328)
			(xy 378.408104 -178.257198) (xy 378.450602 -178.256692) (xy 378.491715 -178.257211) (xy 378.57359 -178.264798)
			(xy 378.654416 -178.279906) (xy 378.733503 -178.302408) (xy 378.810176 -178.33211) (xy 378.883782 -178.368761)
			(xy 378.953693 -178.412046) (xy 379.019312 -178.461597) (xy 379.080078 -178.51699) (xy 379.135475 -178.577755)
			(xy 379.185029 -178.643371) (xy 379.228318 -178.713279) (xy 379.264972 -178.786883) (xy 379.294678 -178.863555)
			(xy 379.317184 -178.942641) (xy 379.332296 -179.023466) (xy 379.339887 -179.105341) (xy 379.340364 -179.146454)
			(xy 379.339801 -179.191224) (xy 379.330791 -179.280309) (xy 379.312886 -179.36804) (xy 379.286267 -179.453531)
			(xy 379.269244 -179.494942) (xy 379.265706 -179.50454) (xy 379.265689 -179.524976) (xy 379.269244 -179.534566)
			(xy 379.286249 -179.575917) (xy 379.31286 -179.661279) (xy 379.330766 -179.748882) (xy 379.339788 -179.837839)
			(xy 379.340364 -179.882546) (xy 379.340364 -179.883562) (xy 379.34011 -179.894992) (xy 379.366589 -179.900938)
			(xy 379.418824 -179.915681) (xy 379.444504 -179.924456) (xy 379.452701 -179.92697) (xy 379.469835 -179.92697)
			(xy 379.478032 -179.924456) (xy 379.513248 -179.912493) (xy 379.585251 -179.893839) (xy 379.658572 -179.881331)
			(xy 379.732688 -179.875058) (xy 379.769878 -179.874672) (xy 379.807067 -179.875069) (xy 379.88118 -179.881356)
			(xy 379.9545 -179.893864) (xy 380.026506 -179.912502) (xy 380.061724 -179.924456) (xy 380.069921 -179.92697)
			(xy 380.087055 -179.92697) (xy 380.095252 -179.924456) (xy 380.130466 -179.912487) (xy 380.20247 -179.893835)
			(xy 380.275792 -179.881329) (xy 380.349908 -179.875057) (xy 380.387098 -179.874672) (xy 380.429038 -179.875067)
			(xy 380.512539 -179.88304) (xy 380.594904 -179.898915) (xy 380.675386 -179.922546) (xy 380.753258 -179.953722)
			(xy 380.827814 -179.992158) (xy 380.898379 -180.037507) (xy 380.964314 -180.089358) (xy 381.025021 -180.147242)
			(xy 381.079951 -180.210635) (xy 381.128607 -180.278962) (xy 381.170547 -180.351604) (xy 381.205392 -180.427905)
			(xy 381.232827 -180.507172) (xy 381.252602 -180.588688) (xy 381.26454 -180.671715) (xy 381.264843 -180.678074)
			(xy 384.808476 -180.678074) (xy 384.809046 -180.633305) (xy 384.818054 -180.54422) (xy 384.835957 -180.456489)
			(xy 384.862574 -180.370997) (xy 384.879596 -180.329586) (xy 384.883178 -180.32) (xy 384.883168 -180.299553)
			(xy 384.879596 -180.289962) (xy 384.862549 -180.24856) (xy 384.835917 -180.16307) (xy 384.818016 -180.075335)
			(xy 384.809026 -179.986245) (xy 384.808476 -179.941474) (xy 384.809046 -179.896705) (xy 384.818054 -179.80762)
			(xy 384.835957 -179.719889) (xy 384.862574 -179.634397) (xy 384.879596 -179.592986) (xy 384.883178 -179.5834)
			(xy 384.883168 -179.562953) (xy 384.879596 -179.553362) (xy 384.862549 -179.51196) (xy 384.835917 -179.42647)
			(xy 384.818016 -179.338735) (xy 384.809026 -179.249645) (xy 384.808476 -179.204874) (xy 384.808874 -179.163758)
			(xy 384.816464 -179.081876) (xy 384.831576 -179.001043) (xy 384.854083 -178.92195) (xy 384.883791 -178.845272)
			(xy 384.920448 -178.771661) (xy 384.963741 -178.701747) (xy 385.013299 -178.636125) (xy 385.068701 -178.575356)
			(xy 385.129474 -178.519958) (xy 385.195099 -178.470404) (xy 385.265017 -178.427117) (xy 385.33863 -178.390466)
			(xy 385.415311 -178.360763) (xy 385.494406 -178.338262) (xy 385.575239 -178.323155) (xy 385.657122 -178.315571)
			(xy 385.698238 -178.315112) (xy 385.739848 -178.315619) (xy 385.822703 -178.323389) (xy 385.904472 -178.338859)
			(xy 385.98444 -178.361894) (xy 386.061909 -178.392291) (xy 386.136202 -178.429786) (xy 386.171694 -178.45151)
			(xy 386.180833 -178.45667) (xy 386.201549 -178.459885) (xy 386.221823 -178.454554) (xy 386.230368 -178.448462)
			(xy 386.264029 -178.422514) (xy 386.335417 -178.376384) (xy 386.410882 -178.337278) (xy 386.489734 -178.305551)
			(xy 386.571254 -178.281495) (xy 386.654698 -178.265328) (xy 386.739304 -178.257198) (xy 386.781802 -178.256692)
			(xy 386.822915 -178.257211) (xy 386.90479 -178.264798) (xy 386.985616 -178.279906) (xy 387.064703 -178.302408)
			(xy 387.141376 -178.33211) (xy 387.214982 -178.368761) (xy 387.284893 -178.412046) (xy 387.350512 -178.461597)
			(xy 387.411278 -178.51699) (xy 387.466675 -178.577755) (xy 387.516229 -178.643371) (xy 387.559518 -178.713279)
			(xy 387.596172 -178.786883) (xy 387.625878 -178.863555) (xy 387.648384 -178.942641) (xy 387.663496 -179.023466)
			(xy 387.671087 -179.105341) (xy 387.671564 -179.146454) (xy 387.671001 -179.191224) (xy 387.661991 -179.280309)
			(xy 387.644086 -179.36804) (xy 387.617467 -179.453531) (xy 387.600444 -179.494942) (xy 387.596906 -179.50454)
			(xy 387.596889 -179.524976) (xy 387.600444 -179.534566) (xy 387.617449 -179.575917) (xy 387.64406 -179.661279)
			(xy 387.661966 -179.748882) (xy 387.670988 -179.837839) (xy 387.671564 -179.882546) (xy 387.671564 -179.883562)
			(xy 387.67131 -179.894992) (xy 387.697789 -179.900938) (xy 387.750024 -179.915681) (xy 387.775704 -179.924456)
			(xy 387.783901 -179.92697) (xy 387.801035 -179.92697) (xy 387.809232 -179.924456) (xy 387.844448 -179.912493)
			(xy 387.916451 -179.893839) (xy 387.989772 -179.881331) (xy 388.063888 -179.875058) (xy 388.101078 -179.874672)
			(xy 388.138267 -179.875069) (xy 388.21238 -179.881356) (xy 388.2857 -179.893864) (xy 388.357706 -179.912502)
			(xy 388.392924 -179.924456) (xy 388.401121 -179.92697) (xy 388.418255 -179.92697) (xy 388.426452 -179.924456)
			(xy 388.461666 -179.912487) (xy 388.53367 -179.893835) (xy 388.606992 -179.881329) (xy 388.681108 -179.875057)
			(xy 388.718298 -179.874672) (xy 388.760238 -179.875067) (xy 388.843739 -179.88304) (xy 388.926104 -179.898915)
			(xy 389.006586 -179.922546) (xy 389.084458 -179.953722) (xy 389.159014 -179.992158) (xy 389.229579 -180.037507)
			(xy 389.295514 -180.089358) (xy 389.356221 -180.147242) (xy 389.411151 -180.210635) (xy 389.459807 -180.278962)
			(xy 389.501747 -180.351604) (xy 389.536592 -180.427905) (xy 389.564027 -180.507172) (xy 389.583802 -180.588688)
			(xy 389.59574 -180.671715) (xy 389.599731 -180.7555) (xy 389.59574 -180.839285) (xy 389.583802 -180.922312)
			(xy 389.564027 -181.003828) (xy 389.536592 -181.083095) (xy 389.501747 -181.159396) (xy 389.459807 -181.232038)
			(xy 389.411151 -181.300365) (xy 389.356221 -181.363758) (xy 389.295514 -181.421642) (xy 389.229579 -181.473493)
			(xy 389.159014 -181.518842) (xy 389.084458 -181.557278) (xy 389.006586 -181.588454) (xy 388.926104 -181.612085)
			(xy 388.843739 -181.62796) (xy 388.760238 -181.635933) (xy 388.718298 -181.636416) (xy 388.681108 -181.636027)
			(xy 388.606996 -181.629737) (xy 388.533676 -181.617227) (xy 388.46167 -181.598587) (xy 388.426452 -181.586632)
			(xy 388.418255 -181.584118) (xy 388.401121 -181.584118) (xy 388.392924 -181.586632) (xy 388.365208 -181.596078)
			(xy 388.308773 -181.611711) (xy 388.280148 -181.617874) (xy 388.270401 -181.620348) (xy 388.25379 -181.63165)
			(xy 388.242792 -181.648464) (xy 388.240524 -181.65826) (xy 388.231054 -181.705587) (xy 388.203179 -181.797995)
			(xy 388.184898 -181.842664) (xy 388.181281 -181.852235) (xy 388.18114 -181.872676) (xy 388.184644 -181.882288)
			(xy 388.201684 -181.923659) (xy 388.228298 -182.009088) (xy 388.246197 -182.096758) (xy 388.255201 -182.185783)
			(xy 388.255764 -182.230522) (xy 388.255764 -182.230776) (xy 388.25526 -182.273124) (xy 388.247209 -182.357438)
			(xy 388.23118 -182.440604) (xy 388.207319 -182.521871) (xy 388.17584 -182.600501) (xy 388.137029 -182.675782)
			(xy 388.091239 -182.747034) (xy 388.038883 -182.81361) (xy 387.980435 -182.874908) (xy 387.916425 -182.930373)
			(xy 387.847433 -182.979502) (xy 387.774083 -183.021851) (xy 387.69704 -183.057035) (xy 387.617001 -183.084737)
			(xy 387.534692 -183.104705) (xy 387.450857 -183.116758) (xy 387.366256 -183.120789) (xy 387.281655 -183.116758)
			(xy 387.19782 -183.104705) (xy 387.115511 -183.084737) (xy 387.035472 -183.057035) (xy 386.958429 -183.021851)
			(xy 386.885079 -182.979502) (xy 386.816087 -182.930373) (xy 386.752077 -182.874908) (xy 386.693629 -182.81361)
			(xy 386.641273 -182.747034) (xy 386.595483 -182.675782) (xy 386.556672 -182.600501) (xy 386.525193 -182.521871)
			(xy 386.501332 -182.440604) (xy 386.485303 -182.357438) (xy 386.477252 -182.273124) (xy 386.476748 -182.230776)
			(xy 386.476748 -182.230522) (xy 386.477311 -182.185784) (xy 386.486329 -182.096762) (xy 386.504235 -182.009095)
			(xy 386.53085 -181.923667) (xy 386.547868 -181.882288) (xy 386.551445 -181.872701) (xy 386.551436 -181.852255)
			(xy 386.547868 -181.842664) (xy 386.53084 -181.801254) (xy 386.504206 -181.715766) (xy 386.4863 -181.628034)
			(xy 386.477302 -181.538946) (xy 386.476748 -181.494176) (xy 386.477087 -181.458262) (xy 386.482864 -181.386666)
			(xy 386.494395 -181.315769) (xy 386.502656 -181.280816) (xy 386.504356 -181.272508) (xy 386.502799 -181.255633)
			(xy 386.495808 -181.240195) (xy 386.49021 -181.233826) (xy 386.44957 -181.1909) (xy 386.43941 -181.193186)
			(xy 386.430637 -181.195432) (xy 386.415405 -181.205208) (xy 386.409692 -181.212236) (xy 386.384552 -181.244927)
			(xy 386.329156 -181.306026) (xy 386.268343 -181.361734) (xy 386.202634 -181.411575) (xy 386.132593 -181.455119)
			(xy 386.058822 -181.491993) (xy 385.981955 -181.521881) (xy 385.902652 -181.544524) (xy 385.821593 -181.55973)
			(xy 385.739474 -181.567368) (xy 385.698238 -181.567836) (xy 385.657123 -181.567365) (xy 385.575243 -181.559781)
			(xy 385.494413 -181.544674) (xy 385.415321 -181.522173) (xy 385.338643 -181.49247) (xy 385.265033 -181.455819)
			(xy 385.195119 -181.412532) (xy 385.129497 -181.362978) (xy 385.068728 -181.30758) (xy 385.01333 -181.246812)
			(xy 384.963775 -181.181191) (xy 384.920487 -181.111277) (xy 384.883834 -181.037668) (xy 384.854131 -180.96099)
			(xy 384.831629 -180.881899) (xy 384.81652 -180.801068) (xy 384.808935 -180.719189) (xy 384.808476 -180.678074)
			(xy 381.264843 -180.678074) (xy 381.268531 -180.7555) (xy 381.26454 -180.839285) (xy 381.252602 -180.922312)
			(xy 381.232827 -181.003828) (xy 381.205392 -181.083095) (xy 381.170547 -181.159396) (xy 381.128607 -181.232038)
			(xy 381.079951 -181.300365) (xy 381.025021 -181.363758) (xy 380.964314 -181.421642) (xy 380.898379 -181.473493)
			(xy 380.827814 -181.518842) (xy 380.753258 -181.557278) (xy 380.675386 -181.588454) (xy 380.594904 -181.612085)
			(xy 380.512539 -181.62796) (xy 380.429038 -181.635933) (xy 380.387098 -181.636416) (xy 380.349908 -181.636027)
			(xy 380.275796 -181.629737) (xy 380.202476 -181.617227) (xy 380.13047 -181.598587) (xy 380.095252 -181.586632)
			(xy 380.087055 -181.584118) (xy 380.069921 -181.584118) (xy 380.061724 -181.586632) (xy 380.034008 -181.596078)
			(xy 379.977573 -181.611711) (xy 379.948948 -181.617874) (xy 379.939201 -181.620348) (xy 379.92259 -181.63165)
			(xy 379.911592 -181.648464) (xy 379.909324 -181.65826) (xy 379.899854 -181.705587) (xy 379.871979 -181.797995)
			(xy 379.853698 -181.842664) (xy 379.850081 -181.852235) (xy 379.84994 -181.872676) (xy 379.853444 -181.882288)
			(xy 379.870484 -181.923659) (xy 379.897098 -182.009088) (xy 379.914997 -182.096758) (xy 379.924001 -182.185783)
			(xy 379.924564 -182.230522) (xy 379.924564 -182.230776) (xy 379.92406 -182.273124) (xy 379.916009 -182.357438)
			(xy 379.89998 -182.440604) (xy 379.876119 -182.521871) (xy 379.84464 -182.600501) (xy 379.805829 -182.675782)
			(xy 379.760039 -182.747034) (xy 379.707683 -182.81361) (xy 379.649235 -182.874908) (xy 379.585225 -182.930373)
			(xy 379.516233 -182.979502) (xy 379.442883 -183.021851) (xy 379.36584 -183.057035) (xy 379.285801 -183.084737)
			(xy 379.203492 -183.104705) (xy 379.119657 -183.116758) (xy 379.035056 -183.120789) (xy 378.950455 -183.116758)
			(xy 378.86662 -183.104705) (xy 378.784311 -183.084737) (xy 378.704272 -183.057035) (xy 378.627229 -183.021851)
			(xy 378.553879 -182.979502) (xy 378.484887 -182.930373) (xy 378.420877 -182.874908) (xy 378.362429 -182.81361)
			(xy 378.310073 -182.747034) (xy 378.264283 -182.675782) (xy 378.225472 -182.600501) (xy 378.193993 -182.521871)
			(xy 378.170132 -182.440604) (xy 378.154103 -182.357438) (xy 378.146052 -182.273124) (xy 378.145548 -182.230776)
			(xy 378.145548 -182.230522) (xy 378.146111 -182.185784) (xy 378.155129 -182.096762) (xy 378.173035 -182.009095)
			(xy 378.19965 -181.923667) (xy 378.216668 -181.882288) (xy 378.220245 -181.872701) (xy 378.220236 -181.852255)
			(xy 378.216668 -181.842664) (xy 378.19964 -181.801254) (xy 378.173006 -181.715766) (xy 378.1551 -181.628034)
			(xy 378.146102 -181.538946) (xy 378.145548 -181.494176) (xy 378.145887 -181.458262) (xy 378.151664 -181.386666)
			(xy 378.163195 -181.315769) (xy 378.171456 -181.280816) (xy 378.173156 -181.272508) (xy 378.171599 -181.255633)
			(xy 378.164608 -181.240195) (xy 378.15901 -181.233826) (xy 378.11837 -181.1909) (xy 378.10821 -181.193186)
			(xy 378.099437 -181.195432) (xy 378.084205 -181.205208) (xy 378.078492 -181.212236) (xy 378.053352 -181.244927)
			(xy 377.997956 -181.306026) (xy 377.937143 -181.361734) (xy 377.871434 -181.411575) (xy 377.801393 -181.455119)
			(xy 377.727622 -181.491993) (xy 377.650755 -181.521881) (xy 377.571452 -181.544524) (xy 377.490393 -181.55973)
			(xy 377.408274 -181.567368) (xy 377.367038 -181.567836) (xy 377.325923 -181.567365) (xy 377.244043 -181.559781)
			(xy 377.163213 -181.544674) (xy 377.084121 -181.522173) (xy 377.007443 -181.49247) (xy 376.933833 -181.455819)
			(xy 376.863919 -181.412532) (xy 376.798297 -181.362978) (xy 376.737528 -181.30758) (xy 376.68213 -181.246812)
			(xy 376.632575 -181.181191) (xy 376.589287 -181.111277) (xy 376.552634 -181.037668) (xy 376.522931 -180.96099)
			(xy 376.500429 -180.881899) (xy 376.48532 -180.801068) (xy 376.477735 -180.719189) (xy 376.477276 -180.678074)
			(xy 372.848069 -180.678074) (xy 372.8541 -180.720015) (xy 372.858091 -180.8038) (xy 372.8541 -180.887585)
			(xy 372.842162 -180.97061) (xy 372.822386 -181.052125) (xy 372.794951 -181.131391) (xy 372.760105 -181.20769)
			(xy 372.718163 -181.280331) (xy 372.669507 -181.348656) (xy 372.614576 -181.412047) (xy 372.553868 -181.469929)
			(xy 372.487932 -181.521778) (xy 372.417367 -181.567124) (xy 372.34281 -181.605557) (xy 372.264938 -181.636728)
			(xy 372.184455 -181.660356) (xy 372.10209 -181.676226) (xy 372.01859 -181.684195) (xy 371.97665 -181.684676)
			(xy 371.939461 -181.684274) (xy 371.865348 -181.677988) (xy 371.792028 -181.665482) (xy 371.720022 -181.646845)
			(xy 371.684804 -181.634892) (xy 371.676607 -181.632378) (xy 371.659473 -181.632378) (xy 371.651276 -181.634892)
			(xy 371.611916 -181.648156) (xy 371.531285 -181.66812) (xy 371.449135 -181.680416) (xy 371.40769 -181.683152)
			(xy 371.397889 -181.684131) (xy 371.380113 -181.692579) (xy 371.36683 -181.707102) (xy 371.362986 -181.716172)
			(xy 371.348 -181.753764) (xy 371.344428 -181.763418) (xy 371.344429 -181.783987) (xy 371.348 -181.793642)
			(xy 371.365038 -181.835014) (xy 371.391656 -181.920442) (xy 371.409557 -182.008112) (xy 371.418559 -182.097137)
			(xy 371.41912 -182.141876) (xy 371.418616 -182.184237) (xy 371.410563 -182.268574) (xy 371.394529 -182.351764)
			(xy 371.370661 -182.433054) (xy 371.339173 -182.511706) (xy 371.300351 -182.587009) (xy 371.254548 -182.658281)
			(xy 371.202177 -182.724877) (xy 371.143712 -182.786192) (xy 371.079684 -182.841673) (xy 371.010672 -182.890816)
			(xy 370.937302 -182.933176) (xy 370.860237 -182.968371) (xy 370.780175 -182.99608) (xy 370.697842 -183.016054)
			(xy 370.613983 -183.028111) (xy 370.529358 -183.032143) (xy 370.444733 -183.028111) (xy 370.360874 -183.016054)
			(xy 370.278541 -182.99608) (xy 370.198479 -182.968371) (xy 370.121414 -182.933176) (xy 370.048044 -182.890816)
			(xy 369.979032 -182.841673) (xy 369.915004 -182.786192) (xy 369.856539 -182.724877) (xy 369.804168 -182.658281)
			(xy 369.758365 -182.587009) (xy 369.719543 -182.511706) (xy 369.688055 -182.433054) (xy 369.664187 -182.351764)
			(xy 369.648153 -182.268574) (xy 369.6401 -182.184237) (xy 369.639596 -182.141876) (xy 369.640165 -182.097107)
			(xy 369.649173 -182.008022) (xy 369.667076 -181.92029) (xy 369.693694 -181.834799) (xy 369.710716 -181.793388)
			(xy 369.714296 -181.783802) (xy 369.714287 -181.763355) (xy 369.710716 -181.753764) (xy 369.693665 -181.712364)
			(xy 369.667035 -181.626872) (xy 369.649135 -181.539137) (xy 369.640146 -181.450047) (xy 369.639596 -181.405276)
			(xy 369.639771 -181.384669) (xy 369.641804 -181.343504) (xy 369.64366 -181.32298) (xy 369.644023 -181.312283)
			(xy 369.63707 -181.292069) (xy 369.630198 -181.283864) (xy 369.57127 -181.22011) (xy 369.551204 -181.211728)
			(xy 369.540282 -181.211982) (xy 369.523264 -181.212236) (xy 369.522756 -181.212236) (xy 369.481649 -181.211766)
			(xy 369.399787 -181.204159) (xy 369.318976 -181.189032) (xy 369.239905 -181.166515) (xy 369.163248 -181.136799)
			(xy 369.08966 -181.100138) (xy 369.019768 -181.056844) (xy 368.954168 -181.007287) (xy 368.893419 -180.95189)
			(xy 368.83804 -180.891125) (xy 368.788503 -180.825509) (xy 368.745231 -180.755604) (xy 368.708592 -180.682005)
			(xy 368.678899 -180.605339) (xy 368.656406 -180.526261) (xy 368.641304 -180.445446) (xy 368.633721 -180.363581)
			(xy 368.633248 -180.322474) (xy 368.6337 -180.283493) (xy 368.640575 -180.205835) (xy 368.654226 -180.129077)
			(xy 368.663982 -180.091334) (xy 368.666037 -180.082278) (xy 368.664208 -180.063813) (xy 368.655908 -180.047218)
			(xy 368.642231 -180.034679) (xy 368.633756 -180.030882) (xy 368.596114 -180.015301) (xy 368.523548 -179.97826)
			(xy 368.454673 -179.934739) (xy 368.390066 -179.885102) (xy 368.330268 -179.829767) (xy 368.27578 -179.769195)
			(xy 368.227059 -179.703896) (xy 368.184512 -179.634415) (xy 368.148496 -179.561335) (xy 368.119314 -179.485268)
			(xy 368.097208 -179.406851) (xy 368.082365 -179.326741) (xy 368.074909 -179.24561) (xy 368.074448 -179.204874)
			(xy 97.329275 -179.204874) (xy 97.326783 -179.229509) (xy 97.308877 -179.31724) (xy 97.282259 -179.402731)
			(xy 97.265236 -179.444142) (xy 97.261699 -179.453741) (xy 97.261682 -179.474176) (xy 97.265236 -179.483766)
			(xy 97.28224 -179.525117) (xy 97.308851 -179.610479) (xy 97.326758 -179.698082) (xy 97.33578 -179.787039)
			(xy 97.336356 -179.831746) (xy 97.336356 -179.832762) (xy 97.336102 -179.844192) (xy 97.362581 -179.850138)
			(xy 97.414816 -179.864881) (xy 97.440496 -179.873656) (xy 97.448693 -179.87617) (xy 97.465827 -179.87617)
			(xy 97.474024 -179.873656) (xy 97.50924 -179.861695) (xy 97.581244 -179.843041) (xy 97.654565 -179.830532)
			(xy 97.72868 -179.824259) (xy 97.76587 -179.823872) (xy 97.803059 -179.824271) (xy 97.877172 -179.830558)
			(xy 97.950492 -179.843065) (xy 98.022498 -179.861703) (xy 98.057716 -179.873656) (xy 98.065913 -179.87617)
			(xy 98.083047 -179.87617) (xy 98.091244 -179.873656) (xy 98.126459 -179.861689) (xy 98.198462 -179.843037)
			(xy 98.271784 -179.83053) (xy 98.3459 -179.824258) (xy 98.38309 -179.823872) (xy 98.42503 -179.824267)
			(xy 98.508532 -179.832239) (xy 98.590897 -179.848113) (xy 98.67138 -179.871744) (xy 98.749253 -179.902919)
			(xy 98.82381 -179.941355) (xy 98.894375 -179.986704) (xy 98.96031 -180.038555) (xy 99.021018 -180.096439)
			(xy 99.075949 -180.159832) (xy 99.124605 -180.228159) (xy 99.166546 -180.300802) (xy 99.201391 -180.377103)
			(xy 99.228826 -180.45637) (xy 99.248602 -180.537887) (xy 99.26054 -180.620914) (xy 99.264531 -180.7047)
			(xy 99.26054 -180.788486) (xy 99.248602 -180.871513) (xy 99.228826 -180.95303) (xy 99.201391 -181.032297)
			(xy 99.166546 -181.108598) (xy 99.124605 -181.181241) (xy 99.075949 -181.249568) (xy 99.021018 -181.312961)
			(xy 98.96031 -181.370845) (xy 98.894375 -181.422696) (xy 98.82381 -181.468045) (xy 98.749253 -181.506481)
			(xy 98.67138 -181.537656) (xy 98.590897 -181.561287) (xy 98.508532 -181.577161) (xy 98.42503 -181.585133)
			(xy 98.38309 -181.585616) (xy 98.3459 -181.585229) (xy 98.271787 -181.578939) (xy 98.198468 -181.566428)
			(xy 98.126462 -181.547787) (xy 98.091244 -181.535832) (xy 98.083047 -181.533318) (xy 98.065913 -181.533318)
			(xy 98.057716 -181.535832) (xy 98.015534 -181.549982) (xy 97.929009 -181.570726) (xy 97.884996 -181.577234)
			(xy 97.875031 -181.57898) (xy 97.85759 -181.589205) (xy 97.845466 -181.605383) (xy 97.842578 -181.61508)
			(xy 97.833805 -181.648299) (xy 97.811813 -181.713397) (xy 97.798636 -181.745128) (xy 97.79505 -181.754712)
			(xy 97.795064 -181.775161) (xy 97.798636 -181.784752) (xy 97.815664 -181.826127) (xy 97.842281 -181.911555)
			(xy 97.860184 -181.999224) (xy 97.869191 -182.088247) (xy 97.869756 -182.132986) (xy 97.869756 -182.13324)
			(xy 97.869252 -182.175588) (xy 97.861201 -182.259902) (xy 97.845172 -182.343068) (xy 97.821311 -182.424335)
			(xy 97.789832 -182.502965) (xy 97.751021 -182.578246) (xy 97.705231 -182.649498) (xy 97.652875 -182.716074)
			(xy 97.594427 -182.777372) (xy 97.530417 -182.832837) (xy 97.461425 -182.881966) (xy 97.388075 -182.924315)
			(xy 97.311032 -182.959499) (xy 97.230993 -182.987201) (xy 97.148684 -183.007169) (xy 97.064849 -183.019222)
			(xy 96.980248 -183.023253) (xy 96.895647 -183.019222) (xy 96.811812 -183.007169) (xy 96.729503 -182.987201)
			(xy 96.649464 -182.959499) (xy 96.572421 -182.924315) (xy 96.499071 -182.881966) (xy 96.430079 -182.832837)
			(xy 96.366069 -182.777372) (xy 96.307621 -182.716074) (xy 96.255265 -182.649498) (xy 96.209475 -182.578246)
			(xy 96.170664 -182.502965) (xy 96.139185 -182.424335) (xy 96.115324 -182.343068) (xy 96.099295 -182.259902)
			(xy 96.091244 -182.175588) (xy 96.09074 -182.13324) (xy 96.09074 -182.132986) (xy 96.091318 -182.088248)
			(xy 96.10033 -181.999226) (xy 96.118232 -181.911559) (xy 96.144843 -181.826131) (xy 96.16186 -181.784752)
			(xy 96.165401 -181.775154) (xy 96.165416 -181.754718) (xy 96.16186 -181.745128) (xy 96.144825 -181.703755)
			(xy 96.11821 -181.618327) (xy 96.100309 -181.530657) (xy 96.091304 -181.441633) (xy 96.09074 -181.396894)
			(xy 96.09074 -181.395878) (xy 96.090368 -181.38632) (xy 96.083332 -181.368547) (xy 96.070254 -181.354605)
			(xy 96.061784 -181.350158) (xy 95.965264 -181.304184) (xy 95.936308 -181.30774) (xy 95.924878 -181.317138)
			(xy 95.890853 -181.344159) (xy 95.818459 -181.392213) (xy 95.741724 -181.43298) (xy 95.66138 -181.466069)
			(xy 95.578192 -181.491168) (xy 95.492953 -181.508035) (xy 95.406476 -181.51651) (xy 95.36303 -181.517036)
			(xy 95.321915 -181.516573) (xy 95.240035 -181.508988) (xy 95.159204 -181.49388) (xy 95.080113 -181.471379)
			(xy 95.003435 -181.441675) (xy 94.929825 -181.405023) (xy 94.859911 -181.361735) (xy 94.794289 -181.312181)
			(xy 94.73352 -181.256783) (xy 94.678122 -181.196014) (xy 94.628567 -181.130393) (xy 94.585279 -181.060479)
			(xy 94.548626 -180.986869) (xy 94.518922 -180.910191) (xy 94.49642 -180.831099) (xy 94.481312 -180.750269)
			(xy 94.473727 -180.668389) (xy 94.473268 -180.627274) (xy 90.869375 -180.627274) (xy 90.872244 -180.6875)
			(xy 90.868253 -180.771275) (xy 90.856317 -180.854292) (xy 90.836544 -180.935798) (xy 90.809114 -181.015056)
			(xy 90.774274 -181.091347) (xy 90.732339 -181.163981) (xy 90.683691 -181.2323) (xy 90.628768 -181.295686)
			(xy 90.56807 -181.353564) (xy 90.502144 -181.405411) (xy 90.431589 -181.450756) (xy 90.357043 -181.489189)
			(xy 90.279182 -181.520363) (xy 90.198709 -181.543994) (xy 90.116355 -181.559869) (xy 90.032865 -181.567844)
			(xy 89.99093 -181.568344) (xy 89.953741 -181.567944) (xy 89.879628 -181.561657) (xy 89.806308 -181.54915)
			(xy 89.734302 -181.530513) (xy 89.699084 -181.51856) (xy 89.690887 -181.516046) (xy 89.673753 -181.516046)
			(xy 89.665556 -181.51856) (xy 89.630433 -181.5305) (xy 89.558617 -181.54912) (xy 89.485489 -181.561626)
			(xy 89.411567 -181.56793) (xy 89.374472 -181.568344) (xy 89.372948 -181.568344) (xy 89.365328 -181.56809)
			(xy 89.355809 -181.6135) (xy 89.328579 -181.702202) (xy 89.310972 -181.745128) (xy 89.307384 -181.754712)
			(xy 89.307399 -181.775161) (xy 89.310972 -181.784752) (xy 89.327996 -181.826163) (xy 89.354632 -181.91165)
			(xy 89.37254 -181.999382) (xy 89.381538 -182.08847) (xy 89.382092 -182.13324) (xy 89.381588 -182.175601)
			(xy 89.373535 -182.259938) (xy 89.357501 -182.343128) (xy 89.333633 -182.424418) (xy 89.302145 -182.50307)
			(xy 89.263323 -182.578373) (xy 89.21752 -182.649645) (xy 89.165149 -182.716241) (xy 89.106684 -182.777556)
			(xy 89.042656 -182.833037) (xy 88.973644 -182.88218) (xy 88.900274 -182.92454) (xy 88.823209 -182.959735)
			(xy 88.743147 -182.987444) (xy 88.660814 -183.007418) (xy 88.576955 -183.019475) (xy 88.49233 -183.023507)
			(xy 88.407705 -183.019475) (xy 88.323846 -183.007418) (xy 88.241513 -182.987444) (xy 88.161451 -182.959735)
			(xy 88.084386 -182.92454) (xy 88.011016 -182.88218) (xy 87.942004 -182.833037) (xy 87.877976 -182.777556)
			(xy 87.819511 -182.716241) (xy 87.76714 -182.649645) (xy 87.721337 -182.578373) (xy 87.682515 -182.50307)
			(xy 87.651027 -182.424418) (xy 87.627159 -182.343128) (xy 87.611125 -182.259938) (xy 87.603072 -182.175601)
			(xy 87.602568 -182.13324) (xy 87.603127 -182.08847) (xy 87.612138 -181.999385) (xy 87.630045 -181.911654)
			(xy 87.656665 -181.826163) (xy 87.673688 -181.784752) (xy 87.677232 -181.775155) (xy 87.677247 -181.754718)
			(xy 87.673688 -181.745128) (xy 87.65877 -181.708939) (xy 87.634581 -181.634489) (xy 87.617023 -181.558202)
			(xy 87.606232 -181.480668) (xy 87.603838 -181.441598) (xy 87.602983 -181.432757) (xy 87.596138 -181.416387)
			(xy 87.58411 -181.403342) (xy 87.576406 -181.398926) (xy 87.486236 -181.352444) (xy 87.459312 -181.35346)
			(xy 87.447882 -181.360826) (xy 87.412209 -181.38294) (xy 87.337447 -181.421096) (xy 87.259425 -181.452047)
			(xy 87.178837 -181.475518) (xy 87.096397 -181.4913) (xy 87.012838 -181.499253) (xy 86.97087 -181.499764)
			(xy 86.929755 -181.499316) (xy 86.847877 -181.491726) (xy 86.767048 -181.476614) (xy 86.687959 -181.454109)
			(xy 86.611283 -181.424402) (xy 86.537675 -181.387748) (xy 86.467763 -181.344458) (xy 86.402144 -181.294902)
			(xy 86.341376 -181.239504) (xy 86.28598 -181.178735) (xy 86.236426 -181.113114) (xy 86.193139 -181.043201)
			(xy 86.156487 -180.969592) (xy 86.126782 -180.892915) (xy 86.10428 -180.813824) (xy 86.08917 -180.732995)
			(xy 86.081583 -180.651117) (xy 86.081108 -180.610002) (xy 82.462267 -180.610002) (xy 82.47114 -180.671714)
			(xy 82.475131 -180.7555) (xy 82.47114 -180.839286) (xy 82.459202 -180.922313) (xy 82.439426 -181.00383)
			(xy 82.411991 -181.083097) (xy 82.377146 -181.159398) (xy 82.335205 -181.232041) (xy 82.286549 -181.300368)
			(xy 82.231618 -181.363761) (xy 82.17091 -181.421645) (xy 82.104975 -181.473496) (xy 82.03441 -181.518845)
			(xy 81.959853 -181.557281) (xy 81.88198 -181.588456) (xy 81.801497 -181.612087) (xy 81.719132 -181.627961)
			(xy 81.63563 -181.635933) (xy 81.59369 -181.636416) (xy 81.5565 -181.636029) (xy 81.482387 -181.629739)
			(xy 81.409068 -181.617228) (xy 81.337062 -181.598587) (xy 81.301844 -181.586632) (xy 81.293647 -181.584118)
			(xy 81.276513 -181.584118) (xy 81.268316 -181.586632) (xy 81.24011 -181.596266) (xy 81.182657 -181.612157)
			(xy 81.153508 -181.618382) (xy 81.143879 -181.620834) (xy 81.127394 -181.631892) (xy 81.116335 -181.648377)
			(xy 81.113884 -181.658006) (xy 81.104396 -181.702491) (xy 81.07755 -181.789404) (xy 81.06029 -181.831488)
			(xy 81.056659 -181.841055) (xy 81.056528 -181.861499) (xy 81.060036 -181.871112) (xy 81.077051 -181.912492)
			(xy 81.103672 -181.997918) (xy 81.121578 -182.085585) (xy 81.130589 -182.174608) (xy 81.131156 -182.219346)
			(xy 81.131156 -182.2196) (xy 81.130652 -182.261948) (xy 81.122601 -182.346262) (xy 81.106572 -182.429428)
			(xy 81.082711 -182.510695) (xy 81.051232 -182.589325) (xy 81.012421 -182.664606) (xy 80.966631 -182.735858)
			(xy 80.914275 -182.802434) (xy 80.855827 -182.863732) (xy 80.791817 -182.919197) (xy 80.722825 -182.968326)
			(xy 80.649475 -183.010675) (xy 80.572432 -183.045859) (xy 80.492393 -183.073561) (xy 80.410084 -183.093529)
			(xy 80.326249 -183.105582) (xy 80.241648 -183.109613) (xy 80.157047 -183.105582) (xy 80.073212 -183.093529)
			(xy 79.990903 -183.073561) (xy 79.910864 -183.045859) (xy 79.833821 -183.010675) (xy 79.760471 -182.968326)
			(xy 79.691479 -182.919197) (xy 79.627469 -182.863732) (xy 79.569021 -182.802434) (xy 79.516665 -182.735858)
			(xy 79.470875 -182.664606) (xy 79.432064 -182.589325) (xy 79.400585 -182.510695) (xy 79.376724 -182.429428)
			(xy 79.360695 -182.346262) (xy 79.352644 -182.261948) (xy 79.35214 -182.2196) (xy 79.35214 -182.219346)
			(xy 79.352704 -182.174608) (xy 79.361721 -182.085586) (xy 79.379627 -181.997918) (xy 79.406242 -181.912491)
			(xy 79.42326 -181.871112) (xy 79.426824 -181.861521) (xy 79.426824 -181.841079) (xy 79.42326 -181.831488)
			(xy 79.406239 -181.790076) (xy 79.379604 -181.704589) (xy 79.361695 -181.616857) (xy 79.352696 -181.52777)
			(xy 79.35214 -181.483) (xy 79.352578 -181.44277) (xy 79.359832 -181.362636) (xy 79.366618 -181.32298)
			(xy 79.366618 -181.322726) (xy 79.368105 -181.310829) (xy 79.361202 -181.287898) (xy 79.35341 -181.278784)
			(xy 79.287878 -181.210204) (xy 79.265018 -181.202076) (xy 79.252826 -181.203854) (xy 79.222877 -181.207733)
			(xy 79.162627 -181.21193) (xy 79.13243 -181.212236) (xy 79.091315 -181.211773) (xy 79.009435 -181.204188)
			(xy 78.928604 -181.18908) (xy 78.849513 -181.166579) (xy 78.772835 -181.136875) (xy 78.699225 -181.100223)
			(xy 78.629311 -181.056935) (xy 78.563689 -181.007381) (xy 78.50292 -180.951983) (xy 78.447522 -180.891214)
			(xy 78.397967 -180.825593) (xy 78.354679 -180.755679) (xy 78.318026 -180.682069) (xy 78.288322 -180.605391)
			(xy 78.26582 -180.526299) (xy 78.250712 -180.445469) (xy 78.243127 -180.363589) (xy 78.242668 -180.322474)
			(xy 78.243154 -180.279736) (xy 78.251333 -180.194653) (xy 78.267631 -180.110746) (xy 78.2919 -180.028788)
			(xy 78.307438 -179.988972) (xy 78.311043 -179.978929) (xy 78.310391 -179.957622) (xy 78.306168 -179.947824)
			(xy 78.289089 -179.911553) (xy 78.260784 -179.836541) (xy 78.239347 -179.759284) (xy 78.224953 -179.680411)
			(xy 78.217719 -179.600562) (xy 78.217268 -179.560474) (xy 78.21746 -179.533866) (xy 78.220637 -179.480744)
			(xy 78.223618 -179.454302) (xy 78.224368 -179.443055) (xy 78.217254 -179.421697) (xy 78.209902 -179.413154)
			(xy 78.180933 -179.382157) (xy 78.128411 -179.31552) (xy 78.082469 -179.244186) (xy 78.043525 -179.168805)
			(xy 78.011931 -179.090059) (xy 77.987974 -179.008663) (xy 77.971872 -178.925358) (xy 77.963772 -178.840898)
			(xy 77.963268 -178.798474) (xy 9.44304 -178.798474) (xy 9.441677 -178.801459) (xy 9.412211 -178.847309)
			(xy 9.37652 -178.8885) (xy 9.335329 -178.924191) (xy 9.289479 -178.953657) (xy 9.239902 -178.976299)
			(xy 9.187607 -178.991654) (xy 9.133659 -178.99941) (xy 9.079157 -178.99941) (xy 9.025209 -178.991654)
			(xy 8.972914 -178.976299) (xy 8.923337 -178.953657) (xy 8.877487 -178.924191) (xy 8.836296 -178.8885)
			(xy 8.800605 -178.847309) (xy 8.771139 -178.801459) (xy 8.748497 -178.751882) (xy 8.733142 -178.699587)
			(xy 8.725386 -178.645639) (xy 8.7249 -178.618388) (xy 2.509012 -178.618388) (xy 2.509012 -190.64715)
			(xy 220.414866 -190.64715) (xy 220.414866 -190.59265) (xy 220.422621 -190.538705) (xy 220.437974 -190.486413)
			(xy 220.460612 -190.436837) (xy 220.490075 -190.390988) (xy 220.525762 -190.349798) (xy 220.566948 -190.314105)
			(xy 220.612793 -190.284636) (xy 220.662366 -190.261992) (xy 220.714656 -190.246632) (xy 220.7686 -190.238869)
			(xy 220.79585 -190.23838) (xy 221.78645 -190.23838) (xy 221.813704 -190.238864) (xy 221.867659 -190.246615)
			(xy 221.919961 -190.261966) (xy 221.969546 -190.284605) (xy 222.015404 -190.314071) (xy 222.056601 -190.349763)
			(xy 222.092299 -190.390956) (xy 222.121771 -190.43681) (xy 222.144416 -190.486392) (xy 222.159775 -190.538692)
			(xy 222.167533 -190.592646) (xy 222.167533 -190.647154) (xy 222.159775 -190.701108) (xy 222.144416 -190.753408)
			(xy 222.121771 -190.80299) (xy 222.092299 -190.848844) (xy 222.056601 -190.890037) (xy 222.015404 -190.925729)
			(xy 221.969546 -190.955195) (xy 221.919961 -190.977834) (xy 221.867659 -190.993185) (xy 221.813704 -191.000936)
			(xy 221.78645 -191.001396) (xy 220.79585 -191.001396) (xy 220.7686 -191.000931) (xy 220.714656 -190.993168)
			(xy 220.662366 -190.977808) (xy 220.612793 -190.955164) (xy 220.566948 -190.925695) (xy 220.525762 -190.890002)
			(xy 220.490075 -190.848812) (xy 220.460612 -190.802963) (xy 220.437974 -190.753387) (xy 220.422621 -190.701095)
			(xy 220.414866 -190.64715) (xy 2.509012 -190.64715) (xy 2.509012 -194.296284) (xy 255.545336 -194.296284)
			(xy 255.545336 -193.432684) (xy 255.545822 -193.405415) (xy 255.553584 -193.351431) (xy 255.568949 -193.299101)
			(xy 255.591606 -193.249491) (xy 255.621092 -193.20361) (xy 255.656807 -193.162393) (xy 255.698024 -193.126678)
			(xy 255.743905 -193.097192) (xy 255.793515 -193.074535) (xy 255.845845 -193.05917) (xy 255.899829 -193.051408)
			(xy 255.954367 -193.051408) (xy 256.008351 -193.05917) (xy 256.060681 -193.074535) (xy 256.110291 -193.097192)
			(xy 256.156172 -193.126678) (xy 256.197389 -193.162393) (xy 256.233104 -193.20361) (xy 256.26259 -193.249491)
			(xy 256.285247 -193.299101) (xy 256.300612 -193.351431) (xy 256.308374 -193.405415) (xy 256.30886 -193.432684)
			(xy 256.30886 -194.296284) (xy 256.308374 -194.323553) (xy 256.300612 -194.377537) (xy 256.285247 -194.429867)
			(xy 256.26259 -194.479477) (xy 256.25414 -194.492626) (xy 260.09346 -194.492626) (xy 260.09346 -193.502026)
			(xy 260.093946 -193.474757) (xy 260.101708 -193.420773) (xy 260.117073 -193.368443) (xy 260.13973 -193.318833)
			(xy 260.169216 -193.272952) (xy 260.204931 -193.231735) (xy 260.246148 -193.19602) (xy 260.292029 -193.166534)
			(xy 260.341639 -193.143877) (xy 260.393969 -193.128512) (xy 260.447953 -193.12075) (xy 260.502491 -193.12075)
			(xy 260.556475 -193.128512) (xy 260.608805 -193.143877) (xy 260.658415 -193.166534) (xy 260.704296 -193.19602)
			(xy 260.745513 -193.231735) (xy 260.781228 -193.272952) (xy 260.810714 -193.318833) (xy 260.833371 -193.368443)
			(xy 260.848736 -193.420773) (xy 260.856498 -193.474757) (xy 260.856984 -193.502026) (xy 260.856984 -194.492626)
			(xy 260.856498 -194.519895) (xy 260.848736 -194.573879) (xy 260.833371 -194.626209) (xy 260.810714 -194.675819)
			(xy 260.781228 -194.7217) (xy 260.745513 -194.762917) (xy 260.704296 -194.798632) (xy 260.658415 -194.828118)
			(xy 260.608805 -194.850775) (xy 260.556475 -194.86614) (xy 260.502491 -194.873902) (xy 260.447953 -194.873902)
			(xy 260.393969 -194.86614) (xy 260.341639 -194.850775) (xy 260.292029 -194.828118) (xy 260.246148 -194.798632)
			(xy 260.204931 -194.762917) (xy 260.169216 -194.7217) (xy 260.13973 -194.675819) (xy 260.117073 -194.626209)
			(xy 260.101708 -194.573879) (xy 260.093946 -194.519895) (xy 260.09346 -194.492626) (xy 256.25414 -194.492626)
			(xy 256.233104 -194.525358) (xy 256.197389 -194.566575) (xy 256.156172 -194.60229) (xy 256.110291 -194.631776)
			(xy 256.060681 -194.654433) (xy 256.008351 -194.669798) (xy 255.954367 -194.67756) (xy 255.899829 -194.67756)
			(xy 255.845845 -194.669798) (xy 255.793515 -194.654433) (xy 255.743905 -194.631776) (xy 255.698024 -194.60229)
			(xy 255.656807 -194.566575) (xy 255.621092 -194.525358) (xy 255.591606 -194.479477) (xy 255.568949 -194.429867)
			(xy 255.553584 -194.377537) (xy 255.545822 -194.323553) (xy 255.545336 -194.296284) (xy 2.509012 -194.296284)
			(xy 2.509012 -197.07352) (xy 255.545336 -197.07352) (xy 255.545336 -196.20992) (xy 255.545822 -196.182651)
			(xy 255.553584 -196.128667) (xy 255.568949 -196.076337) (xy 255.591606 -196.026727) (xy 255.621092 -195.980846)
			(xy 255.656807 -195.939629) (xy 255.698024 -195.903914) (xy 255.743905 -195.874428) (xy 255.793515 -195.851771)
			(xy 255.845845 -195.836406) (xy 255.899829 -195.828644) (xy 255.954367 -195.828644) (xy 256.008351 -195.836406)
			(xy 256.060681 -195.851771) (xy 256.110291 -195.874428) (xy 256.156172 -195.903914) (xy 256.197389 -195.939629)
			(xy 256.233104 -195.980846) (xy 256.26259 -196.026727) (xy 256.285247 -196.076337) (xy 256.300612 -196.128667)
			(xy 256.308374 -196.182651) (xy 256.30886 -196.20992) (xy 256.30886 -197.07352) (xy 256.308374 -197.100789)
			(xy 256.300612 -197.154773) (xy 256.285247 -197.207103) (xy 256.26259 -197.256713) (xy 256.233104 -197.302594)
			(xy 256.197389 -197.343811) (xy 256.156172 -197.379526) (xy 256.110291 -197.409012) (xy 256.060681 -197.431669)
			(xy 256.008351 -197.447034) (xy 255.954367 -197.454796) (xy 255.899829 -197.454796) (xy 255.845845 -197.447034)
			(xy 255.793515 -197.431669) (xy 255.743905 -197.409012) (xy 255.698024 -197.379526) (xy 255.656807 -197.343811)
			(xy 255.621092 -197.302594) (xy 255.591606 -197.256713) (xy 255.568949 -197.207103) (xy 255.553584 -197.154773)
			(xy 255.545822 -197.100789) (xy 255.545336 -197.07352) (xy 2.509012 -197.07352) (xy 2.509012 -199.868028)
			(xy 255.545336 -199.868028) (xy 255.545336 -199.004428) (xy 255.545822 -198.977159) (xy 255.553584 -198.923175)
			(xy 255.568949 -198.870845) (xy 255.591606 -198.821235) (xy 255.621092 -198.775354) (xy 255.656807 -198.734137)
			(xy 255.698024 -198.698422) (xy 255.743905 -198.668936) (xy 255.793515 -198.646279) (xy 255.845845 -198.630914)
			(xy 255.899829 -198.623152) (xy 255.954367 -198.623152) (xy 256.008351 -198.630914) (xy 256.060681 -198.646279)
			(xy 256.110291 -198.668936) (xy 256.156172 -198.698422) (xy 256.197389 -198.734137) (xy 256.233104 -198.775354)
			(xy 256.26259 -198.821235) (xy 256.285247 -198.870845) (xy 256.300612 -198.923175) (xy 256.308374 -198.977159)
			(xy 256.30886 -199.004428) (xy 256.30886 -199.868028) (xy 256.308374 -199.895297) (xy 256.300612 -199.949281)
			(xy 256.285247 -200.001611) (xy 256.26259 -200.051221) (xy 256.233104 -200.097102) (xy 256.197389 -200.138319)
			(xy 256.156172 -200.174034) (xy 256.110291 -200.20352) (xy 256.060681 -200.226177) (xy 256.008351 -200.241542)
			(xy 255.954367 -200.249304) (xy 255.899829 -200.249304) (xy 255.845845 -200.241542) (xy 255.793515 -200.226177)
			(xy 255.743905 -200.20352) (xy 255.698024 -200.174034) (xy 255.656807 -200.138319) (xy 255.621092 -200.097102)
			(xy 255.591606 -200.051221) (xy 255.568949 -200.001611) (xy 255.553584 -199.949281) (xy 255.545822 -199.895297)
			(xy 255.545336 -199.868028) (xy 2.509012 -199.868028) (xy 2.509012 -202.662536) (xy 255.545336 -202.662536)
			(xy 255.545336 -201.798936) (xy 255.545822 -201.771667) (xy 255.553584 -201.717683) (xy 255.568949 -201.665353)
			(xy 255.591606 -201.615743) (xy 255.621092 -201.569862) (xy 255.656807 -201.528645) (xy 255.698024 -201.49293)
			(xy 255.743905 -201.463444) (xy 255.793515 -201.440787) (xy 255.845845 -201.425422) (xy 255.899829 -201.41766)
			(xy 255.954367 -201.41766) (xy 256.008351 -201.425422) (xy 256.060681 -201.440787) (xy 256.110291 -201.463444)
			(xy 256.156172 -201.49293) (xy 256.197389 -201.528645) (xy 256.233104 -201.569862) (xy 256.26259 -201.615743)
			(xy 256.285247 -201.665353) (xy 256.300612 -201.717683) (xy 256.308374 -201.771667) (xy 256.30886 -201.798936)
			(xy 256.30886 -202.662536) (xy 256.308374 -202.689805) (xy 256.300612 -202.743789) (xy 256.285247 -202.796119)
			(xy 256.26259 -202.845729) (xy 256.233104 -202.89161) (xy 256.197389 -202.932827) (xy 256.156172 -202.968542)
			(xy 256.110291 -202.998028) (xy 256.060681 -203.020685) (xy 256.008351 -203.03605) (xy 255.954367 -203.043812)
			(xy 255.899829 -203.043812) (xy 255.845845 -203.03605) (xy 255.793515 -203.020685) (xy 255.743905 -202.998028)
			(xy 255.698024 -202.968542) (xy 255.656807 -202.932827) (xy 255.621092 -202.89161) (xy 255.591606 -202.845729)
			(xy 255.568949 -202.796119) (xy 255.553584 -202.743789) (xy 255.545822 -202.689805) (xy 255.545336 -202.662536)
			(xy 2.509012 -202.662536) (xy 2.509012 -205.439772) (xy 255.545336 -205.439772) (xy 255.545336 -204.576172)
			(xy 255.545822 -204.548903) (xy 255.553584 -204.494919) (xy 255.568949 -204.442589) (xy 255.591606 -204.392979)
			(xy 255.621092 -204.347098) (xy 255.656807 -204.305881) (xy 255.698024 -204.270166) (xy 255.743905 -204.24068)
			(xy 255.793515 -204.218023) (xy 255.845845 -204.202658) (xy 255.899829 -204.194896) (xy 255.954367 -204.194896)
			(xy 256.008351 -204.202658) (xy 256.060681 -204.218023) (xy 256.110291 -204.24068) (xy 256.156172 -204.270166)
			(xy 256.197389 -204.305881) (xy 256.233104 -204.347098) (xy 256.26259 -204.392979) (xy 256.285247 -204.442589)
			(xy 256.300612 -204.494919) (xy 256.308374 -204.548903) (xy 256.30886 -204.576172) (xy 256.30886 -205.439772)
			(xy 256.308374 -205.467041) (xy 256.300612 -205.521025) (xy 256.285247 -205.573355) (xy 256.26259 -205.622965)
			(xy 256.233104 -205.668846) (xy 256.197389 -205.710063) (xy 256.156172 -205.745778) (xy 256.110291 -205.775264)
			(xy 256.060681 -205.797921) (xy 256.008351 -205.813286) (xy 255.954367 -205.821048) (xy 255.899829 -205.821048)
			(xy 255.845845 -205.813286) (xy 255.793515 -205.797921) (xy 255.743905 -205.775264) (xy 255.698024 -205.745778)
			(xy 255.656807 -205.710063) (xy 255.621092 -205.668846) (xy 255.591606 -205.622965) (xy 255.568949 -205.573355)
			(xy 255.553584 -205.521025) (xy 255.545822 -205.467041) (xy 255.545336 -205.439772) (xy 2.509012 -205.439772)
			(xy 2.509012 -207.499458) (xy 97.408492 -207.499458) (xy 97.408492 -206.635858) (xy 97.408978 -206.608589)
			(xy 97.41674 -206.554605) (xy 97.432105 -206.502275) (xy 97.454762 -206.452665) (xy 97.484248 -206.406784)
			(xy 97.519963 -206.365567) (xy 97.56118 -206.329852) (xy 97.607061 -206.300366) (xy 97.656671 -206.277709)
			(xy 97.709001 -206.262344) (xy 97.762985 -206.254582) (xy 97.817523 -206.254582) (xy 97.871507 -206.262344)
			(xy 97.923837 -206.277709) (xy 97.973447 -206.300366) (xy 98.019328 -206.329852) (xy 98.060545 -206.365567)
			(xy 98.09626 -206.406784) (xy 98.125746 -206.452665) (xy 98.148403 -206.502275) (xy 98.163768 -206.554605)
			(xy 98.17153 -206.608589) (xy 98.172016 -206.635858) (xy 98.172016 -207.499458) (xy 98.17153 -207.526727)
			(xy 98.163768 -207.580711) (xy 98.148403 -207.633041) (xy 98.125746 -207.682651) (xy 98.09626 -207.728532)
			(xy 98.060545 -207.769749) (xy 98.019328 -207.805464) (xy 97.973447 -207.83495) (xy 97.923837 -207.857607)
			(xy 97.871507 -207.872972) (xy 97.817523 -207.880734) (xy 97.762985 -207.880734) (xy 97.709001 -207.872972)
			(xy 97.656671 -207.857607) (xy 97.607061 -207.83495) (xy 97.56118 -207.805464) (xy 97.519963 -207.769749)
			(xy 97.484248 -207.728532) (xy 97.454762 -207.682651) (xy 97.432105 -207.633041) (xy 97.41674 -207.580711)
			(xy 97.408978 -207.526727) (xy 97.408492 -207.499458) (xy 2.509012 -207.499458) (xy 2.509012 -209.023458)
			(xy 94.105984 -209.023458) (xy 94.105984 -208.159858) (xy 94.10647 -208.132589) (xy 94.114232 -208.078605)
			(xy 94.129597 -208.026275) (xy 94.152254 -207.976665) (xy 94.18174 -207.930784) (xy 94.217455 -207.889567)
			(xy 94.258672 -207.853852) (xy 94.304553 -207.824366) (xy 94.354163 -207.801709) (xy 94.406493 -207.786344)
			(xy 94.460477 -207.778582) (xy 94.515015 -207.778582) (xy 94.568999 -207.786344) (xy 94.621329 -207.801709)
			(xy 94.670939 -207.824366) (xy 94.71682 -207.853852) (xy 94.758037 -207.889567) (xy 94.793752 -207.930784)
			(xy 94.823238 -207.976665) (xy 94.845895 -208.026275) (xy 94.86126 -208.078605) (xy 94.869022 -208.132589)
			(xy 94.869508 -208.159858) (xy 94.869508 -208.217008) (xy 255.545336 -208.217008) (xy 255.545336 -207.353408)
			(xy 255.545822 -207.326139) (xy 255.553584 -207.272155) (xy 255.568949 -207.219825) (xy 255.591606 -207.170215)
			(xy 255.621092 -207.124334) (xy 255.656807 -207.083117) (xy 255.698024 -207.047402) (xy 255.743905 -207.017916)
			(xy 255.793515 -206.995259) (xy 255.845845 -206.979894) (xy 255.899829 -206.972132) (xy 255.954367 -206.972132)
			(xy 256.008351 -206.979894) (xy 256.060681 -206.995259) (xy 256.110291 -207.017916) (xy 256.156172 -207.047402)
			(xy 256.197389 -207.083117) (xy 256.233104 -207.124334) (xy 256.26259 -207.170215) (xy 256.285247 -207.219825)
			(xy 256.300612 -207.272155) (xy 256.308374 -207.326139) (xy 256.30886 -207.353408) (xy 256.30886 -208.217008)
			(xy 256.308374 -208.244277) (xy 256.300612 -208.298261) (xy 256.285247 -208.350591) (xy 256.26259 -208.400201)
			(xy 256.233104 -208.446082) (xy 256.197389 -208.487299) (xy 256.156172 -208.523014) (xy 256.110291 -208.5525)
			(xy 256.060681 -208.575157) (xy 256.008351 -208.590522) (xy 255.954367 -208.598284) (xy 255.899829 -208.598284)
			(xy 255.845845 -208.590522) (xy 255.793515 -208.575157) (xy 255.743905 -208.5525) (xy 255.698024 -208.523014)
			(xy 255.656807 -208.487299) (xy 255.621092 -208.446082) (xy 255.591606 -208.400201) (xy 255.568949 -208.350591)
			(xy 255.553584 -208.298261) (xy 255.545822 -208.244277) (xy 255.545336 -208.217008) (xy 94.869508 -208.217008)
			(xy 94.869508 -209.023458) (xy 94.869022 -209.050727) (xy 94.86126 -209.104711) (xy 94.845895 -209.157041)
			(xy 94.823238 -209.206651) (xy 94.793752 -209.252532) (xy 94.758037 -209.293749) (xy 94.71682 -209.329464)
			(xy 94.670939 -209.35895) (xy 94.621329 -209.381607) (xy 94.568999 -209.396972) (xy 94.515015 -209.404734)
			(xy 94.460477 -209.404734) (xy 94.406493 -209.396972) (xy 94.354163 -209.381607) (xy 94.304553 -209.35895)
			(xy 94.258672 -209.329464) (xy 94.217455 -209.293749) (xy 94.18174 -209.252532) (xy 94.152254 -209.206651)
			(xy 94.129597 -209.157041) (xy 94.114232 -209.104711) (xy 94.10647 -209.050727) (xy 94.105984 -209.023458)
			(xy 2.509012 -209.023458) (xy 2.509012 -212.98027) (xy 78.81214 -212.98027) (xy 78.81617 -212.837935)
			(xy 78.828245 -212.696055) (xy 78.848328 -212.555087) (xy 78.876355 -212.41548) (xy 78.912235 -212.277682)
			(xy 78.955853 -212.142135) (xy 79.00707 -212.009273) (xy 79.065721 -211.879521) (xy 79.131619 -211.753295)
			(xy 79.204553 -211.630999) (xy 79.28429 -211.513026) (xy 79.370572 -211.399753) (xy 79.463125 -211.291542)
			(xy 79.561652 -211.188741) (xy 79.665837 -211.091679) (xy 79.775346 -211.000667) (xy 79.889829 -210.915995)
			(xy 80.008919 -210.837937) (xy 80.132234 -210.766741) (xy 80.25938 -210.702635) (xy 80.389949 -210.645826)
			(xy 80.523523 -210.596494) (xy 80.659674 -210.554798) (xy 80.797965 -210.520872) (xy 80.937955 -210.494824)
			(xy 81.079194 -210.476738) (xy 81.22123 -210.466671) (xy 81.363608 -210.464656) (xy 81.505872 -210.470699)
			(xy 81.647566 -210.484781) (xy 81.788236 -210.506857) (xy 81.927433 -210.536857) (xy 82.064709 -210.574683)
			(xy 82.199625 -210.620215) (xy 82.331749 -210.673306) (xy 82.460658 -210.733788) (xy 82.585939 -210.801466)
			(xy 82.70719 -210.876123) (xy 82.824023 -210.957521) (xy 82.936064 -211.045398) (xy 83.042954 -211.139473)
			(xy 83.144351 -211.239445) (xy 83.239929 -211.344993) (xy 83.329383 -211.455779) (xy 83.412425 -211.571448)
			(xy 83.488791 -211.691631) (xy 83.558235 -211.815941) (xy 83.620535 -211.943982) (xy 83.675491 -212.075341)
			(xy 83.69835 -212.140038) (xy 94.106492 -212.140038) (xy 94.106492 -211.276438) (xy 94.106978 -211.249187)
			(xy 94.114734 -211.195239) (xy 94.130089 -211.142944) (xy 94.152731 -211.093367) (xy 94.182197 -211.047517)
			(xy 94.217888 -211.006326) (xy 94.259079 -210.970635) (xy 94.304929 -210.941169) (xy 94.354506 -210.918527)
			(xy 94.406801 -210.903172) (xy 94.460749 -210.895416) (xy 94.515251 -210.895416) (xy 94.569199 -210.903172)
			(xy 94.621494 -210.918527) (xy 94.671071 -210.941169) (xy 94.716921 -210.970635) (xy 94.758112 -211.006326)
			(xy 94.793803 -211.047517) (xy 94.823269 -211.093367) (xy 94.845911 -211.142944) (xy 94.861266 -211.195239)
			(xy 94.869022 -211.249187) (xy 94.869508 -211.276438) (xy 94.869508 -212.140038) (xy 94.869022 -212.167289)
			(xy 94.861266 -212.221237) (xy 94.845911 -212.273532) (xy 94.823269 -212.323109) (xy 94.793803 -212.368959)
			(xy 94.758112 -212.41015) (xy 94.716921 -212.445841) (xy 94.671071 -212.475307) (xy 94.621494 -212.497949)
			(xy 94.569199 -212.513304) (xy 94.515251 -212.52106) (xy 94.460749 -212.52106) (xy 94.406801 -212.513304)
			(xy 94.354506 -212.497949) (xy 94.304929 -212.475307) (xy 94.259079 -212.445841) (xy 94.217888 -212.41015)
			(xy 94.182197 -212.368959) (xy 94.152731 -212.323109) (xy 94.130089 -212.273532) (xy 94.114734 -212.221237)
			(xy 94.106978 -212.167289) (xy 94.106492 -212.140038) (xy 83.69835 -212.140038) (xy 83.722928 -212.2096)
			(xy 83.762692 -212.346327) (xy 83.794658 -212.485085) (xy 83.818723 -212.625429) (xy 83.834809 -212.76691)
			(xy 83.842864 -212.909074) (xy 83.843368 -212.98027) (xy 140.011408 -212.98027) (xy 140.015438 -212.837906)
			(xy 140.027516 -212.695998) (xy 140.047604 -212.555001) (xy 140.075636 -212.415366) (xy 140.111523 -212.27754)
			(xy 140.15515 -212.141966) (xy 140.206377 -212.009077) (xy 140.26504 -211.879298) (xy 140.330952 -211.753047)
			(xy 140.403901 -211.630727) (xy 140.483653 -211.51273) (xy 140.569953 -211.399434) (xy 140.662525 -211.291201)
			(xy 140.761071 -211.188379) (xy 140.865277 -211.091298) (xy 140.974809 -211.000267) (xy 141.089315 -210.915579)
			(xy 141.208429 -210.837504) (xy 141.331769 -210.766294) (xy 141.45894 -210.702175) (xy 141.589536 -210.645354)
			(xy 141.723136 -210.596013) (xy 141.859315 -210.554308) (xy 141.997634 -210.520375) (xy 142.137652 -210.494322)
			(xy 142.278919 -210.476232) (xy 142.420984 -210.466163) (xy 142.563391 -210.464148) (xy 142.705684 -210.470192)
			(xy 142.847406 -210.484278) (xy 142.988105 -210.506358) (xy 143.12733 -210.536363) (xy 143.264634 -210.574197)
			(xy 143.399577 -210.619738) (xy 143.531728 -210.672841) (xy 143.660663 -210.733335) (xy 143.785969 -210.801026)
			(xy 143.907245 -210.875699) (xy 144.024101 -210.957113) (xy 144.093464 -211.011516) (xy 255.545336 -211.011516)
			(xy 255.545336 -210.147916) (xy 255.545822 -210.120647) (xy 255.553584 -210.066663) (xy 255.568949 -210.014333)
			(xy 255.591606 -209.964723) (xy 255.621092 -209.918842) (xy 255.656807 -209.877625) (xy 255.698024 -209.84191)
			(xy 255.743905 -209.812424) (xy 255.793515 -209.789767) (xy 255.845845 -209.774402) (xy 255.899829 -209.76664)
			(xy 255.954367 -209.76664) (xy 256.008351 -209.774402) (xy 256.060681 -209.789767) (xy 256.110291 -209.812424)
			(xy 256.156172 -209.84191) (xy 256.197389 -209.877625) (xy 256.233104 -209.918842) (xy 256.26259 -209.964723)
			(xy 256.285247 -210.014333) (xy 256.300612 -210.066663) (xy 256.308374 -210.120647) (xy 256.30886 -210.147916)
			(xy 256.30886 -211.011516) (xy 256.308374 -211.038785) (xy 256.300612 -211.092769) (xy 256.285247 -211.145099)
			(xy 256.26259 -211.194709) (xy 256.233104 -211.24059) (xy 256.197389 -211.281807) (xy 256.156172 -211.317522)
			(xy 256.110291 -211.347008) (xy 256.060681 -211.369665) (xy 256.008351 -211.38503) (xy 255.954367 -211.392792)
			(xy 255.899829 -211.392792) (xy 255.845845 -211.38503) (xy 255.793515 -211.369665) (xy 255.743905 -211.347008)
			(xy 255.698024 -211.317522) (xy 255.656807 -211.281807) (xy 255.621092 -211.24059) (xy 255.591606 -211.194709)
			(xy 255.568949 -211.145099) (xy 255.553584 -211.092769) (xy 255.545822 -211.038785) (xy 255.545336 -211.011516)
			(xy 144.093464 -211.011516) (xy 144.136165 -211.045007) (xy 144.243077 -211.139101) (xy 144.344494 -211.239093)
			(xy 144.440091 -211.344662) (xy 144.529563 -211.455471) (xy 144.612622 -211.571164) (xy 144.689003 -211.691371)
			(xy 144.758461 -211.815706) (xy 144.820774 -211.943772) (xy 144.875741 -212.075159) (xy 144.923187 -212.209444)
			(xy 144.96296 -212.346199) (xy 144.994932 -212.484985) (xy 145.019002 -212.625357) (xy 145.035091 -212.766867)
			(xy 145.043148 -212.909059) (xy 145.043652 -212.98027) (xy 145.043148 -213.051481) (xy 145.035091 -213.193673)
			(xy 145.019002 -213.335183) (xy 144.994932 -213.475555) (xy 144.96296 -213.614341) (xy 144.923187 -213.751096)
			(xy 144.90378 -213.806024) (xy 255.545336 -213.806024) (xy 255.545336 -212.942424) (xy 255.545822 -212.915155)
			(xy 255.553584 -212.861171) (xy 255.568949 -212.808841) (xy 255.591606 -212.759231) (xy 255.621092 -212.71335)
			(xy 255.656807 -212.672133) (xy 255.698024 -212.636418) (xy 255.743905 -212.606932) (xy 255.793515 -212.584275)
			(xy 255.845845 -212.56891) (xy 255.899829 -212.561148) (xy 255.954367 -212.561148) (xy 256.008351 -212.56891)
			(xy 256.060681 -212.584275) (xy 256.110291 -212.606932) (xy 256.156172 -212.636418) (xy 256.197389 -212.672133)
			(xy 256.233104 -212.71335) (xy 256.26259 -212.759231) (xy 256.285247 -212.808841) (xy 256.300612 -212.861171)
			(xy 256.308374 -212.915155) (xy 256.30886 -212.942424) (xy 256.30886 -212.980016) (xy 326.752208 -212.980016)
			(xy 326.756238 -212.837681) (xy 326.768313 -212.695801) (xy 326.788396 -212.554833) (xy 326.816423 -212.415226)
			(xy 326.852303 -212.277428) (xy 326.895921 -212.141881) (xy 326.947138 -212.009019) (xy 327.005789 -211.879267)
			(xy 327.071687 -211.753041) (xy 327.144621 -211.630745) (xy 327.224358 -211.512772) (xy 327.31064 -211.399499)
			(xy 327.403193 -211.291288) (xy 327.50172 -211.188487) (xy 327.605905 -211.091425) (xy 327.715414 -211.000413)
			(xy 327.829897 -210.915741) (xy 327.948987 -210.837683) (xy 328.072302 -210.766487) (xy 328.199448 -210.702381)
			(xy 328.330017 -210.645572) (xy 328.463591 -210.59624) (xy 328.599742 -210.554544) (xy 328.738033 -210.520618)
			(xy 328.878023 -210.49457) (xy 329.019262 -210.476484) (xy 329.161298 -210.466417) (xy 329.303676 -210.464402)
			(xy 329.44594 -210.470445) (xy 329.587634 -210.484527) (xy 329.728304 -210.506603) (xy 329.867501 -210.536603)
			(xy 330.004777 -210.574429) (xy 330.139693 -210.619961) (xy 330.271817 -210.673052) (xy 330.400726 -210.733534)
			(xy 330.526007 -210.801212) (xy 330.647258 -210.875869) (xy 330.764091 -210.957267) (xy 330.876132 -211.045144)
			(xy 330.983022 -211.139219) (xy 331.084419 -211.239191) (xy 331.179997 -211.344739) (xy 331.269451 -211.455525)
			(xy 331.352493 -211.571194) (xy 331.428859 -211.691377) (xy 331.498303 -211.815687) (xy 331.560603 -211.943728)
			(xy 331.615559 -212.075087) (xy 331.662996 -212.209346) (xy 331.70276 -212.346073) (xy 331.734726 -212.484831)
			(xy 331.758791 -212.625175) (xy 331.774877 -212.766656) (xy 331.782932 -212.90882) (xy 331.783436 -212.980016)
			(xy 387.951476 -212.980016) (xy 387.955506 -212.837652) (xy 387.967584 -212.695744) (xy 387.987672 -212.554747)
			(xy 388.015704 -212.415112) (xy 388.051591 -212.277286) (xy 388.095218 -212.141712) (xy 388.146445 -212.008823)
			(xy 388.205108 -211.879044) (xy 388.27102 -211.752793) (xy 388.343969 -211.630473) (xy 388.423721 -211.512476)
			(xy 388.510021 -211.39918) (xy 388.602593 -211.290947) (xy 388.701139 -211.188125) (xy 388.805345 -211.091044)
			(xy 388.914877 -211.000013) (xy 389.029383 -210.915325) (xy 389.148497 -210.83725) (xy 389.271837 -210.76604)
			(xy 389.399008 -210.701921) (xy 389.529604 -210.6451) (xy 389.663204 -210.595759) (xy 389.799383 -210.554054)
			(xy 389.937702 -210.520121) (xy 390.07772 -210.494068) (xy 390.218987 -210.475978) (xy 390.361052 -210.465909)
			(xy 390.503459 -210.463894) (xy 390.645752 -210.469938) (xy 390.787474 -210.484024) (xy 390.928173 -210.506104)
			(xy 391.067398 -210.536109) (xy 391.204702 -210.573943) (xy 391.339645 -210.619484) (xy 391.471796 -210.672587)
			(xy 391.600731 -210.733081) (xy 391.726037 -210.800772) (xy 391.847313 -210.875445) (xy 391.964169 -210.956859)
			(xy 392.076233 -211.044753) (xy 392.183145 -211.138847) (xy 392.284562 -211.238839) (xy 392.380159 -211.344408)
			(xy 392.469631 -211.455217) (xy 392.55269 -211.57091) (xy 392.629071 -211.691117) (xy 392.698529 -211.815452)
			(xy 392.760842 -211.943518) (xy 392.815809 -212.074905) (xy 392.863255 -212.20919) (xy 392.903028 -212.345945)
			(xy 392.935 -212.484731) (xy 392.95907 -212.625103) (xy 392.975159 -212.766613) (xy 392.983216 -212.908805)
			(xy 392.98372 -212.980016) (xy 392.983216 -213.051227) (xy 392.975159 -213.193419) (xy 392.95907 -213.334929)
			(xy 392.935 -213.475301) (xy 392.903028 -213.614087) (xy 392.863255 -213.750842) (xy 392.815809 -213.885127)
			(xy 392.760842 -214.016514) (xy 392.698529 -214.14458) (xy 392.629071 -214.268915) (xy 392.55269 -214.389122)
			(xy 392.469631 -214.504815) (xy 392.380159 -214.615624) (xy 392.284562 -214.721193) (xy 392.183145 -214.821185)
			(xy 392.076233 -214.915279) (xy 391.964169 -215.003173) (xy 391.847313 -215.084587) (xy 391.726037 -215.15926)
			(xy 391.600731 -215.226951) (xy 391.471796 -215.287445) (xy 391.339645 -215.340548) (xy 391.204702 -215.386089)
			(xy 391.067398 -215.423923) (xy 390.928173 -215.453928) (xy 390.787474 -215.476008) (xy 390.645752 -215.490094)
			(xy 390.503459 -215.496138) (xy 390.361052 -215.494123) (xy 390.218987 -215.484054) (xy 390.07772 -215.465964)
			(xy 389.937702 -215.439911) (xy 389.799383 -215.405978) (xy 389.663204 -215.364273) (xy 389.529604 -215.314932)
			(xy 389.399008 -215.258111) (xy 389.271837 -215.193992) (xy 389.148497 -215.122782) (xy 389.029383 -215.044707)
			(xy 388.914877 -214.960019) (xy 388.805345 -214.868988) (xy 388.701139 -214.771907) (xy 388.602593 -214.669085)
			(xy 388.510021 -214.560852) (xy 388.423721 -214.447556) (xy 388.343969 -214.329559) (xy 388.27102 -214.207239)
			(xy 388.205108 -214.080988) (xy 388.146445 -213.951209) (xy 388.095218 -213.81832) (xy 388.051591 -213.682746)
			(xy 388.015704 -213.54492) (xy 387.987672 -213.405285) (xy 387.967584 -213.264288) (xy 387.955506 -213.12238)
			(xy 387.951476 -212.980016) (xy 331.783436 -212.980016) (xy 331.782932 -213.051212) (xy 331.774877 -213.193376)
			(xy 331.758791 -213.334857) (xy 331.734726 -213.475201) (xy 331.70276 -213.613959) (xy 331.662996 -213.750686)
			(xy 331.615559 -213.884945) (xy 331.560603 -214.016304) (xy 331.498303 -214.144345) (xy 331.428859 -214.268655)
			(xy 331.352493 -214.388838) (xy 331.269451 -214.504507) (xy 331.179997 -214.615293) (xy 331.084419 -214.720841)
			(xy 330.983022 -214.820813) (xy 330.876132 -214.914888) (xy 330.764091 -215.002765) (xy 330.647258 -215.084163)
			(xy 330.526007 -215.15882) (xy 330.400726 -215.226498) (xy 330.271817 -215.28698) (xy 330.139693 -215.340071)
			(xy 330.004777 -215.385603) (xy 329.867501 -215.423429) (xy 329.728304 -215.453429) (xy 329.587634 -215.475505)
			(xy 329.44594 -215.489587) (xy 329.303676 -215.49563) (xy 329.161298 -215.493615) (xy 329.019262 -215.483548)
			(xy 328.878023 -215.465462) (xy 328.738033 -215.439414) (xy 328.599742 -215.405488) (xy 328.463591 -215.363792)
			(xy 328.330017 -215.31446) (xy 328.199448 -215.257651) (xy 328.072302 -215.193545) (xy 327.948987 -215.122349)
			(xy 327.829897 -215.044291) (xy 327.715414 -214.959619) (xy 327.605905 -214.868607) (xy 327.50172 -214.771545)
			(xy 327.403193 -214.668744) (xy 327.31064 -214.560533) (xy 327.224358 -214.44726) (xy 327.144621 -214.329287)
			(xy 327.071687 -214.206991) (xy 327.005789 -214.080765) (xy 326.947138 -213.951013) (xy 326.895921 -213.818151)
			(xy 326.852303 -213.682604) (xy 326.816423 -213.544806) (xy 326.788396 -213.405199) (xy 326.768313 -213.264231)
			(xy 326.756238 -213.122351) (xy 326.752208 -212.980016) (xy 256.30886 -212.980016) (xy 256.30886 -213.806024)
			(xy 256.308374 -213.833293) (xy 256.300612 -213.887277) (xy 256.285247 -213.939607) (xy 256.26259 -213.989217)
			(xy 256.233104 -214.035098) (xy 256.197389 -214.076315) (xy 256.156172 -214.11203) (xy 256.110291 -214.141516)
			(xy 256.060681 -214.164173) (xy 256.008351 -214.179538) (xy 255.954367 -214.1873) (xy 255.899829 -214.1873)
			(xy 255.845845 -214.179538) (xy 255.793515 -214.164173) (xy 255.743905 -214.141516) (xy 255.698024 -214.11203)
			(xy 255.656807 -214.076315) (xy 255.621092 -214.035098) (xy 255.591606 -213.989217) (xy 255.568949 -213.939607)
			(xy 255.553584 -213.887277) (xy 255.545822 -213.833293) (xy 255.545336 -213.806024) (xy 144.90378 -213.806024)
			(xy 144.875741 -213.885381) (xy 144.820774 -214.016768) (xy 144.758461 -214.144834) (xy 144.689003 -214.269169)
			(xy 144.612622 -214.389376) (xy 144.529563 -214.505069) (xy 144.440091 -214.615878) (xy 144.344494 -214.721447)
			(xy 144.243077 -214.821439) (xy 144.136165 -214.915533) (xy 144.024101 -215.003427) (xy 143.907245 -215.084841)
			(xy 143.785969 -215.159514) (xy 143.660663 -215.227205) (xy 143.531728 -215.287699) (xy 143.399577 -215.340802)
			(xy 143.264634 -215.386343) (xy 143.12733 -215.424177) (xy 142.988105 -215.454182) (xy 142.847406 -215.476262)
			(xy 142.705684 -215.490348) (xy 142.563391 -215.496392) (xy 142.420984 -215.494377) (xy 142.278919 -215.484308)
			(xy 142.137652 -215.466218) (xy 141.997634 -215.440165) (xy 141.859315 -215.406232) (xy 141.723136 -215.364527)
			(xy 141.589536 -215.315186) (xy 141.45894 -215.258365) (xy 141.331769 -215.194246) (xy 141.208429 -215.123036)
			(xy 141.089315 -215.044961) (xy 140.974809 -214.960273) (xy 140.865277 -214.869242) (xy 140.761071 -214.772161)
			(xy 140.662525 -214.669339) (xy 140.569953 -214.561106) (xy 140.483653 -214.44781) (xy 140.403901 -214.329813)
			(xy 140.330952 -214.207493) (xy 140.26504 -214.081242) (xy 140.206377 -213.951463) (xy 140.15515 -213.818574)
			(xy 140.111523 -213.683) (xy 140.075636 -213.545174) (xy 140.047604 -213.405539) (xy 140.027516 -213.264542)
			(xy 140.015438 -213.122634) (xy 140.011408 -212.98027) (xy 83.843368 -212.98027) (xy 83.842864 -213.051466)
			(xy 83.834809 -213.19363) (xy 83.818723 -213.335111) (xy 83.794658 -213.475455) (xy 83.762692 -213.614213)
			(xy 83.722928 -213.75094) (xy 83.675491 -213.885199) (xy 83.620535 -214.016558) (xy 83.558235 -214.144599)
			(xy 83.488791 -214.268909) (xy 83.412425 -214.389092) (xy 83.329383 -214.504761) (xy 83.239929 -214.615547)
			(xy 83.144351 -214.721095) (xy 83.042954 -214.821067) (xy 82.936064 -214.915142) (xy 82.837488 -214.992458)
			(xy 94.106492 -214.992458) (xy 94.106492 -214.128858) (xy 94.106978 -214.101607) (xy 94.114734 -214.047659)
			(xy 94.130089 -213.995364) (xy 94.152731 -213.945787) (xy 94.182197 -213.899937) (xy 94.217888 -213.858746)
			(xy 94.259079 -213.823055) (xy 94.304929 -213.793589) (xy 94.354506 -213.770947) (xy 94.406801 -213.755592)
			(xy 94.460749 -213.747836) (xy 94.515251 -213.747836) (xy 94.569199 -213.755592) (xy 94.621494 -213.770947)
			(xy 94.671071 -213.793589) (xy 94.716921 -213.823055) (xy 94.758112 -213.858746) (xy 94.793803 -213.899937)
			(xy 94.823269 -213.945787) (xy 94.845911 -213.995364) (xy 94.861266 -214.047659) (xy 94.869022 -214.101607)
			(xy 94.869508 -214.128858) (xy 94.869508 -214.992458) (xy 94.869022 -215.019709) (xy 94.861266 -215.073657)
			(xy 94.845911 -215.125952) (xy 94.823269 -215.175529) (xy 94.793803 -215.221379) (xy 94.758112 -215.26257)
			(xy 94.716921 -215.298261) (xy 94.671071 -215.327727) (xy 94.621494 -215.350369) (xy 94.569199 -215.365724)
			(xy 94.515251 -215.37348) (xy 94.460749 -215.37348) (xy 94.406801 -215.365724) (xy 94.354506 -215.350369)
			(xy 94.304929 -215.327727) (xy 94.259079 -215.298261) (xy 94.217888 -215.26257) (xy 94.182197 -215.221379)
			(xy 94.152731 -215.175529) (xy 94.130089 -215.125952) (xy 94.114734 -215.073657) (xy 94.106978 -215.019709)
			(xy 94.106492 -214.992458) (xy 82.837488 -214.992458) (xy 82.824023 -215.003019) (xy 82.70719 -215.084417)
			(xy 82.585939 -215.159074) (xy 82.460658 -215.226752) (xy 82.331749 -215.287234) (xy 82.199625 -215.340325)
			(xy 82.064709 -215.385857) (xy 81.927433 -215.423683) (xy 81.788236 -215.453683) (xy 81.647566 -215.475759)
			(xy 81.505872 -215.489841) (xy 81.363608 -215.495884) (xy 81.22123 -215.493869) (xy 81.079194 -215.483802)
			(xy 80.937955 -215.465716) (xy 80.797965 -215.439668) (xy 80.659674 -215.405742) (xy 80.523523 -215.364046)
			(xy 80.389949 -215.314714) (xy 80.25938 -215.257905) (xy 80.132234 -215.193799) (xy 80.008919 -215.122603)
			(xy 79.889829 -215.044545) (xy 79.775346 -214.959873) (xy 79.665837 -214.868861) (xy 79.561652 -214.771799)
			(xy 79.463125 -214.668998) (xy 79.370572 -214.560787) (xy 79.28429 -214.447514) (xy 79.204553 -214.329541)
			(xy 79.131619 -214.207245) (xy 79.065721 -214.081019) (xy 79.00707 -213.951267) (xy 78.955853 -213.818405)
			(xy 78.912235 -213.682858) (xy 78.876355 -213.54506) (xy 78.848328 -213.405453) (xy 78.828245 -213.264485)
			(xy 78.81617 -213.122605) (xy 78.81214 -212.98027) (xy 2.509012 -212.98027) (xy 2.509012 -217.548574)
			(xy 338.152884 -217.548574) (xy 338.152884 -217.494026) (xy 338.160647 -217.440032) (xy 338.176017 -217.387693)
			(xy 338.198679 -217.338074) (xy 338.228172 -217.292186) (xy 338.263897 -217.250963) (xy 338.305125 -217.215244)
			(xy 338.351016 -217.185756) (xy 338.400638 -217.1631) (xy 338.452979 -217.147737) (xy 338.506973 -217.13998)
			(xy 338.534248 -217.13952) (xy 339.550248 -217.13952) (xy 339.577514 -217.140046) (xy 339.63149 -217.147813)
			(xy 339.683811 -217.163181) (xy 339.733413 -217.185839) (xy 339.779286 -217.215325) (xy 339.820495 -217.251039)
			(xy 339.856204 -217.292253) (xy 339.885684 -217.338129) (xy 339.908336 -217.387734) (xy 339.923698 -217.440057)
			(xy 339.931458 -217.494034) (xy 339.931458 -217.548566) (xy 339.923698 -217.602543) (xy 339.908336 -217.654866)
			(xy 339.885684 -217.704471) (xy 339.856204 -217.750347) (xy 339.820495 -217.791561) (xy 339.779286 -217.827275)
			(xy 339.733413 -217.856761) (xy 339.683811 -217.879419) (xy 339.63149 -217.894787) (xy 339.577514 -217.902554)
			(xy 339.550248 -217.903044) (xy 338.534248 -217.903044) (xy 338.506973 -217.90262) (xy 338.452979 -217.894863)
			(xy 338.400638 -217.8795) (xy 338.351016 -217.856844) (xy 338.305125 -217.827356) (xy 338.263897 -217.791637)
			(xy 338.228172 -217.750414) (xy 338.198679 -217.704526) (xy 338.176017 -217.654907) (xy 338.160647 -217.602568)
			(xy 338.152884 -217.548574) (xy 2.509012 -217.548574) (xy 2.509012 -219.820372) (xy 129.049982 -219.820372)
			(xy 129.049982 -219.765828) (xy 129.057745 -219.71184) (xy 129.073111 -219.659505) (xy 129.095769 -219.609891)
			(xy 129.125257 -219.564005) (xy 129.160975 -219.522783) (xy 129.202196 -219.487064) (xy 129.24808 -219.457575)
			(xy 129.297694 -219.434915) (xy 129.350028 -219.419547) (xy 129.404016 -219.411783) (xy 129.431288 -219.411296)
			(xy 130.447288 -219.411296) (xy 130.474557 -219.411843) (xy 130.528539 -219.419602) (xy 130.580867 -219.434966)
			(xy 130.630476 -219.45762) (xy 130.676357 -219.487104) (xy 130.717574 -219.522818) (xy 130.753288 -219.564034)
			(xy 130.782774 -219.609913) (xy 130.80543 -219.659522) (xy 130.820795 -219.711849) (xy 130.828557 -219.765831)
			(xy 130.828557 -219.820369) (xy 130.820795 -219.874351) (xy 130.80543 -219.926678) (xy 130.782774 -219.976287)
			(xy 130.753288 -220.022166) (xy 130.717574 -220.063382) (xy 130.676357 -220.099096) (xy 130.630476 -220.12858)
			(xy 130.580867 -220.151234) (xy 130.528539 -220.166598) (xy 130.474557 -220.174357) (xy 130.447288 -220.17482)
			(xy 129.431288 -220.17482) (xy 129.404016 -220.174417) (xy 129.350028 -220.166653) (xy 129.297694 -220.151285)
			(xy 129.24808 -220.128625) (xy 129.202196 -220.099136) (xy 129.160975 -220.063417) (xy 129.125257 -220.022195)
			(xy 129.095769 -219.976309) (xy 129.073111 -219.926695) (xy 129.057745 -219.87436) (xy 129.049982 -219.820372)
			(xy 2.509012 -219.820372) (xy 2.509012 -258.880356) (xy 67.312036 -258.880356) (xy 67.316066 -258.738021)
			(xy 67.328141 -258.596141) (xy 67.348224 -258.455173) (xy 67.376251 -258.315566) (xy 67.412131 -258.177768)
			(xy 67.455749 -258.042221) (xy 67.506966 -257.909359) (xy 67.565617 -257.779607) (xy 67.631515 -257.653381)
			(xy 67.704449 -257.531085) (xy 67.784186 -257.413112) (xy 67.870468 -257.299839) (xy 67.963021 -257.191628)
			(xy 68.061548 -257.088827) (xy 68.165733 -256.991765) (xy 68.275242 -256.900753) (xy 68.389725 -256.816081)
			(xy 68.508815 -256.738023) (xy 68.63213 -256.666827) (xy 68.759276 -256.602721) (xy 68.889845 -256.545912)
			(xy 69.023419 -256.49658) (xy 69.15957 -256.454884) (xy 69.297861 -256.420958) (xy 69.437851 -256.39491)
			(xy 69.57909 -256.376824) (xy 69.721126 -256.366757) (xy 69.863504 -256.364742) (xy 70.005768 -256.370785)
			(xy 70.147462 -256.384867) (xy 70.288132 -256.406943) (xy 70.427329 -256.436943) (xy 70.564605 -256.474769)
			(xy 70.699521 -256.520301) (xy 70.831645 -256.573392) (xy 70.960554 -256.633874) (xy 71.085835 -256.701552)
			(xy 71.207086 -256.776209) (xy 71.323919 -256.857607) (xy 71.43596 -256.945484) (xy 71.54285 -257.039559)
			(xy 71.644247 -257.139531) (xy 71.739825 -257.245079) (xy 71.829279 -257.355865) (xy 71.912321 -257.471534)
			(xy 71.988687 -257.591717) (xy 72.058131 -257.716027) (xy 72.120431 -257.844068) (xy 72.175387 -257.975427)
			(xy 72.222824 -258.109686) (xy 72.262588 -258.246413) (xy 72.294554 -258.385171) (xy 72.318619 -258.525515)
			(xy 72.334705 -258.666996) (xy 72.34276 -258.80916) (xy 72.343264 -258.880356) (xy 151.51202 -258.880356)
			(xy 151.51605 -258.738021) (xy 151.528125 -258.596141) (xy 151.548208 -258.455173) (xy 151.576235 -258.315566)
			(xy 151.612115 -258.177768) (xy 151.655733 -258.042221) (xy 151.70695 -257.909359) (xy 151.765601 -257.779607)
			(xy 151.831499 -257.653381) (xy 151.904433 -257.531085) (xy 151.98417 -257.413112) (xy 152.070452 -257.299839)
			(xy 152.163005 -257.191628) (xy 152.261532 -257.088827) (xy 152.365717 -256.991765) (xy 152.475226 -256.900753)
			(xy 152.589709 -256.816081) (xy 152.708799 -256.738023) (xy 152.832114 -256.666827) (xy 152.95926 -256.602721)
			(xy 153.089829 -256.545912) (xy 153.223403 -256.49658) (xy 153.359554 -256.454884) (xy 153.497845 -256.420958)
			(xy 153.637835 -256.39491) (xy 153.779074 -256.376824) (xy 153.92111 -256.366757) (xy 154.063488 -256.364742)
			(xy 154.205752 -256.370785) (xy 154.347446 -256.384867) (xy 154.488116 -256.406943) (xy 154.627313 -256.436943)
			(xy 154.764589 -256.474769) (xy 154.899505 -256.520301) (xy 155.031629 -256.573392) (xy 155.160538 -256.633874)
			(xy 155.285819 -256.701552) (xy 155.40707 -256.776209) (xy 155.523903 -256.857607) (xy 155.635944 -256.945484)
			(xy 155.742834 -257.039559) (xy 155.844231 -257.139531) (xy 155.939809 -257.245079) (xy 156.029263 -257.355865)
			(xy 156.112305 -257.471534) (xy 156.188671 -257.591717) (xy 156.258115 -257.716027) (xy 156.320415 -257.844068)
			(xy 156.375371 -257.975427) (xy 156.422808 -258.109686) (xy 156.462572 -258.246413) (xy 156.494538 -258.385171)
			(xy 156.518603 -258.525515) (xy 156.534689 -258.666996) (xy 156.542744 -258.80916) (xy 156.543246 -258.880102)
			(xy 315.252104 -258.880102) (xy 315.256134 -258.737767) (xy 315.268209 -258.595887) (xy 315.288292 -258.454919)
			(xy 315.316319 -258.315312) (xy 315.352199 -258.177514) (xy 315.395817 -258.041967) (xy 315.447034 -257.909105)
			(xy 315.505685 -257.779353) (xy 315.571583 -257.653127) (xy 315.644517 -257.530831) (xy 315.724254 -257.412858)
			(xy 315.810536 -257.299585) (xy 315.903089 -257.191374) (xy 316.001616 -257.088573) (xy 316.105801 -256.991511)
			(xy 316.21531 -256.900499) (xy 316.329793 -256.815827) (xy 316.448883 -256.737769) (xy 316.572198 -256.666573)
			(xy 316.699344 -256.602467) (xy 316.829913 -256.545658) (xy 316.963487 -256.496326) (xy 317.099638 -256.45463)
			(xy 317.237929 -256.420704) (xy 317.377919 -256.394656) (xy 317.519158 -256.37657) (xy 317.661194 -256.366503)
			(xy 317.803572 -256.364488) (xy 317.945836 -256.370531) (xy 318.08753 -256.384613) (xy 318.2282 -256.406689)
			(xy 318.367397 -256.436689) (xy 318.504673 -256.474515) (xy 318.639589 -256.520047) (xy 318.771713 -256.573138)
			(xy 318.900622 -256.63362) (xy 319.025903 -256.701298) (xy 319.147154 -256.775955) (xy 319.263987 -256.857353)
			(xy 319.376028 -256.94523) (xy 319.482918 -257.039305) (xy 319.584315 -257.139277) (xy 319.679893 -257.244825)
			(xy 319.769347 -257.355611) (xy 319.852389 -257.47128) (xy 319.928755 -257.591463) (xy 319.998199 -257.715773)
			(xy 320.060499 -257.843814) (xy 320.115455 -257.975173) (xy 320.162892 -258.109432) (xy 320.202656 -258.246159)
			(xy 320.234622 -258.384917) (xy 320.258687 -258.525261) (xy 320.274773 -258.666742) (xy 320.282828 -258.808906)
			(xy 320.283332 -258.880102) (xy 399.452088 -258.880102) (xy 399.456118 -258.737767) (xy 399.468193 -258.595887)
			(xy 399.488276 -258.454919) (xy 399.516303 -258.315312) (xy 399.552183 -258.177514) (xy 399.595801 -258.041967)
			(xy 399.647018 -257.909105) (xy 399.705669 -257.779353) (xy 399.771567 -257.653127) (xy 399.844501 -257.530831)
			(xy 399.924238 -257.412858) (xy 400.01052 -257.299585) (xy 400.103073 -257.191374) (xy 400.2016 -257.088573)
			(xy 400.305785 -256.991511) (xy 400.415294 -256.900499) (xy 400.529777 -256.815827) (xy 400.648867 -256.737769)
			(xy 400.772182 -256.666573) (xy 400.899328 -256.602467) (xy 401.029897 -256.545658) (xy 401.163471 -256.496326)
			(xy 401.299622 -256.45463) (xy 401.437913 -256.420704) (xy 401.577903 -256.394656) (xy 401.719142 -256.37657)
			(xy 401.861178 -256.366503) (xy 402.003556 -256.364488) (xy 402.14582 -256.370531) (xy 402.287514 -256.384613)
			(xy 402.428184 -256.406689) (xy 402.567381 -256.436689) (xy 402.704657 -256.474515) (xy 402.839573 -256.520047)
			(xy 402.971697 -256.573138) (xy 403.100606 -256.63362) (xy 403.225887 -256.701298) (xy 403.347138 -256.775955)
			(xy 403.463971 -256.857353) (xy 403.576012 -256.94523) (xy 403.682902 -257.039305) (xy 403.784299 -257.139277)
			(xy 403.879877 -257.244825) (xy 403.969331 -257.355611) (xy 404.052373 -257.47128) (xy 404.128739 -257.591463)
			(xy 404.198183 -257.715773) (xy 404.260483 -257.843814) (xy 404.315439 -257.975173) (xy 404.362876 -258.109432)
			(xy 404.40264 -258.246159) (xy 404.434606 -258.384917) (xy 404.458671 -258.525261) (xy 404.474757 -258.666742)
			(xy 404.482812 -258.808906) (xy 404.483316 -258.880102) (xy 404.482812 -258.951298) (xy 404.474757 -259.093462)
			(xy 404.458671 -259.234943) (xy 404.434606 -259.375287) (xy 404.40264 -259.514045) (xy 404.362876 -259.650772)
			(xy 404.315439 -259.785031) (xy 404.260483 -259.91639) (xy 404.198183 -260.044431) (xy 404.128739 -260.168741)
			(xy 404.052373 -260.288924) (xy 403.969331 -260.404593) (xy 403.879877 -260.515379) (xy 403.784299 -260.620927)
			(xy 403.682902 -260.720899) (xy 403.576012 -260.814974) (xy 403.463971 -260.902851) (xy 403.347138 -260.984249)
			(xy 403.225887 -261.058906) (xy 403.100606 -261.126584) (xy 402.971697 -261.187066) (xy 402.839573 -261.240157)
			(xy 402.704657 -261.285689) (xy 402.567381 -261.323515) (xy 402.428184 -261.353515) (xy 402.287514 -261.375591)
			(xy 402.14582 -261.389673) (xy 402.003556 -261.395716) (xy 401.861178 -261.393701) (xy 401.719142 -261.383634)
			(xy 401.577903 -261.365548) (xy 401.437913 -261.3395) (xy 401.299622 -261.305574) (xy 401.163471 -261.263878)
			(xy 401.029897 -261.214546) (xy 400.899328 -261.157737) (xy 400.772182 -261.093631) (xy 400.648867 -261.022435)
			(xy 400.529777 -260.944377) (xy 400.415294 -260.859705) (xy 400.305785 -260.768693) (xy 400.2016 -260.671631)
			(xy 400.103073 -260.56883) (xy 400.01052 -260.460619) (xy 399.924238 -260.347346) (xy 399.844501 -260.229373)
			(xy 399.771567 -260.107077) (xy 399.705669 -259.980851) (xy 399.647018 -259.851099) (xy 399.595801 -259.718237)
			(xy 399.552183 -259.58269) (xy 399.516303 -259.444892) (xy 399.488276 -259.305285) (xy 399.468193 -259.164317)
			(xy 399.456118 -259.022437) (xy 399.452088 -258.880102) (xy 320.283332 -258.880102) (xy 320.282828 -258.951298)
			(xy 320.274773 -259.093462) (xy 320.258687 -259.234943) (xy 320.234622 -259.375287) (xy 320.202656 -259.514045)
			(xy 320.162892 -259.650772) (xy 320.115455 -259.785031) (xy 320.060499 -259.91639) (xy 319.998199 -260.044431)
			(xy 319.928755 -260.168741) (xy 319.852389 -260.288924) (xy 319.769347 -260.404593) (xy 319.679893 -260.515379)
			(xy 319.584315 -260.620927) (xy 319.482918 -260.720899) (xy 319.376028 -260.814974) (xy 319.263987 -260.902851)
			(xy 319.147154 -260.984249) (xy 319.025903 -261.058906) (xy 318.900622 -261.126584) (xy 318.771713 -261.187066)
			(xy 318.639589 -261.240157) (xy 318.504673 -261.285689) (xy 318.367397 -261.323515) (xy 318.2282 -261.353515)
			(xy 318.08753 -261.375591) (xy 317.945836 -261.389673) (xy 317.803572 -261.395716) (xy 317.661194 -261.393701)
			(xy 317.519158 -261.383634) (xy 317.377919 -261.365548) (xy 317.237929 -261.3395) (xy 317.099638 -261.305574)
			(xy 316.963487 -261.263878) (xy 316.829913 -261.214546) (xy 316.699344 -261.157737) (xy 316.572198 -261.093631)
			(xy 316.448883 -261.022435) (xy 316.329793 -260.944377) (xy 316.21531 -260.859705) (xy 316.105801 -260.768693)
			(xy 316.001616 -260.671631) (xy 315.903089 -260.56883) (xy 315.810536 -260.460619) (xy 315.724254 -260.347346)
			(xy 315.644517 -260.229373) (xy 315.571583 -260.107077) (xy 315.505685 -259.980851) (xy 315.447034 -259.851099)
			(xy 315.395817 -259.718237) (xy 315.352199 -259.58269) (xy 315.316319 -259.444892) (xy 315.288292 -259.305285)
			(xy 315.268209 -259.164317) (xy 315.256134 -259.022437) (xy 315.252104 -258.880102) (xy 156.543246 -258.880102)
			(xy 156.543248 -258.880356) (xy 156.542744 -258.951552) (xy 156.534689 -259.093716) (xy 156.518603 -259.235197)
			(xy 156.494538 -259.375541) (xy 156.462572 -259.514299) (xy 156.422808 -259.651026) (xy 156.375371 -259.785285)
			(xy 156.320415 -259.916644) (xy 156.258115 -260.044685) (xy 156.188671 -260.168995) (xy 156.112305 -260.289178)
			(xy 156.029263 -260.404847) (xy 155.939809 -260.515633) (xy 155.844231 -260.621181) (xy 155.742834 -260.721153)
			(xy 155.635944 -260.815228) (xy 155.523903 -260.903105) (xy 155.40707 -260.984503) (xy 155.285819 -261.05916)
			(xy 155.160538 -261.126838) (xy 155.031629 -261.18732) (xy 154.899505 -261.240411) (xy 154.764589 -261.285943)
			(xy 154.627313 -261.323769) (xy 154.488116 -261.353769) (xy 154.347446 -261.375845) (xy 154.205752 -261.389927)
			(xy 154.063488 -261.39597) (xy 153.92111 -261.393955) (xy 153.779074 -261.383888) (xy 153.637835 -261.365802)
			(xy 153.497845 -261.339754) (xy 153.359554 -261.305828) (xy 153.223403 -261.264132) (xy 153.089829 -261.2148)
			(xy 152.95926 -261.157991) (xy 152.832114 -261.093885) (xy 152.708799 -261.022689) (xy 152.589709 -260.944631)
			(xy 152.475226 -260.859959) (xy 152.365717 -260.768947) (xy 152.261532 -260.671885) (xy 152.163005 -260.569084)
			(xy 152.070452 -260.460873) (xy 151.98417 -260.3476) (xy 151.904433 -260.229627) (xy 151.831499 -260.107331)
			(xy 151.765601 -259.981105) (xy 151.70695 -259.851353) (xy 151.655733 -259.718491) (xy 151.612115 -259.582944)
			(xy 151.576235 -259.445146) (xy 151.548208 -259.305539) (xy 151.528125 -259.164571) (xy 151.51605 -259.022691)
			(xy 151.51202 -258.880356) (xy 72.343264 -258.880356) (xy 72.34276 -258.951552) (xy 72.334705 -259.093716)
			(xy 72.318619 -259.235197) (xy 72.294554 -259.375541) (xy 72.262588 -259.514299) (xy 72.222824 -259.651026)
			(xy 72.175387 -259.785285) (xy 72.120431 -259.916644) (xy 72.058131 -260.044685) (xy 71.988687 -260.168995)
			(xy 71.912321 -260.289178) (xy 71.829279 -260.404847) (xy 71.739825 -260.515633) (xy 71.644247 -260.621181)
			(xy 71.54285 -260.721153) (xy 71.43596 -260.815228) (xy 71.323919 -260.903105) (xy 71.207086 -260.984503)
			(xy 71.085835 -261.05916) (xy 70.960554 -261.126838) (xy 70.831645 -261.18732) (xy 70.699521 -261.240411)
			(xy 70.564605 -261.285943) (xy 70.427329 -261.323769) (xy 70.288132 -261.353769) (xy 70.147462 -261.375845)
			(xy 70.005768 -261.389927) (xy 69.863504 -261.39597) (xy 69.721126 -261.393955) (xy 69.57909 -261.383888)
			(xy 69.437851 -261.365802) (xy 69.297861 -261.339754) (xy 69.15957 -261.305828) (xy 69.023419 -261.264132)
			(xy 68.889845 -261.2148) (xy 68.759276 -261.157991) (xy 68.63213 -261.093885) (xy 68.508815 -261.022689)
			(xy 68.389725 -260.944631) (xy 68.275242 -260.859959) (xy 68.165733 -260.768947) (xy 68.061548 -260.671885)
			(xy 67.963021 -260.569084) (xy 67.870468 -260.460873) (xy 67.784186 -260.3476) (xy 67.704449 -260.229627)
			(xy 67.631515 -260.107331) (xy 67.565617 -259.981105) (xy 67.506966 -259.851353) (xy 67.455749 -259.718491)
			(xy 67.412131 -259.582944) (xy 67.376251 -259.445146) (xy 67.348224 -259.305539) (xy 67.328141 -259.164571)
			(xy 67.316066 -259.022691) (xy 67.312036 -258.880356) (xy 2.509012 -258.880356) (xy 2.509012 -300.146974)
			(xy 340.219284 -300.146974) (xy 340.219284 -299.130974) (xy 340.21977 -299.103723) (xy 340.227526 -299.049775)
			(xy 340.242881 -298.99748) (xy 340.265523 -298.947903) (xy 340.294989 -298.902053) (xy 340.33068 -298.860862)
			(xy 340.371871 -298.825171) (xy 340.417721 -298.795705) (xy 340.467298 -298.773063) (xy 340.519593 -298.757708)
			(xy 340.573541 -298.749952) (xy 340.628043 -298.749952) (xy 340.681991 -298.757708) (xy 340.734286 -298.773063)
			(xy 340.783863 -298.795705) (xy 340.829713 -298.825171) (xy 340.870904 -298.860862) (xy 340.906595 -298.902053)
			(xy 340.936061 -298.947903) (xy 340.958703 -298.99748) (xy 340.974058 -299.049775) (xy 340.981814 -299.103723)
			(xy 340.9823 -299.130974) (xy 340.9823 -300.146974) (xy 340.981814 -300.174225) (xy 340.974058 -300.228173)
			(xy 340.958703 -300.280468) (xy 340.936061 -300.330045) (xy 340.906595 -300.375895) (xy 340.870904 -300.417086)
			(xy 340.829713 -300.452777) (xy 340.783863 -300.482243) (xy 340.734286 -300.504885) (xy 340.681991 -300.52024)
			(xy 340.628043 -300.527996) (xy 340.573541 -300.527996) (xy 340.519593 -300.52024) (xy 340.467298 -300.504885)
			(xy 340.417721 -300.482243) (xy 340.371871 -300.452777) (xy 340.33068 -300.417086) (xy 340.294989 -300.375895)
			(xy 340.265523 -300.330045) (xy 340.242881 -300.280468) (xy 340.227526 -300.228173) (xy 340.21977 -300.174225)
			(xy 340.219284 -300.146974) (xy 2.509012 -300.146974) (xy 2.509012 -304.780442) (xy 78.811886 -304.780442)
			(xy 78.815916 -304.638092) (xy 78.827993 -304.496199) (xy 78.848078 -304.355216) (xy 78.876107 -304.215595)
			(xy 78.911991 -304.077783) (xy 78.955613 -303.942222) (xy 79.006835 -303.809347) (xy 79.065493 -303.679582)
			(xy 79.131398 -303.553343) (xy 79.204339 -303.431035) (xy 79.284083 -303.31305) (xy 79.370375 -303.199765)
			(xy 79.462937 -303.091544) (xy 79.561474 -302.988732) (xy 79.665669 -302.89166) (xy 79.77519 -302.800639)
			(xy 79.889684 -302.715959) (xy 80.008786 -302.637893) (xy 80.132114 -302.566689) (xy 80.259272 -302.502577)
			(xy 80.389854 -302.445762) (xy 80.523442 -302.396425) (xy 80.659606 -302.354725) (xy 80.797912 -302.320796)
			(xy 80.937915 -302.294745) (xy 81.079169 -302.276657) (xy 81.221219 -302.266589) (xy 81.363611 -302.264574)
			(xy 81.50589 -302.270618) (xy 81.647598 -302.284701) (xy 81.788283 -302.30678) (xy 81.927493 -302.336782)
			(xy 82.064783 -302.374612) (xy 82.199713 -302.420148) (xy 82.331851 -302.473246) (xy 82.460773 -302.533733)
			(xy 82.586066 -302.601418) (xy 82.707329 -302.676083) (xy 82.824174 -302.757489) (xy 82.936227 -302.845375)
			(xy 83.043127 -302.939459) (xy 83.144534 -303.039441) (xy 83.240122 -303.144999) (xy 83.329585 -303.255797)
			(xy 83.412636 -303.371478) (xy 83.489009 -303.491673) (xy 83.55846 -303.615996) (xy 83.620766 -303.744049)
			(xy 83.675728 -303.875422) (xy 83.723169 -304.009694) (xy 83.762938 -304.146435) (xy 83.794907 -304.285207)
			(xy 83.818974 -304.425565) (xy 83.835062 -304.56706) (xy 83.843118 -304.709239) (xy 83.843622 -304.780442)
			(xy 140.011408 -304.780442) (xy 140.015438 -304.638078) (xy 140.027516 -304.49617) (xy 140.047604 -304.355173)
			(xy 140.075636 -304.215538) (xy 140.111523 -304.077712) (xy 140.15515 -303.942138) (xy 140.206377 -303.809249)
			(xy 140.26504 -303.67947) (xy 140.330952 -303.553219) (xy 140.403901 -303.430899) (xy 140.483653 -303.312902)
			(xy 140.569953 -303.199606) (xy 140.662525 -303.091373) (xy 140.761071 -302.988551) (xy 140.865277 -302.89147)
			(xy 140.974809 -302.800439) (xy 141.089315 -302.715751) (xy 141.208429 -302.637676) (xy 141.331769 -302.566466)
			(xy 141.45894 -302.502347) (xy 141.589536 -302.445526) (xy 141.723136 -302.396185) (xy 141.859315 -302.35448)
			(xy 141.997634 -302.320547) (xy 142.137652 -302.294494) (xy 142.278919 -302.276404) (xy 142.420984 -302.266335)
			(xy 142.563391 -302.26432) (xy 142.705684 -302.270364) (xy 142.847406 -302.28445) (xy 142.988105 -302.30653)
			(xy 143.12733 -302.336535) (xy 143.264634 -302.374369) (xy 143.399577 -302.41991) (xy 143.531728 -302.473013)
			(xy 143.660663 -302.533507) (xy 143.785969 -302.601198) (xy 143.907245 -302.675871) (xy 144.024101 -302.757285)
			(xy 144.136165 -302.845179) (xy 144.243077 -302.939273) (xy 144.344494 -303.039265) (xy 144.440091 -303.144834)
			(xy 144.529563 -303.255643) (xy 144.612622 -303.371336) (xy 144.689003 -303.491543) (xy 144.758461 -303.615878)
			(xy 144.820774 -303.743944) (xy 144.875741 -303.875331) (xy 144.923187 -304.009616) (xy 144.96296 -304.146371)
			(xy 144.994932 -304.285157) (xy 145.019002 -304.425529) (xy 145.035091 -304.567039) (xy 145.043148 -304.709231)
			(xy 145.04365 -304.780188) (xy 326.751954 -304.780188) (xy 326.755984 -304.637838) (xy 326.768061 -304.495945)
			(xy 326.788146 -304.354962) (xy 326.816175 -304.215341) (xy 326.852059 -304.077529) (xy 326.895681 -303.941968)
			(xy 326.946903 -303.809093) (xy 327.005561 -303.679328) (xy 327.071466 -303.553089) (xy 327.144407 -303.430781)
			(xy 327.224151 -303.312796) (xy 327.310443 -303.199511) (xy 327.403005 -303.09129) (xy 327.501542 -302.988478)
			(xy 327.605737 -302.891406) (xy 327.715258 -302.800385) (xy 327.829752 -302.715705) (xy 327.948854 -302.637639)
			(xy 328.072182 -302.566435) (xy 328.19934 -302.502323) (xy 328.329922 -302.445508) (xy 328.46351 -302.396171)
			(xy 328.599674 -302.354471) (xy 328.73798 -302.320542) (xy 328.877983 -302.294491) (xy 329.019237 -302.276403)
			(xy 329.161287 -302.266335) (xy 329.303679 -302.26432) (xy 329.445958 -302.270364) (xy 329.587666 -302.284447)
			(xy 329.728351 -302.306526) (xy 329.867561 -302.336528) (xy 330.004851 -302.374358) (xy 330.139781 -302.419894)
			(xy 330.271919 -302.472992) (xy 330.400841 -302.533479) (xy 330.526134 -302.601164) (xy 330.647397 -302.675829)
			(xy 330.764242 -302.757235) (xy 330.876295 -302.845121) (xy 330.983195 -302.939205) (xy 331.084602 -303.039187)
			(xy 331.18019 -303.144745) (xy 331.269653 -303.255543) (xy 331.352704 -303.371224) (xy 331.429077 -303.491419)
			(xy 331.498528 -303.615742) (xy 331.560834 -303.743795) (xy 331.615796 -303.875168) (xy 331.663237 -304.00944)
			(xy 331.703006 -304.146181) (xy 331.734975 -304.284953) (xy 331.759042 -304.425311) (xy 331.77513 -304.566806)
			(xy 331.781608 -304.681128) (xy 333.795116 -304.681128) (xy 333.795116 -303.817528) (xy 333.795602 -303.790259)
			(xy 333.803364 -303.736275) (xy 333.818729 -303.683945) (xy 333.841386 -303.634335) (xy 333.870872 -303.588454)
			(xy 333.906587 -303.547237) (xy 333.947804 -303.511522) (xy 333.993685 -303.482036) (xy 334.043295 -303.459379)
			(xy 334.095625 -303.444014) (xy 334.149609 -303.436252) (xy 334.204147 -303.436252) (xy 334.258131 -303.444014)
			(xy 334.310461 -303.459379) (xy 334.360071 -303.482036) (xy 334.405952 -303.511522) (xy 334.447169 -303.547237)
			(xy 334.482884 -303.588454) (xy 334.51237 -303.634335) (xy 334.535027 -303.683945) (xy 334.550392 -303.736275)
			(xy 334.558154 -303.790259) (xy 334.55864 -303.817528) (xy 334.55864 -304.681128) (xy 334.558154 -304.708397)
			(xy 334.550392 -304.762381) (xy 334.545164 -304.780188) (xy 387.951476 -304.780188) (xy 387.955506 -304.637824)
			(xy 387.967584 -304.495916) (xy 387.987672 -304.354919) (xy 388.015704 -304.215284) (xy 388.051591 -304.077458)
			(xy 388.095218 -303.941884) (xy 388.146445 -303.808995) (xy 388.205108 -303.679216) (xy 388.27102 -303.552965)
			(xy 388.343969 -303.430645) (xy 388.423721 -303.312648) (xy 388.510021 -303.199352) (xy 388.602593 -303.091119)
			(xy 388.701139 -302.988297) (xy 388.805345 -302.891216) (xy 388.914877 -302.800185) (xy 389.029383 -302.715497)
			(xy 389.148497 -302.637422) (xy 389.271837 -302.566212) (xy 389.399008 -302.502093) (xy 389.529604 -302.445272)
			(xy 389.663204 -302.395931) (xy 389.799383 -302.354226) (xy 389.937702 -302.320293) (xy 390.07772 -302.29424)
			(xy 390.218987 -302.27615) (xy 390.361052 -302.266081) (xy 390.503459 -302.264066) (xy 390.645752 -302.27011)
			(xy 390.787474 -302.284196) (xy 390.928173 -302.306276) (xy 391.067398 -302.336281) (xy 391.204702 -302.374115)
			(xy 391.339645 -302.419656) (xy 391.471796 -302.472759) (xy 391.600731 -302.533253) (xy 391.726037 -302.600944)
			(xy 391.847313 -302.675617) (xy 391.964169 -302.757031) (xy 392.076233 -302.844925) (xy 392.183145 -302.939019)
			(xy 392.284562 -303.039011) (xy 392.380159 -303.14458) (xy 392.469631 -303.255389) (xy 392.55269 -303.371082)
			(xy 392.629071 -303.491289) (xy 392.698529 -303.615624) (xy 392.760842 -303.74369) (xy 392.815809 -303.875077)
			(xy 392.863255 -304.009362) (xy 392.903028 -304.146117) (xy 392.935 -304.284903) (xy 392.95907 -304.425275)
			(xy 392.975159 -304.566785) (xy 392.983216 -304.708977) (xy 392.98372 -304.780188) (xy 392.983216 -304.851399)
			(xy 392.975159 -304.993591) (xy 392.95907 -305.135101) (xy 392.935 -305.275473) (xy 392.903028 -305.414259)
			(xy 392.863255 -305.551014) (xy 392.815809 -305.685299) (xy 392.760842 -305.816686) (xy 392.698529 -305.944752)
			(xy 392.629071 -306.069087) (xy 392.55269 -306.189294) (xy 392.469631 -306.304987) (xy 392.380159 -306.415796)
			(xy 392.284562 -306.521365) (xy 392.183145 -306.621357) (xy 392.076233 -306.715451) (xy 391.964169 -306.803345)
			(xy 391.847313 -306.884759) (xy 391.726037 -306.959432) (xy 391.600731 -307.027123) (xy 391.471796 -307.087617)
			(xy 391.339645 -307.14072) (xy 391.204702 -307.186261) (xy 391.067398 -307.224095) (xy 390.928173 -307.2541)
			(xy 390.787474 -307.27618) (xy 390.645752 -307.290266) (xy 390.503459 -307.29631) (xy 390.361052 -307.294295)
			(xy 390.218987 -307.284226) (xy 390.07772 -307.266136) (xy 389.937702 -307.240083) (xy 389.799383 -307.20615)
			(xy 389.663204 -307.164445) (xy 389.529604 -307.115104) (xy 389.399008 -307.058283) (xy 389.271837 -306.994164)
			(xy 389.148497 -306.922954) (xy 389.029383 -306.844879) (xy 388.914877 -306.760191) (xy 388.805345 -306.66916)
			(xy 388.701139 -306.572079) (xy 388.602593 -306.469257) (xy 388.510021 -306.361024) (xy 388.423721 -306.247728)
			(xy 388.343969 -306.129731) (xy 388.27102 -306.007411) (xy 388.205108 -305.88116) (xy 388.146445 -305.751381)
			(xy 388.095218 -305.618492) (xy 388.051591 -305.482918) (xy 388.015704 -305.345092) (xy 387.987672 -305.205457)
			(xy 387.967584 -305.06446) (xy 387.955506 -304.922552) (xy 387.951476 -304.780188) (xy 334.545164 -304.780188)
			(xy 334.535027 -304.814711) (xy 334.51237 -304.864321) (xy 334.482884 -304.910202) (xy 334.447169 -304.951419)
			(xy 334.405952 -304.987134) (xy 334.360071 -305.01662) (xy 334.310461 -305.039277) (xy 334.258131 -305.054642)
			(xy 334.204147 -305.062404) (xy 334.149609 -305.062404) (xy 334.095625 -305.054642) (xy 334.043295 -305.039277)
			(xy 333.993685 -305.01662) (xy 333.947804 -304.987134) (xy 333.906587 -304.951419) (xy 333.870872 -304.910202)
			(xy 333.841386 -304.864321) (xy 333.818729 -304.814711) (xy 333.803364 -304.762381) (xy 333.795602 -304.708397)
			(xy 333.795116 -304.681128) (xy 331.781608 -304.681128) (xy 331.783186 -304.708985) (xy 331.78369 -304.780188)
			(xy 331.783186 -304.851391) (xy 331.77513 -304.99357) (xy 331.759042 -305.135065) (xy 331.734975 -305.275423)
			(xy 331.703006 -305.414195) (xy 331.663237 -305.550936) (xy 331.615796 -305.685208) (xy 331.560834 -305.816581)
			(xy 331.498528 -305.944634) (xy 331.429077 -306.068957) (xy 331.352704 -306.189152) (xy 331.269653 -306.304833)
			(xy 331.18019 -306.415631) (xy 331.164492 -306.432966) (xy 340.495636 -306.432966) (xy 340.495636 -305.569366)
			(xy 340.496122 -305.542115) (xy 340.503878 -305.488167) (xy 340.519233 -305.435872) (xy 340.541875 -305.386295)
			(xy 340.571341 -305.340445) (xy 340.607032 -305.299254) (xy 340.648223 -305.263563) (xy 340.694073 -305.234097)
			(xy 340.74365 -305.211455) (xy 340.795945 -305.1961) (xy 340.849893 -305.188344) (xy 340.904395 -305.188344)
			(xy 340.958343 -305.1961) (xy 341.010638 -305.211455) (xy 341.060215 -305.234097) (xy 341.106065 -305.263563)
			(xy 341.147256 -305.299254) (xy 341.182947 -305.340445) (xy 341.212413 -305.386295) (xy 341.235055 -305.435872)
			(xy 341.25041 -305.488167) (xy 341.258166 -305.542115) (xy 341.258652 -305.569366) (xy 341.258652 -306.432966)
			(xy 341.258166 -306.460217) (xy 341.25041 -306.514165) (xy 341.235055 -306.56646) (xy 341.212413 -306.616037)
			(xy 341.182947 -306.661887) (xy 341.147256 -306.703078) (xy 341.106065 -306.738769) (xy 341.060215 -306.768235)
			(xy 341.010638 -306.790877) (xy 340.958343 -306.806232) (xy 340.904395 -306.813988) (xy 340.849893 -306.813988)
			(xy 340.795945 -306.806232) (xy 340.74365 -306.790877) (xy 340.694073 -306.768235) (xy 340.648223 -306.738769)
			(xy 340.607032 -306.703078) (xy 340.571341 -306.661887) (xy 340.541875 -306.616037) (xy 340.519233 -306.56646)
			(xy 340.503878 -306.514165) (xy 340.496122 -306.460217) (xy 340.495636 -306.432966) (xy 331.164492 -306.432966)
			(xy 331.084602 -306.521189) (xy 330.983195 -306.621171) (xy 330.876295 -306.715255) (xy 330.764242 -306.803141)
			(xy 330.647397 -306.884547) (xy 330.526134 -306.959212) (xy 330.400841 -307.026897) (xy 330.271919 -307.087384)
			(xy 330.139781 -307.140482) (xy 330.004851 -307.186018) (xy 329.867561 -307.223848) (xy 329.728351 -307.25385)
			(xy 329.587666 -307.275929) (xy 329.445958 -307.290012) (xy 329.303679 -307.296056) (xy 329.161287 -307.294041)
			(xy 329.019237 -307.283973) (xy 328.877983 -307.265885) (xy 328.73798 -307.239834) (xy 328.599674 -307.205905)
			(xy 328.46351 -307.164205) (xy 328.329922 -307.114868) (xy 328.19934 -307.058053) (xy 328.072182 -306.993941)
			(xy 327.948854 -306.922737) (xy 327.829752 -306.844671) (xy 327.715258 -306.759991) (xy 327.605737 -306.66897)
			(xy 327.501542 -306.571898) (xy 327.403005 -306.469086) (xy 327.310443 -306.360865) (xy 327.224151 -306.24758)
			(xy 327.144407 -306.129595) (xy 327.071466 -306.007287) (xy 327.005561 -305.881048) (xy 326.946903 -305.751283)
			(xy 326.895681 -305.618408) (xy 326.852059 -305.482847) (xy 326.816175 -305.345035) (xy 326.788146 -305.205414)
			(xy 326.768061 -305.064431) (xy 326.755984 -304.922538) (xy 326.751954 -304.780188) (xy 145.04365 -304.780188)
			(xy 145.043652 -304.780442) (xy 145.043148 -304.851653) (xy 145.035091 -304.993845) (xy 145.019002 -305.135355)
			(xy 144.994932 -305.275727) (xy 144.96296 -305.414513) (xy 144.923187 -305.551268) (xy 144.875741 -305.685553)
			(xy 144.820774 -305.81694) (xy 144.758461 -305.945006) (xy 144.689003 -306.069341) (xy 144.612622 -306.189548)
			(xy 144.529563 -306.305241) (xy 144.440091 -306.41605) (xy 144.344494 -306.521619) (xy 144.243077 -306.621611)
			(xy 144.136165 -306.715705) (xy 144.024101 -306.803599) (xy 143.907245 -306.885013) (xy 143.785969 -306.959686)
			(xy 143.660663 -307.027377) (xy 143.531728 -307.087871) (xy 143.399577 -307.140974) (xy 143.264634 -307.186515)
			(xy 143.12733 -307.224349) (xy 142.988105 -307.254354) (xy 142.847406 -307.276434) (xy 142.705684 -307.29052)
			(xy 142.563391 -307.296564) (xy 142.420984 -307.294549) (xy 142.278919 -307.28448) (xy 142.137652 -307.26639)
			(xy 141.997634 -307.240337) (xy 141.859315 -307.206404) (xy 141.723136 -307.164699) (xy 141.589536 -307.115358)
			(xy 141.45894 -307.058537) (xy 141.331769 -306.994418) (xy 141.208429 -306.923208) (xy 141.089315 -306.845133)
			(xy 140.974809 -306.760445) (xy 140.865277 -306.669414) (xy 140.761071 -306.572333) (xy 140.662525 -306.469511)
			(xy 140.569953 -306.361278) (xy 140.483653 -306.247982) (xy 140.403901 -306.129985) (xy 140.330952 -306.007665)
			(xy 140.26504 -305.881414) (xy 140.206377 -305.751635) (xy 140.15515 -305.618746) (xy 140.111523 -305.483172)
			(xy 140.075636 -305.345346) (xy 140.047604 -305.205711) (xy 140.027516 -305.064714) (xy 140.015438 -304.922806)
			(xy 140.011408 -304.780442) (xy 83.843622 -304.780442) (xy 83.843118 -304.851645) (xy 83.835062 -304.993824)
			(xy 83.818974 -305.135319) (xy 83.794907 -305.275677) (xy 83.762938 -305.414449) (xy 83.723169 -305.55119)
			(xy 83.675728 -305.685462) (xy 83.620766 -305.816835) (xy 83.55846 -305.944888) (xy 83.489009 -306.069211)
			(xy 83.412636 -306.189406) (xy 83.329585 -306.305087) (xy 83.240122 -306.415885) (xy 83.144534 -306.521443)
			(xy 83.043127 -306.621425) (xy 82.936227 -306.715509) (xy 82.824174 -306.803395) (xy 82.707329 -306.884801)
			(xy 82.586066 -306.959466) (xy 82.460773 -307.027151) (xy 82.331851 -307.087638) (xy 82.199713 -307.140736)
			(xy 82.064783 -307.186272) (xy 81.927493 -307.224102) (xy 81.788283 -307.254104) (xy 81.647598 -307.276183)
			(xy 81.50589 -307.290266) (xy 81.363611 -307.29631) (xy 81.221219 -307.294295) (xy 81.079169 -307.284227)
			(xy 80.937915 -307.266139) (xy 80.797912 -307.240088) (xy 80.659606 -307.206159) (xy 80.523442 -307.164459)
			(xy 80.389854 -307.115122) (xy 80.259272 -307.058307) (xy 80.132114 -306.994195) (xy 80.008786 -306.922991)
			(xy 79.889684 -306.844925) (xy 79.77519 -306.760245) (xy 79.665669 -306.669224) (xy 79.561474 -306.572152)
			(xy 79.462937 -306.46934) (xy 79.370375 -306.361119) (xy 79.284083 -306.247834) (xy 79.204339 -306.129849)
			(xy 79.131398 -306.007541) (xy 79.065493 -305.881302) (xy 79.006835 -305.751537) (xy 78.955613 -305.618662)
			(xy 78.911991 -305.483101) (xy 78.876107 -305.345289) (xy 78.848078 -305.205668) (xy 78.827993 -305.064685)
			(xy 78.815916 -304.922792) (xy 78.811886 -304.780442) (xy 2.509012 -304.780442) (xy 2.509012 -309.504588)
			(xy 79.192628 -309.504588) (xy 79.192628 -308.640988) (xy 79.193114 -308.613737) (xy 79.20087 -308.559789)
			(xy 79.216225 -308.507494) (xy 79.238867 -308.457917) (xy 79.268333 -308.412067) (xy 79.304024 -308.370876)
			(xy 79.345215 -308.335185) (xy 79.391065 -308.305719) (xy 79.440642 -308.283077) (xy 79.492937 -308.267722)
			(xy 79.546885 -308.259966) (xy 79.601387 -308.259966) (xy 79.655335 -308.267722) (xy 79.70763 -308.283077)
			(xy 79.757207 -308.305719) (xy 79.803057 -308.335185) (xy 79.844248 -308.370876) (xy 79.879939 -308.412067)
			(xy 79.909405 -308.457917) (xy 79.92811 -308.498873) (xy 93.275072 -308.498873) (xy 93.275072 -308.444327)
			(xy 93.282834 -308.390335) (xy 93.298202 -308.337998) (xy 93.320862 -308.288381) (xy 93.350352 -308.242493)
			(xy 93.386073 -308.20127) (xy 93.427297 -308.16555) (xy 93.473184 -308.13606) (xy 93.522802 -308.113401)
			(xy 93.575139 -308.098034) (xy 93.629131 -308.090271) (xy 93.656404 -308.089808) (xy 94.520004 -308.089808)
			(xy 94.547271 -308.090355) (xy 94.60125 -308.098116) (xy 94.653575 -308.113481) (xy 94.703181 -308.136135)
			(xy 94.749058 -308.165619) (xy 94.790271 -308.201331) (xy 94.825983 -308.242546) (xy 94.855467 -308.288423)
			(xy 94.878121 -308.338029) (xy 94.893485 -308.390354) (xy 94.901246 -308.444333) (xy 94.901246 -308.498867)
			(xy 94.893485 -308.552846) (xy 94.878121 -308.605171) (xy 94.855467 -308.654777) (xy 94.825983 -308.700654)
			(xy 94.790271 -308.741869) (xy 94.749058 -308.777581) (xy 94.703181 -308.807065) (xy 94.653575 -308.829719)
			(xy 94.60125 -308.845084) (xy 94.547271 -308.852845) (xy 94.520004 -308.853332) (xy 93.656404 -308.853332)
			(xy 93.629131 -308.852929) (xy 93.575139 -308.845166) (xy 93.522802 -308.829799) (xy 93.473184 -308.80714)
			(xy 93.427297 -308.77765) (xy 93.386073 -308.74193) (xy 93.350352 -308.700707) (xy 93.320862 -308.654819)
			(xy 93.298202 -308.605202) (xy 93.282834 -308.552865) (xy 93.275072 -308.498873) (xy 79.92811 -308.498873)
			(xy 79.932047 -308.507494) (xy 79.947402 -308.559789) (xy 79.955158 -308.613737) (xy 79.955644 -308.640988)
			(xy 79.955644 -309.303166) (xy 341.51824 -309.303166) (xy 341.51824 -308.439566) (xy 341.518726 -308.412297)
			(xy 341.526488 -308.358313) (xy 341.541853 -308.305983) (xy 341.56451 -308.256373) (xy 341.593996 -308.210492)
			(xy 341.629711 -308.169275) (xy 341.670928 -308.13356) (xy 341.716809 -308.104074) (xy 341.766419 -308.081417)
			(xy 341.818749 -308.066052) (xy 341.872733 -308.05829) (xy 341.927271 -308.05829) (xy 341.981255 -308.066052)
			(xy 342.033585 -308.081417) (xy 342.083195 -308.104074) (xy 342.129076 -308.13356) (xy 342.170293 -308.169275)
			(xy 342.206008 -308.210492) (xy 342.235494 -308.256373) (xy 342.258151 -308.305983) (xy 342.273516 -308.358313)
			(xy 342.281278 -308.412297) (xy 342.281764 -308.439566) (xy 342.281764 -309.303166) (xy 342.281278 -309.330435)
			(xy 342.273516 -309.384419) (xy 342.258151 -309.436749) (xy 342.235494 -309.486359) (xy 342.206008 -309.53224)
			(xy 342.170293 -309.573457) (xy 342.129076 -309.609172) (xy 342.083195 -309.638658) (xy 342.033585 -309.661315)
			(xy 341.981255 -309.67668) (xy 341.927271 -309.684442) (xy 341.872733 -309.684442) (xy 341.818749 -309.67668)
			(xy 341.766419 -309.661315) (xy 341.716809 -309.638658) (xy 341.670928 -309.609172) (xy 341.629711 -309.573457)
			(xy 341.593996 -309.53224) (xy 341.56451 -309.486359) (xy 341.541853 -309.436749) (xy 341.526488 -309.384419)
			(xy 341.518726 -309.330435) (xy 341.51824 -309.303166) (xy 79.955644 -309.303166) (xy 79.955644 -309.504588)
			(xy 79.955158 -309.531839) (xy 79.947402 -309.585787) (xy 79.932047 -309.638082) (xy 79.909405 -309.687659)
			(xy 79.879939 -309.733509) (xy 79.844248 -309.7747) (xy 79.803057 -309.810391) (xy 79.757207 -309.839857)
			(xy 79.70763 -309.862499) (xy 79.655335 -309.877854) (xy 79.601387 -309.88561) (xy 79.546885 -309.88561)
			(xy 79.492937 -309.877854) (xy 79.440642 -309.862499) (xy 79.391065 -309.839857) (xy 79.345215 -309.810391)
			(xy 79.304024 -309.7747) (xy 79.268333 -309.733509) (xy 79.238867 -309.687659) (xy 79.216225 -309.638082)
			(xy 79.20087 -309.585787) (xy 79.193114 -309.531839) (xy 79.192628 -309.504588) (xy 2.509012 -309.504588)
			(xy 2.509012 -310.603646) (xy 98.925888 -310.603646) (xy 98.925888 -309.740046) (xy 98.926374 -309.712795)
			(xy 98.93413 -309.658847) (xy 98.949485 -309.606552) (xy 98.972127 -309.556975) (xy 99.001593 -309.511125)
			(xy 99.037284 -309.469934) (xy 99.078475 -309.434243) (xy 99.124325 -309.404777) (xy 99.173902 -309.382135)
			(xy 99.226197 -309.36678) (xy 99.280145 -309.359024) (xy 99.334647 -309.359024) (xy 99.388595 -309.36678)
			(xy 99.44089 -309.382135) (xy 99.490467 -309.404777) (xy 99.536317 -309.434243) (xy 99.577508 -309.469934)
			(xy 99.613199 -309.511125) (xy 99.642665 -309.556975) (xy 99.665307 -309.606552) (xy 99.680662 -309.658847)
			(xy 99.688418 -309.712795) (xy 99.688904 -309.740046) (xy 99.688904 -310.603646) (xy 99.688418 -310.630897)
			(xy 99.680662 -310.684845) (xy 99.665307 -310.73714) (xy 99.642665 -310.786717) (xy 99.613199 -310.832567)
			(xy 99.577508 -310.873758) (xy 99.536317 -310.909449) (xy 99.490467 -310.938915) (xy 99.44089 -310.961557)
			(xy 99.388595 -310.976912) (xy 99.334647 -310.984668) (xy 99.280145 -310.984668) (xy 99.226197 -310.976912)
			(xy 99.173902 -310.961557) (xy 99.124325 -310.938915) (xy 99.078475 -310.909449) (xy 99.037284 -310.873758)
			(xy 99.001593 -310.832567) (xy 98.972127 -310.786717) (xy 98.949485 -310.73714) (xy 98.93413 -310.684845)
			(xy 98.926374 -310.630897) (xy 98.925888 -310.603646) (xy 2.509012 -310.603646) (xy 2.509012 -311.513728)
			(xy 347.772228 -311.513728) (xy 347.772228 -310.650128) (xy 347.772714 -310.622859) (xy 347.780476 -310.568875)
			(xy 347.795841 -310.516545) (xy 347.818498 -310.466935) (xy 347.847984 -310.421054) (xy 347.883699 -310.379837)
			(xy 347.924916 -310.344122) (xy 347.970797 -310.314636) (xy 348.020407 -310.291979) (xy 348.072737 -310.276614)
			(xy 348.126721 -310.268852) (xy 348.181259 -310.268852) (xy 348.235243 -310.276614) (xy 348.287573 -310.291979)
			(xy 348.337183 -310.314636) (xy 348.383064 -310.344122) (xy 348.424281 -310.379837) (xy 348.459996 -310.421054)
			(xy 348.489482 -310.466935) (xy 348.512139 -310.516545) (xy 348.527504 -310.568875) (xy 348.535266 -310.622859)
			(xy 348.535752 -310.650128) (xy 348.535752 -311.513728) (xy 348.535266 -311.540997) (xy 348.527504 -311.594981)
			(xy 348.512139 -311.647311) (xy 348.489482 -311.696921) (xy 348.459996 -311.742802) (xy 348.424281 -311.784019)
			(xy 348.383064 -311.819734) (xy 348.337183 -311.84922) (xy 348.287573 -311.871877) (xy 348.235243 -311.887242)
			(xy 348.181259 -311.895004) (xy 348.126721 -311.895004) (xy 348.072737 -311.887242) (xy 348.020407 -311.871877)
			(xy 347.970797 -311.84922) (xy 347.924916 -311.819734) (xy 347.883699 -311.784019) (xy 347.847984 -311.742802)
			(xy 347.818498 -311.696921) (xy 347.795841 -311.647311) (xy 347.780476 -311.594981) (xy 347.772714 -311.540997)
			(xy 347.772228 -311.513728) (xy 2.509012 -311.513728) (xy 2.509012 -314.997338) (xy 98.330512 -314.997338)
			(xy 98.330512 -314.133738) (xy 98.330998 -314.106487) (xy 98.338754 -314.052539) (xy 98.354109 -314.000244)
			(xy 98.376751 -313.950667) (xy 98.406217 -313.904817) (xy 98.441908 -313.863626) (xy 98.483099 -313.827935)
			(xy 98.528949 -313.798469) (xy 98.578526 -313.775827) (xy 98.630821 -313.760472) (xy 98.684769 -313.752716)
			(xy 98.739271 -313.752716) (xy 98.793219 -313.760472) (xy 98.845514 -313.775827) (xy 98.895091 -313.798469)
			(xy 98.940941 -313.827935) (xy 98.982132 -313.863626) (xy 99.017823 -313.904817) (xy 99.047289 -313.950667)
			(xy 99.069931 -314.000244) (xy 99.085286 -314.052539) (xy 99.093042 -314.106487) (xy 99.093528 -314.133738)
			(xy 99.093528 -314.997338) (xy 99.093042 -315.024589) (xy 99.085286 -315.078537) (xy 99.069931 -315.130832)
			(xy 99.047289 -315.180409) (xy 99.017823 -315.226259) (xy 98.982132 -315.26745) (xy 98.940941 -315.303141)
			(xy 98.895091 -315.332607) (xy 98.845514 -315.355249) (xy 98.793219 -315.370604) (xy 98.739271 -315.37836)
			(xy 98.684769 -315.37836) (xy 98.630821 -315.370604) (xy 98.578526 -315.355249) (xy 98.528949 -315.332607)
			(xy 98.483099 -315.303141) (xy 98.441908 -315.26745) (xy 98.406217 -315.226259) (xy 98.376751 -315.180409)
			(xy 98.354109 -315.130832) (xy 98.338754 -315.078537) (xy 98.330998 -315.024589) (xy 98.330512 -314.997338)
			(xy 2.509012 -314.997338) (xy 2.509012 -336.9884) (xy 70.218517 -336.9884) (xy 70.222508 -336.904617)
			(xy 70.234446 -336.821593) (xy 70.254221 -336.74008) (xy 70.281655 -336.660815) (xy 70.3165 -336.584518)
			(xy 70.35844 -336.511878) (xy 70.407095 -336.443554) (xy 70.462025 -336.380164) (xy 70.522731 -336.322283)
			(xy 70.588664 -336.270435) (xy 70.659228 -336.225089) (xy 70.733783 -336.186656) (xy 70.811653 -336.155484)
			(xy 70.892134 -336.131855) (xy 70.974497 -336.115984) (xy 71.057995 -336.108014) (xy 71.099934 -336.107532)
			(xy 71.137123 -336.107938) (xy 71.211236 -336.114223) (xy 71.284556 -336.126727) (xy 71.356562 -336.145363)
			(xy 71.39178 -336.157316) (xy 71.399977 -336.15983) (xy 71.417111 -336.15983) (xy 71.425308 -336.157316)
			(xy 71.460496 -336.145371) (xy 71.532436 -336.126725) (xy 71.605692 -336.114215) (xy 71.679742 -336.107929)
			(xy 71.7169 -336.107532) (xy 71.717408 -336.107532) (xy 71.748142 -336.108294) (xy 71.757646 -336.056715)
			(xy 71.787316 -335.956115) (xy 71.807324 -335.907634) (xy 71.810983 -335.897931) (xy 71.810971 -335.877211)
			(xy 71.807324 -335.867502) (xy 71.790219 -335.826242) (xy 71.763427 -335.741032) (xy 71.74539 -335.653549)
			(xy 71.736293 -335.564691) (xy 71.735696 -335.52003) (xy 71.735696 -335.519268) (xy 71.736195 -335.477343)
			(xy 71.744165 -335.393872) (xy 71.760034 -335.311537) (xy 71.783657 -335.231083) (xy 71.814821 -335.153239)
			(xy 71.853244 -335.078709) (xy 71.898577 -335.00817) (xy 71.95041 -334.942259) (xy 72.008273 -334.881573)
			(xy 72.071643 -334.826663) (xy 72.139946 -334.778025) (xy 72.212563 -334.7361) (xy 72.288836 -334.701267)
			(xy 72.368075 -334.673842) (xy 72.449561 -334.654073) (xy 72.532558 -334.64214) (xy 72.616314 -334.638151)
			(xy 72.70007 -334.64214) (xy 72.783067 -334.654073) (xy 72.864553 -334.673842) (xy 72.943792 -334.701267)
			(xy 73.020065 -334.7361) (xy 73.092682 -334.778025) (xy 73.160985 -334.826663) (xy 73.224355 -334.881573)
			(xy 73.282218 -334.942259) (xy 73.334051 -335.00817) (xy 73.379384 -335.078709) (xy 73.417807 -335.153239)
			(xy 73.448971 -335.231083) (xy 73.472594 -335.311537) (xy 73.488463 -335.393872) (xy 73.496433 -335.477343)
			(xy 73.496932 -335.519268) (xy 73.496932 -335.52003) (xy 73.496371 -335.564694) (xy 73.487295 -335.653559)
			(xy 73.46926 -335.741047) (xy 73.442452 -335.826257) (xy 73.425304 -335.867502) (xy 73.421681 -335.877216)
			(xy 73.421669 -335.897926) (xy 73.425304 -335.907634) (xy 73.441139 -335.945575) (xy 73.466487 -336.02379)
			(xy 73.484436 -336.104027) (xy 73.494829 -336.185587) (xy 73.496678 -336.226658) (xy 73.496932 -336.24012)
			(xy 73.51141 -336.263234) (xy 73.61301 -336.31759) (xy 73.639934 -336.316828) (xy 73.651618 -336.309462)
			(xy 73.686811 -336.288202) (xy 73.76042 -336.251553) (xy 73.837094 -336.221845) (xy 73.91618 -336.199333)
			(xy 73.997005 -336.184209) (xy 74.07888 -336.1766) (xy 74.119994 -336.176112) (xy 74.161107 -336.176619)
			(xy 74.242983 -336.184205) (xy 74.32381 -336.199313) (xy 74.402898 -336.221815) (xy 74.479573 -336.251518)
			(xy 74.553179 -336.288168) (xy 74.623091 -336.331454) (xy 74.68871 -336.381006) (xy 74.749477 -336.4364)
			(xy 74.804874 -336.497166) (xy 74.854428 -336.562783) (xy 74.897716 -336.632693) (xy 74.934369 -336.706298)
			(xy 74.964075 -336.782971) (xy 74.986579 -336.862059) (xy 75.001691 -336.942885) (xy 75.005252 -336.9813)
			(xy 78.574105 -336.9813) (xy 78.578096 -336.897517) (xy 78.590033 -336.814493) (xy 78.609809 -336.732979)
			(xy 78.637243 -336.653715) (xy 78.672087 -336.577417) (xy 78.714027 -336.504776) (xy 78.762681 -336.436452)
			(xy 78.81761 -336.373061) (xy 78.878316 -336.31518) (xy 78.94425 -336.26333) (xy 79.014813 -336.217984)
			(xy 79.089367 -336.179549) (xy 79.167237 -336.148376) (xy 79.247718 -336.124747) (xy 79.330081 -336.108874)
			(xy 79.413579 -336.100902) (xy 79.455518 -336.10042) (xy 79.492708 -336.100802) (xy 79.566821 -336.107094)
			(xy 79.640141 -336.119606) (xy 79.712146 -336.138248) (xy 79.747364 -336.150204) (xy 79.755561 -336.152718)
			(xy 79.772695 -336.152718) (xy 79.780892 -336.150204) (xy 79.816103 -336.138226) (xy 79.888108 -336.119576)
			(xy 79.961431 -336.107072) (xy 80.035547 -336.100804) (xy 80.072738 -336.10042) (xy 80.10906 -336.101182)
			(xy 80.115245 -336.066241) (xy 80.132513 -335.997409) (xy 80.155273 -335.930194) (xy 80.169004 -335.897474)
			(xy 80.172641 -335.887764) (xy 80.172644 -335.86705) (xy 80.169004 -335.857342) (xy 80.151879 -335.81609)
			(xy 80.125092 -335.730877) (xy 80.107061 -335.643392) (xy 80.09797 -335.554532) (xy 80.097376 -335.50987)
			(xy 80.097376 -335.509108) (xy 80.097875 -335.467183) (xy 80.105845 -335.383712) (xy 80.121714 -335.301377)
			(xy 80.145337 -335.220923) (xy 80.176501 -335.143079) (xy 80.214924 -335.068549) (xy 80.260257 -334.99801)
			(xy 80.31209 -334.932099) (xy 80.369953 -334.871413) (xy 80.433323 -334.816503) (xy 80.501626 -334.767865)
			(xy 80.574243 -334.72594) (xy 80.650516 -334.691107) (xy 80.729755 -334.663682) (xy 80.811241 -334.643913)
			(xy 80.894238 -334.63198) (xy 80.977994 -334.627991) (xy 81.06175 -334.63198) (xy 81.144747 -334.643913)
			(xy 81.226233 -334.663682) (xy 81.305472 -334.691107) (xy 81.381745 -334.72594) (xy 81.454362 -334.767865)
			(xy 81.522665 -334.816503) (xy 81.586035 -334.871413) (xy 81.643898 -334.932099) (xy 81.695731 -334.99801)
			(xy 81.741064 -335.068549) (xy 81.779487 -335.143079) (xy 81.810651 -335.220923) (xy 81.834274 -335.301377)
			(xy 81.850143 -335.383712) (xy 81.858113 -335.467183) (xy 81.858612 -335.509108) (xy 81.858612 -335.50987)
			(xy 81.858066 -335.554534) (xy 81.848986 -335.6434) (xy 81.830947 -335.730888) (xy 81.804134 -335.816098)
			(xy 81.786984 -335.857342) (xy 81.783338 -335.867049) (xy 81.783341 -335.887765) (xy 81.786984 -335.897474)
			(xy 81.802748 -335.935334) (xy 81.827987 -336.013369) (xy 81.845871 -336.093411) (xy 81.856247 -336.174768)
			(xy 81.858104 -336.215736) (xy 81.858828 -336.22455) (xy 81.865419 -336.240944) (xy 81.877182 -336.254128)
			(xy 81.884774 -336.258662) (xy 81.973928 -336.306922) (xy 82.000852 -336.30616) (xy 82.012536 -336.299048)
			(xy 82.047432 -336.278305) (xy 82.120306 -336.242523) (xy 82.19614 -336.213534) (xy 82.2743 -336.191579)
			(xy 82.354137 -336.176843) (xy 82.434985 -336.169448) (xy 82.475578 -336.169) (xy 82.516691 -336.169534)
			(xy 82.598566 -336.177119) (xy 82.679391 -336.192225) (xy 82.758479 -336.214725) (xy 82.835153 -336.244426)
			(xy 82.908759 -336.281075) (xy 82.97867 -336.324359) (xy 83.044289 -336.373909) (xy 83.105056 -336.429302)
			(xy 83.160453 -336.490065) (xy 83.210007 -336.555681) (xy 83.253296 -336.625589) (xy 83.28995 -336.699193)
			(xy 83.319656 -336.775864) (xy 83.342161 -336.85495) (xy 83.357273 -336.935775) (xy 83.360149 -336.9668)
			(xy 86.931981 -336.9668) (xy 86.935971 -336.883042) (xy 86.947905 -336.800043) (xy 86.967674 -336.718554)
			(xy 86.9951 -336.639313) (xy 87.029935 -336.563039) (xy 87.071862 -336.490421) (xy 87.120503 -336.422117)
			(xy 87.175416 -336.358746) (xy 87.236104 -336.300883) (xy 87.302018 -336.24905) (xy 87.37256 -336.203717)
			(xy 87.447092 -336.165296) (xy 87.52494 -336.134133) (xy 87.605396 -336.110512) (xy 87.687734 -336.094645)
			(xy 87.771208 -336.086677) (xy 87.813134 -336.086196) (xy 87.81415 -336.086196) (xy 87.851207 -336.086587)
			(xy 87.925057 -336.092856) (xy 87.998119 -336.105302) (xy 88.069879 -336.123838) (xy 88.10498 -336.135726)
			(xy 88.113177 -336.13824) (xy 88.130311 -336.13824) (xy 88.138508 -336.135726) (xy 88.173727 -336.123789)
			(xy 88.245736 -336.1052) (xy 88.319058 -336.092757) (xy 88.393169 -336.086549) (xy 88.430354 -336.086196)
			(xy 88.454992 -336.08645) (xy 88.464629 -336.040549) (xy 88.49238 -335.950951) (xy 88.510364 -335.907634)
			(xy 88.514021 -335.89793) (xy 88.514009 -335.877211) (xy 88.510364 -335.867502) (xy 88.493256 -335.826243)
			(xy 88.466465 -335.741033) (xy 88.448429 -335.65355) (xy 88.439333 -335.564691) (xy 88.438736 -335.52003)
			(xy 88.438736 -335.519268) (xy 88.439235 -335.477343) (xy 88.447205 -335.393872) (xy 88.463074 -335.311537)
			(xy 88.486697 -335.231083) (xy 88.517861 -335.153239) (xy 88.556284 -335.078709) (xy 88.601617 -335.00817)
			(xy 88.65345 -334.942259) (xy 88.711313 -334.881573) (xy 88.774683 -334.826663) (xy 88.842986 -334.778025)
			(xy 88.915603 -334.7361) (xy 88.991876 -334.701267) (xy 89.071115 -334.673842) (xy 89.152601 -334.654073)
			(xy 89.235598 -334.64214) (xy 89.319354 -334.638151) (xy 89.40311 -334.64214) (xy 89.486107 -334.654073)
			(xy 89.567593 -334.673842) (xy 89.646832 -334.701267) (xy 89.723105 -334.7361) (xy 89.795722 -334.778025)
			(xy 89.864025 -334.826663) (xy 89.927395 -334.881573) (xy 89.985258 -334.942259) (xy 90.037091 -335.00817)
			(xy 90.082424 -335.078709) (xy 90.120847 -335.153239) (xy 90.152011 -335.231083) (xy 90.175634 -335.311537)
			(xy 90.191503 -335.393872) (xy 90.199473 -335.477343) (xy 90.199972 -335.519268) (xy 90.199972 -335.52003)
			(xy 90.199408 -335.564694) (xy 90.190332 -335.653559) (xy 90.172298 -335.741047) (xy 90.145491 -335.826257)
			(xy 90.128344 -335.867502) (xy 90.124724 -335.877216) (xy 90.124712 -335.897925) (xy 90.128344 -335.907634)
			(xy 90.14352 -335.944017) (xy 90.168055 -336.018939) (xy 90.185802 -336.095753) (xy 90.196619 -336.173844)
			(xy 90.198956 -336.213196) (xy 90.198956 -336.21345) (xy 90.199799 -336.222253) (xy 90.206694 -336.238523)
			(xy 90.218709 -336.251482) (xy 90.226388 -336.255868) (xy 90.316812 -336.302604) (xy 90.343482 -336.301334)
			(xy 90.355166 -336.293968) (xy 90.390883 -336.271832) (xy 90.465707 -336.233583) (xy 90.543804 -336.20256)
			(xy 90.624479 -336.17904) (xy 90.707013 -336.163233) (xy 90.790669 -336.155279) (xy 90.832686 -336.154776)
			(xy 90.833194 -336.154776) (xy 90.874302 -336.155218) (xy 90.956167 -336.162803) (xy 91.036983 -336.177907)
			(xy 91.116061 -336.200402) (xy 91.192727 -336.230097) (xy 91.266326 -336.266738) (xy 91.336231 -336.310013)
			(xy 91.401845 -336.359552) (xy 91.46261 -336.414933) (xy 91.518006 -336.475684) (xy 91.567562 -336.541286)
			(xy 91.610854 -336.61118) (xy 91.647513 -336.68477) (xy 91.677227 -336.761428) (xy 91.699742 -336.840501)
			(xy 91.714867 -336.921313) (xy 91.722471 -337.003176) (xy 91.722641 -337.0176) (xy 95.263181 -337.0176)
			(xy 95.267171 -336.933842) (xy 95.279105 -336.850843) (xy 95.298874 -336.769354) (xy 95.3263 -336.690113)
			(xy 95.361135 -336.613839) (xy 95.403062 -336.541221) (xy 95.451703 -336.472917) (xy 95.506616 -336.409546)
			(xy 95.567304 -336.351683) (xy 95.633218 -336.29985) (xy 95.70376 -336.254517) (xy 95.778292 -336.216096)
			(xy 95.85614 -336.184933) (xy 95.936596 -336.161312) (xy 96.018934 -336.145445) (xy 96.102408 -336.137477)
			(xy 96.144334 -336.136996) (xy 96.14535 -336.136996) (xy 96.182407 -336.137387) (xy 96.256257 -336.143656)
			(xy 96.329319 -336.156102) (xy 96.401079 -336.174638) (xy 96.43618 -336.186526) (xy 96.444377 -336.18904)
			(xy 96.461511 -336.18904) (xy 96.469708 -336.186526) (xy 96.504897 -336.174599) (xy 96.576843 -336.15602)
			(xy 96.650101 -336.143577) (xy 96.724146 -336.137359) (xy 96.7613 -336.136996) (xy 96.761808 -336.136996)
			(xy 96.796352 -336.137504) (xy 96.805918 -336.09484) (xy 96.832381 -336.0115) (xy 96.849184 -335.971134)
			(xy 96.852845 -335.961431) (xy 96.852833 -335.940711) (xy 96.849184 -335.931002) (xy 96.832077 -335.889743)
			(xy 96.805286 -335.804532) (xy 96.78725 -335.717049) (xy 96.778153 -335.628191) (xy 96.777556 -335.58353)
			(xy 96.777556 -335.582768) (xy 96.778055 -335.540843) (xy 96.786025 -335.457372) (xy 96.801894 -335.375037)
			(xy 96.825517 -335.294583) (xy 96.856681 -335.216739) (xy 96.895104 -335.142209) (xy 96.940437 -335.07167)
			(xy 96.99227 -335.005759) (xy 97.050133 -334.945073) (xy 97.113503 -334.890163) (xy 97.181806 -334.841525)
			(xy 97.254423 -334.7996) (xy 97.330696 -334.764767) (xy 97.409935 -334.737342) (xy 97.491421 -334.717573)
			(xy 97.574418 -334.70564) (xy 97.658174 -334.701651) (xy 97.74193 -334.70564) (xy 97.824927 -334.717573)
			(xy 97.906413 -334.737342) (xy 97.985652 -334.764767) (xy 98.061925 -334.7996) (xy 98.134542 -334.841525)
			(xy 98.202845 -334.890163) (xy 98.266215 -334.945073) (xy 98.324078 -335.005759) (xy 98.375911 -335.07167)
			(xy 98.421244 -335.142209) (xy 98.459667 -335.216739) (xy 98.490831 -335.294583) (xy 98.514454 -335.375037)
			(xy 98.530323 -335.457372) (xy 98.538293 -335.540843) (xy 98.538792 -335.582768) (xy 98.538792 -335.58353)
			(xy 98.538226 -335.628194) (xy 98.529151 -335.717059) (xy 98.511117 -335.804547) (xy 98.484311 -335.889757)
			(xy 98.467164 -335.931002) (xy 98.463542 -335.940716) (xy 98.463531 -335.961426) (xy 98.467164 -335.971134)
			(xy 98.48433 -336.012473) (xy 98.511159 -336.097874) (xy 98.529194 -336.185554) (xy 98.538249 -336.27461)
			(xy 98.538792 -336.319368) (xy 98.538552 -336.350973) (xy 98.534101 -336.414026) (xy 98.529902 -336.445352)
			(xy 98.528378 -336.45602) (xy 98.53422 -336.477102) (xy 98.590608 -336.543396) (xy 98.597904 -336.55118)
			(xy 98.617064 -336.560504) (xy 98.627692 -336.56143) (xy 98.6282 -336.56143) (xy 98.671147 -336.563026)
			(xy 98.756458 -336.573467) (xy 98.840365 -336.592088) (xy 98.922084 -336.618714) (xy 99.000854 -336.653099)
			(xy 99.07594 -336.69492) (xy 99.146643 -336.743788) (xy 99.212303 -336.799248) (xy 99.272307 -336.860782)
			(xy 99.326097 -336.927817) (xy 99.362614 -336.9836) (xy 318.155561 -336.9836) (xy 318.15955 -336.899842)
			(xy 318.171484 -336.816843) (xy 318.191253 -336.735354) (xy 318.218678 -336.656114) (xy 318.253512 -336.579839)
			(xy 318.295438 -336.50722) (xy 318.344078 -336.438916) (xy 318.398989 -336.375544) (xy 318.459676 -336.317679)
			(xy 318.525589 -336.265845) (xy 318.59613 -336.220511) (xy 318.670661 -336.182087) (xy 318.748507 -336.150922)
			(xy 318.828963 -336.127298) (xy 318.911301 -336.111429) (xy 318.994774 -336.103459) (xy 319.0367 -336.10296)
			(xy 319.037716 -336.10296) (xy 319.074773 -336.103363) (xy 319.148622 -336.109628) (xy 319.221685 -336.122071)
			(xy 319.293445 -336.140604) (xy 319.328546 -336.15249) (xy 319.336743 -336.155004) (xy 319.353877 -336.155004)
			(xy 319.362074 -336.15249) (xy 319.397267 -336.140575) (xy 319.469212 -336.121992) (xy 319.542468 -336.109546)
			(xy 319.616513 -336.103324) (xy 319.653666 -336.10296) (xy 319.654174 -336.10296) (xy 319.681606 -336.103214)
			(xy 319.687655 -336.066844) (xy 319.704988 -335.995173) (xy 319.728195 -335.925184) (xy 319.742312 -335.891124)
			(xy 319.745871 -335.881532) (xy 319.745875 -335.86109) (xy 319.742312 -335.8515) (xy 319.725303 -335.810117)
			(xy 319.698681 -335.724692) (xy 319.680772 -335.637026) (xy 319.671759 -335.548004) (xy 319.671192 -335.503266)
			(xy 319.671192 -335.503012) (xy 319.671696 -335.460664) (xy 319.679747 -335.37635) (xy 319.695776 -335.293184)
			(xy 319.719637 -335.211917) (xy 319.751116 -335.133287) (xy 319.789927 -335.058006) (xy 319.835717 -334.986754)
			(xy 319.888073 -334.920178) (xy 319.946521 -334.85888) (xy 320.010531 -334.803415) (xy 320.079523 -334.754286)
			(xy 320.152873 -334.711937) (xy 320.229916 -334.676753) (xy 320.309955 -334.649051) (xy 320.392264 -334.629083)
			(xy 320.476099 -334.61703) (xy 320.5607 -334.613) (xy 320.645301 -334.61703) (xy 320.729136 -334.629083)
			(xy 320.811445 -334.649051) (xy 320.891484 -334.676753) (xy 320.968527 -334.711937) (xy 321.041877 -334.754286)
			(xy 321.110869 -334.803415) (xy 321.174879 -334.85888) (xy 321.233327 -334.920178) (xy 321.285683 -334.986754)
			(xy 321.331473 -335.058006) (xy 321.370284 -335.133287) (xy 321.401763 -335.211917) (xy 321.425624 -335.293184)
			(xy 321.441653 -335.37635) (xy 321.449704 -335.460664) (xy 321.450208 -335.503012) (xy 321.450208 -335.503266)
			(xy 321.449645 -335.548004) (xy 321.440627 -335.637026) (xy 321.422721 -335.724694) (xy 321.396107 -335.810121)
			(xy 321.379088 -335.8515) (xy 321.375596 -335.861115) (xy 321.37573 -335.881553) (xy 321.379342 -335.891124)
			(xy 321.395061 -335.929255) (xy 321.42019 -336.007817) (xy 321.437947 -336.088366) (xy 321.448179 -336.170212)
			(xy 321.449954 -336.211418) (xy 321.450208 -336.22488) (xy 321.464178 -336.24774) (xy 321.564762 -336.303112)
			(xy 321.591432 -336.302604) (xy 321.603116 -336.295746) (xy 321.637431 -336.275914) (xy 321.708951 -336.241747)
			(xy 321.783227 -336.214078) (xy 321.859671 -336.193127) (xy 321.937675 -336.179058) (xy 322.016621 -336.171985)
			(xy 322.056252 -336.17154) (xy 322.05676 -336.17154) (xy 322.097864 -336.17199) (xy 322.179721 -336.179572)
			(xy 322.26053 -336.194675) (xy 322.3396 -336.21717) (xy 322.416257 -336.246866) (xy 322.489847 -336.283508)
			(xy 322.559742 -336.326784) (xy 322.625346 -336.376325) (xy 322.686098 -336.431708) (xy 322.74148 -336.492461)
			(xy 322.791021 -336.558064) (xy 322.834296 -336.62796) (xy 322.870938 -336.70155) (xy 322.900632 -336.778207)
			(xy 322.923127 -336.857278) (xy 322.938229 -336.938087) (xy 322.941787 -336.9765) (xy 326.511148 -336.9765)
			(xy 326.515138 -336.892742) (xy 326.527072 -336.809743) (xy 326.546841 -336.728254) (xy 326.574266 -336.649013)
			(xy 326.609099 -336.572737) (xy 326.651025 -336.500118) (xy 326.699664 -336.431814) (xy 326.754575 -336.368441)
			(xy 326.815262 -336.310576) (xy 326.881174 -336.258741) (xy 326.951715 -336.213406) (xy 327.026246 -336.174981)
			(xy 327.104092 -336.143815) (xy 327.184547 -336.12019) (xy 327.266885 -336.104319) (xy 327.350358 -336.096347)
			(xy 327.392284 -336.095848) (xy 327.3933 -336.095848) (xy 327.430357 -336.096256) (xy 327.504206 -336.10252)
			(xy 327.577268 -336.114961) (xy 327.649028 -336.133493) (xy 327.68413 -336.145378) (xy 327.692327 -336.147892)
			(xy 327.709461 -336.147892) (xy 327.717658 -336.145378) (xy 327.752881 -336.133453) (xy 327.824889 -336.114861)
			(xy 327.898209 -336.102415) (xy 327.972319 -336.096203) (xy 328.009504 -336.095848) (xy 328.043286 -336.096356)
			(xy 328.05281 -336.047304) (xy 328.081456 -335.951571) (xy 328.100436 -335.905348) (xy 328.10398 -335.895751)
			(xy 328.103994 -335.875314) (xy 328.100436 -335.865724) (xy 328.083404 -335.82435) (xy 328.056787 -335.738922)
			(xy 328.038886 -335.651253) (xy 328.02988 -335.562229) (xy 328.029316 -335.51749) (xy 328.029316 -335.517236)
			(xy 328.02982 -335.474888) (xy 328.037871 -335.390574) (xy 328.0539 -335.307408) (xy 328.077761 -335.226141)
			(xy 328.10924 -335.147511) (xy 328.148051 -335.07223) (xy 328.193841 -335.000978) (xy 328.246197 -334.934402)
			(xy 328.304645 -334.873104) (xy 328.368655 -334.817639) (xy 328.437647 -334.76851) (xy 328.510997 -334.726161)
			(xy 328.58804 -334.690977) (xy 328.668079 -334.663275) (xy 328.750388 -334.643307) (xy 328.834223 -334.631254)
			(xy 328.918824 -334.627224) (xy 329.003425 -334.631254) (xy 329.08726 -334.643307) (xy 329.169569 -334.663275)
			(xy 329.249608 -334.690977) (xy 329.326651 -334.726161) (xy 329.400001 -334.76851) (xy 329.468993 -334.817639)
			(xy 329.533003 -334.873104) (xy 329.591451 -334.934402) (xy 329.643807 -335.000978) (xy 329.689597 -335.07223)
			(xy 329.728408 -335.147511) (xy 329.759887 -335.226141) (xy 329.783748 -335.307408) (xy 329.799777 -335.390574)
			(xy 329.807828 -335.474888) (xy 329.808332 -335.517236) (xy 329.808332 -335.51749) (xy 329.807775 -335.562229)
			(xy 329.798756 -335.651251) (xy 329.780848 -335.738918) (xy 329.754231 -335.824345) (xy 329.737212 -335.865724)
			(xy 329.733624 -335.875308) (xy 329.733638 -335.895757) (xy 329.737212 -335.905348) (xy 329.752022 -335.941175)
			(xy 329.776095 -336.014872) (xy 329.793653 -336.090386) (xy 329.804563 -336.167144) (xy 329.807062 -336.20583)
			(xy 329.807824 -336.219038) (xy 329.822048 -336.24139) (xy 329.91044 -336.288888) (xy 329.918254 -336.292745)
			(xy 329.93547 -336.295369) (xy 329.95256 -336.292022) (xy 329.960224 -336.287872) (xy 329.994483 -336.268147)
			(xy 330.065868 -336.23417) (xy 330.139986 -336.206662) (xy 330.216254 -336.18584) (xy 330.294068 -336.171868)
			(xy 330.372815 -336.164856) (xy 330.412344 -336.164428) (xy 330.453448 -336.164825) (xy 330.535306 -336.172414)
			(xy 330.616114 -336.187524) (xy 330.695183 -336.210025) (xy 330.771839 -336.239726) (xy 330.845427 -336.276373)
			(xy 330.91532 -336.319653) (xy 330.980922 -336.369198) (xy 331.041672 -336.424584) (xy 331.097053 -336.48534)
			(xy 331.146592 -336.550946) (xy 331.189866 -336.620843) (xy 331.226507 -336.694434) (xy 331.256201 -336.771093)
			(xy 331.278695 -336.850164) (xy 331.293797 -336.930973) (xy 331.296671 -336.962) (xy 334.868517 -336.962)
			(xy 334.872507 -336.878219) (xy 334.884444 -336.795197) (xy 334.904219 -336.713686) (xy 334.931652 -336.634423)
			(xy 334.966495 -336.558127) (xy 335.008433 -336.485488) (xy 335.057086 -336.417165) (xy 335.112013 -336.353776)
			(xy 335.172717 -336.295895) (xy 335.238647 -336.244046) (xy 335.309208 -336.198699) (xy 335.38376 -336.160265)
			(xy 335.461628 -336.129092) (xy 335.542106 -336.105461) (xy 335.624466 -336.089588) (xy 335.707962 -336.081615)
			(xy 335.7499 -336.081116) (xy 335.78709 -336.081504) (xy 335.861203 -336.087794) (xy 335.934522 -336.100304)
			(xy 336.006528 -336.118945) (xy 336.041746 -336.1309) (xy 336.049943 -336.133414) (xy 336.067077 -336.133414)
			(xy 336.075274 -336.1309) (xy 336.110487 -336.118927) (xy 336.182491 -336.100276) (xy 336.255813 -336.08777)
			(xy 336.329929 -336.0815) (xy 336.36712 -336.081116) (xy 336.407506 -336.082132) (xy 336.417036 -336.036786)
			(xy 336.444265 -335.948213) (xy 336.461862 -335.905348) (xy 336.465474 -335.895775) (xy 336.465619 -335.875336)
			(xy 336.462116 -335.865724) (xy 336.445083 -335.824351) (xy 336.418467 -335.738922) (xy 336.400565 -335.651253)
			(xy 336.39156 -335.562229) (xy 336.390996 -335.51749) (xy 336.390996 -335.517236) (xy 336.3915 -335.474888)
			(xy 336.399551 -335.390574) (xy 336.41558 -335.307408) (xy 336.439441 -335.226141) (xy 336.47092 -335.147511)
			(xy 336.509731 -335.07223) (xy 336.555521 -335.000978) (xy 336.607877 -334.934402) (xy 336.666325 -334.873104)
			(xy 336.730335 -334.817639) (xy 336.799327 -334.76851) (xy 336.872677 -334.726161) (xy 336.94972 -334.690977)
			(xy 337.029759 -334.663275) (xy 337.112068 -334.643307) (xy 337.195903 -334.631254) (xy 337.280504 -334.627224)
			(xy 337.365105 -334.631254) (xy 337.44894 -334.643307) (xy 337.531249 -334.663275) (xy 337.611288 -334.690977)
			(xy 337.688331 -334.726161) (xy 337.761681 -334.76851) (xy 337.830673 -334.817639) (xy 337.894683 -334.873104)
			(xy 337.953131 -334.934402) (xy 338.005487 -335.000978) (xy 338.051277 -335.07223) (xy 338.090088 -335.147511)
			(xy 338.121567 -335.226141) (xy 338.145428 -335.307408) (xy 338.161457 -335.390574) (xy 338.169508 -335.474888)
			(xy 338.170012 -335.517236) (xy 338.170012 -335.51749) (xy 338.169456 -335.562229) (xy 338.160437 -335.651251)
			(xy 338.142528 -335.738918) (xy 338.115912 -335.824345) (xy 338.098892 -335.865724) (xy 338.095386 -335.875335)
			(xy 338.09553 -335.895777) (xy 338.099146 -335.905348) (xy 338.117792 -335.95091) (xy 338.146101 -336.045203)
			(xy 338.163844 -336.142042) (xy 338.16798 -336.191098) (xy 338.168919 -336.199672) (xy 338.175759 -336.215494)
			(xy 338.187449 -336.228161) (xy 338.194904 -336.2325) (xy 338.283042 -336.278728) (xy 338.309204 -336.27822)
			(xy 338.320634 -336.271616) (xy 338.354723 -336.252133) (xy 338.425722 -336.218592) (xy 338.499399 -336.191437)
			(xy 338.575183 -336.170878) (xy 338.652483 -336.157075) (xy 338.730699 -336.150137) (xy 338.76996 -336.149696)
			(xy 338.81107 -336.150191) (xy 338.89294 -336.157775) (xy 338.97376 -336.172882) (xy 339.052841 -336.195384)
			(xy 339.129508 -336.225088) (xy 339.203107 -336.261741) (xy 339.273008 -336.305029) (xy 339.338617 -336.354584)
			(xy 339.399372 -336.409982) (xy 339.454755 -336.470751) (xy 339.504294 -336.536372) (xy 339.547565 -336.606284)
			(xy 339.5842 -336.679891) (xy 339.613885 -336.756566) (xy 339.636368 -336.835652) (xy 339.651455 -336.916476)
			(xy 339.659019 -336.998348) (xy 339.659177 -337.0128) (xy 343.199717 -337.0128) (xy 343.203707 -336.929019)
			(xy 343.215644 -336.845997) (xy 343.235419 -336.764486) (xy 343.262852 -336.685223) (xy 343.297695 -336.608927)
			(xy 343.339633 -336.536288) (xy 343.388286 -336.467965) (xy 343.443213 -336.404576) (xy 343.503917 -336.346695)
			(xy 343.569847 -336.294846) (xy 343.640408 -336.249499) (xy 343.71496 -336.211065) (xy 343.792828 -336.179892)
			(xy 343.873306 -336.156261) (xy 343.955666 -336.140388) (xy 344.039162 -336.132415) (xy 344.0811 -336.131916)
			(xy 344.11829 -336.132304) (xy 344.192403 -336.138594) (xy 344.265722 -336.151104) (xy 344.337728 -336.169745)
			(xy 344.372946 -336.1817) (xy 344.381143 -336.184214) (xy 344.398277 -336.184214) (xy 344.406474 -336.1817)
			(xy 344.441687 -336.169727) (xy 344.513691 -336.151076) (xy 344.587013 -336.13857) (xy 344.661129 -336.1323)
			(xy 344.69832 -336.131916) (xy 344.712798 -336.13217) (xy 344.724169 -336.131792) (xy 344.744841 -336.122355)
			(xy 344.759419 -336.104924) (xy 344.762836 -336.09407) (xy 344.771457 -336.062103) (xy 344.792812 -335.999426)
			(xy 344.805508 -335.968848) (xy 344.809054 -335.959252) (xy 344.809067 -335.938814) (xy 344.805508 -335.929224)
			(xy 344.788475 -335.887851) (xy 344.761859 -335.802423) (xy 344.743957 -335.714753) (xy 344.734952 -335.625729)
			(xy 344.734388 -335.58099) (xy 344.734388 -335.580736) (xy 344.734892 -335.538388) (xy 344.742943 -335.454074)
			(xy 344.758972 -335.370908) (xy 344.782833 -335.289641) (xy 344.814312 -335.211011) (xy 344.853123 -335.13573)
			(xy 344.898913 -335.064478) (xy 344.951269 -334.997902) (xy 345.009717 -334.936604) (xy 345.073727 -334.881139)
			(xy 345.142719 -334.83201) (xy 345.216069 -334.789661) (xy 345.293112 -334.754477) (xy 345.373151 -334.726775)
			(xy 345.45546 -334.706807) (xy 345.539295 -334.694754) (xy 345.623896 -334.690724) (xy 345.708497 -334.694754)
			(xy 345.792332 -334.706807) (xy 345.874641 -334.726775) (xy 345.95468 -334.754477) (xy 346.031723 -334.789661)
			(xy 346.105073 -334.83201) (xy 346.174065 -334.881139) (xy 346.238075 -334.936604) (xy 346.296523 -334.997902)
			(xy 346.348879 -335.064478) (xy 346.394669 -335.13573) (xy 346.43348 -335.211011) (xy 346.464959 -335.289641)
			(xy 346.48882 -335.370908) (xy 346.504849 -335.454074) (xy 346.5129 -335.538388) (xy 346.513404 -335.580736)
			(xy 346.513404 -335.58099) (xy 346.512849 -335.625729) (xy 346.50383 -335.714751) (xy 346.485921 -335.802418)
			(xy 346.459304 -335.887845) (xy 346.442284 -335.929224) (xy 346.438698 -335.938808) (xy 346.438711 -335.959257)
			(xy 346.442284 -335.968848) (xy 346.459319 -336.010255) (xy 346.48595 -336.095744) (xy 346.503854 -336.183477)
			(xy 346.51285 -336.272565) (xy 346.513404 -336.317336) (xy 346.513182 -336.348682) (xy 346.508857 -336.411225)
			(xy 346.504768 -336.442304) (xy 346.503244 -336.452972) (xy 346.508832 -336.473546) (xy 346.56268 -336.539586)
			(xy 346.569651 -336.547336) (xy 346.588142 -336.55691) (xy 346.598494 -336.558128) (xy 346.599002 -336.558128)
			(xy 346.640786 -336.561293) (xy 346.723543 -336.574476) (xy 346.804694 -336.595383) (xy 346.883519 -336.62383)
			(xy 346.959319 -336.659564) (xy 347.031422 -336.702268) (xy 347.09919 -336.751564) (xy 347.162022 -336.807015)
			(xy 347.21936 -336.868129) (xy 347.270696 -336.934365) (xy 347.315576 -337.005135) (xy 347.353601 -337.079812)
			(xy 347.384434 -337.157734) (xy 347.407802 -337.238211) (xy 347.423499 -337.320529) (xy 347.431384 -337.403958)
			(xy 347.431868 -337.445858) (xy 347.431868 -337.446874) (xy 347.431339 -337.489485) (xy 347.423121 -337.57431)
			(xy 347.406824 -337.657959) (xy 347.382599 -337.739665) (xy 347.367098 -337.77936) (xy 347.363634 -337.789438)
			(xy 347.36443 -337.810709) (xy 347.368622 -337.820508) (xy 347.385666 -337.856788) (xy 347.413917 -337.931808)
			(xy 347.435302 -338.009067) (xy 347.449648 -338.087936) (xy 347.456838 -338.167776) (xy 347.457268 -338.207858)
			(xy 347.456674 -338.254253) (xy 347.447033 -338.346541) (xy 347.42784 -338.437325) (xy 347.399305 -338.525619)
			(xy 347.381068 -338.568284) (xy 347.377284 -338.578233) (xy 347.377268 -338.599491) (xy 347.381068 -338.609432)
			(xy 347.399296 -338.652101) (xy 347.427845 -338.740391) (xy 347.447043 -338.831174) (xy 347.456681 -338.923462)
			(xy 347.457268 -338.969858) (xy 347.456674 -339.016253) (xy 347.447033 -339.108541) (xy 347.42784 -339.199325)
			(xy 347.399305 -339.287619) (xy 347.381068 -339.330284) (xy 347.377284 -339.340233) (xy 347.377268 -339.361491)
			(xy 347.381068 -339.371432) (xy 347.39928 -339.414039) (xy 347.427799 -339.502205) (xy 347.446995 -339.592859)
			(xy 347.456658 -339.685018) (xy 347.457268 -339.73135) (xy 347.457268 -339.731858) (xy 347.456747 -339.772964)
			(xy 347.449167 -339.854825) (xy 347.434067 -339.935639) (xy 347.411576 -340.014714) (xy 347.381885 -340.091377)
			(xy 347.345249 -340.164975) (xy 347.30198 -340.234878) (xy 347.252446 -340.300492) (xy 347.19707 -340.361256)
			(xy 347.136324 -340.416653) (xy 347.070727 -340.466209) (xy 347.000838 -340.509502) (xy 346.927254 -340.546163)
			(xy 346.8506 -340.575879) (xy 346.771533 -340.598397) (xy 346.690725 -340.613525) (xy 346.608866 -340.621133)
			(xy 346.56776 -340.62162) (xy 346.525159 -340.621134) (xy 346.440349 -340.612975) (xy 346.356708 -340.596745)
			(xy 346.275001 -340.572593) (xy 346.195978 -340.540739) (xy 346.120362 -340.501477) (xy 346.048846 -340.455165)
			(xy 345.982085 -340.402229) (xy 345.920691 -340.343152) (xy 345.865226 -340.278476) (xy 345.840304 -340.243922)
			(xy 345.834713 -340.236567) (xy 345.819465 -340.226159) (xy 345.810586 -340.223602) (xy 345.769427 -340.213207)
			(xy 345.689122 -340.185668) (xy 345.611806 -340.150603) (xy 345.538183 -340.108332) (xy 345.468921 -340.05924)
			(xy 345.40465 -340.003772) (xy 345.345957 -339.942434) (xy 345.293373 -339.875784) (xy 345.247379 -339.804427)
			(xy 345.208391 -339.729013) (xy 345.176765 -339.650228) (xy 345.152789 -339.568788) (xy 345.136679 -339.485435)
			(xy 345.128584 -339.400926) (xy 345.128088 -339.358478) (xy 345.128088 -339.358224) (xy 345.128648 -339.313485)
			(xy 345.137666 -339.224464) (xy 345.155574 -339.136796) (xy 345.182189 -339.051369) (xy 345.199208 -339.00999)
			(xy 345.202787 -339.000403) (xy 345.202779 -338.979957) (xy 345.199208 -338.970366) (xy 345.182177 -338.928958)
			(xy 345.155545 -338.843469) (xy 345.13764 -338.755736) (xy 345.128642 -338.666649) (xy 345.128088 -338.621878)
			(xy 345.128637 -338.577108) (xy 345.137642 -338.488021) (xy 345.15555 -338.400289) (xy 345.182178 -338.314799)
			(xy 345.199208 -338.27339) (xy 345.202787 -338.263803) (xy 345.202779 -338.243357) (xy 345.199208 -338.233766)
			(xy 345.182177 -338.192358) (xy 345.155545 -338.106869) (xy 345.13764 -338.019136) (xy 345.128642 -337.930049)
			(xy 345.128088 -337.885278) (xy 345.128088 -337.87334) (xy 345.101609 -337.867394) (xy 345.049374 -337.852651)
			(xy 345.023694 -337.843876) (xy 345.015497 -337.841362) (xy 344.998363 -337.841362) (xy 344.990166 -337.843876)
			(xy 344.95495 -337.855837) (xy 344.882946 -337.874492) (xy 344.809626 -337.887) (xy 344.73551 -337.893274)
			(xy 344.69832 -337.89366) (xy 344.661131 -337.893262) (xy 344.587018 -337.886974) (xy 344.513698 -337.874467)
			(xy 344.441692 -337.855829) (xy 344.406474 -337.843876) (xy 344.398277 -337.841362) (xy 344.381143 -337.841362)
			(xy 344.372946 -337.843876) (xy 344.337731 -337.855842) (xy 344.265728 -337.874496) (xy 344.192406 -337.887003)
			(xy 344.11829 -337.893275) (xy 344.0811 -337.89366) (xy 344.039162 -337.893185) (xy 343.955666 -337.885212)
			(xy 343.873306 -337.869339) (xy 343.792828 -337.845708) (xy 343.71496 -337.814535) (xy 343.640408 -337.776101)
			(xy 343.569847 -337.730754) (xy 343.503917 -337.678905) (xy 343.443213 -337.621024) (xy 343.388286 -337.557635)
			(xy 343.339633 -337.489312) (xy 343.297695 -337.416673) (xy 343.262852 -337.340377) (xy 343.235419 -337.261114)
			(xy 343.215644 -337.179603) (xy 343.203707 -337.096581) (xy 343.199717 -337.0128) (xy 339.659177 -337.0128)
			(xy 339.659468 -337.039458) (xy 339.6589 -337.084228) (xy 339.649901 -337.173314) (xy 339.631999 -337.261046)
			(xy 339.605375 -337.346537) (xy 339.588348 -337.387946) (xy 339.584808 -337.397544) (xy 339.584792 -337.41798)
			(xy 339.588348 -337.42757) (xy 339.605388 -337.468975) (xy 339.632018 -337.554465) (xy 339.649921 -337.642198)
			(xy 339.658915 -337.731287) (xy 339.659468 -337.776058) (xy 339.6589 -337.820828) (xy 339.649901 -337.909914)
			(xy 339.631999 -337.997646) (xy 339.605375 -338.083137) (xy 339.588348 -338.124546) (xy 339.584808 -338.134144)
			(xy 339.584792 -338.15458) (xy 339.588348 -338.16417) (xy 339.605377 -338.205545) (xy 339.631995 -338.290972)
			(xy 339.649897 -338.378641) (xy 339.658904 -338.467665) (xy 339.659468 -338.512404) (xy 339.659468 -338.512658)
			(xy 339.658947 -338.553764) (xy 339.651367 -338.635625) (xy 339.636267 -338.716439) (xy 339.613776 -338.795514)
			(xy 339.584085 -338.872177) (xy 339.547449 -338.945775) (xy 339.50418 -339.015678) (xy 339.454646 -339.081292)
			(xy 339.39927 -339.142056) (xy 339.338524 -339.197453) (xy 339.272927 -339.247009) (xy 339.203038 -339.290302)
			(xy 339.129454 -339.326963) (xy 339.0528 -339.356679) (xy 338.973733 -339.379197) (xy 338.892925 -339.394325)
			(xy 338.811066 -339.401933) (xy 338.76996 -339.40242) (xy 338.728351 -339.40191) (xy 338.645495 -339.394139)
			(xy 338.563727 -339.378669) (xy 338.483759 -339.355636) (xy 338.40629 -339.325239) (xy 338.331996 -339.287745)
			(xy 338.296504 -339.266022) (xy 338.287367 -339.260856) (xy 338.26665 -339.257639) (xy 338.246374 -339.262975)
			(xy 338.23783 -339.26907) (xy 338.204174 -339.295024) (xy 338.132784 -339.341153) (xy 338.057318 -339.380258)
			(xy 337.978465 -339.411983) (xy 337.896945 -339.436039) (xy 337.8135 -339.452205) (xy 337.728894 -339.460335)
			(xy 337.686396 -339.46084) (xy 337.645286 -339.460351) (xy 337.563418 -339.452764) (xy 337.482599 -339.437653)
			(xy 337.403519 -339.415149) (xy 337.326853 -339.385443) (xy 337.253256 -339.348789) (xy 337.183356 -339.3055)
			(xy 337.117748 -339.255944) (xy 337.056994 -339.200546) (xy 337.001611 -339.139778) (xy 336.952073 -339.074158)
			(xy 336.908801 -339.004246) (xy 336.872166 -338.93064) (xy 336.842479 -338.853967) (xy 336.819995 -338.774881)
			(xy 336.804905 -338.694058) (xy 336.797338 -338.612188) (xy 336.796888 -338.571078) (xy 336.797437 -338.526308)
			(xy 336.806442 -338.437221) (xy 336.82435 -338.349489) (xy 336.850978 -338.263999) (xy 336.868008 -338.22259)
			(xy 336.871587 -338.213003) (xy 336.871579 -338.192557) (xy 336.868008 -338.182966) (xy 336.850977 -338.141558)
			(xy 336.824345 -338.056069) (xy 336.80644 -337.968336) (xy 336.797442 -337.879249) (xy 336.796888 -337.834478)
			(xy 336.796888 -337.82254) (xy 336.770409 -337.816594) (xy 336.718174 -337.801851) (xy 336.692494 -337.793076)
			(xy 336.684297 -337.790562) (xy 336.667163 -337.790562) (xy 336.658966 -337.793076) (xy 336.62375 -337.805037)
			(xy 336.551746 -337.823692) (xy 336.478426 -337.8362) (xy 336.40431 -337.842474) (xy 336.36712 -337.84286)
			(xy 336.329931 -337.842462) (xy 336.255818 -337.836174) (xy 336.182498 -337.823667) (xy 336.110492 -337.805029)
			(xy 336.075274 -337.793076) (xy 336.067077 -337.790562) (xy 336.049943 -337.790562) (xy 336.041746 -337.793076)
			(xy 336.006531 -337.805042) (xy 335.934528 -337.823696) (xy 335.861206 -337.836203) (xy 335.78709 -337.842475)
			(xy 335.7499 -337.84286) (xy 335.707962 -337.842385) (xy 335.624466 -337.834412) (xy 335.542106 -337.818539)
			(xy 335.461628 -337.794908) (xy 335.38376 -337.763735) (xy 335.309208 -337.725301) (xy 335.238647 -337.679954)
			(xy 335.172717 -337.628105) (xy 335.112013 -337.570224) (xy 335.057086 -337.506835) (xy 335.008433 -337.438512)
			(xy 334.966495 -337.365873) (xy 334.931652 -337.289577) (xy 334.904219 -337.210314) (xy 334.884444 -337.128803)
			(xy 334.872507 -337.045781) (xy 334.868517 -336.962) (xy 331.296671 -336.962) (xy 331.301379 -337.012832)
			(xy 331.301852 -337.053936) (xy 331.301852 -337.05419) (xy 331.301293 -337.098929) (xy 331.292274 -337.18795)
			(xy 331.274367 -337.275618) (xy 331.247751 -337.361045) (xy 331.230732 -337.402424) (xy 331.227148 -337.412009)
			(xy 331.227161 -337.432457) (xy 331.230732 -337.442048) (xy 331.247764 -337.483456) (xy 331.274397 -337.568945)
			(xy 331.292302 -337.656677) (xy 331.301298 -337.745765) (xy 331.301852 -337.790536) (xy 331.301312 -337.835307)
			(xy 331.292305 -337.924394) (xy 331.274395 -338.012126) (xy 331.247763 -338.097615) (xy 331.230732 -338.139024)
			(xy 331.227148 -338.148609) (xy 331.227161 -338.169057) (xy 331.230732 -338.178648) (xy 331.247759 -338.220024)
			(xy 331.274376 -338.305451) (xy 331.292279 -338.39312) (xy 331.301287 -338.482143) (xy 331.301852 -338.526882)
			(xy 331.301852 -338.527136) (xy 331.301368 -338.568238) (xy 331.29378 -338.65009) (xy 331.278673 -338.730894)
			(xy 331.256175 -338.809959) (xy 331.226478 -338.886611) (xy 331.189836 -338.960196) (xy 331.14656 -339.030087)
			(xy 331.097021 -339.095686) (xy 331.041641 -339.156436) (xy 330.980892 -339.211816) (xy 330.915293 -339.261356)
			(xy 330.845403 -339.304632) (xy 330.771818 -339.341275) (xy 330.695167 -339.370972) (xy 330.616102 -339.393471)
			(xy 330.535298 -339.408579) (xy 330.453446 -339.416167) (xy 330.412344 -339.416644) (xy 330.411582 -339.416644)
			(xy 330.370042 -339.416142) (xy 330.287326 -339.408361) (xy 330.205695 -339.392907) (xy 330.125859 -339.369913)
			(xy 330.048513 -339.339581) (xy 329.97433 -339.302172) (xy 329.938888 -339.2805) (xy 329.929757 -339.275322)
			(xy 329.909036 -339.272112) (xy 329.888759 -339.277452) (xy 329.880214 -339.283548) (xy 329.846565 -339.30947)
			(xy 329.775191 -339.355528) (xy 329.699752 -339.394575) (xy 329.620935 -339.426254) (xy 329.539458 -339.450278)
			(xy 329.456062 -339.466427) (xy 329.371506 -339.474554) (xy 329.329034 -339.475064) (xy 329.32878 -339.475064)
			(xy 329.287675 -339.474667) (xy 329.205817 -339.46708) (xy 329.125007 -339.451972) (xy 329.045936 -339.429472)
			(xy 328.969279 -339.399772) (xy 328.895689 -339.363126) (xy 328.825795 -339.319846) (xy 328.760192 -339.270301)
			(xy 328.69944 -339.214915) (xy 328.644058 -339.154159) (xy 328.594518 -339.088553) (xy 328.551243 -339.018655)
			(xy 328.514602 -338.945062) (xy 328.484908 -338.868403) (xy 328.462414 -338.789331) (xy 328.447312 -338.70852)
			(xy 328.43973 -338.626661) (xy 328.439272 -338.585556) (xy 328.439272 -338.585302) (xy 328.43986 -338.540564)
			(xy 328.44887 -338.451543) (xy 328.466769 -338.363876) (xy 328.493377 -338.278448) (xy 328.510392 -338.237068)
			(xy 328.513984 -338.227485) (xy 328.513968 -338.207035) (xy 328.510392 -338.197444) (xy 328.493353 -338.156039)
			(xy 328.466723 -338.070549) (xy 328.44882 -337.982815) (xy 328.439825 -337.893727) (xy 328.439272 -337.848956)
			(xy 328.439272 -337.837018) (xy 328.412793 -337.831074) (xy 328.360558 -337.81633) (xy 328.334878 -337.807554)
			(xy 328.326681 -337.80504) (xy 328.309547 -337.80504) (xy 328.30135 -337.807554) (xy 328.266125 -337.819474)
			(xy 328.194118 -337.838068) (xy 328.120798 -337.850516) (xy 328.046689 -337.856728) (xy 328.009504 -337.857084)
			(xy 327.97232 -337.856715) (xy 327.898212 -337.850493) (xy 327.824892 -337.838051) (xy 327.752881 -337.819476)
			(xy 327.717658 -337.807554) (xy 327.709461 -337.80504) (xy 327.692327 -337.80504) (xy 327.68413 -337.807554)
			(xy 327.649029 -337.819442) (xy 327.577272 -337.837992) (xy 327.504209 -337.850438) (xy 327.430358 -337.856691)
			(xy 327.3933 -337.857084) (xy 327.392284 -337.857084) (xy 327.350358 -337.856653) (xy 327.266885 -337.848681)
			(xy 327.184547 -337.83281) (xy 327.104092 -337.809185) (xy 327.026246 -337.778019) (xy 326.951715 -337.739594)
			(xy 326.881174 -337.694259) (xy 326.815262 -337.642424) (xy 326.754575 -337.584559) (xy 326.699664 -337.521186)
			(xy 326.651025 -337.452882) (xy 326.609099 -337.380263) (xy 326.574266 -337.303987) (xy 326.546841 -337.224746)
			(xy 326.527072 -337.143257) (xy 326.515138 -337.060258) (xy 326.511148 -336.9765) (xy 322.941787 -336.9765)
			(xy 322.94581 -337.019944) (xy 322.946268 -337.061048) (xy 322.946268 -337.061302) (xy 322.945685 -337.10604)
			(xy 322.936674 -337.195061) (xy 322.918774 -337.282729) (xy 322.892164 -337.368156) (xy 322.875148 -337.409536)
			(xy 322.871556 -337.419119) (xy 322.871574 -337.439569) (xy 322.875148 -337.44916) (xy 322.892185 -337.490566)
			(xy 322.918816 -337.576056) (xy 322.93672 -337.663789) (xy 322.945715 -337.752877) (xy 322.946268 -337.797648)
			(xy 322.945697 -337.842418) (xy 322.936698 -337.931504) (xy 322.918797 -338.019236) (xy 322.892175 -338.104727)
			(xy 322.875148 -338.146136) (xy 322.871556 -338.155719) (xy 322.871574 -338.176169) (xy 322.875148 -338.18576)
			(xy 322.892174 -338.227136) (xy 322.918792 -338.312563) (xy 322.936696 -338.400232) (xy 322.945704 -338.489255)
			(xy 322.946268 -338.533994) (xy 322.946268 -338.534248) (xy 322.945879 -338.575352) (xy 322.938289 -338.65721)
			(xy 322.923179 -338.738019) (xy 322.900678 -338.817088) (xy 322.870976 -338.893744) (xy 322.834329 -338.967333)
			(xy 322.791048 -339.037226) (xy 322.741503 -339.102828) (xy 322.686116 -339.163578) (xy 322.62536 -339.218959)
			(xy 322.559753 -339.268498) (xy 322.489856 -339.311772) (xy 322.416264 -339.348412) (xy 322.339605 -339.378106)
			(xy 322.260533 -339.400599) (xy 322.179723 -339.415702) (xy 322.097864 -339.423283) (xy 322.05676 -339.423756)
			(xy 322.055998 -339.423756) (xy 322.014458 -339.423244) (xy 321.931742 -339.415465) (xy 321.850112 -339.400013)
			(xy 321.770276 -339.377021) (xy 321.69293 -339.34669) (xy 321.618746 -339.309284) (xy 321.583304 -339.287612)
			(xy 321.574167 -339.282447) (xy 321.55345 -339.279232) (xy 321.533175 -339.284566) (xy 321.52463 -339.29066)
			(xy 321.491012 -339.316622) (xy 321.419631 -339.362677) (xy 321.344187 -339.401718) (xy 321.265365 -339.433392)
			(xy 321.183883 -339.457409) (xy 321.100483 -339.47355) (xy 321.015924 -339.48167) (xy 320.97345 -339.482176)
			(xy 320.973196 -339.482176) (xy 320.932092 -339.481752) (xy 320.850234 -339.474166) (xy 320.769426 -339.459059)
			(xy 320.690356 -339.436561) (xy 320.613699 -339.406863) (xy 320.54011 -339.370219) (xy 320.470216 -339.326941)
			(xy 320.404613 -339.277398) (xy 320.343861 -339.222013) (xy 320.288479 -339.161259) (xy 320.238939 -339.095655)
			(xy 320.195664 -339.025759) (xy 320.159022 -338.952168) (xy 320.129327 -338.87551) (xy 320.106832 -338.796439)
			(xy 320.091729 -338.71563) (xy 320.084147 -338.633772) (xy 320.083688 -338.592668) (xy 320.083688 -338.592414)
			(xy 320.084245 -338.547675) (xy 320.093264 -338.458653) (xy 320.111172 -338.370986) (xy 320.137789 -338.285559)
			(xy 320.154808 -338.24418) (xy 320.158393 -338.234595) (xy 320.158381 -338.214147) (xy 320.154808 -338.204556)
			(xy 320.137774 -338.163149) (xy 320.111142 -338.07766) (xy 320.093238 -337.989927) (xy 320.084242 -337.900839)
			(xy 320.083688 -337.856068) (xy 320.083688 -337.84413) (xy 320.057209 -337.838184) (xy 320.004974 -337.823441)
			(xy 319.979294 -337.814666) (xy 319.971097 -337.812152) (xy 319.953963 -337.812152) (xy 319.945766 -337.814666)
			(xy 319.910549 -337.82661) (xy 319.838539 -337.845197) (xy 319.765217 -337.857638) (xy 319.691106 -337.863844)
			(xy 319.65392 -337.864196) (xy 319.616736 -337.863827) (xy 319.542628 -337.857606) (xy 319.469308 -337.845164)
			(xy 319.397297 -337.826589) (xy 319.362074 -337.814666) (xy 319.353877 -337.812152) (xy 319.336743 -337.812152)
			(xy 319.328546 -337.814666) (xy 319.293452 -337.826578) (xy 319.221693 -337.845121) (xy 319.148627 -337.85756)
			(xy 319.074774 -337.863807) (xy 319.037716 -337.864196) (xy 319.0367 -337.864196) (xy 318.994774 -337.863741)
			(xy 318.911301 -337.855771) (xy 318.828963 -337.839902) (xy 318.748507 -337.816278) (xy 318.670661 -337.785113)
			(xy 318.59613 -337.746689) (xy 318.525589 -337.701355) (xy 318.459676 -337.649521) (xy 318.398989 -337.591656)
			(xy 318.344078 -337.528284) (xy 318.295438 -337.45998) (xy 318.253512 -337.387361) (xy 318.218678 -337.311086)
			(xy 318.191253 -337.231846) (xy 318.171484 -337.150357) (xy 318.15955 -337.067358) (xy 318.155561 -336.9836)
			(xy 99.362614 -336.9836) (xy 99.373171 -336.999727) (xy 99.41309 -337.075842) (xy 99.445481 -337.155452)
			(xy 99.470043 -337.237815) (xy 99.486546 -337.322163) (xy 99.494837 -337.40771) (xy 99.495356 -337.450684)
			(xy 99.494854 -337.493421) (xy 99.48668 -337.578504) (xy 99.470386 -337.662411) (xy 99.446122 -337.744369)
			(xy 99.430586 -337.784186) (xy 99.426944 -337.794219) (xy 99.427619 -337.815536) (xy 99.431856 -337.825334)
			(xy 99.448914 -337.861614) (xy 99.477225 -337.936624) (xy 99.498666 -338.013878) (xy 99.513065 -338.092749)
			(xy 99.520304 -338.172597) (xy 99.520756 -338.212684) (xy 99.520272 -338.252763) (xy 99.512982 -338.33259)
			(xy 99.498549 -338.411439) (xy 99.488244 -338.450174) (xy 99.485843 -338.460698) (xy 99.489132 -338.482012)
			(xy 99.494594 -338.491322) (xy 99.517345 -338.52734) (xy 99.556637 -338.602937) (xy 99.588514 -338.681946)
			(xy 99.612684 -338.763644) (xy 99.628925 -338.847279) (xy 99.637089 -338.932085) (xy 99.637596 -338.974684)
			(xy 99.637001 -339.021087) (xy 99.627302 -339.113385) (xy 99.608039 -339.204171) (xy 99.579422 -339.292455)
			(xy 99.561142 -339.33511) (xy 99.557344 -339.345055) (xy 99.557338 -339.366316) (xy 99.561142 -339.376258)
			(xy 99.579397 -339.418922) (xy 99.607993 -339.507209) (xy 99.627252 -339.597991) (xy 99.636966 -339.690283)
			(xy 99.637596 -339.736684) (xy 99.637118 -339.777779) (xy 99.629538 -339.859619) (xy 99.614439 -339.94041)
			(xy 99.591952 -340.019465) (xy 99.562267 -340.096107) (xy 99.525639 -340.169684) (xy 99.482378 -340.239568)
			(xy 99.432856 -340.305164) (xy 99.377493 -340.36591) (xy 99.316762 -340.421291) (xy 99.251181 -340.470833)
			(xy 99.18131 -340.514113) (xy 99.107743 -340.550763) (xy 99.031109 -340.58047) (xy 98.952062 -340.60298)
			(xy 98.871275 -340.618102) (xy 98.789437 -340.625707) (xy 98.748342 -340.626192) (xy 98.747834 -340.626192)
			(xy 98.704859 -340.625663) (xy 98.619309 -340.617375) (xy 98.534957 -340.600874) (xy 98.45259 -340.576313)
			(xy 98.372977 -340.543922) (xy 98.296859 -340.504001) (xy 98.224947 -340.456925) (xy 98.157912 -340.403131)
			(xy 98.096378 -340.343122) (xy 98.040919 -340.277458) (xy 98.01606 -340.242398) (xy 98.010455 -340.235056)
			(xy 97.995216 -340.224641) (xy 97.986342 -340.222078) (xy 97.94544 -340.211492) (xy 97.865683 -340.183605)
			(xy 97.788928 -340.148281) (xy 97.715869 -340.105839) (xy 97.647164 -340.05666) (xy 97.583432 -340.001188)
			(xy 97.525246 -339.939922) (xy 97.473132 -339.873416) (xy 97.427559 -339.802268) (xy 97.388937 -339.727119)
			(xy 97.357615 -339.648646) (xy 97.333875 -339.567557) (xy 97.317931 -339.484583) (xy 97.309927 -339.40047)
			(xy 97.309432 -339.358224) (xy 97.309829 -339.321956) (xy 97.315809 -339.249667) (xy 97.327648 -339.178103)
			(xy 97.336102 -339.142832) (xy 97.338115 -339.132729) (xy 97.334853 -339.112411) (xy 97.329752 -339.103462)
			(xy 97.30766 -339.067807) (xy 97.269551 -338.993079) (xy 97.238646 -338.915096) (xy 97.215218 -338.83455)
			(xy 97.199477 -338.752156) (xy 97.191562 -338.668646) (xy 97.191068 -338.626704) (xy 97.191648 -338.581935)
			(xy 97.200654 -338.49285) (xy 97.218554 -338.405119) (xy 97.245168 -338.319627) (xy 97.262188 -338.278216)
			(xy 97.265753 -338.268625) (xy 97.265754 -338.248182) (xy 97.262188 -338.238592) (xy 97.245172 -338.197246)
			(xy 97.218563 -338.111882) (xy 97.20066 -338.024278) (xy 97.191642 -337.935319) (xy 97.191068 -337.890612)
			(xy 97.191068 -337.889596) (xy 97.191322 -337.878166) (xy 97.164844 -337.872216) (xy 97.112609 -337.857476)
			(xy 97.086928 -337.848702) (xy 97.078731 -337.846188) (xy 97.061597 -337.846188) (xy 97.0534 -337.848702)
			(xy 97.01818 -337.860638) (xy 96.946171 -337.879227) (xy 96.87285 -337.89167) (xy 96.798739 -337.897878)
			(xy 96.761554 -337.898232) (xy 96.724369 -337.89788) (xy 96.650261 -337.891654) (xy 96.576941 -337.879206)
			(xy 96.504931 -337.860627) (xy 96.469708 -337.848702) (xy 96.461511 -337.846188) (xy 96.444377 -337.846188)
			(xy 96.43618 -337.848702) (xy 96.401082 -337.860602) (xy 96.329324 -337.879149) (xy 96.25626 -337.891592)
			(xy 96.182408 -337.897841) (xy 96.14535 -337.898232) (xy 96.144334 -337.898232) (xy 96.102408 -337.897723)
			(xy 96.018934 -337.889755) (xy 95.936596 -337.873888) (xy 95.85614 -337.850267) (xy 95.778292 -337.819104)
			(xy 95.70376 -337.780683) (xy 95.633218 -337.73535) (xy 95.567304 -337.683517) (xy 95.506616 -337.625654)
			(xy 95.451703 -337.562283) (xy 95.403062 -337.493979) (xy 95.361135 -337.421361) (xy 95.3263 -337.345087)
			(xy 95.298874 -337.265846) (xy 95.279105 -337.184357) (xy 95.267171 -337.101358) (xy 95.263181 -337.0176)
			(xy 91.722641 -337.0176) (xy 91.722956 -337.044284) (xy 91.722404 -337.089054) (xy 91.71339 -337.178139)
			(xy 91.695482 -337.26587) (xy 91.668861 -337.351361) (xy 91.651836 -337.392772) (xy 91.648282 -337.402366)
			(xy 91.648276 -337.422805) (xy 91.651836 -337.432396) (xy 91.668872 -337.473803) (xy 91.695506 -337.559291)
			(xy 91.71341 -337.647024) (xy 91.722404 -337.736113) (xy 91.722956 -337.780884) (xy 91.722404 -337.825654)
			(xy 91.71339 -337.914739) (xy 91.695482 -338.00247) (xy 91.668861 -338.087961) (xy 91.651836 -338.129372)
			(xy 91.648282 -338.138966) (xy 91.648276 -338.159405) (xy 91.651836 -338.168996) (xy 91.668872 -338.210403)
			(xy 91.695506 -338.295891) (xy 91.71341 -338.383624) (xy 91.722404 -338.472713) (xy 91.722956 -338.517484)
			(xy 91.722432 -338.558593) (xy 91.714846 -338.64046) (xy 91.699738 -338.721278) (xy 91.677236 -338.800357)
			(xy 91.647532 -338.877021) (xy 91.610881 -338.950618) (xy 91.567594 -339.020518) (xy 91.518041 -339.086125)
			(xy 91.462645 -339.146879) (xy 91.401879 -339.202262) (xy 91.336261 -339.251801) (xy 91.266352 -339.295073)
			(xy 91.192747 -339.331709) (xy 91.116076 -339.361396) (xy 91.036993 -339.383882) (xy 90.956172 -339.398973)
			(xy 90.874303 -339.406541) (xy 90.833194 -339.406992) (xy 90.791589 -339.406554) (xy 90.70874 -339.398816)
			(xy 90.626975 -339.383379) (xy 90.547007 -339.360379) (xy 90.469535 -339.330016) (xy 90.395235 -339.292555)
			(xy 90.359738 -339.270848) (xy 90.350631 -339.26562) (xy 90.329893 -339.262421) (xy 90.309608 -339.267785)
			(xy 90.301064 -339.273896) (xy 90.267427 -339.299833) (xy 90.196051 -339.345891) (xy 90.12061 -339.384937)
			(xy 90.041791 -339.416615) (xy 89.960312 -339.440636) (xy 89.876914 -339.456781) (xy 89.792357 -339.464905)
			(xy 89.749884 -339.465412) (xy 89.74963 -339.465412) (xy 89.708522 -339.464959) (xy 89.626657 -339.457377)
			(xy 89.545841 -339.442274) (xy 89.466762 -339.41978) (xy 89.390096 -339.390087) (xy 89.316497 -339.353447)
			(xy 89.246591 -339.310173) (xy 89.180976 -339.260635) (xy 89.120211 -339.205254) (xy 89.064815 -339.144504)
			(xy 89.015259 -339.078902) (xy 88.971967 -339.009008) (xy 88.935308 -338.935418) (xy 88.905594 -338.85876)
			(xy 88.883079 -338.779687) (xy 88.867956 -338.698875) (xy 88.860352 -338.617012) (xy 88.859868 -338.575904)
			(xy 88.860448 -338.531135) (xy 88.869454 -338.44205) (xy 88.887354 -338.354319) (xy 88.913968 -338.268827)
			(xy 88.930988 -338.227416) (xy 88.934553 -338.217825) (xy 88.934554 -338.197382) (xy 88.930988 -338.187792)
			(xy 88.913972 -338.146446) (xy 88.887363 -338.061082) (xy 88.86946 -337.973478) (xy 88.860442 -337.884519)
			(xy 88.859868 -337.839812) (xy 88.859868 -337.838796) (xy 88.860122 -337.827366) (xy 88.833644 -337.821416)
			(xy 88.781409 -337.806676) (xy 88.755728 -337.797902) (xy 88.747531 -337.795388) (xy 88.730397 -337.795388)
			(xy 88.7222 -337.797902) (xy 88.68698 -337.809838) (xy 88.614971 -337.828427) (xy 88.54165 -337.84087)
			(xy 88.467539 -337.847078) (xy 88.430354 -337.847432) (xy 88.393169 -337.84708) (xy 88.319061 -337.840854)
			(xy 88.245741 -337.828406) (xy 88.173731 -337.809827) (xy 88.138508 -337.797902) (xy 88.130311 -337.795388)
			(xy 88.113177 -337.795388) (xy 88.10498 -337.797902) (xy 88.069882 -337.809802) (xy 87.998124 -337.828349)
			(xy 87.92506 -337.840792) (xy 87.851208 -337.847041) (xy 87.81415 -337.847432) (xy 87.813134 -337.847432)
			(xy 87.771208 -337.846923) (xy 87.687734 -337.838955) (xy 87.605396 -337.823088) (xy 87.52494 -337.799467)
			(xy 87.447092 -337.768304) (xy 87.37256 -337.729883) (xy 87.302018 -337.68455) (xy 87.236104 -337.632717)
			(xy 87.175416 -337.574854) (xy 87.120503 -337.511483) (xy 87.071862 -337.443179) (xy 87.029935 -337.370561)
			(xy 86.9951 -337.294287) (xy 86.967674 -337.215046) (xy 86.947905 -337.133557) (xy 86.935971 -337.050558)
			(xy 86.931981 -336.9668) (xy 83.360149 -336.9668) (xy 83.364863 -337.017649) (xy 83.36534 -337.058762)
			(xy 83.364781 -337.103532) (xy 83.35577 -337.192617) (xy 83.337863 -337.280348) (xy 83.311243 -337.365839)
			(xy 83.29422 -337.40725) (xy 83.290679 -337.416847) (xy 83.290665 -337.437283) (xy 83.29422 -337.446874)
			(xy 83.311248 -337.488284) (xy 83.337884 -337.573771) (xy 83.355791 -337.661503) (xy 83.364787 -337.750591)
			(xy 83.36534 -337.795362) (xy 83.364781 -337.840132) (xy 83.35577 -337.929217) (xy 83.337863 -338.016948)
			(xy 83.311243 -338.102439) (xy 83.29422 -338.14385) (xy 83.290679 -338.153447) (xy 83.290665 -338.173883)
			(xy 83.29422 -338.183474) (xy 83.311248 -338.224884) (xy 83.337884 -338.310371) (xy 83.355791 -338.398103)
			(xy 83.364787 -338.487191) (xy 83.36534 -338.531962) (xy 83.364865 -338.573077) (xy 83.357281 -338.654956)
			(xy 83.342174 -338.735786) (xy 83.319674 -338.814878) (xy 83.289971 -338.891556) (xy 83.253319 -338.965166)
			(xy 83.210032 -339.03508) (xy 83.160479 -339.100701) (xy 83.105082 -339.16147) (xy 83.044313 -339.216869)
			(xy 82.978693 -339.266423) (xy 82.90878 -339.309712) (xy 82.83517 -339.346364) (xy 82.758493 -339.376068)
			(xy 82.679402 -339.398571) (xy 82.598572 -339.413679) (xy 82.516693 -339.421265) (xy 82.475578 -339.421724)
			(xy 82.433968 -339.421253) (xy 82.351111 -339.413475) (xy 82.269342 -339.397998) (xy 82.189374 -339.374957)
			(xy 82.111906 -339.344554) (xy 82.037613 -339.307053) (xy 82.002122 -339.285326) (xy 81.992978 -339.280175)
			(xy 81.972265 -339.276953) (xy 81.951992 -339.282282) (xy 81.943448 -339.288374) (xy 81.909821 -339.314367)
			(xy 81.838426 -339.360491) (xy 81.762954 -339.399592) (xy 81.684096 -339.431311) (xy 81.602571 -339.455361)
			(xy 81.519123 -339.471521) (xy 81.434513 -339.479643) (xy 81.392014 -339.480144) (xy 81.350899 -339.479688)
			(xy 81.269019 -339.472102) (xy 81.188189 -339.456993) (xy 81.109097 -339.434491) (xy 81.032419 -339.404786)
			(xy 80.95881 -339.368133) (xy 80.888896 -339.324845) (xy 80.823275 -339.27529) (xy 80.762506 -339.219892)
			(xy 80.707108 -339.159122) (xy 80.657553 -339.093501) (xy 80.614265 -339.023587) (xy 80.577612 -338.949977)
			(xy 80.547908 -338.873299) (xy 80.525406 -338.794207) (xy 80.510297 -338.713377) (xy 80.502712 -338.631497)
			(xy 80.502252 -338.590382) (xy 80.502826 -338.545613) (xy 80.511834 -338.456528) (xy 80.529735 -338.368797)
			(xy 80.556351 -338.283305) (xy 80.573372 -338.241894) (xy 80.576945 -338.232306) (xy 80.576939 -338.211861)
			(xy 80.573372 -338.20227) (xy 80.556348 -338.160927) (xy 80.529742 -338.075562) (xy 80.511841 -337.987957)
			(xy 80.502825 -337.898997) (xy 80.502252 -337.85429) (xy 80.502252 -337.853274) (xy 80.502506 -337.841844)
			(xy 80.476028 -337.835896) (xy 80.423793 -337.821155) (xy 80.398112 -337.81238) (xy 80.389915 -337.809866)
			(xy 80.372781 -337.809866) (xy 80.364584 -337.81238) (xy 80.329366 -337.824336) (xy 80.257364 -337.842992)
			(xy 80.184043 -337.855502) (xy 80.109928 -337.861777) (xy 80.072738 -337.862164) (xy 80.035549 -337.861761)
			(xy 79.961436 -337.855475) (xy 79.888116 -337.842969) (xy 79.81611 -337.824332) (xy 79.780892 -337.81238)
			(xy 79.772695 -337.809866) (xy 79.755561 -337.809866) (xy 79.747364 -337.81238) (xy 79.712148 -337.824342)
			(xy 79.640145 -337.842996) (xy 79.566824 -337.855505) (xy 79.492708 -337.861778) (xy 79.455518 -337.862164)
			(xy 79.413579 -337.861698) (xy 79.330081 -337.853726) (xy 79.247718 -337.837853) (xy 79.167237 -337.814224)
			(xy 79.089367 -337.783051) (xy 79.014813 -337.744616) (xy 78.94425 -337.69927) (xy 78.878316 -337.64742)
			(xy 78.81761 -337.589539) (xy 78.762681 -337.526148) (xy 78.714027 -337.457824) (xy 78.672087 -337.385183)
			(xy 78.637243 -337.308885) (xy 78.609809 -337.229621) (xy 78.590033 -337.148107) (xy 78.578096 -337.065083)
			(xy 78.574105 -336.9813) (xy 75.005252 -336.9813) (xy 75.00928 -337.024761) (xy 75.009756 -337.065874)
			(xy 75.009201 -337.110644) (xy 75.000188 -337.199729) (xy 74.982281 -337.28746) (xy 74.95566 -337.372951)
			(xy 74.938636 -337.414362) (xy 74.935088 -337.423957) (xy 74.935078 -337.444395) (xy 74.938636 -337.453986)
			(xy 74.955669 -337.495394) (xy 74.982303 -337.580882) (xy 75.000209 -337.668615) (xy 75.009203 -337.757703)
			(xy 75.009756 -337.802474) (xy 75.009201 -337.847244) (xy 75.000188 -337.936329) (xy 74.982281 -338.02406)
			(xy 74.95566 -338.109551) (xy 74.938636 -338.150962) (xy 74.935088 -338.160557) (xy 74.935078 -338.180995)
			(xy 74.938636 -338.190586) (xy 74.955669 -338.231994) (xy 74.982303 -338.317482) (xy 75.000209 -338.405215)
			(xy 75.009203 -338.494303) (xy 75.009756 -338.539074) (xy 75.009277 -338.580189) (xy 75.001692 -338.662067)
			(xy 74.986584 -338.742897) (xy 74.964083 -338.821988) (xy 74.93438 -338.898665) (xy 74.897729 -338.972274)
			(xy 74.854442 -339.042187) (xy 74.804888 -339.107809) (xy 74.749492 -339.168577) (xy 74.688724 -339.223976)
			(xy 74.623104 -339.27353) (xy 74.553192 -339.316819) (xy 74.479583 -339.353472) (xy 74.402907 -339.383177)
			(xy 74.323816 -339.40568) (xy 74.242987 -339.420789) (xy 74.161109 -339.428376) (xy 74.119994 -339.428836)
			(xy 74.078384 -339.428356) (xy 73.995528 -339.420579) (xy 73.913759 -339.405104) (xy 73.833791 -339.382065)
			(xy 73.756322 -339.351663) (xy 73.682029 -339.314164) (xy 73.646538 -339.292438) (xy 73.63743 -339.287211)
			(xy 73.616693 -339.284013) (xy 73.596408 -339.289376) (xy 73.587864 -339.295486) (xy 73.554233 -339.321473)
			(xy 73.482838 -339.367598) (xy 73.407368 -339.406699) (xy 73.32851 -339.438419) (xy 73.246986 -339.46247)
			(xy 73.163538 -339.47863) (xy 73.078929 -339.486754) (xy 73.03643 -339.487256) (xy 72.995315 -339.486773)
			(xy 72.913437 -339.479188) (xy 72.832607 -339.464081) (xy 72.753517 -339.44158) (xy 72.67684 -339.411877)
			(xy 72.60323 -339.375226) (xy 72.533317 -339.33194) (xy 72.467696 -339.282387) (xy 72.406927 -339.22699)
			(xy 72.351529 -339.166223) (xy 72.301974 -339.100603) (xy 72.258685 -339.030691) (xy 72.222032 -338.957082)
			(xy 72.192327 -338.880406) (xy 72.169824 -338.801316) (xy 72.154715 -338.720487) (xy 72.147128 -338.638609)
			(xy 72.146668 -338.597494) (xy 72.147245 -338.552725) (xy 72.156251 -338.46364) (xy 72.174152 -338.375909)
			(xy 72.200767 -338.290417) (xy 72.217788 -338.249006) (xy 72.221359 -338.239417) (xy 72.221356 -338.218972)
			(xy 72.217788 -338.209382) (xy 72.200768 -338.168037) (xy 72.174161 -338.082673) (xy 72.156259 -337.995068)
			(xy 72.147241 -337.906109) (xy 72.146668 -337.861402) (xy 72.146668 -337.860386) (xy 72.146922 -337.848956)
			(xy 72.120444 -337.843006) (xy 72.068209 -337.828266) (xy 72.042528 -337.819492) (xy 72.034331 -337.816978)
			(xy 72.017197 -337.816978) (xy 72.009 -337.819492) (xy 71.973781 -337.831444) (xy 71.901779 -337.850101)
			(xy 71.828459 -337.862612) (xy 71.754344 -337.868888) (xy 71.717154 -337.869276) (xy 71.679965 -337.868873)
			(xy 71.605852 -337.862587) (xy 71.532532 -337.850082) (xy 71.460526 -337.831445) (xy 71.425308 -337.819492)
			(xy 71.417111 -337.816978) (xy 71.399977 -337.816978) (xy 71.39178 -337.819492) (xy 71.356562 -337.83145)
			(xy 71.28456 -337.850105) (xy 71.211239 -337.862615) (xy 71.137124 -337.868889) (xy 71.099934 -337.869276)
			(xy 71.057995 -337.868786) (xy 70.974497 -337.860816) (xy 70.892134 -337.844945) (xy 70.811653 -337.821316)
			(xy 70.733783 -337.790144) (xy 70.659228 -337.751711) (xy 70.588664 -337.706365) (xy 70.522731 -337.654517)
			(xy 70.462025 -337.596636) (xy 70.407095 -337.533246) (xy 70.35844 -337.464922) (xy 70.3165 -337.392282)
			(xy 70.281655 -337.315985) (xy 70.254221 -337.23672) (xy 70.234446 -337.155207) (xy 70.222508 -337.072183)
			(xy 70.218517 -336.9884) (xy 2.509012 -336.9884) (xy 2.509012 -341.9277) (xy 103.538816 -341.9277)
			(xy 103.542807 -341.843921) (xy 103.554743 -341.760902) (xy 103.574517 -341.679392) (xy 103.601948 -341.600131)
			(xy 103.63679 -341.523837) (xy 103.678726 -341.4512) (xy 103.727376 -341.382878) (xy 103.7823 -341.319489)
			(xy 103.843001 -341.261608) (xy 103.908929 -341.20976) (xy 103.979486 -341.164412) (xy 104.054035 -341.125977)
			(xy 104.131899 -341.094802) (xy 104.212375 -341.071169) (xy 104.294732 -341.055293) (xy 104.378225 -341.047317)
			(xy 104.420162 -341.046816) (xy 104.457351 -341.047215) (xy 104.531464 -341.053502) (xy 104.604784 -341.066008)
			(xy 104.67679 -341.084646) (xy 104.712008 -341.0966) (xy 104.720205 -341.099114) (xy 104.737339 -341.099114)
			(xy 104.745536 -341.0966) (xy 104.780752 -341.084638) (xy 104.852755 -341.065983) (xy 104.926076 -341.053475)
			(xy 105.000192 -341.047202) (xy 105.037382 -341.046816) (xy 105.07218 -341.047578) (xy 105.081741 -341.004913)
			(xy 105.108207 -340.921573) (xy 105.125012 -340.881208) (xy 105.128629 -340.871492) (xy 105.128644 -340.850784)
			(xy 105.125012 -340.841076) (xy 105.107898 -340.799819) (xy 105.081109 -340.714608) (xy 105.063074 -340.627124)
			(xy 105.053979 -340.538265) (xy 105.053384 -340.493604) (xy 105.053384 -340.492842) (xy 105.053883 -340.450917)
			(xy 105.061853 -340.367446) (xy 105.077722 -340.285111) (xy 105.101345 -340.204657) (xy 105.132509 -340.126813)
			(xy 105.170932 -340.052283) (xy 105.216265 -339.981744) (xy 105.268098 -339.915833) (xy 105.325961 -339.855147)
			(xy 105.389331 -339.800237) (xy 105.457634 -339.751599) (xy 105.530251 -339.709674) (xy 105.606524 -339.674841)
			(xy 105.685763 -339.647416) (xy 105.767249 -339.627647) (xy 105.850246 -339.615714) (xy 105.934002 -339.611725)
			(xy 106.017758 -339.615714) (xy 106.100755 -339.627647) (xy 106.182241 -339.647416) (xy 106.26148 -339.674841)
			(xy 106.337753 -339.709674) (xy 106.41037 -339.751599) (xy 106.478673 -339.800237) (xy 106.542043 -339.855147)
			(xy 106.599906 -339.915833) (xy 106.651739 -339.981744) (xy 106.697072 -340.052283) (xy 106.735495 -340.126813)
			(xy 106.766659 -340.204657) (xy 106.790282 -340.285111) (xy 106.806151 -340.367446) (xy 106.814121 -340.450917)
			(xy 106.81462 -340.492842) (xy 106.81462 -340.493604) (xy 106.814051 -340.538267) (xy 106.804977 -340.627133)
			(xy 106.786945 -340.714621) (xy 106.760139 -340.799831) (xy 106.742992 -340.841076) (xy 106.739326 -340.850777)
			(xy 106.739342 -340.871499) (xy 106.742992 -340.881208) (xy 106.751628 -340.901528) (xy 106.756582 -340.912278)
			(xy 106.774248 -340.927996) (xy 106.797062 -340.934212) (xy 106.808778 -340.932516) (xy 106.8525 -340.924198)
			(xy 106.941059 -340.915292) (xy 106.985562 -340.914736) (xy 106.98607 -340.914736) (xy 107.027176 -340.915241)
			(xy 107.109038 -340.922823) (xy 107.189852 -340.937924) (xy 107.268928 -340.960416) (xy 107.345591 -340.990108)
			(xy 107.419189 -341.026745) (xy 107.489092 -341.070016) (xy 107.554706 -341.119551) (xy 107.61547 -341.174927)
			(xy 107.670867 -341.235674) (xy 107.720423 -341.301272) (xy 107.763716 -341.371161) (xy 107.800377 -341.444747)
			(xy 107.830093 -341.521401) (xy 107.85261 -341.60047) (xy 107.867738 -341.681278) (xy 107.875346 -341.763138)
			(xy 107.875832 -341.804244) (xy 107.875268 -341.849014) (xy 107.867795 -341.9229) (xy 351.475729 -341.9229)
			(xy 351.479719 -341.839138) (xy 351.491654 -341.756134) (xy 351.511424 -341.674641) (xy 351.538852 -341.595396)
			(xy 351.573688 -341.519117) (xy 351.615617 -341.446494) (xy 351.66426 -341.378187) (xy 351.719176 -341.314813)
			(xy 351.779867 -341.256945) (xy 351.845785 -341.205109) (xy 351.916331 -341.159774) (xy 351.990867 -341.12135)
			(xy 352.068718 -341.090185) (xy 352.149179 -341.066562) (xy 352.231522 -341.050694) (xy 352.314999 -341.042726)
			(xy 352.356928 -341.042244) (xy 352.357944 -341.042244) (xy 352.395001 -341.04264) (xy 352.46885 -341.048907)
			(xy 352.541913 -341.061352) (xy 352.613673 -341.079887) (xy 352.648774 -341.091774) (xy 352.656971 -341.094288)
			(xy 352.674105 -341.094288) (xy 352.682302 -341.091774) (xy 352.717522 -341.079841) (xy 352.789531 -341.06125)
			(xy 352.862852 -341.048806) (xy 352.936963 -341.042598) (xy 352.974148 -341.042244) (xy 352.988626 -341.042244)
			(xy 352.999994 -341.041829) (xy 353.020668 -341.032414) (xy 353.035248 -341.014994) (xy 353.038664 -341.004144)
			(xy 353.047281 -340.972176) (xy 353.068638 -340.909499) (xy 353.081336 -340.878922) (xy 353.084895 -340.86933)
			(xy 353.084899 -340.848889) (xy 353.081336 -340.839298) (xy 353.064328 -340.797915) (xy 353.037705 -340.71249)
			(xy 353.019796 -340.624824) (xy 353.010783 -340.535802) (xy 353.010216 -340.491064) (xy 353.010216 -340.49081)
			(xy 353.01072 -340.448462) (xy 353.018771 -340.364148) (xy 353.0348 -340.280982) (xy 353.058661 -340.199715)
			(xy 353.09014 -340.121085) (xy 353.128951 -340.045804) (xy 353.174741 -339.974552) (xy 353.227097 -339.907976)
			(xy 353.285545 -339.846678) (xy 353.349555 -339.791213) (xy 353.418547 -339.742084) (xy 353.491897 -339.699735)
			(xy 353.56894 -339.664551) (xy 353.648979 -339.636849) (xy 353.731288 -339.616881) (xy 353.815123 -339.604828)
			(xy 353.899724 -339.600798) (xy 353.984325 -339.604828) (xy 354.06816 -339.616881) (xy 354.150469 -339.636849)
			(xy 354.230508 -339.664551) (xy 354.307551 -339.699735) (xy 354.380901 -339.742084) (xy 354.449893 -339.791213)
			(xy 354.513903 -339.846678) (xy 354.572351 -339.907976) (xy 354.624707 -339.974552) (xy 354.670497 -340.045804)
			(xy 354.709308 -340.121085) (xy 354.740787 -340.199715) (xy 354.764648 -340.280982) (xy 354.780677 -340.364148)
			(xy 354.788728 -340.448462) (xy 354.789232 -340.49081) (xy 354.789232 -340.491064) (xy 354.788666 -340.535802)
			(xy 354.779649 -340.624824) (xy 354.761744 -340.712491) (xy 354.73513 -340.797919) (xy 354.718112 -340.839298)
			(xy 354.714539 -340.848887) (xy 354.714543 -340.869332) (xy 354.718112 -340.878922) (xy 354.735129 -340.920302)
			(xy 354.761749 -341.005728) (xy 354.779655 -341.093395) (xy 354.788666 -341.182417) (xy 354.789232 -341.227156)
			(xy 354.789232 -341.228172) (xy 354.789643 -341.238195) (xy 354.79731 -341.256718) (xy 354.811486 -341.270892)
			(xy 354.830009 -341.278557) (xy 354.840032 -341.278972) (xy 354.840286 -341.278972) (xy 354.84794 -341.278603)
			(xy 354.862532 -341.273956) (xy 354.868988 -341.269828) (xy 354.869242 -341.269828) (xy 354.906515 -341.244617)
			(xy 354.985224 -341.200991) (xy 355.067937 -341.165538) (xy 355.153807 -341.13862) (xy 355.241957 -341.120513)
			(xy 355.331485 -341.111402) (xy 355.37648 -341.110824) (xy 355.376988 -341.110824) (xy 355.418092 -341.111264)
			(xy 355.499949 -341.118848) (xy 355.580757 -341.133953) (xy 355.659827 -341.15645) (xy 355.736484 -341.186147)
			(xy 355.810073 -341.22279) (xy 355.879967 -341.266067) (xy 355.94557 -341.315609) (xy 356.006322 -341.370992)
			(xy 356.061704 -341.431745) (xy 356.111244 -341.497349) (xy 356.15452 -341.567245) (xy 356.191162 -341.640835)
			(xy 356.220857 -341.717492) (xy 356.243352 -341.796562) (xy 356.258455 -341.877371) (xy 356.266037 -341.959228)
			(xy 356.266496 -342.000332) (xy 356.266496 -342.000586) (xy 356.26594 -342.045325) (xy 356.256921 -342.134347)
			(xy 356.239013 -342.222014) (xy 356.212396 -342.307441) (xy 356.195376 -342.34882) (xy 356.191792 -342.358405)
			(xy 356.191804 -342.378853) (xy 356.195376 -342.388444) (xy 356.212409 -342.429852) (xy 356.239041 -342.515341)
			(xy 356.256946 -342.603073) (xy 356.265942 -342.692161) (xy 356.266496 -342.736932) (xy 356.265952 -342.781703)
			(xy 356.256945 -342.87079) (xy 356.239036 -342.958522) (xy 356.212407 -343.044011) (xy 356.195376 -343.08542)
			(xy 356.191792 -343.095005) (xy 356.191804 -343.115453) (xy 356.195376 -343.125044) (xy 356.212398 -343.166422)
			(xy 356.239017 -343.251848) (xy 356.256922 -343.339516) (xy 356.265931 -343.428539) (xy 356.266496 -343.473278)
			(xy 356.266496 -343.473532) (xy 356.266064 -343.514635) (xy 356.258476 -343.596491) (xy 356.243368 -343.677298)
			(xy 356.220868 -343.756366) (xy 356.191169 -343.83302) (xy 356.154525 -343.906608) (xy 356.111246 -343.9765)
			(xy 356.061704 -344.042101) (xy 356.00632 -344.102851) (xy 355.945567 -344.158232) (xy 355.879964 -344.207771)
			(xy 355.810069 -344.251046) (xy 355.73648 -344.287687) (xy 355.659824 -344.317382) (xy 355.580755 -344.339878)
			(xy 355.499948 -344.354982) (xy 355.418091 -344.362566) (xy 355.376988 -344.36304) (xy 355.376226 -344.36304)
			(xy 355.334685 -344.362565) (xy 355.251968 -344.35478) (xy 355.170337 -344.33932) (xy 355.090501 -344.316321)
			(xy 355.013156 -344.285984) (xy 354.938974 -344.248571) (xy 354.903532 -344.226896) (xy 354.894382 -344.221758)
			(xy 354.873674 -344.218535) (xy 354.853403 -344.223857) (xy 354.844858 -344.229944) (xy 354.811228 -344.255891)
			(xy 354.73985 -344.301947) (xy 354.664408 -344.340991) (xy 354.585588 -344.372667) (xy 354.504107 -344.396686)
			(xy 354.420709 -344.412831) (xy 354.336151 -344.420953) (xy 354.293678 -344.42146) (xy 354.293424 -344.42146)
			(xy 354.25232 -344.421025) (xy 354.170462 -344.413441) (xy 354.089653 -344.398337) (xy 354.010583 -344.375841)
			(xy 353.933926 -344.346144) (xy 353.860336 -344.309501) (xy 353.790441 -344.266224) (xy 353.724837 -344.216682)
			(xy 353.664085 -344.161298) (xy 353.608703 -344.100544) (xy 353.559163 -344.03494) (xy 353.515887 -343.965043)
			(xy 353.479246 -343.891453) (xy 353.449552 -343.814794) (xy 353.427057 -343.735723) (xy 353.411955 -343.654914)
			(xy 353.404374 -343.573056) (xy 353.403916 -343.531952) (xy 353.403916 -343.531698) (xy 353.4045 -343.48696)
			(xy 353.413511 -343.397939) (xy 353.431411 -343.310272) (xy 353.45802 -343.224844) (xy 353.475036 -343.183464)
			(xy 353.478628 -343.173881) (xy 353.47861 -343.153431) (xy 353.475036 -343.14384) (xy 353.457998 -343.102434)
			(xy 353.431368 -343.016945) (xy 353.413464 -342.929211) (xy 353.404469 -342.840123) (xy 353.403916 -342.795352)
			(xy 353.403916 -342.783414) (xy 353.377438 -342.777466) (xy 353.325203 -342.762725) (xy 353.299522 -342.75395)
			(xy 353.291325 -342.751436) (xy 353.274191 -342.751436) (xy 353.265994 -342.75395) (xy 353.230774 -342.765885)
			(xy 353.158765 -342.784475) (xy 353.085444 -342.796919) (xy 353.011333 -342.803127) (xy 352.974148 -342.80348)
			(xy 352.936964 -342.803098) (xy 352.862857 -342.79688) (xy 352.789537 -342.784441) (xy 352.717525 -342.76587)
			(xy 352.682302 -342.75395) (xy 352.674105 -342.751436) (xy 352.656971 -342.751436) (xy 352.648774 -342.75395)
			(xy 352.613678 -342.765853) (xy 352.541919 -342.784399) (xy 352.468854 -342.796841) (xy 352.395002 -342.80309)
			(xy 352.357944 -342.80348) (xy 352.356928 -342.80348) (xy 352.314999 -342.803074) (xy 352.231522 -342.795106)
			(xy 352.149179 -342.779238) (xy 352.068718 -342.755615) (xy 351.990867 -342.72445) (xy 351.916331 -342.686026)
			(xy 351.845785 -342.640691) (xy 351.779867 -342.588855) (xy 351.719176 -342.530987) (xy 351.66426 -342.467613)
			(xy 351.615617 -342.399306) (xy 351.573688 -342.326683) (xy 351.538852 -342.250404) (xy 351.511424 -342.171159)
			(xy 351.491654 -342.089666) (xy 351.479719 -342.006662) (xy 351.475729 -341.9229) (xy 107.867795 -341.9229)
			(xy 107.866258 -341.938099) (xy 107.848353 -342.02583) (xy 107.821735 -342.111321) (xy 107.804712 -342.152732)
			(xy 107.80112 -342.162315) (xy 107.801136 -342.182765) (xy 107.804712 -342.192356) (xy 107.821734 -342.233768)
			(xy 107.848372 -342.319255) (xy 107.86628 -342.406986) (xy 107.875278 -342.496074) (xy 107.875832 -342.540844)
			(xy 107.875405 -342.579435) (xy 107.868704 -342.656327) (xy 107.855365 -342.732349) (xy 107.835489 -342.806929)
			(xy 107.822746 -342.843358) (xy 107.81982 -342.852801) (xy 107.820595 -342.872535) (xy 107.82427 -342.881712)
			(xy 107.843314 -342.925129) (xy 107.873091 -343.015145) (xy 107.893121 -343.107819) (xy 107.903177 -343.202097)
			(xy 107.903772 -343.249504) (xy 107.903199 -343.294273) (xy 107.894192 -343.383358) (xy 107.87629 -343.471089)
			(xy 107.849674 -343.556581) (xy 107.832652 -343.597992) (xy 107.829086 -343.607582) (xy 107.829087 -343.628025)
			(xy 107.832652 -343.637616) (xy 107.849695 -343.67902) (xy 107.876327 -343.76451) (xy 107.894229 -343.852244)
			(xy 107.903221 -343.941333) (xy 107.903772 -343.986104) (xy 107.903338 -344.0272) (xy 107.895755 -344.109042)
			(xy 107.880654 -344.189835) (xy 107.858164 -344.268891) (xy 107.828477 -344.345534) (xy 107.791846 -344.419112)
			(xy 107.748583 -344.488997) (xy 107.699057 -344.554593) (xy 107.643692 -344.61534) (xy 107.582958 -344.670721)
			(xy 107.517374 -344.720262) (xy 107.447499 -344.763541) (xy 107.37393 -344.80019) (xy 107.297294 -344.829896)
			(xy 107.218244 -344.852405) (xy 107.137454 -344.867525) (xy 107.055614 -344.875128) (xy 107.014518 -344.875612)
			(xy 107.01401 -344.875612) (xy 106.971454 -344.875048) (xy 106.886731 -344.866913) (xy 106.803172 -344.850725)
			(xy 106.72154 -344.826633) (xy 106.642582 -344.794856) (xy 106.567018 -344.755685) (xy 106.49554 -344.709478)
			(xy 106.428801 -344.656658) (xy 106.36741 -344.597706) (xy 106.311928 -344.533162) (xy 106.262863 -344.463615)
			(xy 106.220663 -344.389701) (xy 106.202734 -344.351102) (xy 106.197143 -344.340314) (xy 106.178175 -344.325188)
			(xy 106.166412 -344.322146) (xy 106.123815 -344.31302) (xy 106.04054 -344.287419) (xy 105.960165 -344.253801)
			(xy 105.883461 -344.212489) (xy 105.811162 -344.163878) (xy 105.74396 -344.108434) (xy 105.682498 -344.046687)
			(xy 105.627365 -343.979229) (xy 105.579089 -343.906705) (xy 105.538133 -343.829811) (xy 105.504888 -343.749281)
			(xy 105.479672 -343.665888) (xy 105.462727 -343.58043) (xy 105.454216 -343.493725) (xy 105.453688 -343.450164)
			(xy 105.454253 -343.405394) (xy 105.463263 -343.316309) (xy 105.481167 -343.228578) (xy 105.507785 -343.143087)
			(xy 105.524808 -343.101676) (xy 105.528395 -343.092092) (xy 105.528382 -343.071643) (xy 105.524808 -343.062052)
			(xy 105.508891 -343.02338) (xy 105.483531 -342.943684) (xy 105.46577 -342.861957) (xy 105.460292 -342.820498)
			(xy 105.458558 -342.81058) (xy 105.448632 -342.793088) (xy 105.43277 -342.780723) (xy 105.423208 -342.777572)
			(xy 105.40795 -342.773353) (xy 105.377717 -342.763951) (xy 105.362756 -342.758776) (xy 105.354559 -342.756262)
			(xy 105.337425 -342.756262) (xy 105.329228 -342.758776) (xy 105.294015 -342.770747) (xy 105.222011 -342.789399)
			(xy 105.148689 -342.801905) (xy 105.074572 -342.808175) (xy 105.037382 -342.80856) (xy 105.000192 -342.808173)
			(xy 104.926079 -342.801882) (xy 104.85276 -342.789372) (xy 104.780754 -342.770731) (xy 104.745536 -342.758776)
			(xy 104.737339 -342.756262) (xy 104.720205 -342.756262) (xy 104.712008 -342.758776) (xy 104.676797 -342.770753)
			(xy 104.604792 -342.789403) (xy 104.531469 -342.801908) (xy 104.457353 -342.808176) (xy 104.420162 -342.80856)
			(xy 104.378225 -342.808083) (xy 104.294732 -342.800107) (xy 104.212375 -342.784231) (xy 104.131899 -342.760598)
			(xy 104.054035 -342.729423) (xy 103.979486 -342.690988) (xy 103.908929 -342.64564) (xy 103.843001 -342.593792)
			(xy 103.7823 -342.535911) (xy 103.727376 -342.472522) (xy 103.678726 -342.4042) (xy 103.63679 -342.331563)
			(xy 103.601948 -342.255269) (xy 103.574517 -342.176008) (xy 103.554743 -342.094498) (xy 103.542807 -342.011479)
			(xy 103.538816 -341.9277) (xy 2.509012 -341.9277) (xy 2.509012 -345.238324) (xy 88.42502 -345.238324)
			(xy 88.42502 -345.237562) (xy 88.425476 -345.196455) (xy 88.433064 -345.114592) (xy 88.448171 -345.033778)
			(xy 88.470668 -344.954703) (xy 88.500364 -344.87804) (xy 88.537005 -344.804443) (xy 88.58028 -344.73454)
			(xy 88.629818 -344.668927) (xy 88.685198 -344.608163) (xy 88.745947 -344.552768) (xy 88.811546 -344.503212)
			(xy 88.881438 -344.459919) (xy 88.955025 -344.423259) (xy 89.031681 -344.393542) (xy 89.110751 -344.371024)
			(xy 89.19156 -344.355896) (xy 89.273421 -344.348287) (xy 89.314528 -344.3478) (xy 89.358923 -344.348358)
			(xy 89.447268 -344.357247) (xy 89.534288 -344.374894) (xy 89.619117 -344.401123) (xy 89.660222 -344.417904)
			(xy 89.668919 -344.421068) (xy 89.687398 -344.421734) (xy 89.69629 -344.419174) (xy 89.742575 -344.404089)
			(xy 89.837607 -344.382956) (xy 89.934379 -344.372329) (xy 89.983056 -344.371676) (xy 90.021372 -344.372058)
			(xy 90.097725 -344.378586) (xy 90.173232 -344.391667) (xy 90.247331 -344.411203) (xy 90.283538 -344.423746)
			(xy 90.291854 -344.426332) (xy 90.309258 -344.426332) (xy 90.317574 -344.423746) (xy 90.353782 -344.41121)
			(xy 90.427885 -344.391692) (xy 90.503391 -344.378612) (xy 90.579741 -344.372068) (xy 90.618056 -344.371676)
			(xy 90.664451 -344.372276) (xy 90.756739 -344.381916) (xy 90.847523 -344.401107) (xy 90.935817 -344.429641)
			(xy 90.978482 -344.447876) (xy 90.988424 -344.451682) (xy 91.009688 -344.451682) (xy 91.01963 -344.447876)
			(xy 91.062298 -344.429645) (xy 91.150588 -344.401097) (xy 91.241371 -344.381901) (xy 91.33366 -344.372263)
			(xy 91.380056 -344.371676) (xy 91.418372 -344.372058) (xy 91.494725 -344.378586) (xy 91.570232 -344.391667)
			(xy 91.644331 -344.411203) (xy 91.680538 -344.423746) (xy 91.688854 -344.426332) (xy 91.706258 -344.426332)
			(xy 91.714574 -344.423746) (xy 91.750782 -344.41121) (xy 91.824885 -344.391692) (xy 91.900391 -344.378612)
			(xy 91.976741 -344.372068) (xy 92.015056 -344.371676) (xy 92.053372 -344.372058) (xy 92.129725 -344.378586)
			(xy 92.205232 -344.391667) (xy 92.279331 -344.411203) (xy 92.315538 -344.423746) (xy 92.323854 -344.426332)
			(xy 92.341258 -344.426332) (xy 92.349574 -344.423746) (xy 92.385691 -344.411238) (xy 92.459606 -344.391753)
			(xy 92.534918 -344.378674) (xy 92.611074 -344.372097) (xy 92.649294 -344.371676) (xy 92.650056 -344.371676)
			(xy 92.691158 -344.372194) (xy 92.773012 -344.379775) (xy 92.853817 -344.394876) (xy 92.932883 -344.417369)
			(xy 93.009537 -344.447061) (xy 93.083125 -344.4837) (xy 93.153018 -344.526972) (xy 93.21862 -344.576508)
			(xy 93.279371 -344.631887) (xy 93.334753 -344.692634) (xy 93.384294 -344.758233) (xy 93.427571 -344.828123)
			(xy 93.464215 -344.901708) (xy 93.493912 -344.97836) (xy 93.51641 -345.057425) (xy 93.531517 -345.138229)
			(xy 93.539103 -345.220082) (xy 93.539564 -345.261184) (xy 93.539564 -345.261692) (xy 93.539139 -345.302203)
			(xy 93.531771 -345.38289) (xy 93.517086 -345.462571) (xy 93.495207 -345.540583) (xy 93.466315 -345.616279)
			(xy 93.448886 -345.652852) (xy 93.444973 -345.661871) (xy 93.443532 -345.68146) (xy 93.446092 -345.690952)
			(xy 93.460285 -345.736019) (xy 93.480192 -345.828387) (xy 93.490186 -345.922345) (xy 93.490796 -345.96959)
			(xy 93.490238 -346.015229) (xy 93.480936 -346.106032) (xy 93.462388 -346.195406) (xy 93.44914 -346.239084)
			(xy 93.446696 -346.248096) (xy 93.447735 -346.266724) (xy 93.451172 -346.275406) (xy 93.469867 -346.318487)
			(xy 93.49915 -346.407722) (xy 93.518862 -346.499547) (xy 93.527728 -346.583) (xy 200.85558 -346.583)
			(xy 200.856207 -346.536598) (xy 200.865897 -346.444301) (xy 200.88515 -346.353515) (xy 200.913758 -346.26523)
			(xy 200.932034 -346.222574) (xy 200.935843 -346.212632) (xy 200.935843 -346.191368) (xy 200.932034 -346.181426)
			(xy 200.913772 -346.138765) (xy 200.885179 -346.050477) (xy 200.865922 -345.959694) (xy 200.856209 -345.867401)
			(xy 200.85558 -345.821) (xy 200.856064 -345.779859) (xy 200.863695 -345.69793) (xy 200.878855 -345.617056)
			(xy 200.901414 -345.537926) (xy 200.931179 -345.461215) (xy 200.967897 -345.38758) (xy 200.989184 -345.35237)
			(xy 200.993752 -345.344157) (xy 200.997195 -345.3257) (xy 200.993752 -345.307243) (xy 200.989184 -345.29903)
			(xy 200.967885 -345.263826) (xy 200.931155 -345.190194) (xy 200.901383 -345.113484) (xy 200.878824 -345.034352)
			(xy 200.86367 -344.953474) (xy 200.856051 -344.871542) (xy 200.85558 -344.8304) (xy 200.856207 -344.783998)
			(xy 200.865897 -344.691701) (xy 200.88515 -344.600915) (xy 200.913758 -344.51263) (xy 200.932034 -344.469974)
			(xy 200.935843 -344.460032) (xy 200.935843 -344.438768) (xy 200.932034 -344.428826) (xy 200.913772 -344.386165)
			(xy 200.885179 -344.297877) (xy 200.865922 -344.207094) (xy 200.856209 -344.114801) (xy 200.85558 -344.0684)
			(xy 200.856084 -344.026039) (xy 200.864137 -343.941702) (xy 200.880171 -343.858512) (xy 200.904039 -343.777222)
			(xy 200.935527 -343.69857) (xy 200.974349 -343.623267) (xy 201.020152 -343.551995) (xy 201.072523 -343.485399)
			(xy 201.130988 -343.424084) (xy 201.195016 -343.368603) (xy 201.264028 -343.31946) (xy 201.337398 -343.2771)
			(xy 201.414463 -343.241905) (xy 201.494525 -343.214196) (xy 201.576858 -343.194222) (xy 201.660717 -343.182165)
			(xy 201.745342 -343.178134) (xy 201.829967 -343.182165) (xy 201.913826 -343.194222) (xy 201.996159 -343.214196)
			(xy 202.076221 -343.241905) (xy 202.153286 -343.2771) (xy 202.226656 -343.31946) (xy 202.295668 -343.368603)
			(xy 202.359696 -343.424084) (xy 202.418161 -343.485399) (xy 202.470532 -343.551995) (xy 202.516335 -343.623267)
			(xy 202.555157 -343.69857) (xy 202.586645 -343.777222) (xy 202.610513 -343.858512) (xy 202.626547 -343.941702)
			(xy 202.6346 -344.026039) (xy 202.635104 -344.0684) (xy 202.634479 -344.114802) (xy 202.624789 -344.2071)
			(xy 202.605534 -344.297885) (xy 202.576926 -344.38617) (xy 202.55865 -344.428826) (xy 202.554842 -344.438768)
			(xy 202.554842 -344.460032) (xy 202.55865 -344.469974) (xy 202.576911 -344.512635) (xy 202.605505 -344.600923)
			(xy 202.624762 -344.691706) (xy 202.634475 -344.783999) (xy 202.635104 -344.8304) (xy 202.634622 -344.871541)
			(xy 202.626991 -344.95347) (xy 202.611831 -345.034344) (xy 202.589272 -345.113474) (xy 202.559506 -345.190185)
			(xy 202.522787 -345.263821) (xy 202.5015 -345.29903) (xy 202.496933 -345.307243) (xy 202.493491 -345.3257)
			(xy 202.496933 -345.344157) (xy 202.5015 -345.35237) (xy 202.522797 -345.387575) (xy 202.559528 -345.461207)
			(xy 202.5893 -345.537917) (xy 202.61186 -345.617049) (xy 202.627014 -345.697926) (xy 202.634633 -345.779858)
			(xy 202.635104 -345.821) (xy 202.634479 -345.867402) (xy 202.624789 -345.9597) (xy 202.605534 -346.050485)
			(xy 202.576926 -346.13877) (xy 202.55865 -346.181426) (xy 202.554842 -346.191368) (xy 202.554842 -346.212632)
			(xy 202.55865 -346.222574) (xy 202.576911 -346.265235) (xy 202.605505 -346.353523) (xy 202.624762 -346.444306)
			(xy 202.634475 -346.536599) (xy 202.635104 -346.583) (xy 202.6346 -346.625361) (xy 202.626547 -346.709698)
			(xy 202.610513 -346.792888) (xy 202.586645 -346.874178) (xy 202.555157 -346.95283) (xy 202.516335 -347.028133)
			(xy 202.470532 -347.099405) (xy 202.418161 -347.166001) (xy 202.359696 -347.227316) (xy 202.295668 -347.282797)
			(xy 202.226656 -347.33194) (xy 202.153286 -347.3743) (xy 202.076221 -347.409495) (xy 201.996159 -347.437204)
			(xy 201.913826 -347.457178) (xy 201.829967 -347.469235) (xy 201.745342 -347.473267) (xy 201.660717 -347.469235)
			(xy 201.576858 -347.457178) (xy 201.494525 -347.437204) (xy 201.414463 -347.409495) (xy 201.337398 -347.3743)
			(xy 201.264028 -347.33194) (xy 201.195016 -347.282797) (xy 201.130988 -347.227316) (xy 201.072523 -347.166001)
			(xy 201.020152 -347.099405) (xy 200.974349 -347.028133) (xy 200.935527 -346.95283) (xy 200.904039 -346.874178)
			(xy 200.880171 -346.792888) (xy 200.864137 -346.709698) (xy 200.856084 -346.625361) (xy 200.85558 -346.583)
			(xy 93.527728 -346.583) (xy 93.528784 -346.592938) (xy 93.529404 -346.639896) (xy 93.528944 -346.681007)
			(xy 93.521356 -346.762877) (xy 93.506246 -346.843698) (xy 93.483741 -346.92278) (xy 93.454034 -346.999447)
			(xy 93.417379 -347.073045) (xy 93.374088 -347.142947) (xy 93.324531 -347.208555) (xy 93.269131 -347.26931)
			(xy 93.20836 -347.324693) (xy 93.142737 -347.374232) (xy 93.072823 -347.417503) (xy 92.999214 -347.454137)
			(xy 92.922539 -347.483822) (xy 92.843451 -347.506304) (xy 92.762626 -347.521391) (xy 92.680753 -347.528955)
			(xy 92.639642 -347.529404) (xy 92.601326 -347.529024) (xy 92.524973 -347.522495) (xy 92.449466 -347.509414)
			(xy 92.375367 -347.489878) (xy 92.33916 -347.477334) (xy 92.330844 -347.474748) (xy 92.31344 -347.474748)
			(xy 92.305124 -347.477334) (xy 92.268906 -347.489842) (xy 92.194807 -347.509368) (xy 92.119304 -347.522455)
			(xy 92.042956 -347.529008) (xy 92.004642 -347.529404) (xy 91.961529 -347.52892) (xy 91.875703 -347.520642)
			(xy 91.791081 -347.504091) (xy 91.70846 -347.479423) (xy 91.668346 -347.463618) (xy 91.658977 -347.460281)
			(xy 91.639107 -347.460281) (xy 91.629738 -347.463618) (xy 91.589623 -347.479419) (xy 91.506999 -347.504075)
			(xy 91.422379 -347.520627) (xy 91.336554 -347.528919) (xy 91.293442 -347.529404) (xy 91.255126 -347.529024)
			(xy 91.178773 -347.522495) (xy 91.103266 -347.509414) (xy 91.029167 -347.489878) (xy 90.99296 -347.477334)
			(xy 90.984644 -347.474748) (xy 90.96724 -347.474748) (xy 90.958924 -347.477334) (xy 90.922706 -347.489842)
			(xy 90.848607 -347.509368) (xy 90.773104 -347.522455) (xy 90.696756 -347.529008) (xy 90.658442 -347.529404)
			(xy 90.620126 -347.529024) (xy 90.543773 -347.522495) (xy 90.468266 -347.509414) (xy 90.394167 -347.489878)
			(xy 90.35796 -347.477334) (xy 90.349644 -347.474748) (xy 90.33224 -347.474748) (xy 90.323924 -347.477334)
			(xy 90.287706 -347.489842) (xy 90.213607 -347.509368) (xy 90.138104 -347.522455) (xy 90.061756 -347.529008)
			(xy 90.023442 -347.529404) (xy 89.985126 -347.529024) (xy 89.908773 -347.522495) (xy 89.833266 -347.509414)
			(xy 89.759167 -347.489878) (xy 89.72296 -347.477334) (xy 89.714644 -347.474748) (xy 89.69724 -347.474748)
			(xy 89.688924 -347.477334) (xy 89.652807 -347.489842) (xy 89.578892 -347.509327) (xy 89.50358 -347.522407)
			(xy 89.427424 -347.528983) (xy 89.389204 -347.529404) (xy 89.388442 -347.529404) (xy 89.347337 -347.528847)
			(xy 89.265478 -347.521267) (xy 89.184667 -347.506168) (xy 89.105593 -347.483678) (xy 89.028932 -347.453989)
			(xy 88.955336 -347.417355) (xy 88.885433 -347.374087) (xy 88.81982 -347.324556) (xy 88.759057 -347.269183)
			(xy 88.70366 -347.20844) (xy 88.654104 -347.142846) (xy 88.61081 -347.07296) (xy 88.574148 -346.999378)
			(xy 88.54443 -346.922728) (xy 88.52191 -346.843663) (xy 88.506779 -346.762857) (xy 88.499168 -346.681001)
			(xy 88.49868 -346.639896) (xy 88.49928 -346.594251) (xy 88.508675 -346.503445) (xy 88.527305 -346.414075)
			(xy 88.54059 -346.370402) (xy 88.543039 -346.361391) (xy 88.541996 -346.342762) (xy 88.538558 -346.33408)
			(xy 88.519895 -346.290993) (xy 88.490688 -346.201748) (xy 88.471043 -346.109924) (xy 88.461176 -346.016541)
			(xy 88.46058 -345.96959) (xy 88.460997 -345.930463) (xy 88.467845 -345.852508) (xy 88.481506 -345.775455)
			(xy 88.501874 -345.699897) (xy 88.514936 -345.663012) (xy 88.517951 -345.653293) (xy 88.516917 -345.632991)
			(xy 88.512904 -345.623642) (xy 88.496039 -345.587523) (xy 88.46806 -345.512874) (xy 88.44687 -345.436021)
			(xy 88.432638 -345.357582) (xy 88.425479 -345.278184) (xy 88.42502 -345.238324) (xy 2.509012 -345.238324)
			(xy 2.509012 -348.70949) (xy 28.410141 -348.70949) (xy 28.414132 -348.625708) (xy 28.426069 -348.542686)
			(xy 28.445844 -348.461173) (xy 28.473277 -348.38191) (xy 28.508121 -348.305613) (xy 28.550059 -348.232974)
			(xy 28.598712 -348.16465) (xy 28.65364 -348.101261) (xy 28.714345 -348.043379) (xy 28.780276 -347.99153)
			(xy 28.850838 -347.946183) (xy 28.92539 -347.907749) (xy 29.003259 -347.876576) (xy 29.083738 -347.852945)
			(xy 29.166099 -347.837072) (xy 29.249596 -347.829099) (xy 29.291534 -347.828616) (xy 29.328723 -347.829023)
			(xy 29.402836 -347.835307) (xy 29.476156 -347.847812) (xy 29.548162 -347.866448) (xy 29.58338 -347.8784)
			(xy 29.591577 -347.880914) (xy 29.608711 -347.880914) (xy 29.616908 -347.8784) (xy 29.652035 -347.866473)
			(xy 29.723849 -347.847849) (xy 29.796976 -347.835339) (xy 29.870898 -347.829031) (xy 29.907992 -347.828616)
			(xy 29.909516 -347.828616) (xy 29.916374 -347.82887) (xy 29.922431 -347.792721) (xy 29.939716 -347.721486)
			(xy 29.962803 -347.651915) (xy 29.976826 -347.61805) (xy 29.980289 -347.608427) (xy 29.980173 -347.587996)
			(xy 29.976572 -347.578426) (xy 29.959544 -347.537016) (xy 29.932908 -347.451529) (xy 29.915001 -347.363797)
			(xy 29.906005 -347.274709) (xy 29.905452 -347.229938) (xy 29.905933 -347.189355) (xy 29.913331 -347.108527)
			(xy 29.928059 -347.028709) (xy 29.949995 -346.950564) (xy 29.978957 -346.874741) (xy 30.014703 -346.801871)
			(xy 30.056938 -346.732559) (xy 30.10531 -346.667382) (xy 30.159416 -346.606881) (xy 30.218807 -346.551559)
			(xy 30.28299 -346.501876) (xy 30.351431 -346.458245) (xy 30.38729 -346.439236) (xy 30.395816 -346.434265)
			(xy 30.408633 -346.419285) (xy 30.414885 -346.400588) (xy 30.414722 -346.390722) (xy 30.41396 -346.365322)
			(xy 30.414481 -346.337437) (xy 30.422793 -346.28229) (xy 30.439231 -346.228998) (xy 30.463429 -346.178752)
			(xy 30.494845 -346.132673) (xy 30.532778 -346.091791) (xy 30.57638 -346.057019) (xy 30.624678 -346.029134)
			(xy 30.676593 -346.008759) (xy 30.730964 -345.996349) (xy 30.786578 -345.992182) (xy 30.842192 -345.996349)
			(xy 30.896563 -346.008759) (xy 30.948478 -346.029134) (xy 30.996776 -346.057019) (xy 31.040378 -346.091791)
			(xy 31.078311 -346.132673) (xy 31.109727 -346.178752) (xy 31.133925 -346.228998) (xy 31.150363 -346.28229)
			(xy 31.158675 -346.337437) (xy 31.159196 -346.365322) (xy 31.158688 -346.383356) (xy 31.15866 -346.393249)
			(xy 31.165282 -346.411875) (xy 31.178455 -346.426614) (xy 31.187136 -346.431362) (xy 31.224041 -346.449965)
			(xy 31.294555 -346.49308) (xy 31.360766 -346.542551) (xy 31.4221 -346.597952) (xy 31.47803 -346.658805)
			(xy 31.528073 -346.724585) (xy 31.571797 -346.794724) (xy 31.608825 -346.868616) (xy 31.638837 -346.945626)
			(xy 31.661575 -347.025088) (xy 31.676842 -347.106317) (xy 31.684507 -347.188612) (xy 31.684976 -347.229938)
			(xy 31.684414 -347.274708) (xy 31.675404 -347.363793) (xy 31.657499 -347.451524) (xy 31.630879 -347.537015)
			(xy 31.613856 -347.578426) (xy 31.61027 -347.58801) (xy 31.610284 -347.608459) (xy 31.613856 -347.61805)
			(xy 31.630031 -347.657368) (xy 31.655701 -347.738424) (xy 31.673532 -347.821557) (xy 31.68336 -347.906011)
			(xy 31.684722 -347.948504) (xy 31.684976 -347.96222) (xy 31.6992 -347.985588) (xy 31.788862 -348.034102)
			(xy 31.796927 -348.038113) (xy 31.814734 -348.040741) (xy 31.832352 -348.037052) (xy 31.84017 -348.032578)
			(xy 31.875522 -348.010993) (xy 31.949529 -347.973778) (xy 32.026677 -347.943609) (xy 32.106297 -347.920748)
			(xy 32.187699 -347.905393) (xy 32.270176 -347.897677) (xy 32.311594 -347.897196) (xy 32.352707 -347.897719)
			(xy 32.434582 -347.905305) (xy 32.515408 -347.920413) (xy 32.594495 -347.942914) (xy 32.671169 -347.972616)
			(xy 32.744775 -348.009266) (xy 32.814686 -348.05255) (xy 32.880304 -348.102101) (xy 32.941071 -348.157495)
			(xy 32.996468 -348.218259) (xy 33.046022 -348.283875) (xy 33.089311 -348.353783) (xy 33.125965 -348.427387)
			(xy 33.155671 -348.504059) (xy 33.178176 -348.583145) (xy 33.193289 -348.66397) (xy 33.197509 -348.70949)
			(xy 36.690541 -348.70949) (xy 36.694532 -348.625708) (xy 36.706469 -348.542686) (xy 36.726244 -348.461173)
			(xy 36.753677 -348.38191) (xy 36.788521 -348.305613) (xy 36.830459 -348.232974) (xy 36.879112 -348.16465)
			(xy 36.93404 -348.101261) (xy 36.994745 -348.043379) (xy 37.060676 -347.99153) (xy 37.131238 -347.946183)
			(xy 37.20579 -347.907749) (xy 37.283659 -347.876576) (xy 37.364138 -347.852945) (xy 37.446499 -347.837072)
			(xy 37.529996 -347.829099) (xy 37.571934 -347.828616) (xy 37.609123 -347.829023) (xy 37.683236 -347.835307)
			(xy 37.756556 -347.847812) (xy 37.828562 -347.866448) (xy 37.86378 -347.8784) (xy 37.871977 -347.880914)
			(xy 37.889111 -347.880914) (xy 37.897308 -347.8784) (xy 37.93549 -347.865472) (xy 38.013674 -347.845816)
			(xy 38.093328 -347.833391) (xy 38.133528 -347.830394) (xy 38.144516 -347.829167) (xy 38.163935 -347.818636)
			(xy 38.177169 -347.800949) (xy 38.18001 -347.790262) (xy 38.189419 -347.748079) (xy 38.215379 -347.665637)
			(xy 38.231826 -347.62567) (xy 38.235335 -347.61606) (xy 38.235189 -347.595617) (xy 38.231572 -347.586046)
			(xy 38.21455 -347.544634) (xy 38.187912 -347.459147) (xy 38.170004 -347.371416) (xy 38.161006 -347.282328)
			(xy 38.160452 -347.237558) (xy 38.160956 -347.195197) (xy 38.169009 -347.11086) (xy 38.185043 -347.02767)
			(xy 38.208911 -346.94638) (xy 38.240399 -346.867728) (xy 38.279221 -346.792425) (xy 38.325024 -346.721153)
			(xy 38.377395 -346.654557) (xy 38.43586 -346.593242) (xy 38.499888 -346.537761) (xy 38.5689 -346.488618)
			(xy 38.64227 -346.446258) (xy 38.719335 -346.411063) (xy 38.799397 -346.383354) (xy 38.88173 -346.36338)
			(xy 38.965589 -346.351323) (xy 39.050214 -346.347292) (xy 39.134839 -346.351323) (xy 39.218698 -346.36338)
			(xy 39.301031 -346.383354) (xy 39.381093 -346.411063) (xy 39.458158 -346.446258) (xy 39.531528 -346.488618)
			(xy 39.60054 -346.537761) (xy 39.664568 -346.593242) (xy 39.723033 -346.654557) (xy 39.775404 -346.721153)
			(xy 39.821207 -346.792425) (xy 39.860029 -346.867728) (xy 39.891517 -346.94638) (xy 39.915385 -347.02767)
			(xy 39.931419 -347.11086) (xy 39.939472 -347.195197) (xy 39.939976 -347.237558) (xy 39.939421 -347.282328)
			(xy 39.930409 -347.371413) (xy 39.912502 -347.459144) (xy 39.88588 -347.544635) (xy 39.868856 -347.586046)
			(xy 39.865251 -347.595621) (xy 39.865104 -347.616057) (xy 39.868602 -347.62567) (xy 39.88516 -347.665899)
			(xy 39.911278 -347.748887) (xy 39.929176 -347.834027) (xy 39.938683 -347.920507) (xy 39.939722 -347.963998)
			(xy 39.939722 -347.964252) (xy 39.94031 -347.973302) (xy 39.94696 -347.990157) (xy 39.959055 -348.003648)
			(xy 39.9669 -348.008194) (xy 40.058086 -348.056454) (xy 40.086026 -348.05493) (xy 40.09771 -348.04731)
			(xy 40.134305 -348.023444) (xy 40.211348 -347.98223) (xy 40.292061 -347.948768) (xy 40.375665 -347.923381)
			(xy 40.461356 -347.906311) (xy 40.548307 -347.897725) (xy 40.591994 -347.897196) (xy 40.633107 -347.897719)
			(xy 40.714982 -347.905305) (xy 40.795808 -347.920413) (xy 40.874895 -347.942914) (xy 40.951569 -347.972616)
			(xy 41.025175 -348.009266) (xy 41.095086 -348.05255) (xy 41.160704 -348.102101) (xy 41.221471 -348.157495)
			(xy 41.276868 -348.218259) (xy 41.326422 -348.283875) (xy 41.369711 -348.353783) (xy 41.406365 -348.427387)
			(xy 41.436071 -348.504059) (xy 41.458576 -348.583145) (xy 41.473689 -348.66397) (xy 41.47791 -348.7095)
			(xy 44.996301 -348.7095) (xy 45.000292 -348.625716) (xy 45.01223 -348.54269) (xy 45.032006 -348.461175)
			(xy 45.05944 -348.381909) (xy 45.094286 -348.30561) (xy 45.136227 -348.232969) (xy 45.184883 -348.164644)
			(xy 45.239813 -348.101253) (xy 45.30052 -348.043371) (xy 45.366455 -347.991522) (xy 45.43702 -347.946175)
			(xy 45.511576 -347.907741) (xy 45.589448 -347.876568) (xy 45.66993 -347.852939) (xy 45.752294 -347.837068)
			(xy 45.835794 -347.829098) (xy 45.877734 -347.828616) (xy 45.914923 -347.829023) (xy 45.989036 -347.835307)
			(xy 46.062356 -347.847812) (xy 46.134362 -347.866448) (xy 46.16958 -347.8784) (xy 46.177777 -347.880914)
			(xy 46.194911 -347.880914) (xy 46.203108 -347.8784) (xy 46.238327 -347.866445) (xy 46.310329 -347.847789)
			(xy 46.383649 -347.835279) (xy 46.457764 -347.829003) (xy 46.494954 -347.828616) (xy 46.496732 -347.82887)
			(xy 46.506097 -347.78788) (xy 46.53154 -347.707736) (xy 46.547532 -347.66885) (xy 46.551076 -347.659253)
			(xy 46.55109 -347.638816) (xy 46.547532 -347.629226) (xy 46.530501 -347.587817) (xy 46.503866 -347.502329)
			(xy 46.485961 -347.414597) (xy 46.476965 -347.325509) (xy 46.476412 -347.280738) (xy 46.476916 -347.238377)
			(xy 46.484969 -347.15404) (xy 46.501003 -347.07085) (xy 46.524871 -346.98956) (xy 46.556359 -346.910908)
			(xy 46.595181 -346.835605) (xy 46.640984 -346.764333) (xy 46.693355 -346.697737) (xy 46.75182 -346.636422)
			(xy 46.815848 -346.580941) (xy 46.88486 -346.531798) (xy 46.95823 -346.489438) (xy 47.035295 -346.454243)
			(xy 47.115357 -346.426534) (xy 47.19769 -346.40656) (xy 47.281549 -346.394503) (xy 47.366174 -346.390472)
			(xy 47.450799 -346.394503) (xy 47.534658 -346.40656) (xy 47.616991 -346.426534) (xy 47.697053 -346.454243)
			(xy 47.774118 -346.489438) (xy 47.847488 -346.531798) (xy 47.9165 -346.580941) (xy 47.980528 -346.636422)
			(xy 48.038993 -346.697737) (xy 48.091364 -346.764333) (xy 48.137167 -346.835605) (xy 48.175989 -346.910908)
			(xy 48.207477 -346.98956) (xy 48.231345 -347.07085) (xy 48.247379 -347.15404) (xy 48.255432 -347.238377)
			(xy 48.255936 -347.280738) (xy 48.25537 -347.325508) (xy 48.24636 -347.414592) (xy 48.228456 -347.502324)
			(xy 48.201838 -347.587815) (xy 48.184816 -347.629226) (xy 48.181232 -347.638811) (xy 48.181246 -347.659259)
			(xy 48.184816 -347.66885) (xy 48.199304 -347.703977) (xy 48.222973 -347.776187) (xy 48.2404 -347.850153)
			(xy 48.251457 -347.925335) (xy 48.254158 -347.963236) (xy 48.255104 -347.972078) (xy 48.26215 -347.988388)
			(xy 48.274337 -348.001315) (xy 48.282098 -348.005654) (xy 48.37303 -348.051374) (xy 48.3997 -348.04985)
			(xy 48.41113 -348.04223) (xy 48.447343 -348.019182) (xy 48.523387 -347.979349) (xy 48.602912 -347.947022)
			(xy 48.685181 -347.922504) (xy 48.769429 -347.90602) (xy 48.854872 -347.897725) (xy 48.897794 -347.897196)
			(xy 48.938907 -347.897719) (xy 49.020782 -347.905305) (xy 49.101608 -347.920413) (xy 49.180695 -347.942914)
			(xy 49.257369 -347.972616) (xy 49.330975 -348.009266) (xy 49.400886 -348.05255) (xy 49.466504 -348.102101)
			(xy 49.527271 -348.157495) (xy 49.582668 -348.218259) (xy 49.632222 -348.283875) (xy 49.675511 -348.353783)
			(xy 49.712165 -348.427387) (xy 49.741871 -348.504059) (xy 49.764376 -348.583145) (xy 49.779489 -348.66397)
			(xy 49.78371 -348.7095) (xy 53.352901 -348.7095) (xy 53.356892 -348.625716) (xy 53.36883 -348.54269)
			(xy 53.388606 -348.461175) (xy 53.41604 -348.381909) (xy 53.450886 -348.30561) (xy 53.492827 -348.232969)
			(xy 53.541483 -348.164644) (xy 53.596413 -348.101253) (xy 53.65712 -348.043371) (xy 53.723055 -347.991522)
			(xy 53.79362 -347.946175) (xy 53.868176 -347.907741) (xy 53.946048 -347.876568) (xy 54.02653 -347.852939)
			(xy 54.108894 -347.837068) (xy 54.192394 -347.829098) (xy 54.234334 -347.828616) (xy 54.271523 -347.829023)
			(xy 54.345636 -347.835307) (xy 54.418956 -347.847812) (xy 54.490962 -347.866448) (xy 54.52618 -347.8784)
			(xy 54.534377 -347.880914) (xy 54.551511 -347.880914) (xy 54.559708 -347.8784) (xy 54.594654 -347.86653)
			(xy 54.66609 -347.847969) (xy 54.738831 -347.835458) (xy 54.812365 -347.829087) (xy 54.849268 -347.828616)
			(xy 54.85384 -347.82887) (xy 54.854348 -347.82887) (xy 54.863907 -347.782599) (xy 54.89152 -347.692237)
			(xy 54.909466 -347.64853) (xy 54.912939 -347.63891) (xy 54.912815 -347.618477) (xy 54.909212 -347.608906)
			(xy 54.892173 -347.5675) (xy 54.865541 -347.482011) (xy 54.847637 -347.394278) (xy 54.838644 -347.305189)
			(xy 54.838092 -347.260418) (xy 54.838596 -347.218057) (xy 54.846649 -347.13372) (xy 54.862683 -347.05053)
			(xy 54.886551 -346.96924) (xy 54.918039 -346.890588) (xy 54.956861 -346.815285) (xy 55.002664 -346.744013)
			(xy 55.055035 -346.677417) (xy 55.1135 -346.616102) (xy 55.177528 -346.560621) (xy 55.24654 -346.511478)
			(xy 55.31991 -346.469118) (xy 55.396975 -346.433923) (xy 55.477037 -346.406214) (xy 55.55937 -346.38624)
			(xy 55.643229 -346.374183) (xy 55.727854 -346.370152) (xy 55.812479 -346.374183) (xy 55.896338 -346.38624)
			(xy 55.978671 -346.406214) (xy 56.058733 -346.433923) (xy 56.135798 -346.469118) (xy 56.209168 -346.511478)
			(xy 56.27818 -346.560621) (xy 56.342208 -346.616102) (xy 56.400673 -346.677417) (xy 56.453044 -346.744013)
			(xy 56.498847 -346.815285) (xy 56.537669 -346.890588) (xy 56.569157 -346.96924) (xy 56.593025 -347.05053)
			(xy 56.609059 -347.13372) (xy 56.617112 -347.218057) (xy 56.617616 -347.260418) (xy 56.617044 -347.305187)
			(xy 56.608037 -347.394272) (xy 56.590134 -347.482003) (xy 56.563518 -347.567495) (xy 56.546496 -347.608906)
			(xy 56.542919 -347.618493) (xy 56.542926 -347.63894) (xy 56.546496 -347.64853) (xy 56.561684 -347.685398)
			(xy 56.586189 -347.761282) (xy 56.603812 -347.839053) (xy 56.614411 -347.918088) (xy 56.6166 -347.957902)
			(xy 56.617108 -347.971364) (xy 56.63184 -347.994224) (xy 56.734456 -348.047564) (xy 56.761634 -348.04604)
			(xy 56.773064 -348.038674) (xy 56.808981 -348.016152) (xy 56.88432 -347.977266) (xy 56.963017 -347.945725)
			(xy 57.044358 -347.921816) (xy 57.127605 -347.905754) (xy 57.212003 -347.897686) (xy 57.254394 -347.897196)
			(xy 57.295507 -347.897719) (xy 57.377382 -347.905305) (xy 57.458208 -347.920413) (xy 57.537295 -347.942914)
			(xy 57.613969 -347.972616) (xy 57.687575 -348.009266) (xy 57.757486 -348.05255) (xy 57.823104 -348.102101)
			(xy 57.883871 -348.157495) (xy 57.939268 -348.218259) (xy 57.988822 -348.283875) (xy 58.032111 -348.353783)
			(xy 58.068765 -348.427387) (xy 58.098471 -348.504059) (xy 58.120976 -348.583145) (xy 58.136089 -348.66397)
			(xy 58.14031 -348.7095) (xy 61.684101 -348.7095) (xy 61.688092 -348.625716) (xy 61.70003 -348.54269)
			(xy 61.719806 -348.461175) (xy 61.74724 -348.381909) (xy 61.782086 -348.30561) (xy 61.824027 -348.232969)
			(xy 61.872683 -348.164644) (xy 61.927613 -348.101253) (xy 61.98832 -348.043371) (xy 62.054255 -347.991522)
			(xy 62.12482 -347.946175) (xy 62.199376 -347.907741) (xy 62.277248 -347.876568) (xy 62.35773 -347.852939)
			(xy 62.440094 -347.837068) (xy 62.523594 -347.829098) (xy 62.565534 -347.828616) (xy 62.602723 -347.829023)
			(xy 62.676836 -347.835307) (xy 62.750156 -347.847812) (xy 62.822162 -347.866448) (xy 62.85738 -347.8784)
			(xy 62.865577 -347.880914) (xy 62.882711 -347.880914) (xy 62.890908 -347.8784) (xy 62.926096 -347.866455)
			(xy 62.998036 -347.847809) (xy 63.071292 -347.835299) (xy 63.145342 -347.829013) (xy 63.1825 -347.828616)
			(xy 63.183008 -347.828616) (xy 63.206122 -347.829124) (xy 63.215205 -347.793715) (xy 63.238479 -347.724411)
			(xy 63.252604 -347.690694) (xy 63.256229 -347.680981) (xy 63.25624 -347.66027) (xy 63.252604 -347.650562)
			(xy 63.235485 -347.609307) (xy 63.208697 -347.524095) (xy 63.190664 -347.436611) (xy 63.181571 -347.347751)
			(xy 63.180976 -347.30309) (xy 63.180976 -347.302328) (xy 63.181475 -347.260403) (xy 63.189445 -347.176932)
			(xy 63.205314 -347.094597) (xy 63.228937 -347.014143) (xy 63.260101 -346.936299) (xy 63.298524 -346.861769)
			(xy 63.343857 -346.79123) (xy 63.39569 -346.725319) (xy 63.453553 -346.664633) (xy 63.516923 -346.609723)
			(xy 63.585226 -346.561085) (xy 63.657843 -346.51916) (xy 63.734116 -346.484327) (xy 63.813355 -346.456902)
			(xy 63.894841 -346.437133) (xy 63.977838 -346.4252) (xy 64.061594 -346.421211) (xy 64.14535 -346.4252)
			(xy 64.228347 -346.437133) (xy 64.309833 -346.456902) (xy 64.389072 -346.484327) (xy 64.465345 -346.51916)
			(xy 64.537962 -346.561085) (xy 64.606265 -346.609723) (xy 64.669635 -346.664633) (xy 64.727498 -346.725319)
			(xy 64.779331 -346.79123) (xy 64.824664 -346.861769) (xy 64.863087 -346.936299) (xy 64.894251 -347.014143)
			(xy 64.917874 -347.094597) (xy 64.933743 -347.176932) (xy 64.941713 -347.260403) (xy 64.942212 -347.302328)
			(xy 64.942212 -347.30309) (xy 64.941639 -347.347753) (xy 64.932567 -347.436619) (xy 64.914535 -347.524107)
			(xy 64.88773 -347.609317) (xy 64.870584 -347.650562) (xy 64.866927 -347.660266) (xy 64.866937 -347.680985)
			(xy 64.870584 -347.690694) (xy 64.888862 -347.734789) (xy 64.91689 -347.826038) (xy 64.934892 -347.919782)
			(xy 64.939418 -347.9673) (xy 64.940434 -347.980508) (xy 64.955674 -348.00286) (xy 65.046352 -348.047056)
			(xy 65.054393 -348.050544) (xy 65.071798 -348.052482) (xy 65.088843 -348.048463) (xy 65.09639 -348.044008)
			(xy 65.096644 -348.043754) (xy 65.132959 -348.020439) (xy 65.209305 -347.980191) (xy 65.289189 -347.947525)
			(xy 65.371861 -347.922748) (xy 65.456544 -347.906093) (xy 65.542442 -347.897716) (xy 65.585594 -347.897196)
			(xy 65.626707 -347.897719) (xy 65.708582 -347.905305) (xy 65.789408 -347.920413) (xy 65.868495 -347.942914)
			(xy 65.945169 -347.972616) (xy 66.018775 -348.009266) (xy 66.088686 -348.05255) (xy 66.154304 -348.102101)
			(xy 66.215071 -348.157495) (xy 66.270468 -348.218259) (xy 66.320022 -348.283875) (xy 66.363311 -348.353783)
			(xy 66.399965 -348.427387) (xy 66.429671 -348.504059) (xy 66.452176 -348.583145) (xy 66.467289 -348.66397)
			(xy 66.474879 -348.745845) (xy 66.475356 -348.786958) (xy 66.474795 -348.831728) (xy 66.467942 -348.89948)
			(xy 81.294224 -348.89948) (xy 81.294687 -348.858913) (xy 81.30208 -348.778118) (xy 81.316804 -348.698332)
			(xy 81.338734 -348.620219) (xy 81.36769 -348.544429) (xy 81.385156 -348.507812) (xy 81.389058 -348.498717)
			(xy 81.390365 -348.478988) (xy 81.387696 -348.469458) (xy 81.373498 -348.424437) (xy 81.353605 -348.332151)
			(xy 81.343609 -348.238277) (xy 81.342992 -348.191074) (xy 81.343496 -348.148713) (xy 81.351549 -348.064376)
			(xy 81.367583 -347.981186) (xy 81.391451 -347.899896) (xy 81.422939 -347.821244) (xy 81.461761 -347.745941)
			(xy 81.507564 -347.674669) (xy 81.559935 -347.608073) (xy 81.6184 -347.546758) (xy 81.682428 -347.491277)
			(xy 81.75144 -347.442134) (xy 81.82481 -347.399774) (xy 81.901875 -347.364579) (xy 81.981937 -347.33687)
			(xy 82.06427 -347.316896) (xy 82.148129 -347.304839) (xy 82.232754 -347.300808) (xy 82.317379 -347.304839)
			(xy 82.401238 -347.316896) (xy 82.483571 -347.33687) (xy 82.563633 -347.364579) (xy 82.640698 -347.399774)
			(xy 82.714068 -347.442134) (xy 82.78308 -347.491277) (xy 82.847108 -347.546758) (xy 82.905573 -347.608073)
			(xy 82.957944 -347.674669) (xy 83.003747 -347.745941) (xy 83.042569 -347.821244) (xy 83.074057 -347.899896)
			(xy 83.097925 -347.981186) (xy 83.113959 -348.064376) (xy 83.122012 -348.148713) (xy 83.122516 -348.191074)
			(xy 83.12207 -348.231641) (xy 83.114672 -348.312437) (xy 83.099945 -348.392223) (xy 83.07801 -348.470336)
			(xy 83.049051 -348.546125) (xy 83.031584 -348.582742) (xy 83.027707 -348.591846) (xy 83.026383 -348.611567)
			(xy 83.029044 -348.621096) (xy 83.043232 -348.66612) (xy 83.063129 -348.758404) (xy 83.073129 -348.852278)
			(xy 83.073245 -348.861126) (xy 83.956144 -348.861126) (xy 83.956552 -348.820564) (xy 83.963891 -348.739773)
			(xy 83.978566 -348.659987) (xy 84.000454 -348.581872) (xy 84.029373 -348.506078) (xy 84.046822 -348.469458)
			(xy 84.05073 -348.460437) (xy 84.052174 -348.440849) (xy 84.049616 -348.431358) (xy 84.035467 -348.386455)
			(xy 84.015597 -348.294425) (xy 84.005567 -348.200811) (xy 84.004912 -348.153736) (xy 84.004912 -348.15272)
			(xy 84.005416 -348.110372) (xy 84.013467 -348.026058) (xy 84.029496 -347.942892) (xy 84.053357 -347.861625)
			(xy 84.084836 -347.782995) (xy 84.123647 -347.707714) (xy 84.169437 -347.636462) (xy 84.221793 -347.569886)
			(xy 84.280241 -347.508588) (xy 84.344251 -347.453123) (xy 84.413243 -347.403994) (xy 84.486593 -347.361645)
			(xy 84.563636 -347.326461) (xy 84.643675 -347.298759) (xy 84.725984 -347.278791) (xy 84.809819 -347.266738)
			(xy 84.89442 -347.262708) (xy 84.979021 -347.266738) (xy 85.062856 -347.278791) (xy 85.145165 -347.298759)
			(xy 85.225204 -347.326461) (xy 85.302247 -347.361645) (xy 85.375597 -347.403994) (xy 85.444589 -347.453123)
			(xy 85.508599 -347.508588) (xy 85.567047 -347.569886) (xy 85.619403 -347.636462) (xy 85.665193 -347.707714)
			(xy 85.704004 -347.782995) (xy 85.735483 -347.861625) (xy 85.759344 -347.942892) (xy 85.775373 -348.026058)
			(xy 85.783424 -348.110372) (xy 85.783928 -348.15272) (xy 85.783928 -348.153228) (xy 85.783471 -348.193738)
			(xy 85.77611 -348.274424) (xy 85.761432 -348.354104) (xy 85.73956 -348.432117) (xy 85.710675 -348.507814)
			(xy 85.69325 -348.544388) (xy 85.689318 -348.553401) (xy 85.687887 -348.572996) (xy 85.690456 -348.582488)
			(xy 85.70466 -348.627551) (xy 85.721282 -348.7047) (xy 275.231844 -348.7047) (xy 275.235834 -348.620942)
			(xy 275.247768 -348.537942) (xy 275.267537 -348.456452) (xy 275.294962 -348.377211) (xy 275.329796 -348.300935)
			(xy 275.371722 -348.228316) (xy 275.420361 -348.16001) (xy 275.475273 -348.096638) (xy 275.53596 -348.038772)
			(xy 275.601873 -347.986937) (xy 275.672414 -347.941602) (xy 275.746946 -347.903177) (xy 275.824792 -347.872011)
			(xy 275.905248 -347.848386) (xy 275.987586 -347.832515) (xy 276.071059 -347.824543) (xy 276.112986 -347.824044)
			(xy 276.114002 -347.824044) (xy 276.151059 -347.824452) (xy 276.224908 -347.830716) (xy 276.29797 -347.843157)
			(xy 276.36973 -347.861689) (xy 276.404832 -347.873574) (xy 276.413029 -347.876088) (xy 276.430163 -347.876088)
			(xy 276.43836 -347.873574) (xy 276.478966 -347.8599) (xy 276.562216 -347.839604) (xy 276.647042 -347.827484)
			(xy 276.68982 -347.82506) (xy 276.700434 -347.823969) (xy 276.719453 -347.814348) (xy 276.732947 -347.797851)
			(xy 276.736302 -347.787722) (xy 276.744404 -347.759433) (xy 276.763852 -347.703889) (xy 276.775164 -347.676724)
			(xy 276.778721 -347.667131) (xy 276.778725 -347.646691) (xy 276.775164 -347.6371) (xy 276.758127 -347.595694)
			(xy 276.731493 -347.510205) (xy 276.713589 -347.422472) (xy 276.704596 -347.333383) (xy 276.704044 -347.288612)
			(xy 276.704548 -347.246251) (xy 276.712601 -347.161914) (xy 276.728635 -347.078724) (xy 276.752503 -346.997434)
			(xy 276.783991 -346.918782) (xy 276.822813 -346.843479) (xy 276.868616 -346.772207) (xy 276.920987 -346.705611)
			(xy 276.979452 -346.644296) (xy 277.04348 -346.588815) (xy 277.112492 -346.539672) (xy 277.185862 -346.497312)
			(xy 277.262927 -346.462117) (xy 277.342989 -346.434408) (xy 277.425322 -346.414434) (xy 277.509181 -346.402377)
			(xy 277.593806 -346.398346) (xy 277.678431 -346.402377) (xy 277.76229 -346.414434) (xy 277.844623 -346.434408)
			(xy 277.924685 -346.462117) (xy 278.00175 -346.497312) (xy 278.07512 -346.539672) (xy 278.144132 -346.588815)
			(xy 278.20816 -346.644296) (xy 278.266625 -346.705611) (xy 278.318996 -346.772207) (xy 278.364799 -346.843479)
			(xy 278.403621 -346.918782) (xy 278.435109 -346.997434) (xy 278.458977 -347.078724) (xy 278.475011 -347.161914)
			(xy 278.483064 -347.246251) (xy 278.483568 -347.288612) (xy 278.482998 -347.333381) (xy 278.47399 -347.422466)
			(xy 278.456088 -347.510198) (xy 278.42947 -347.595689) (xy 278.412448 -347.6371) (xy 278.408812 -347.646665)
			(xy 278.408686 -347.667111) (xy 278.412194 -347.676724) (xy 278.426408 -347.711074) (xy 278.449728 -347.781668)
			(xy 278.467082 -347.85396) (xy 278.478348 -347.927447) (xy 278.481282 -347.964506) (xy 278.482267 -347.973327)
			(xy 278.489457 -347.989544) (xy 278.501708 -348.002373) (xy 278.509476 -348.00667) (xy 278.600662 -348.051628)
			(xy 278.62784 -348.049596) (xy 278.639016 -348.04223) (xy 278.675581 -348.018458) (xy 278.752524 -347.977387)
			(xy 278.833117 -347.944041) (xy 278.916586 -347.91874) (xy 279.00213 -347.901729) (xy 279.088929 -347.893169)
			(xy 279.132538 -347.892624) (xy 279.133046 -347.892624) (xy 279.174153 -347.893069) (xy 279.256016 -347.900657)
			(xy 279.336831 -347.915765) (xy 279.415907 -347.938263) (xy 279.49257 -347.96796) (xy 279.566167 -348.004602)
			(xy 279.63607 -348.047877) (xy 279.701683 -348.097416) (xy 279.762447 -348.152796) (xy 279.817842 -348.213546)
			(xy 279.867398 -348.279147) (xy 279.91069 -348.349039) (xy 279.947351 -348.422627) (xy 279.977067 -348.499283)
			(xy 279.999585 -348.578353) (xy 280.014712 -348.659164) (xy 280.018945 -348.7047) (xy 283.512244 -348.7047)
			(xy 283.516234 -348.620942) (xy 283.528168 -348.537942) (xy 283.547937 -348.456452) (xy 283.575362 -348.377211)
			(xy 283.610196 -348.300935) (xy 283.652122 -348.228316) (xy 283.700761 -348.16001) (xy 283.755673 -348.096638)
			(xy 283.81636 -348.038772) (xy 283.882273 -347.986937) (xy 283.952814 -347.941602) (xy 284.027346 -347.903177)
			(xy 284.105192 -347.872011) (xy 284.185648 -347.848386) (xy 284.267986 -347.832515) (xy 284.351459 -347.824543)
			(xy 284.393386 -347.824044) (xy 284.394402 -347.824044) (xy 284.431459 -347.824452) (xy 284.505308 -347.830716)
			(xy 284.57837 -347.843157) (xy 284.65013 -347.861689) (xy 284.685232 -347.873574) (xy 284.693429 -347.876088)
			(xy 284.710563 -347.876088) (xy 284.71876 -347.873574) (xy 284.756938 -347.860634) (xy 284.835124 -347.840982)
			(xy 284.91478 -347.828562) (xy 284.95498 -347.825568) (xy 284.965838 -347.82436) (xy 284.985096 -347.814096)
			(xy 284.99831 -347.79673) (xy 285.001208 -347.786198) (xy 285.010486 -347.747118) (xy 285.035162 -347.670674)
			(xy 285.050484 -347.633544) (xy 285.054028 -347.623948) (xy 285.05404 -347.603511) (xy 285.050484 -347.59392)
			(xy 285.033454 -347.552511) (xy 285.006819 -347.467023) (xy 284.988912 -347.379291) (xy 284.979917 -347.290203)
			(xy 284.979364 -347.245432) (xy 284.979868 -347.203071) (xy 284.987921 -347.118734) (xy 285.003955 -347.035544)
			(xy 285.027823 -346.954254) (xy 285.059311 -346.875602) (xy 285.098133 -346.800299) (xy 285.143936 -346.729027)
			(xy 285.196307 -346.662431) (xy 285.254772 -346.601116) (xy 285.3188 -346.545635) (xy 285.387812 -346.496492)
			(xy 285.461182 -346.454132) (xy 285.538247 -346.418937) (xy 285.618309 -346.391228) (xy 285.700642 -346.371254)
			(xy 285.784501 -346.359197) (xy 285.869126 -346.355166) (xy 285.953751 -346.359197) (xy 286.03761 -346.371254)
			(xy 286.119943 -346.391228) (xy 286.200005 -346.418937) (xy 286.27707 -346.454132) (xy 286.35044 -346.496492)
			(xy 286.419452 -346.545635) (xy 286.48348 -346.601116) (xy 286.541945 -346.662431) (xy 286.594316 -346.729027)
			(xy 286.640119 -346.800299) (xy 286.678941 -346.875602) (xy 286.710429 -346.954254) (xy 286.734297 -347.035544)
			(xy 286.750331 -347.118734) (xy 286.758384 -347.203071) (xy 286.758888 -347.245432) (xy 286.758323 -347.290202)
			(xy 286.749314 -347.379287) (xy 286.73141 -347.467018) (xy 286.704791 -347.552509) (xy 286.687768 -347.59392)
			(xy 286.684185 -347.603505) (xy 286.684197 -347.623953) (xy 286.687768 -347.633544) (xy 286.703871 -347.672618)
			(xy 286.72945 -347.753174) (xy 286.747275 -347.835792) (xy 286.757183 -347.919728) (xy 286.758634 -347.961966)
			(xy 286.758888 -347.975936) (xy 286.77362 -347.999558) (xy 286.86506 -348.047056) (xy 286.873276 -348.050887)
			(xy 286.891249 -348.053129) (xy 286.908879 -348.048973) (xy 286.916622 -348.044262) (xy 286.916876 -348.044008)
			(xy 286.95358 -348.019938) (xy 287.030887 -347.978361) (xy 287.111915 -347.944605) (xy 287.195876 -347.918998)
			(xy 287.281951 -347.901791) (xy 287.369303 -347.893149) (xy 287.413192 -347.892624) (xy 287.413446 -347.892624)
			(xy 287.454553 -347.893069) (xy 287.536416 -347.900657) (xy 287.617231 -347.915765) (xy 287.696307 -347.938263)
			(xy 287.77297 -347.96796) (xy 287.846567 -348.004602) (xy 287.91647 -348.047877) (xy 287.982083 -348.097416)
			(xy 288.042847 -348.152796) (xy 288.098242 -348.213546) (xy 288.147798 -348.279147) (xy 288.19109 -348.349039)
			(xy 288.227751 -348.422627) (xy 288.257467 -348.499283) (xy 288.279985 -348.578353) (xy 288.295112 -348.659164)
			(xy 288.299345 -348.7047) (xy 291.818044 -348.7047) (xy 291.822034 -348.620942) (xy 291.833968 -348.537942)
			(xy 291.853737 -348.456452) (xy 291.881162 -348.377211) (xy 291.915996 -348.300935) (xy 291.957922 -348.228316)
			(xy 292.006561 -348.16001) (xy 292.061473 -348.096638) (xy 292.12216 -348.038772) (xy 292.188073 -347.986937)
			(xy 292.258614 -347.941602) (xy 292.333146 -347.903177) (xy 292.410992 -347.872011) (xy 292.491448 -347.848386)
			(xy 292.573786 -347.832515) (xy 292.657259 -347.824543) (xy 292.699186 -347.824044) (xy 292.700202 -347.824044)
			(xy 292.737259 -347.824452) (xy 292.811108 -347.830716) (xy 292.88417 -347.843157) (xy 292.95593 -347.861689)
			(xy 292.991032 -347.873574) (xy 292.999229 -347.876088) (xy 293.016363 -347.876088) (xy 293.02456 -347.873574)
			(xy 293.057737 -347.862322) (xy 293.125493 -347.844496) (xy 293.194454 -347.832123) (xy 293.229284 -347.828362)
			(xy 293.240044 -347.82673) (xy 293.258819 -347.815766) (xy 293.271409 -347.798041) (xy 293.273988 -347.787468)
			(xy 293.28351 -347.742121) (xy 293.310744 -347.653548) (xy 293.328344 -347.610684) (xy 293.331924 -347.601098)
			(xy 293.331914 -347.580651) (xy 293.328344 -347.57106) (xy 293.311293 -347.529659) (xy 293.284663 -347.444168)
			(xy 293.266763 -347.356433) (xy 293.257774 -347.267343) (xy 293.257224 -347.222572) (xy 293.257728 -347.180211)
			(xy 293.265781 -347.095874) (xy 293.281815 -347.012684) (xy 293.305683 -346.931394) (xy 293.337171 -346.852742)
			(xy 293.375993 -346.777439) (xy 293.421796 -346.706167) (xy 293.474167 -346.639571) (xy 293.532632 -346.578256)
			(xy 293.59666 -346.522775) (xy 293.665672 -346.473632) (xy 293.739042 -346.431272) (xy 293.816107 -346.396077)
			(xy 293.896169 -346.368368) (xy 293.978502 -346.348394) (xy 294.062361 -346.336337) (xy 294.146986 -346.332306)
			(xy 294.231611 -346.336337) (xy 294.31547 -346.348394) (xy 294.397803 -346.368368) (xy 294.477865 -346.396077)
			(xy 294.55493 -346.431272) (xy 294.6283 -346.473632) (xy 294.697312 -346.522775) (xy 294.76134 -346.578256)
			(xy 294.819805 -346.639571) (xy 294.872176 -346.706167) (xy 294.917979 -346.777439) (xy 294.956801 -346.852742)
			(xy 294.988289 -346.931394) (xy 295.012157 -347.012684) (xy 295.028191 -347.095874) (xy 295.036244 -347.180211)
			(xy 295.036748 -347.222572) (xy 295.036192 -347.267342) (xy 295.027179 -347.356427) (xy 295.009272 -347.444158)
			(xy 294.982652 -347.529649) (xy 294.965628 -347.57106) (xy 294.962081 -347.580656) (xy 294.96207 -347.601093)
			(xy 294.965628 -347.610684) (xy 294.982659 -347.652092) (xy 295.009295 -347.73758) (xy 295.0272 -347.825313)
			(xy 295.036195 -347.914401) (xy 295.036748 -347.959172) (xy 295.036494 -347.977206) (xy 295.03624 -347.991684)
			(xy 295.050718 -348.016576) (xy 295.157144 -348.071948) (xy 295.185846 -348.069916) (xy 295.19753 -348.061534)
			(xy 295.230035 -348.038582) (xy 295.298406 -347.997866) (xy 295.370142 -347.963421) (xy 295.444669 -347.935524)
			(xy 295.521391 -347.914398) (xy 295.599693 -347.900211) (xy 295.67895 -347.893078) (xy 295.718738 -347.892624)
			(xy 295.719246 -347.892624) (xy 295.760353 -347.893069) (xy 295.842216 -347.900657) (xy 295.923031 -347.915765)
			(xy 296.002107 -347.938263) (xy 296.07877 -347.96796) (xy 296.152367 -348.004602) (xy 296.22227 -348.047877)
			(xy 296.287883 -348.097416) (xy 296.348647 -348.152796) (xy 296.404042 -348.213546) (xy 296.453598 -348.279147)
			(xy 296.49689 -348.349039) (xy 296.533551 -348.422627) (xy 296.563267 -348.499283) (xy 296.585785 -348.578353)
			(xy 296.600912 -348.659164) (xy 296.605145 -348.7047) (xy 300.174644 -348.7047) (xy 300.178634 -348.620942)
			(xy 300.190568 -348.537942) (xy 300.210337 -348.456452) (xy 300.237762 -348.377211) (xy 300.272596 -348.300935)
			(xy 300.314522 -348.228316) (xy 300.363161 -348.16001) (xy 300.418073 -348.096638) (xy 300.47876 -348.038772)
			(xy 300.544673 -347.986937) (xy 300.615214 -347.941602) (xy 300.689746 -347.903177) (xy 300.767592 -347.872011)
			(xy 300.848048 -347.848386) (xy 300.930386 -347.832515) (xy 301.013859 -347.824543) (xy 301.055786 -347.824044)
			(xy 301.056802 -347.824044) (xy 301.093859 -347.824452) (xy 301.167708 -347.830716) (xy 301.24077 -347.843157)
			(xy 301.31253 -347.861689) (xy 301.347632 -347.873574) (xy 301.355829 -347.876088) (xy 301.372963 -347.876088)
			(xy 301.38116 -347.873574) (xy 301.419296 -347.860641) (xy 301.497398 -347.840993) (xy 301.576968 -347.828568)
			(xy 301.617126 -347.825568) (xy 301.627844 -347.824451) (xy 301.646914 -347.814446) (xy 301.660249 -347.797535)
			(xy 301.663354 -347.787214) (xy 301.672203 -347.75314) (xy 301.694583 -347.686387) (xy 301.708058 -347.653864)
			(xy 301.711569 -347.644255) (xy 301.711421 -347.623811) (xy 301.707804 -347.61424) (xy 301.690776 -347.57283)
			(xy 301.66414 -347.487343) (xy 301.646234 -347.39961) (xy 301.637237 -347.310523) (xy 301.636684 -347.265752)
			(xy 301.637188 -347.223391) (xy 301.645241 -347.139054) (xy 301.661275 -347.055864) (xy 301.685143 -346.974574)
			(xy 301.716631 -346.895922) (xy 301.755453 -346.820619) (xy 301.801256 -346.749347) (xy 301.853627 -346.682751)
			(xy 301.912092 -346.621436) (xy 301.97612 -346.565955) (xy 302.045132 -346.516812) (xy 302.118502 -346.474452)
			(xy 302.195567 -346.439257) (xy 302.275629 -346.411548) (xy 302.357962 -346.391574) (xy 302.441821 -346.379517)
			(xy 302.526446 -346.375486) (xy 302.611071 -346.379517) (xy 302.69493 -346.391574) (xy 302.777263 -346.411548)
			(xy 302.857325 -346.439257) (xy 302.93439 -346.474452) (xy 303.00776 -346.516812) (xy 303.076772 -346.565955)
			(xy 303.1408 -346.621436) (xy 303.199265 -346.682751) (xy 303.251636 -346.749347) (xy 303.297439 -346.820619)
			(xy 303.336261 -346.895922) (xy 303.367749 -346.974574) (xy 303.391617 -347.055864) (xy 303.407651 -347.139054)
			(xy 303.415704 -347.223391) (xy 303.416208 -347.265752) (xy 303.415649 -347.310522) (xy 303.406637 -347.399607)
			(xy 303.388731 -347.487338) (xy 303.362111 -347.572829) (xy 303.345088 -347.61424) (xy 303.341549 -347.623838)
			(xy 303.341532 -347.644274) (xy 303.345088 -347.653864) (xy 303.36051 -347.691224) (xy 303.385289 -347.768163)
			(xy 303.402976 -347.847034) (xy 303.413426 -347.927187) (xy 303.415446 -347.967554) (xy 303.415954 -347.981524)
			(xy 303.430686 -348.004638) (xy 303.535334 -348.057216) (xy 303.562766 -348.055184) (xy 303.574196 -348.04731)
			(xy 303.611146 -348.022772) (xy 303.689046 -347.980345) (xy 303.770779 -347.945874) (xy 303.855535 -347.919702)
			(xy 303.942473 -347.902087) (xy 304.030732 -347.893205) (xy 304.075084 -347.892624) (xy 304.075846 -347.892624)
			(xy 304.116953 -347.893069) (xy 304.198816 -347.900657) (xy 304.279631 -347.915765) (xy 304.358707 -347.938263)
			(xy 304.43537 -347.96796) (xy 304.508967 -348.004602) (xy 304.57887 -348.047877) (xy 304.644483 -348.097416)
			(xy 304.705247 -348.152796) (xy 304.760642 -348.213546) (xy 304.810198 -348.279147) (xy 304.85349 -348.349039)
			(xy 304.890151 -348.422627) (xy 304.919867 -348.499283) (xy 304.942385 -348.578353) (xy 304.957512 -348.659164)
			(xy 304.961745 -348.7047) (xy 308.505844 -348.7047) (xy 308.509834 -348.620942) (xy 308.521768 -348.537942)
			(xy 308.541537 -348.456452) (xy 308.568962 -348.377211) (xy 308.603796 -348.300935) (xy 308.645722 -348.228316)
			(xy 308.694361 -348.16001) (xy 308.749273 -348.096638) (xy 308.80996 -348.038772) (xy 308.875873 -347.986937)
			(xy 308.946414 -347.941602) (xy 309.020946 -347.903177) (xy 309.098792 -347.872011) (xy 309.179248 -347.848386)
			(xy 309.261586 -347.832515) (xy 309.345059 -347.824543) (xy 309.386986 -347.824044) (xy 309.388002 -347.824044)
			(xy 309.425059 -347.824452) (xy 309.498908 -347.830716) (xy 309.57197 -347.843157) (xy 309.64373 -347.861689)
			(xy 309.678832 -347.873574) (xy 309.687029 -347.876088) (xy 309.704163 -347.876088) (xy 309.71236 -347.873574)
			(xy 309.752087 -347.860214) (xy 309.833476 -347.84017) (xy 309.916402 -347.827952) (xy 309.958232 -347.825314)
			(xy 309.969008 -347.824123) (xy 309.988202 -347.814097) (xy 310.001607 -347.79709) (xy 310.004714 -347.786706)
			(xy 310.013576 -347.75276) (xy 310.035956 -347.686262) (xy 310.049418 -347.653864) (xy 310.052931 -347.644255)
			(xy 310.052783 -347.623811) (xy 310.049164 -347.61424) (xy 310.03214 -347.572829) (xy 310.005503 -347.487342)
			(xy 309.987595 -347.39961) (xy 309.978598 -347.310522) (xy 309.978044 -347.265752) (xy 309.978548 -347.223391)
			(xy 309.986601 -347.139054) (xy 310.002635 -347.055864) (xy 310.026503 -346.974574) (xy 310.057991 -346.895922)
			(xy 310.096813 -346.820619) (xy 310.142616 -346.749347) (xy 310.194987 -346.682751) (xy 310.253452 -346.621436)
			(xy 310.31748 -346.565955) (xy 310.386492 -346.516812) (xy 310.459862 -346.474452) (xy 310.536927 -346.439257)
			(xy 310.616989 -346.411548) (xy 310.699322 -346.391574) (xy 310.783181 -346.379517) (xy 310.867806 -346.375486)
			(xy 310.952431 -346.379517) (xy 311.03629 -346.391574) (xy 311.118623 -346.411548) (xy 311.198685 -346.439257)
			(xy 311.27575 -346.474452) (xy 311.34912 -346.516812) (xy 311.418132 -346.565955) (xy 311.48216 -346.621436)
			(xy 311.540625 -346.682751) (xy 311.592996 -346.749347) (xy 311.638799 -346.820619) (xy 311.677621 -346.895922)
			(xy 311.709109 -346.974574) (xy 311.732977 -347.055864) (xy 311.749011 -347.139054) (xy 311.757064 -347.223391)
			(xy 311.757568 -347.265752) (xy 311.757012 -347.310522) (xy 311.748 -347.399607) (xy 311.730093 -347.487338)
			(xy 311.703472 -347.572829) (xy 311.686448 -347.61424) (xy 311.682911 -347.623839) (xy 311.682894 -347.644274)
			(xy 311.686448 -347.653864) (xy 311.701578 -347.690518) (xy 311.725997 -347.765967) (xy 311.743615 -347.843288)
			(xy 311.754293 -347.921869) (xy 311.756552 -347.961458) (xy 311.757251 -347.970429) (xy 311.764179 -347.987026)
			(xy 311.776392 -348.000229) (xy 311.784238 -348.004638) (xy 311.875678 -348.050866) (xy 311.902856 -348.049088)
			(xy 311.914286 -348.041468) (xy 311.950798 -348.017804) (xy 312.027605 -347.976914) (xy 312.10804 -347.943725)
			(xy 312.191333 -347.918554) (xy 312.276687 -347.901641) (xy 312.363285 -347.893148) (xy 312.406792 -347.892624)
			(xy 312.407046 -347.892624) (xy 312.448153 -347.893069) (xy 312.530016 -347.900657) (xy 312.610831 -347.915765)
			(xy 312.689907 -347.938263) (xy 312.76657 -347.96796) (xy 312.840167 -348.004602) (xy 312.91007 -348.047877)
			(xy 312.975683 -348.097416) (xy 313.036447 -348.152796) (xy 313.091842 -348.213546) (xy 313.141398 -348.279147)
			(xy 313.18469 -348.349039) (xy 313.221351 -348.422627) (xy 313.251067 -348.499283) (xy 313.273585 -348.578353)
			(xy 313.288712 -348.659164) (xy 313.296321 -348.741025) (xy 313.296808 -348.782132) (xy 313.296242 -348.826902)
			(xy 313.287233 -348.915987) (xy 313.269329 -349.003718) (xy 313.242711 -349.089209) (xy 313.225688 -349.13062)
			(xy 313.222104 -349.140205) (xy 313.222115 -349.160653) (xy 313.225688 -349.170244) (xy 313.242711 -349.211656)
			(xy 313.269347 -349.297143) (xy 313.287256 -349.384874) (xy 313.291976 -349.43161) (xy 326.552821 -349.43161)
			(xy 326.556826 -349.325861) (xy 326.568816 -349.220718) (xy 326.588725 -349.116783) (xy 326.616436 -349.014651)
			(xy 326.651793 -348.914907) (xy 326.694591 -348.818123) (xy 326.744587 -348.724853) (xy 326.801494 -348.635632)
			(xy 326.864985 -348.550969) (xy 326.934697 -348.471351) (xy 327.010231 -348.397233) (xy 327.091154 -348.32904)
			(xy 327.177003 -348.267162) (xy 327.267286 -348.211955) (xy 327.361485 -348.163733) (xy 327.459062 -348.122773)
			(xy 327.559457 -348.089311) (xy 327.662095 -348.063537) (xy 327.766388 -348.045599) (xy 327.871739 -348.0356)
			(xy 327.977545 -348.033597) (xy 328.083199 -348.039602) (xy 328.188096 -348.053581) (xy 328.291636 -348.075452)
			(xy 328.393225 -348.105092) (xy 328.492282 -348.14233) (xy 328.588239 -348.186952) (xy 328.680546 -348.238704)
			(xy 328.768675 -348.297289) (xy 328.852121 -348.362371) (xy 328.930405 -348.433577) (xy 329.00308 -348.5105)
			(xy 329.06973 -348.5927) (xy 329.129972 -348.679704) (xy 329.183461 -348.771015) (xy 329.229892 -348.86611)
			(xy 329.268997 -348.964444) (xy 329.300554 -349.065455) (xy 329.324381 -349.168562) (xy 329.340342 -349.273176)
			(xy 329.348346 -349.378698) (xy 329.348846 -349.43161) (xy 334.012801 -349.43161) (xy 334.016806 -349.325861)
			(xy 334.028796 -349.220718) (xy 334.048705 -349.116783) (xy 334.076416 -349.014651) (xy 334.111773 -348.914907)
			(xy 334.154571 -348.818123) (xy 334.204567 -348.724853) (xy 334.261474 -348.635632) (xy 334.324965 -348.550969)
			(xy 334.394677 -348.471351) (xy 334.470211 -348.397233) (xy 334.551134 -348.32904) (xy 334.636983 -348.267162)
			(xy 334.727266 -348.211955) (xy 334.821465 -348.163733) (xy 334.919042 -348.122773) (xy 335.019437 -348.089311)
			(xy 335.122075 -348.063537) (xy 335.226368 -348.045599) (xy 335.331719 -348.0356) (xy 335.437525 -348.033597)
			(xy 335.543179 -348.039602) (xy 335.648076 -348.053581) (xy 335.751616 -348.075452) (xy 335.853205 -348.105092)
			(xy 335.952262 -348.14233) (xy 336.048219 -348.186952) (xy 336.140526 -348.238704) (xy 336.228655 -348.297289)
			(xy 336.312101 -348.362371) (xy 336.390385 -348.433577) (xy 336.46306 -348.5105) (xy 336.52971 -348.5927)
			(xy 336.589952 -348.679704) (xy 336.643441 -348.771015) (xy 336.689872 -348.86611) (xy 336.728977 -348.964444)
			(xy 336.760534 -349.065455) (xy 336.784361 -349.168562) (xy 336.800322 -349.273176) (xy 336.808326 -349.378698)
			(xy 336.808826 -349.43161) (xy 336.808326 -349.484522) (xy 336.800322 -349.590044) (xy 336.784361 -349.694658)
			(xy 336.760534 -349.797765) (xy 336.728977 -349.898776) (xy 336.689872 -349.99711) (xy 336.643441 -350.092205)
			(xy 336.589952 -350.183516) (xy 336.52971 -350.27052) (xy 336.46306 -350.35272) (xy 336.390385 -350.429643)
			(xy 336.312101 -350.500849) (xy 336.228655 -350.565931) (xy 336.140526 -350.624516) (xy 336.048219 -350.676268)
			(xy 335.952262 -350.72089) (xy 335.853205 -350.758128) (xy 335.751616 -350.787768) (xy 335.648076 -350.809639)
			(xy 335.543179 -350.823618) (xy 335.437525 -350.829623) (xy 335.331719 -350.82762) (xy 335.226368 -350.817621)
			(xy 335.122075 -350.799683) (xy 335.019437 -350.773909) (xy 334.919042 -350.740447) (xy 334.821465 -350.699487)
			(xy 334.727266 -350.651265) (xy 334.636983 -350.596058) (xy 334.551134 -350.53418) (xy 334.470211 -350.465987)
			(xy 334.394677 -350.391869) (xy 334.324965 -350.312251) (xy 334.261474 -350.227588) (xy 334.204567 -350.138367)
			(xy 334.154571 -350.045097) (xy 334.111773 -349.948313) (xy 334.076416 -349.848569) (xy 334.048705 -349.746437)
			(xy 334.028796 -349.642502) (xy 334.016806 -349.537359) (xy 334.012801 -349.43161) (xy 329.348846 -349.43161)
			(xy 329.348346 -349.484522) (xy 329.340342 -349.590044) (xy 329.324381 -349.694658) (xy 329.300554 -349.797765)
			(xy 329.268997 -349.898776) (xy 329.229892 -349.99711) (xy 329.183461 -350.092205) (xy 329.129972 -350.183516)
			(xy 329.06973 -350.27052) (xy 329.00308 -350.35272) (xy 328.930405 -350.429643) (xy 328.852121 -350.500849)
			(xy 328.768675 -350.565931) (xy 328.680546 -350.624516) (xy 328.588239 -350.676268) (xy 328.492282 -350.72089)
			(xy 328.393225 -350.758128) (xy 328.291636 -350.787768) (xy 328.188096 -350.809639) (xy 328.083199 -350.823618)
			(xy 327.977545 -350.829623) (xy 327.871739 -350.82762) (xy 327.766388 -350.817621) (xy 327.662095 -350.799683)
			(xy 327.559457 -350.773909) (xy 327.459062 -350.740447) (xy 327.361485 -350.699487) (xy 327.267286 -350.651265)
			(xy 327.177003 -350.596058) (xy 327.091154 -350.53418) (xy 327.010231 -350.465987) (xy 326.934697 -350.391869)
			(xy 326.864985 -350.312251) (xy 326.801494 -350.227588) (xy 326.744587 -350.138367) (xy 326.694591 -350.045097)
			(xy 326.651793 -349.948313) (xy 326.616436 -349.848569) (xy 326.588725 -349.746437) (xy 326.568816 -349.642502)
			(xy 326.556826 -349.537359) (xy 326.552821 -349.43161) (xy 313.291976 -349.43161) (xy 313.296254 -349.473962)
			(xy 313.296808 -349.518732) (xy 313.296242 -349.563502) (xy 313.287233 -349.652587) (xy 313.269329 -349.740318)
			(xy 313.242711 -349.825809) (xy 313.225688 -349.86722) (xy 313.222104 -349.876805) (xy 313.222115 -349.897253)
			(xy 313.225688 -349.906844) (xy 313.242711 -349.948256) (xy 313.269347 -350.033743) (xy 313.287256 -350.121474)
			(xy 313.296254 -350.210562) (xy 313.296808 -350.255332) (xy 313.296378 -350.296443) (xy 313.288787 -350.378314)
			(xy 313.273674 -350.459136) (xy 313.251166 -350.538217) (xy 313.221457 -350.614885) (xy 313.184799 -350.688483)
			(xy 313.141506 -350.758385) (xy 313.091947 -350.823993) (xy 313.036545 -350.884747) (xy 312.975772 -350.94013)
			(xy 312.910148 -350.989668) (xy 312.840233 -351.032938) (xy 312.766623 -351.069572) (xy 312.689946 -351.099257)
			(xy 312.610857 -351.121739) (xy 312.530031 -351.136827) (xy 312.448157 -351.144391) (xy 312.407046 -351.14484)
			(xy 312.365442 -351.14437) (xy 312.282594 -351.136637) (xy 312.200829 -351.121206) (xy 312.120862 -351.098211)
			(xy 312.043389 -351.067854) (xy 311.969088 -351.0304) (xy 311.93359 -351.008696) (xy 311.924458 -351.003521)
			(xy 311.903738 -351.00031) (xy 311.883461 -351.005649) (xy 311.874916 -351.011744) (xy 311.841266 -351.037664)
			(xy 311.769892 -351.083723) (xy 311.694453 -351.12277) (xy 311.615637 -351.15445) (xy 311.53416 -351.178473)
			(xy 311.450764 -351.194623) (xy 311.366208 -351.20275) (xy 311.323736 -351.20326) (xy 311.323482 -351.20326)
			(xy 311.282375 -351.202805) (xy 311.200511 -351.195219) (xy 311.119697 -351.180113) (xy 311.04062 -351.157617)
			(xy 310.963956 -351.127921) (xy 310.890359 -351.09128) (xy 310.820455 -351.048006) (xy 310.754841 -350.998468)
			(xy 310.694077 -350.943088) (xy 310.638682 -350.882339) (xy 310.589126 -350.816738) (xy 310.545833 -350.746846)
			(xy 310.509173 -350.673258) (xy 310.479458 -350.596602) (xy 310.456941 -350.517531) (xy 310.441814 -350.43672)
			(xy 310.434206 -350.354859) (xy 310.43372 -350.313752) (xy 310.434279 -350.268982) (xy 310.44329 -350.179897)
			(xy 310.461196 -350.092166) (xy 310.487816 -350.006675) (xy 310.50484 -349.965264) (xy 310.508432 -349.955681)
			(xy 310.508415 -349.935231) (xy 310.50484 -349.92564) (xy 310.487836 -349.884289) (xy 310.461225 -349.798927)
			(xy 310.443318 -349.711324) (xy 310.434296 -349.622367) (xy 310.43372 -349.57766) (xy 310.43372 -349.576644)
			(xy 310.433974 -349.565214) (xy 310.407495 -349.559269) (xy 310.35526 -349.544526) (xy 310.32958 -349.53575)
			(xy 310.321383 -349.533236) (xy 310.304249 -349.533236) (xy 310.296052 -349.53575) (xy 310.260836 -349.547697)
			(xy 310.188826 -349.566284) (xy 310.115503 -349.578724) (xy 310.041392 -349.584928) (xy 310.004206 -349.58528)
			(xy 309.967022 -349.584911) (xy 309.892914 -349.578689) (xy 309.819594 -349.566246) (xy 309.747583 -349.547672)
			(xy 309.71236 -349.53575) (xy 309.704163 -349.533236) (xy 309.687029 -349.533236) (xy 309.678832 -349.53575)
			(xy 309.64373 -349.547637) (xy 309.571974 -349.566187) (xy 309.498911 -349.578634) (xy 309.42506 -349.584887)
			(xy 309.388002 -349.58528) (xy 309.386986 -349.58528) (xy 309.345059 -349.584857) (xy 309.261586 -349.576885)
			(xy 309.179248 -349.561014) (xy 309.098792 -349.537389) (xy 309.020946 -349.506223) (xy 308.946414 -349.467798)
			(xy 308.875873 -349.422463) (xy 308.80996 -349.370628) (xy 308.749273 -349.312762) (xy 308.694361 -349.24939)
			(xy 308.645722 -349.181084) (xy 308.603796 -349.108465) (xy 308.568962 -349.032189) (xy 308.541537 -348.952948)
			(xy 308.521768 -348.871458) (xy 308.509834 -348.788458) (xy 308.505844 -348.7047) (xy 304.961745 -348.7047)
			(xy 304.965121 -348.741025) (xy 304.965608 -348.782132) (xy 304.965042 -348.826902) (xy 304.956033 -348.915987)
			(xy 304.938129 -349.003718) (xy 304.911511 -349.089209) (xy 304.894488 -349.13062) (xy 304.890904 -349.140205)
			(xy 304.890915 -349.160653) (xy 304.894488 -349.170244) (xy 304.911511 -349.211656) (xy 304.938147 -349.297143)
			(xy 304.956056 -349.384874) (xy 304.965054 -349.473962) (xy 304.965608 -349.518732) (xy 304.965042 -349.563502)
			(xy 304.956033 -349.652587) (xy 304.938129 -349.740318) (xy 304.911511 -349.825809) (xy 304.894488 -349.86722)
			(xy 304.890904 -349.876805) (xy 304.890915 -349.897253) (xy 304.894488 -349.906844) (xy 304.911511 -349.948256)
			(xy 304.938147 -350.033743) (xy 304.956056 -350.121474) (xy 304.965054 -350.210562) (xy 304.965608 -350.255332)
			(xy 304.965178 -350.296443) (xy 304.957587 -350.378314) (xy 304.942474 -350.459136) (xy 304.919966 -350.538217)
			(xy 304.890257 -350.614885) (xy 304.853599 -350.688483) (xy 304.810306 -350.758385) (xy 304.760747 -350.823993)
			(xy 304.705345 -350.884747) (xy 304.644572 -350.94013) (xy 304.578948 -350.989668) (xy 304.509033 -351.032938)
			(xy 304.435423 -351.069572) (xy 304.358746 -351.099257) (xy 304.279657 -351.121739) (xy 304.198831 -351.136827)
			(xy 304.116957 -351.144391) (xy 304.075846 -351.14484) (xy 304.034242 -351.14437) (xy 303.951394 -351.136637)
			(xy 303.869629 -351.121206) (xy 303.789662 -351.098211) (xy 303.712189 -351.067854) (xy 303.637888 -351.0304)
			(xy 303.60239 -351.008696) (xy 303.593258 -351.003521) (xy 303.572538 -351.00031) (xy 303.552261 -351.005649)
			(xy 303.543716 -351.011744) (xy 303.510066 -351.037664) (xy 303.438692 -351.083723) (xy 303.363253 -351.12277)
			(xy 303.284437 -351.15445) (xy 303.20296 -351.178473) (xy 303.119564 -351.194623) (xy 303.035008 -351.20275)
			(xy 302.992536 -351.20326) (xy 302.992282 -351.20326) (xy 302.951175 -351.202805) (xy 302.869311 -351.195219)
			(xy 302.788497 -351.180113) (xy 302.70942 -351.157617) (xy 302.632756 -351.127921) (xy 302.559159 -351.09128)
			(xy 302.489255 -351.048006) (xy 302.423641 -350.998468) (xy 302.362877 -350.943088) (xy 302.307482 -350.882339)
			(xy 302.257926 -350.816738) (xy 302.214633 -350.746846) (xy 302.177973 -350.673258) (xy 302.148258 -350.596602)
			(xy 302.125741 -350.517531) (xy 302.110614 -350.43672) (xy 302.103006 -350.354859) (xy 302.10252 -350.313752)
			(xy 302.103079 -350.268982) (xy 302.11209 -350.179897) (xy 302.129996 -350.092166) (xy 302.156616 -350.006675)
			(xy 302.17364 -349.965264) (xy 302.177232 -349.955681) (xy 302.177215 -349.935231) (xy 302.17364 -349.92564)
			(xy 302.156636 -349.884289) (xy 302.130025 -349.798927) (xy 302.112118 -349.711324) (xy 302.103096 -349.622367)
			(xy 302.10252 -349.57766) (xy 302.10252 -349.576644) (xy 302.102774 -349.565214) (xy 302.076295 -349.559269)
			(xy 302.02406 -349.544526) (xy 301.99838 -349.53575) (xy 301.990183 -349.533236) (xy 301.973049 -349.533236)
			(xy 301.964852 -349.53575) (xy 301.929636 -349.547697) (xy 301.857626 -349.566284) (xy 301.784303 -349.578724)
			(xy 301.710192 -349.584928) (xy 301.673006 -349.58528) (xy 301.635822 -349.584911) (xy 301.561714 -349.578689)
			(xy 301.488394 -349.566246) (xy 301.416383 -349.547672) (xy 301.38116 -349.53575) (xy 301.372963 -349.533236)
			(xy 301.355829 -349.533236) (xy 301.347632 -349.53575) (xy 301.31253 -349.547637) (xy 301.240774 -349.566187)
			(xy 301.167711 -349.578634) (xy 301.09386 -349.584887) (xy 301.056802 -349.58528) (xy 301.055786 -349.58528)
			(xy 301.013859 -349.584857) (xy 300.930386 -349.576885) (xy 300.848048 -349.561014) (xy 300.767592 -349.537389)
			(xy 300.689746 -349.506223) (xy 300.615214 -349.467798) (xy 300.544673 -349.422463) (xy 300.47876 -349.370628)
			(xy 300.418073 -349.312762) (xy 300.363161 -349.24939) (xy 300.314522 -349.181084) (xy 300.272596 -349.108465)
			(xy 300.237762 -349.032189) (xy 300.210337 -348.952948) (xy 300.190568 -348.871458) (xy 300.178634 -348.788458)
			(xy 300.174644 -348.7047) (xy 296.605145 -348.7047) (xy 296.608521 -348.741025) (xy 296.609008 -348.782132)
			(xy 296.608442 -348.826902) (xy 296.599433 -348.915987) (xy 296.581529 -349.003718) (xy 296.554911 -349.089209)
			(xy 296.537888 -349.13062) (xy 296.534304 -349.140205) (xy 296.534315 -349.160653) (xy 296.537888 -349.170244)
			(xy 296.554911 -349.211656) (xy 296.581547 -349.297143) (xy 296.599456 -349.384874) (xy 296.608454 -349.473962)
			(xy 296.609008 -349.518732) (xy 296.608442 -349.563502) (xy 296.599433 -349.652587) (xy 296.581529 -349.740318)
			(xy 296.554911 -349.825809) (xy 296.537888 -349.86722) (xy 296.534304 -349.876805) (xy 296.534315 -349.897253)
			(xy 296.537888 -349.906844) (xy 296.554911 -349.948256) (xy 296.581547 -350.033743) (xy 296.599456 -350.121474)
			(xy 296.608454 -350.210562) (xy 296.609008 -350.255332) (xy 296.608578 -350.296443) (xy 296.600987 -350.378314)
			(xy 296.585874 -350.459136) (xy 296.563366 -350.538217) (xy 296.533657 -350.614885) (xy 296.496999 -350.688483)
			(xy 296.453706 -350.758385) (xy 296.404147 -350.823993) (xy 296.348745 -350.884747) (xy 296.287972 -350.94013)
			(xy 296.222348 -350.989668) (xy 296.152433 -351.032938) (xy 296.078823 -351.069572) (xy 296.002146 -351.099257)
			(xy 295.923057 -351.121739) (xy 295.842231 -351.136827) (xy 295.760357 -351.144391) (xy 295.719246 -351.14484)
			(xy 295.677642 -351.14437) (xy 295.594794 -351.136637) (xy 295.513029 -351.121206) (xy 295.433062 -351.098211)
			(xy 295.355589 -351.067854) (xy 295.281288 -351.0304) (xy 295.24579 -351.008696) (xy 295.236658 -351.003521)
			(xy 295.215938 -351.00031) (xy 295.195661 -351.005649) (xy 295.187116 -351.011744) (xy 295.153466 -351.037664)
			(xy 295.082092 -351.083723) (xy 295.006653 -351.12277) (xy 294.927837 -351.15445) (xy 294.84636 -351.178473)
			(xy 294.762964 -351.194623) (xy 294.678408 -351.20275) (xy 294.635936 -351.20326) (xy 294.635682 -351.20326)
			(xy 294.594575 -351.202805) (xy 294.512711 -351.195219) (xy 294.431897 -351.180113) (xy 294.35282 -351.157617)
			(xy 294.276156 -351.127921) (xy 294.202559 -351.09128) (xy 294.132655 -351.048006) (xy 294.067041 -350.998468)
			(xy 294.006277 -350.943088) (xy 293.950882 -350.882339) (xy 293.901326 -350.816738) (xy 293.858033 -350.746846)
			(xy 293.821373 -350.673258) (xy 293.791658 -350.596602) (xy 293.769141 -350.517531) (xy 293.754014 -350.43672)
			(xy 293.746406 -350.354859) (xy 293.74592 -350.313752) (xy 293.746479 -350.268982) (xy 293.75549 -350.179897)
			(xy 293.773396 -350.092166) (xy 293.800016 -350.006675) (xy 293.81704 -349.965264) (xy 293.820632 -349.955681)
			(xy 293.820615 -349.935231) (xy 293.81704 -349.92564) (xy 293.800036 -349.884289) (xy 293.773425 -349.798927)
			(xy 293.755518 -349.711324) (xy 293.746496 -349.622367) (xy 293.74592 -349.57766) (xy 293.74592 -349.576644)
			(xy 293.746174 -349.565214) (xy 293.719695 -349.559269) (xy 293.66746 -349.544526) (xy 293.64178 -349.53575)
			(xy 293.633583 -349.533236) (xy 293.616449 -349.533236) (xy 293.608252 -349.53575) (xy 293.573036 -349.547697)
			(xy 293.501026 -349.566284) (xy 293.427703 -349.578724) (xy 293.353592 -349.584928) (xy 293.316406 -349.58528)
			(xy 293.279222 -349.584911) (xy 293.205114 -349.578689) (xy 293.131794 -349.566246) (xy 293.059783 -349.547672)
			(xy 293.02456 -349.53575) (xy 293.016363 -349.533236) (xy 292.999229 -349.533236) (xy 292.991032 -349.53575)
			(xy 292.95593 -349.547637) (xy 292.884174 -349.566187) (xy 292.811111 -349.578634) (xy 292.73726 -349.584887)
			(xy 292.700202 -349.58528) (xy 292.699186 -349.58528) (xy 292.657259 -349.584857) (xy 292.573786 -349.576885)
			(xy 292.491448 -349.561014) (xy 292.410992 -349.537389) (xy 292.333146 -349.506223) (xy 292.258614 -349.467798)
			(xy 292.188073 -349.422463) (xy 292.12216 -349.370628) (xy 292.061473 -349.312762) (xy 292.006561 -349.24939)
			(xy 291.957922 -349.181084) (xy 291.915996 -349.108465) (xy 291.881162 -349.032189) (xy 291.853737 -348.952948)
			(xy 291.833968 -348.871458) (xy 291.822034 -348.788458) (xy 291.818044 -348.7047) (xy 288.299345 -348.7047)
			(xy 288.302721 -348.741025) (xy 288.303208 -348.782132) (xy 288.302642 -348.826902) (xy 288.293633 -348.915987)
			(xy 288.275729 -349.003718) (xy 288.249111 -349.089209) (xy 288.232088 -349.13062) (xy 288.228504 -349.140205)
			(xy 288.228515 -349.160653) (xy 288.232088 -349.170244) (xy 288.249111 -349.211656) (xy 288.275747 -349.297143)
			(xy 288.293656 -349.384874) (xy 288.302654 -349.473962) (xy 288.303208 -349.518732) (xy 288.302642 -349.563502)
			(xy 288.293633 -349.652587) (xy 288.275729 -349.740318) (xy 288.249111 -349.825809) (xy 288.232088 -349.86722)
			(xy 288.228504 -349.876805) (xy 288.228515 -349.897253) (xy 288.232088 -349.906844) (xy 288.249111 -349.948256)
			(xy 288.275747 -350.033743) (xy 288.293656 -350.121474) (xy 288.302654 -350.210562) (xy 288.303208 -350.255332)
			(xy 288.302778 -350.296443) (xy 288.295187 -350.378314) (xy 288.280074 -350.459136) (xy 288.257566 -350.538217)
			(xy 288.227857 -350.614885) (xy 288.191199 -350.688483) (xy 288.147906 -350.758385) (xy 288.098347 -350.823993)
			(xy 288.042945 -350.884747) (xy 287.982172 -350.94013) (xy 287.916548 -350.989668) (xy 287.846633 -351.032938)
			(xy 287.773023 -351.069572) (xy 287.696346 -351.099257) (xy 287.617257 -351.121739) (xy 287.536431 -351.136827)
			(xy 287.454557 -351.144391) (xy 287.413446 -351.14484) (xy 287.371842 -351.14437) (xy 287.288994 -351.136637)
			(xy 287.207229 -351.121206) (xy 287.127262 -351.098211) (xy 287.049789 -351.067854) (xy 286.975488 -351.0304)
			(xy 286.93999 -351.008696) (xy 286.930858 -351.003521) (xy 286.910138 -351.00031) (xy 286.889861 -351.005649)
			(xy 286.881316 -351.011744) (xy 286.847666 -351.037664) (xy 286.776292 -351.083723) (xy 286.700853 -351.12277)
			(xy 286.622037 -351.15445) (xy 286.54056 -351.178473) (xy 286.457164 -351.194623) (xy 286.372608 -351.20275)
			(xy 286.330136 -351.20326) (xy 286.329882 -351.20326) (xy 286.288775 -351.202805) (xy 286.206911 -351.195219)
			(xy 286.126097 -351.180113) (xy 286.04702 -351.157617) (xy 285.970356 -351.127921) (xy 285.896759 -351.09128)
			(xy 285.826855 -351.048006) (xy 285.761241 -350.998468) (xy 285.700477 -350.943088) (xy 285.645082 -350.882339)
			(xy 285.595526 -350.816738) (xy 285.552233 -350.746846) (xy 285.515573 -350.673258) (xy 285.485858 -350.596602)
			(xy 285.463341 -350.517531) (xy 285.448214 -350.43672) (xy 285.440606 -350.354859) (xy 285.44012 -350.313752)
			(xy 285.440679 -350.268982) (xy 285.44969 -350.179897) (xy 285.467596 -350.092166) (xy 285.494216 -350.006675)
			(xy 285.51124 -349.965264) (xy 285.514832 -349.955681) (xy 285.514815 -349.935231) (xy 285.51124 -349.92564)
			(xy 285.494236 -349.884289) (xy 285.467625 -349.798927) (xy 285.449718 -349.711324) (xy 285.440696 -349.622367)
			(xy 285.44012 -349.57766) (xy 285.44012 -349.576644) (xy 285.440374 -349.565214) (xy 285.413895 -349.559269)
			(xy 285.36166 -349.544526) (xy 285.33598 -349.53575) (xy 285.327783 -349.533236) (xy 285.310649 -349.533236)
			(xy 285.302452 -349.53575) (xy 285.267236 -349.547697) (xy 285.195226 -349.566284) (xy 285.121903 -349.578724)
			(xy 285.047792 -349.584928) (xy 285.010606 -349.58528) (xy 284.973422 -349.584911) (xy 284.899314 -349.578689)
			(xy 284.825994 -349.566246) (xy 284.753983 -349.547672) (xy 284.71876 -349.53575) (xy 284.710563 -349.533236)
			(xy 284.693429 -349.533236) (xy 284.685232 -349.53575) (xy 284.65013 -349.547637) (xy 284.578374 -349.566187)
			(xy 284.505311 -349.578634) (xy 284.43146 -349.584887) (xy 284.394402 -349.58528) (xy 284.393386 -349.58528)
			(xy 284.351459 -349.584857) (xy 284.267986 -349.576885) (xy 284.185648 -349.561014) (xy 284.105192 -349.537389)
			(xy 284.027346 -349.506223) (xy 283.952814 -349.467798) (xy 283.882273 -349.422463) (xy 283.81636 -349.370628)
			(xy 283.755673 -349.312762) (xy 283.700761 -349.24939) (xy 283.652122 -349.181084) (xy 283.610196 -349.108465)
			(xy 283.575362 -349.032189) (xy 283.547937 -348.952948) (xy 283.528168 -348.871458) (xy 283.516234 -348.788458)
			(xy 283.512244 -348.7047) (xy 280.018945 -348.7047) (xy 280.022321 -348.741025) (xy 280.022808 -348.782132)
			(xy 280.022242 -348.826902) (xy 280.013233 -348.915987) (xy 279.995329 -349.003718) (xy 279.968711 -349.089209)
			(xy 279.951688 -349.13062) (xy 279.948104 -349.140205) (xy 279.948115 -349.160653) (xy 279.951688 -349.170244)
			(xy 279.968711 -349.211656) (xy 279.995347 -349.297143) (xy 280.013256 -349.384874) (xy 280.022254 -349.473962)
			(xy 280.022808 -349.518732) (xy 280.022242 -349.563502) (xy 280.013233 -349.652587) (xy 279.995329 -349.740318)
			(xy 279.968711 -349.825809) (xy 279.951688 -349.86722) (xy 279.948104 -349.876805) (xy 279.948115 -349.897253)
			(xy 279.951688 -349.906844) (xy 279.968711 -349.948256) (xy 279.995347 -350.033743) (xy 280.013256 -350.121474)
			(xy 280.022254 -350.210562) (xy 280.022808 -350.255332) (xy 280.022378 -350.296443) (xy 280.014787 -350.378314)
			(xy 279.999674 -350.459136) (xy 279.977166 -350.538217) (xy 279.947457 -350.614885) (xy 279.910799 -350.688483)
			(xy 279.867506 -350.758385) (xy 279.817947 -350.823993) (xy 279.762545 -350.884747) (xy 279.701772 -350.94013)
			(xy 279.636148 -350.989668) (xy 279.566233 -351.032938) (xy 279.492623 -351.069572) (xy 279.415946 -351.099257)
			(xy 279.336857 -351.121739) (xy 279.256031 -351.136827) (xy 279.174157 -351.144391) (xy 279.133046 -351.14484)
			(xy 279.091442 -351.14437) (xy 279.008594 -351.136637) (xy 278.926829 -351.121206) (xy 278.846862 -351.098211)
			(xy 278.769389 -351.067854) (xy 278.695088 -351.0304) (xy 278.65959 -351.008696) (xy 278.650458 -351.003521)
			(xy 278.629738 -351.00031) (xy 278.609461 -351.005649) (xy 278.600916 -351.011744) (xy 278.567266 -351.037664)
			(xy 278.495892 -351.083723) (xy 278.420453 -351.12277) (xy 278.341637 -351.15445) (xy 278.26016 -351.178473)
			(xy 278.176764 -351.194623) (xy 278.092208 -351.20275) (xy 278.049736 -351.20326) (xy 278.049482 -351.20326)
			(xy 278.008375 -351.202805) (xy 277.926511 -351.195219) (xy 277.845697 -351.180113) (xy 277.76662 -351.157617)
			(xy 277.689956 -351.127921) (xy 277.616359 -351.09128) (xy 277.546455 -351.048006) (xy 277.480841 -350.998468)
			(xy 277.420077 -350.943088) (xy 277.364682 -350.882339) (xy 277.315126 -350.816738) (xy 277.271833 -350.746846)
			(xy 277.235173 -350.673258) (xy 277.205458 -350.596602) (xy 277.182941 -350.517531) (xy 277.167814 -350.43672)
			(xy 277.160206 -350.354859) (xy 277.15972 -350.313752) (xy 277.160279 -350.268982) (xy 277.16929 -350.179897)
			(xy 277.187196 -350.092166) (xy 277.213816 -350.006675) (xy 277.23084 -349.965264) (xy 277.234432 -349.955681)
			(xy 277.234415 -349.935231) (xy 277.23084 -349.92564) (xy 277.213836 -349.884289) (xy 277.187225 -349.798927)
			(xy 277.169318 -349.711324) (xy 277.160296 -349.622367) (xy 277.15972 -349.57766) (xy 277.15972 -349.576644)
			(xy 277.159974 -349.565214) (xy 277.133495 -349.559269) (xy 277.08126 -349.544526) (xy 277.05558 -349.53575)
			(xy 277.047383 -349.533236) (xy 277.030249 -349.533236) (xy 277.022052 -349.53575) (xy 276.986836 -349.547697)
			(xy 276.914826 -349.566284) (xy 276.841503 -349.578724) (xy 276.767392 -349.584928) (xy 276.730206 -349.58528)
			(xy 276.693022 -349.584911) (xy 276.618914 -349.578689) (xy 276.545594 -349.566246) (xy 276.473583 -349.547672)
			(xy 276.43836 -349.53575) (xy 276.430163 -349.533236) (xy 276.413029 -349.533236) (xy 276.404832 -349.53575)
			(xy 276.36973 -349.547637) (xy 276.297974 -349.566187) (xy 276.224911 -349.578634) (xy 276.15106 -349.584887)
			(xy 276.114002 -349.58528) (xy 276.112986 -349.58528) (xy 276.071059 -349.584857) (xy 275.987586 -349.576885)
			(xy 275.905248 -349.561014) (xy 275.824792 -349.537389) (xy 275.746946 -349.506223) (xy 275.672414 -349.467798)
			(xy 275.601873 -349.422463) (xy 275.53596 -349.370628) (xy 275.475273 -349.312762) (xy 275.420361 -349.24939)
			(xy 275.371722 -349.181084) (xy 275.329796 -349.108465) (xy 275.294962 -349.032189) (xy 275.267537 -348.952948)
			(xy 275.247768 -348.871458) (xy 275.235834 -348.788458) (xy 275.231844 -348.7047) (xy 85.721282 -348.7047)
			(xy 85.724562 -348.719921) (xy 85.734552 -348.813881) (xy 85.73516 -348.861126) (xy 85.734613 -348.906766)
			(xy 85.725307 -348.997569) (xy 85.706754 -349.086942) (xy 85.693504 -349.13062) (xy 85.691044 -349.139629)
			(xy 85.692095 -349.15826) (xy 85.695536 -349.166942) (xy 85.714247 -349.210016) (xy 85.743525 -349.299254)
			(xy 85.763232 -349.391081) (xy 85.77315 -349.484473) (xy 85.773768 -349.531432) (xy 85.77323 -349.574377)
			(xy 85.764932 -349.659867) (xy 85.748446 -349.744161) (xy 85.723925 -349.826477) (xy 85.708236 -349.866458)
			(xy 85.704966 -349.875707) (xy 85.704968 -349.895308) (xy 85.708236 -349.904558) (xy 85.723959 -349.944561)
			(xy 85.748521 -350.026936) (xy 85.765013 -350.111298) (xy 85.773281 -350.196858) (xy 85.773768 -350.239838)
			(xy 85.773264 -350.282199) (xy 85.765211 -350.366536) (xy 85.749177 -350.449726) (xy 85.725309 -350.531016)
			(xy 85.693821 -350.609668) (xy 85.654999 -350.684971) (xy 85.609196 -350.756243) (xy 85.556825 -350.822839)
			(xy 85.49836 -350.884154) (xy 85.434332 -350.939635) (xy 85.36532 -350.988778) (xy 85.29195 -351.031138)
			(xy 85.214885 -351.066333) (xy 85.134823 -351.094042) (xy 85.05249 -351.114016) (xy 84.968631 -351.126073)
			(xy 84.884006 -351.130105) (xy 84.799381 -351.126073) (xy 84.715522 -351.114016) (xy 84.633189 -351.094042)
			(xy 84.553127 -351.066333) (xy 84.476062 -351.031138) (xy 84.402692 -350.988778) (xy 84.33368 -350.939635)
			(xy 84.269652 -350.884154) (xy 84.211187 -350.822839) (xy 84.158816 -350.756243) (xy 84.113013 -350.684971)
			(xy 84.074191 -350.609668) (xy 84.042703 -350.531016) (xy 84.018835 -350.449726) (xy 84.002801 -350.366536)
			(xy 83.994748 -350.282199) (xy 83.994244 -350.239838) (xy 83.994769 -350.196861) (xy 84.003053 -350.111306)
			(xy 84.01954 -350.026947) (xy 84.044076 -349.944568) (xy 84.059776 -349.904558) (xy 84.063037 -349.895306)
			(xy 84.06304 -349.875708) (xy 84.059776 -349.866458) (xy 84.044053 -349.826489) (xy 84.019511 -349.744174)
			(xy 84.003027 -349.659876) (xy 83.994754 -349.57438) (xy 83.994244 -349.531432) (xy 83.994855 -349.485787)
			(xy 84.004246 -349.394981) (xy 84.022872 -349.305612) (xy 84.036154 -349.261938) (xy 84.038586 -349.252923)
			(xy 84.037555 -349.234298) (xy 84.034122 -349.225616) (xy 84.015469 -349.182525) (xy 83.98626 -349.093282)
			(xy 83.966612 -349.001459) (xy 83.956742 -348.908077) (xy 83.956144 -348.861126) (xy 83.073245 -348.861126)
			(xy 83.073748 -348.89948) (xy 83.073141 -348.945125) (xy 83.063748 -349.035931) (xy 83.045121 -349.1253)
			(xy 83.031838 -349.168974) (xy 83.0294 -349.177987) (xy 83.030435 -349.196614) (xy 83.03387 -349.205296)
			(xy 83.052527 -349.248385) (xy 83.081735 -349.337629) (xy 83.101382 -349.429453) (xy 83.111251 -349.522835)
			(xy 83.111848 -349.569786) (xy 83.111412 -349.610119) (xy 83.104141 -349.690457) (xy 83.08963 -349.769807)
			(xy 83.067997 -349.847519) (xy 83.039422 -349.922954) (xy 83.022186 -349.959422) (xy 83.017653 -349.970011)
			(xy 83.017661 -349.993024) (xy 83.022186 -350.003618) (xy 83.039397 -350.040069) (xy 83.067953 -350.115455)
			(xy 83.089579 -350.193114) (xy 83.104099 -350.27241) (xy 83.111393 -350.352693) (xy 83.111848 -350.393)
			(xy 83.111344 -350.435361) (xy 83.103291 -350.519698) (xy 83.087257 -350.602888) (xy 83.063389 -350.684178)
			(xy 83.031901 -350.76283) (xy 82.993079 -350.838133) (xy 82.947276 -350.909405) (xy 82.894905 -350.976001)
			(xy 82.83644 -351.037316) (xy 82.772412 -351.092797) (xy 82.7034 -351.14194) (xy 82.63003 -351.1843)
			(xy 82.552965 -351.219495) (xy 82.472903 -351.247204) (xy 82.39057 -351.267178) (xy 82.306711 -351.279235)
			(xy 82.222086 -351.283267) (xy 82.137461 -351.279235) (xy 82.053602 -351.267178) (xy 81.971269 -351.247204)
			(xy 81.891207 -351.219495) (xy 81.814142 -351.1843) (xy 81.740772 -351.14194) (xy 81.67176 -351.092797)
			(xy 81.607732 -351.037316) (xy 81.549267 -350.976001) (xy 81.496896 -350.909405) (xy 81.451093 -350.838133)
			(xy 81.412271 -350.76283) (xy 81.380783 -350.684178) (xy 81.356915 -350.602888) (xy 81.340881 -350.519698)
			(xy 81.332828 -350.435361) (xy 81.332324 -350.393) (xy 81.332778 -350.35266) (xy 81.340081 -350.272312)
			(xy 81.354637 -350.192956) (xy 81.376326 -350.115246) (xy 81.404968 -350.039822) (xy 81.42224 -350.003364)
			(xy 81.426812 -349.992711) (xy 81.426828 -349.969558) (xy 81.42224 -349.958914) (xy 81.405059 -349.922483)
			(xy 81.376548 -349.847143) (xy 81.35497 -349.769534) (xy 81.340501 -349.69029) (xy 81.33326 -349.610063)
			(xy 81.332832 -349.569786) (xy 81.333382 -349.524146) (xy 81.342687 -349.433343) (xy 81.361239 -349.34397)
			(xy 81.374488 -349.300292) (xy 81.376942 -349.291282) (xy 81.375896 -349.272652) (xy 81.372456 -349.26397)
			(xy 81.353748 -349.220894) (xy 81.32447 -349.131657) (xy 81.304762 -349.039831) (xy 81.294843 -348.946439)
			(xy 81.294224 -348.89948) (xy 66.467942 -348.89948) (xy 66.465784 -348.920813) (xy 66.447878 -349.008544)
			(xy 66.421259 -349.094035) (xy 66.404236 -349.135446) (xy 66.400697 -349.145044) (xy 66.400681 -349.16548)
			(xy 66.404236 -349.17507) (xy 66.421263 -349.21648) (xy 66.4479 -349.301967) (xy 66.465806 -349.3897)
			(xy 66.474803 -349.478787) (xy 66.475356 -349.523558) (xy 66.474795 -349.568328) (xy 66.465784 -349.657413)
			(xy 66.447878 -349.745144) (xy 66.421259 -349.830635) (xy 66.404236 -349.872046) (xy 66.400697 -349.881644)
			(xy 66.400681 -349.90208) (xy 66.404236 -349.91167) (xy 66.421263 -349.95308) (xy 66.4479 -350.038567)
			(xy 66.465806 -350.1263) (xy 66.474803 -350.215387) (xy 66.475356 -350.260158) (xy 66.474861 -350.301272)
			(xy 66.467278 -350.383151) (xy 66.452172 -350.46398) (xy 66.429672 -350.54307) (xy 66.39997 -350.619748)
			(xy 66.36332 -350.693357) (xy 66.320034 -350.76327) (xy 66.270482 -350.828891) (xy 66.215086 -350.88966)
			(xy 66.154319 -350.945059) (xy 66.0887 -350.994614) (xy 66.018788 -351.037902) (xy 65.94518 -351.074555)
			(xy 65.868505 -351.10426) (xy 65.789415 -351.126764) (xy 65.708586 -351.141873) (xy 65.626708 -351.14946)
			(xy 65.585594 -351.14992) (xy 65.543984 -351.149442) (xy 65.461127 -351.141665) (xy 65.379358 -351.12619)
			(xy 65.299391 -351.10315) (xy 65.221922 -351.072748) (xy 65.147629 -351.035248) (xy 65.112138 -351.013522)
			(xy 65.10303 -351.008297) (xy 65.082293 -351.005101) (xy 65.062008 -351.010462) (xy 65.053464 -351.01657)
			(xy 65.019831 -351.042555) (xy 64.948437 -351.08868) (xy 64.872967 -351.127782) (xy 64.79411 -351.159503)
			(xy 64.712585 -351.183553) (xy 64.629138 -351.199714) (xy 64.544529 -351.207838) (xy 64.50203 -351.20834)
			(xy 64.460915 -351.207873) (xy 64.379035 -351.200288) (xy 64.298205 -351.185181) (xy 64.219114 -351.162679)
			(xy 64.142436 -351.132976) (xy 64.068826 -351.096324) (xy 63.998912 -351.053036) (xy 63.93329 -351.003482)
			(xy 63.872521 -350.948084) (xy 63.817123 -350.887316) (xy 63.767568 -350.821695) (xy 63.72428 -350.751781)
			(xy 63.687628 -350.678172) (xy 63.657923 -350.601494) (xy 63.635421 -350.522403) (xy 63.620313 -350.441573)
			(xy 63.612727 -350.359693) (xy 63.612268 -350.318578) (xy 63.61284 -350.273809) (xy 63.621847 -350.184724)
			(xy 63.63975 -350.096993) (xy 63.666366 -350.011501) (xy 63.683388 -349.97009) (xy 63.686968 -349.960503)
			(xy 63.68696 -349.940056) (xy 63.683388 -349.930466) (xy 63.666363 -349.889123) (xy 63.639757 -349.803758)
			(xy 63.621856 -349.716153) (xy 63.612841 -349.627193) (xy 63.612268 -349.582486) (xy 63.612268 -349.58147)
			(xy 63.612522 -349.57004) (xy 63.586044 -349.564091) (xy 63.533809 -349.54935) (xy 63.508128 -349.540576)
			(xy 63.499931 -349.538062) (xy 63.482797 -349.538062) (xy 63.4746 -349.540576) (xy 63.43938 -349.552528)
			(xy 63.367379 -349.571185) (xy 63.294059 -349.583696) (xy 63.219944 -349.589972) (xy 63.182754 -349.59036)
			(xy 63.145565 -349.589952) (xy 63.071452 -349.583667) (xy 62.998133 -349.571163) (xy 62.926126 -349.552528)
			(xy 62.890908 -349.540576) (xy 62.882711 -349.538062) (xy 62.865577 -349.538062) (xy 62.85738 -349.540576)
			(xy 62.822162 -349.552533) (xy 62.75016 -349.571189) (xy 62.676839 -349.583699) (xy 62.602724 -349.589973)
			(xy 62.565534 -349.59036) (xy 62.523594 -349.589902) (xy 62.440094 -349.581932) (xy 62.35773 -349.566061)
			(xy 62.277248 -349.542432) (xy 62.199376 -349.511259) (xy 62.12482 -349.472825) (xy 62.054255 -349.427478)
			(xy 61.98832 -349.375629) (xy 61.927613 -349.317747) (xy 61.872683 -349.254356) (xy 61.824027 -349.186031)
			(xy 61.782086 -349.11339) (xy 61.74724 -349.037091) (xy 61.719806 -348.957825) (xy 61.70003 -348.87631)
			(xy 61.688092 -348.793284) (xy 61.684101 -348.7095) (xy 58.14031 -348.7095) (xy 58.143679 -348.745845)
			(xy 58.144156 -348.786958) (xy 58.143595 -348.831728) (xy 58.134584 -348.920813) (xy 58.116678 -349.008544)
			(xy 58.090059 -349.094035) (xy 58.073036 -349.135446) (xy 58.069497 -349.145044) (xy 58.069481 -349.16548)
			(xy 58.073036 -349.17507) (xy 58.090063 -349.21648) (xy 58.1167 -349.301967) (xy 58.134606 -349.3897)
			(xy 58.143603 -349.478787) (xy 58.144156 -349.523558) (xy 58.143595 -349.568328) (xy 58.134584 -349.657413)
			(xy 58.116678 -349.745144) (xy 58.090059 -349.830635) (xy 58.073036 -349.872046) (xy 58.069497 -349.881644)
			(xy 58.069481 -349.90208) (xy 58.073036 -349.91167) (xy 58.090063 -349.95308) (xy 58.1167 -350.038567)
			(xy 58.134606 -350.1263) (xy 58.143603 -350.215387) (xy 58.144156 -350.260158) (xy 58.143661 -350.301272)
			(xy 58.136078 -350.383151) (xy 58.120972 -350.46398) (xy 58.098472 -350.54307) (xy 58.06877 -350.619748)
			(xy 58.03212 -350.693357) (xy 57.988834 -350.76327) (xy 57.939282 -350.828891) (xy 57.883886 -350.88966)
			(xy 57.823119 -350.945059) (xy 57.7575 -350.994614) (xy 57.687588 -351.037902) (xy 57.61398 -351.074555)
			(xy 57.537305 -351.10426) (xy 57.458215 -351.126764) (xy 57.377386 -351.141873) (xy 57.295508 -351.14946)
			(xy 57.254394 -351.14992) (xy 57.212784 -351.149442) (xy 57.129927 -351.141665) (xy 57.048158 -351.12619)
			(xy 56.968191 -351.10315) (xy 56.890722 -351.072748) (xy 56.816429 -351.035248) (xy 56.780938 -351.013522)
			(xy 56.77183 -351.008297) (xy 56.751093 -351.005101) (xy 56.730808 -351.010462) (xy 56.722264 -351.01657)
			(xy 56.688631 -351.042555) (xy 56.617237 -351.08868) (xy 56.541767 -351.127782) (xy 56.46291 -351.159503)
			(xy 56.381385 -351.183553) (xy 56.297938 -351.199714) (xy 56.213329 -351.207838) (xy 56.17083 -351.20834)
			(xy 56.129715 -351.207873) (xy 56.047835 -351.200288) (xy 55.967005 -351.185181) (xy 55.887914 -351.162679)
			(xy 55.811236 -351.132976) (xy 55.737626 -351.096324) (xy 55.667712 -351.053036) (xy 55.60209 -351.003482)
			(xy 55.541321 -350.948084) (xy 55.485923 -350.887316) (xy 55.436368 -350.821695) (xy 55.39308 -350.751781)
			(xy 55.356428 -350.678172) (xy 55.326723 -350.601494) (xy 55.304221 -350.522403) (xy 55.289113 -350.441573)
			(xy 55.281527 -350.359693) (xy 55.281068 -350.318578) (xy 55.28164 -350.273809) (xy 55.290647 -350.184724)
			(xy 55.30855 -350.096993) (xy 55.335166 -350.011501) (xy 55.352188 -349.97009) (xy 55.355768 -349.960503)
			(xy 55.35576 -349.940056) (xy 55.352188 -349.930466) (xy 55.335163 -349.889123) (xy 55.308557 -349.803758)
			(xy 55.290656 -349.716153) (xy 55.281641 -349.627193) (xy 55.281068 -349.582486) (xy 55.281068 -349.58147)
			(xy 55.281322 -349.57004) (xy 55.254844 -349.564091) (xy 55.202609 -349.54935) (xy 55.176928 -349.540576)
			(xy 55.168731 -349.538062) (xy 55.151597 -349.538062) (xy 55.1434 -349.540576) (xy 55.10818 -349.552528)
			(xy 55.036179 -349.571185) (xy 54.962859 -349.583696) (xy 54.888744 -349.589972) (xy 54.851554 -349.59036)
			(xy 54.814365 -349.589952) (xy 54.740252 -349.583667) (xy 54.666933 -349.571163) (xy 54.594926 -349.552528)
			(xy 54.559708 -349.540576) (xy 54.551511 -349.538062) (xy 54.534377 -349.538062) (xy 54.52618 -349.540576)
			(xy 54.490962 -349.552533) (xy 54.41896 -349.571189) (xy 54.345639 -349.583699) (xy 54.271524 -349.589973)
			(xy 54.234334 -349.59036) (xy 54.192394 -349.589902) (xy 54.108894 -349.581932) (xy 54.02653 -349.566061)
			(xy 53.946048 -349.542432) (xy 53.868176 -349.511259) (xy 53.79362 -349.472825) (xy 53.723055 -349.427478)
			(xy 53.65712 -349.375629) (xy 53.596413 -349.317747) (xy 53.541483 -349.254356) (xy 53.492827 -349.186031)
			(xy 53.450886 -349.11339) (xy 53.41604 -349.037091) (xy 53.388606 -348.957825) (xy 53.36883 -348.87631)
			(xy 53.356892 -348.793284) (xy 53.352901 -348.7095) (xy 49.78371 -348.7095) (xy 49.787079 -348.745845)
			(xy 49.787556 -348.786958) (xy 49.786995 -348.831728) (xy 49.777984 -348.920813) (xy 49.760078 -349.008544)
			(xy 49.733459 -349.094035) (xy 49.716436 -349.135446) (xy 49.712897 -349.145044) (xy 49.712881 -349.16548)
			(xy 49.716436 -349.17507) (xy 49.733463 -349.21648) (xy 49.7601 -349.301967) (xy 49.778006 -349.3897)
			(xy 49.787003 -349.478787) (xy 49.787556 -349.523558) (xy 49.786995 -349.568328) (xy 49.777984 -349.657413)
			(xy 49.760078 -349.745144) (xy 49.733459 -349.830635) (xy 49.716436 -349.872046) (xy 49.712897 -349.881644)
			(xy 49.712881 -349.90208) (xy 49.716436 -349.91167) (xy 49.733463 -349.95308) (xy 49.7601 -350.038567)
			(xy 49.778006 -350.1263) (xy 49.787003 -350.215387) (xy 49.787556 -350.260158) (xy 49.787061 -350.301272)
			(xy 49.779478 -350.383151) (xy 49.764372 -350.46398) (xy 49.741872 -350.54307) (xy 49.71217 -350.619748)
			(xy 49.67552 -350.693357) (xy 49.632234 -350.76327) (xy 49.582682 -350.828891) (xy 49.527286 -350.88966)
			(xy 49.466519 -350.945059) (xy 49.4009 -350.994614) (xy 49.330988 -351.037902) (xy 49.25738 -351.074555)
			(xy 49.180705 -351.10426) (xy 49.101615 -351.126764) (xy 49.020786 -351.141873) (xy 48.938908 -351.14946)
			(xy 48.897794 -351.14992) (xy 48.856184 -351.149442) (xy 48.773327 -351.141665) (xy 48.691558 -351.12619)
			(xy 48.611591 -351.10315) (xy 48.534122 -351.072748) (xy 48.459829 -351.035248) (xy 48.424338 -351.013522)
			(xy 48.41523 -351.008297) (xy 48.394493 -351.005101) (xy 48.374208 -351.010462) (xy 48.365664 -351.01657)
			(xy 48.332031 -351.042555) (xy 48.260637 -351.08868) (xy 48.185167 -351.127782) (xy 48.10631 -351.159503)
			(xy 48.024785 -351.183553) (xy 47.941338 -351.199714) (xy 47.856729 -351.207838) (xy 47.81423 -351.20834)
			(xy 47.773115 -351.207873) (xy 47.691235 -351.200288) (xy 47.610405 -351.185181) (xy 47.531314 -351.162679)
			(xy 47.454636 -351.132976) (xy 47.381026 -351.096324) (xy 47.311112 -351.053036) (xy 47.24549 -351.003482)
			(xy 47.184721 -350.948084) (xy 47.129323 -350.887316) (xy 47.079768 -350.821695) (xy 47.03648 -350.751781)
			(xy 46.999828 -350.678172) (xy 46.970123 -350.601494) (xy 46.947621 -350.522403) (xy 46.932513 -350.441573)
			(xy 46.924927 -350.359693) (xy 46.924468 -350.318578) (xy 46.92504 -350.273809) (xy 46.934047 -350.184724)
			(xy 46.95195 -350.096993) (xy 46.978566 -350.011501) (xy 46.995588 -349.97009) (xy 46.999168 -349.960503)
			(xy 46.99916 -349.940056) (xy 46.995588 -349.930466) (xy 46.978563 -349.889123) (xy 46.951957 -349.803758)
			(xy 46.934056 -349.716153) (xy 46.925041 -349.627193) (xy 46.924468 -349.582486) (xy 46.924468 -349.58147)
			(xy 46.924722 -349.57004) (xy 46.898244 -349.564091) (xy 46.846009 -349.54935) (xy 46.820328 -349.540576)
			(xy 46.812131 -349.538062) (xy 46.794997 -349.538062) (xy 46.7868 -349.540576) (xy 46.75158 -349.552528)
			(xy 46.679579 -349.571185) (xy 46.606259 -349.583696) (xy 46.532144 -349.589972) (xy 46.494954 -349.59036)
			(xy 46.457765 -349.589952) (xy 46.383652 -349.583667) (xy 46.310333 -349.571163) (xy 46.238326 -349.552528)
			(xy 46.203108 -349.540576) (xy 46.194911 -349.538062) (xy 46.177777 -349.538062) (xy 46.16958 -349.540576)
			(xy 46.134362 -349.552533) (xy 46.06236 -349.571189) (xy 45.989039 -349.583699) (xy 45.914924 -349.589973)
			(xy 45.877734 -349.59036) (xy 45.835794 -349.589902) (xy 45.752294 -349.581932) (xy 45.66993 -349.566061)
			(xy 45.589448 -349.542432) (xy 45.511576 -349.511259) (xy 45.43702 -349.472825) (xy 45.366455 -349.427478)
			(xy 45.30052 -349.375629) (xy 45.239813 -349.317747) (xy 45.184883 -349.254356) (xy 45.136227 -349.186031)
			(xy 45.094286 -349.11339) (xy 45.05944 -349.037091) (xy 45.032006 -348.957825) (xy 45.01223 -348.87631)
			(xy 45.000292 -348.793284) (xy 44.996301 -348.7095) (xy 41.47791 -348.7095) (xy 41.481279 -348.745845)
			(xy 41.481756 -348.786958) (xy 41.481195 -348.831728) (xy 41.472184 -348.920813) (xy 41.454278 -349.008544)
			(xy 41.427659 -349.094035) (xy 41.410636 -349.135446) (xy 41.407097 -349.145044) (xy 41.407081 -349.16548)
			(xy 41.410636 -349.17507) (xy 41.427663 -349.21648) (xy 41.4543 -349.301967) (xy 41.472206 -349.3897)
			(xy 41.481203 -349.478787) (xy 41.481756 -349.523558) (xy 41.481195 -349.568328) (xy 41.472184 -349.657413)
			(xy 41.454278 -349.745144) (xy 41.427659 -349.830635) (xy 41.410636 -349.872046) (xy 41.407097 -349.881644)
			(xy 41.407081 -349.90208) (xy 41.410636 -349.91167) (xy 41.427663 -349.95308) (xy 41.4543 -350.038567)
			(xy 41.472206 -350.1263) (xy 41.481203 -350.215387) (xy 41.481756 -350.260158) (xy 41.481261 -350.301272)
			(xy 41.473678 -350.383151) (xy 41.458572 -350.46398) (xy 41.436072 -350.54307) (xy 41.40637 -350.619748)
			(xy 41.36972 -350.693357) (xy 41.326434 -350.76327) (xy 41.276882 -350.828891) (xy 41.221486 -350.88966)
			(xy 41.160719 -350.945059) (xy 41.0951 -350.994614) (xy 41.025188 -351.037902) (xy 40.95158 -351.074555)
			(xy 40.874905 -351.10426) (xy 40.795815 -351.126764) (xy 40.714986 -351.141873) (xy 40.633108 -351.14946)
			(xy 40.591994 -351.14992) (xy 40.550384 -351.149442) (xy 40.467527 -351.141665) (xy 40.385758 -351.12619)
			(xy 40.305791 -351.10315) (xy 40.228322 -351.072748) (xy 40.154029 -351.035248) (xy 40.118538 -351.013522)
			(xy 40.10943 -351.008297) (xy 40.088693 -351.005101) (xy 40.068408 -351.010462) (xy 40.059864 -351.01657)
			(xy 40.026231 -351.042555) (xy 39.954837 -351.08868) (xy 39.879367 -351.127782) (xy 39.80051 -351.159503)
			(xy 39.718985 -351.183553) (xy 39.635538 -351.199714) (xy 39.550929 -351.207838) (xy 39.50843 -351.20834)
			(xy 39.467315 -351.207873) (xy 39.385435 -351.200288) (xy 39.304605 -351.185181) (xy 39.225514 -351.162679)
			(xy 39.148836 -351.132976) (xy 39.075226 -351.096324) (xy 39.005312 -351.053036) (xy 38.93969 -351.003482)
			(xy 38.878921 -350.948084) (xy 38.823523 -350.887316) (xy 38.773968 -350.821695) (xy 38.73068 -350.751781)
			(xy 38.694028 -350.678172) (xy 38.664323 -350.601494) (xy 38.641821 -350.522403) (xy 38.626713 -350.441573)
			(xy 38.619127 -350.359693) (xy 38.618668 -350.318578) (xy 38.61924 -350.273809) (xy 38.628247 -350.184724)
			(xy 38.64615 -350.096993) (xy 38.672766 -350.011501) (xy 38.689788 -349.97009) (xy 38.693368 -349.960503)
			(xy 38.69336 -349.940056) (xy 38.689788 -349.930466) (xy 38.672763 -349.889123) (xy 38.646157 -349.803758)
			(xy 38.628256 -349.716153) (xy 38.619241 -349.627193) (xy 38.618668 -349.582486) (xy 38.618668 -349.58147)
			(xy 38.618922 -349.57004) (xy 38.592444 -349.564091) (xy 38.540209 -349.54935) (xy 38.514528 -349.540576)
			(xy 38.506331 -349.538062) (xy 38.489197 -349.538062) (xy 38.481 -349.540576) (xy 38.44578 -349.552528)
			(xy 38.373779 -349.571185) (xy 38.300459 -349.583696) (xy 38.226344 -349.589972) (xy 38.189154 -349.59036)
			(xy 38.151965 -349.589952) (xy 38.077852 -349.583667) (xy 38.004533 -349.571163) (xy 37.932526 -349.552528)
			(xy 37.897308 -349.540576) (xy 37.889111 -349.538062) (xy 37.871977 -349.538062) (xy 37.86378 -349.540576)
			(xy 37.828562 -349.552533) (xy 37.75656 -349.571189) (xy 37.683239 -349.583699) (xy 37.609124 -349.589973)
			(xy 37.571934 -349.59036) (xy 37.529996 -349.589881) (xy 37.446499 -349.581908) (xy 37.364138 -349.566035)
			(xy 37.283659 -349.542404) (xy 37.20579 -349.511231) (xy 37.131238 -349.472797) (xy 37.060676 -349.42745)
			(xy 36.994745 -349.375601) (xy 36.93404 -349.317719) (xy 36.879112 -349.25433) (xy 36.830459 -349.186006)
			(xy 36.788521 -349.113367) (xy 36.753677 -349.03707) (xy 36.726244 -348.957807) (xy 36.706469 -348.876294)
			(xy 36.694532 -348.793272) (xy 36.690541 -348.70949) (xy 33.197509 -348.70949) (xy 33.200879 -348.745845)
			(xy 33.201356 -348.786958) (xy 33.200795 -348.831728) (xy 33.191784 -348.920813) (xy 33.173878 -349.008544)
			(xy 33.147259 -349.094035) (xy 33.130236 -349.135446) (xy 33.126697 -349.145044) (xy 33.126681 -349.16548)
			(xy 33.130236 -349.17507) (xy 33.147263 -349.21648) (xy 33.1739 -349.301967) (xy 33.191806 -349.3897)
			(xy 33.200803 -349.478787) (xy 33.201356 -349.523558) (xy 33.200795 -349.568328) (xy 33.191784 -349.657413)
			(xy 33.173878 -349.745144) (xy 33.147259 -349.830635) (xy 33.130236 -349.872046) (xy 33.126697 -349.881644)
			(xy 33.126681 -349.90208) (xy 33.130236 -349.91167) (xy 33.147263 -349.95308) (xy 33.1739 -350.038567)
			(xy 33.191806 -350.1263) (xy 33.200803 -350.215387) (xy 33.201356 -350.260158) (xy 33.200861 -350.301272)
			(xy 33.193278 -350.383151) (xy 33.178172 -350.46398) (xy 33.155672 -350.54307) (xy 33.12597 -350.619748)
			(xy 33.08932 -350.693357) (xy 33.046034 -350.76327) (xy 32.996482 -350.828891) (xy 32.941086 -350.88966)
			(xy 32.880319 -350.945059) (xy 32.8147 -350.994614) (xy 32.744788 -351.037902) (xy 32.67118 -351.074555)
			(xy 32.594505 -351.10426) (xy 32.515415 -351.126764) (xy 32.434586 -351.141873) (xy 32.352708 -351.14946)
			(xy 32.311594 -351.14992) (xy 32.269984 -351.149442) (xy 32.187127 -351.141665) (xy 32.105358 -351.12619)
			(xy 32.025391 -351.10315) (xy 31.947922 -351.072748) (xy 31.873629 -351.035248) (xy 31.838138 -351.013522)
			(xy 31.82903 -351.008297) (xy 31.808293 -351.005101) (xy 31.788008 -351.010462) (xy 31.779464 -351.01657)
			(xy 31.745831 -351.042555) (xy 31.674437 -351.08868) (xy 31.598967 -351.127782) (xy 31.52011 -351.159503)
			(xy 31.438585 -351.183553) (xy 31.355138 -351.199714) (xy 31.270529 -351.207838) (xy 31.22803 -351.20834)
			(xy 31.186915 -351.207873) (xy 31.105035 -351.200288) (xy 31.024205 -351.185181) (xy 30.945114 -351.162679)
			(xy 30.868436 -351.132976) (xy 30.794826 -351.096324) (xy 30.724912 -351.053036) (xy 30.65929 -351.003482)
			(xy 30.598521 -350.948084) (xy 30.543123 -350.887316) (xy 30.493568 -350.821695) (xy 30.45028 -350.751781)
			(xy 30.413628 -350.678172) (xy 30.383923 -350.601494) (xy 30.361421 -350.522403) (xy 30.346313 -350.441573)
			(xy 30.338727 -350.359693) (xy 30.338268 -350.318578) (xy 30.33884 -350.273809) (xy 30.347847 -350.184724)
			(xy 30.36575 -350.096993) (xy 30.392366 -350.011501) (xy 30.409388 -349.97009) (xy 30.412968 -349.960503)
			(xy 30.41296 -349.940056) (xy 30.409388 -349.930466) (xy 30.392363 -349.889123) (xy 30.365757 -349.803758)
			(xy 30.347856 -349.716153) (xy 30.338841 -349.627193) (xy 30.338268 -349.582486) (xy 30.338268 -349.58147)
			(xy 30.338522 -349.57004) (xy 30.312044 -349.564091) (xy 30.259809 -349.54935) (xy 30.234128 -349.540576)
			(xy 30.225931 -349.538062) (xy 30.208797 -349.538062) (xy 30.2006 -349.540576) (xy 30.16538 -349.552528)
			(xy 30.093379 -349.571185) (xy 30.020059 -349.583696) (xy 29.945944 -349.589972) (xy 29.908754 -349.59036)
			(xy 29.871565 -349.589952) (xy 29.797452 -349.583667) (xy 29.724133 -349.571163) (xy 29.652126 -349.552528)
			(xy 29.616908 -349.540576) (xy 29.608711 -349.538062) (xy 29.591577 -349.538062) (xy 29.58338 -349.540576)
			(xy 29.548162 -349.552533) (xy 29.47616 -349.571189) (xy 29.402839 -349.583699) (xy 29.328724 -349.589973)
			(xy 29.291534 -349.59036) (xy 29.249596 -349.589881) (xy 29.166099 -349.581908) (xy 29.083738 -349.566035)
			(xy 29.003259 -349.542404) (xy 28.92539 -349.511231) (xy 28.850838 -349.472797) (xy 28.780276 -349.42745)
			(xy 28.714345 -349.375601) (xy 28.65364 -349.317719) (xy 28.598712 -349.25433) (xy 28.550059 -349.186006)
			(xy 28.508121 -349.113367) (xy 28.473277 -349.03707) (xy 28.445844 -348.957807) (xy 28.426069 -348.876294)
			(xy 28.414132 -348.793272) (xy 28.410141 -348.70949) (xy 2.509012 -348.70949) (xy 2.509012 -351.637854)
			(xy 73.92162 -351.637854) (xy 73.922073 -351.597287) (xy 73.929469 -351.516491) (xy 73.944194 -351.436705)
			(xy 73.966127 -351.358593) (xy 73.995085 -351.282803) (xy 74.012552 -351.246186) (xy 74.016468 -351.237096)
			(xy 74.017766 -351.217362) (xy 74.015092 -351.207832) (xy 74.000912 -351.162806) (xy 73.981012 -351.070523)
			(xy 73.971009 -350.97665) (xy 73.970388 -350.929448) (xy 73.970892 -350.887087) (xy 73.978945 -350.80275)
			(xy 73.994979 -350.71956) (xy 74.018847 -350.63827) (xy 74.050335 -350.559618) (xy 74.089157 -350.484315)
			(xy 74.13496 -350.413043) (xy 74.187331 -350.346447) (xy 74.245796 -350.285132) (xy 74.309824 -350.229651)
			(xy 74.378836 -350.180508) (xy 74.452206 -350.138148) (xy 74.529271 -350.102953) (xy 74.609333 -350.075244)
			(xy 74.691666 -350.05527) (xy 74.775525 -350.043213) (xy 74.86015 -350.039182) (xy 74.944775 -350.043213)
			(xy 75.028634 -350.05527) (xy 75.110967 -350.075244) (xy 75.191029 -350.102953) (xy 75.268094 -350.138148)
			(xy 75.341464 -350.180508) (xy 75.410476 -350.229651) (xy 75.474504 -350.285132) (xy 75.532969 -350.346447)
			(xy 75.58534 -350.413043) (xy 75.631143 -350.484315) (xy 75.669965 -350.559618) (xy 75.701453 -350.63827)
			(xy 75.725321 -350.71956) (xy 75.741355 -350.80275) (xy 75.749408 -350.887087) (xy 75.749912 -350.929448)
			(xy 75.749456 -350.970015) (xy 75.742061 -351.05081) (xy 75.727336 -351.130596) (xy 75.705403 -351.208709)
			(xy 75.676446 -351.284499) (xy 75.65898 -351.321116) (xy 75.655063 -351.330206) (xy 75.653765 -351.34994)
			(xy 75.65644 -351.35947) (xy 75.670621 -351.404496) (xy 75.69052 -351.496779) (xy 75.700524 -351.590652)
			(xy 75.70064 -351.5995) (xy 76.58354 -351.5995) (xy 76.583977 -351.558938) (xy 76.59131 -351.478148)
			(xy 76.605978 -351.398363) (xy 76.62786 -351.320247) (xy 76.656772 -351.244452) (xy 76.674218 -351.207832)
			(xy 76.67814 -351.198816) (xy 76.679575 -351.179224) (xy 76.677012 -351.169732) (xy 76.662856 -351.124831)
			(xy 76.642989 -351.0328) (xy 76.632962 -350.939185) (xy 76.632308 -350.89211) (xy 76.632308 -350.891094)
			(xy 76.632812 -350.848746) (xy 76.640863 -350.764432) (xy 76.656892 -350.681266) (xy 76.680753 -350.599999)
			(xy 76.712232 -350.521369) (xy 76.751043 -350.446088) (xy 76.796833 -350.374836) (xy 76.849189 -350.30826)
			(xy 76.907637 -350.246962) (xy 76.971647 -350.191497) (xy 77.040639 -350.142368) (xy 77.113989 -350.100019)
			(xy 77.191032 -350.064835) (xy 77.271071 -350.037133) (xy 77.35338 -350.017165) (xy 77.437215 -350.005112)
			(xy 77.521816 -350.001082) (xy 77.606417 -350.005112) (xy 77.690252 -350.017165) (xy 77.772561 -350.037133)
			(xy 77.8526 -350.064835) (xy 77.929643 -350.100019) (xy 78.002993 -350.142368) (xy 78.071985 -350.191497)
			(xy 78.135995 -350.246962) (xy 78.194443 -350.30826) (xy 78.246799 -350.374836) (xy 78.292589 -350.446088)
			(xy 78.3314 -350.521369) (xy 78.362879 -350.599999) (xy 78.38674 -350.681266) (xy 78.402769 -350.764432)
			(xy 78.41082 -350.848746) (xy 78.411324 -350.891094) (xy 78.411324 -350.891602) (xy 78.410897 -350.932113)
			(xy 78.403528 -351.0128) (xy 78.388844 -351.09248) (xy 78.366965 -351.170492) (xy 78.338074 -351.246189)
			(xy 78.320646 -351.282762) (xy 78.316728 -351.291779) (xy 78.315288 -351.31137) (xy 78.317852 -351.320862)
			(xy 78.33205 -351.365927) (xy 78.351954 -351.458296) (xy 78.361947 -351.552255) (xy 78.362556 -351.5995)
			(xy 78.362003 -351.645139) (xy 78.352699 -351.735943) (xy 78.334149 -351.825316) (xy 78.3209 -351.868994)
			(xy 78.318454 -351.878006) (xy 78.319496 -351.896634) (xy 78.322932 -351.905316) (xy 78.341634 -351.948394)
			(xy 78.370914 -352.03763) (xy 78.390624 -352.129456) (xy 78.400545 -352.222848) (xy 78.401164 -352.269806)
			(xy 78.400653 -352.312784) (xy 78.392364 -352.398339) (xy 78.375873 -352.482698) (xy 78.351334 -352.565076)
			(xy 78.335632 -352.605086) (xy 78.332346 -352.614331) (xy 78.332359 -352.633935) (xy 78.335632 -352.643186)
			(xy 78.351338 -352.683162) (xy 78.375884 -352.765474) (xy 78.392373 -352.84977) (xy 78.400651 -352.935265)
			(xy 78.401164 -352.978212) (xy 78.40066 -353.020573) (xy 78.392607 -353.10491) (xy 78.376573 -353.1881)
			(xy 78.352705 -353.26939) (xy 78.346936 -353.2838) (xy 182.729656 -353.2838) (xy 182.733646 -353.200045)
			(xy 182.745579 -353.117047) (xy 182.765347 -353.035561) (xy 182.792771 -352.956321) (xy 182.827603 -352.880048)
			(xy 182.869527 -352.807431) (xy 182.918163 -352.739127) (xy 182.973072 -352.675756) (xy 183.033756 -352.617891)
			(xy 183.099666 -352.566056) (xy 183.170204 -352.520721) (xy 183.244732 -352.482296) (xy 183.322575 -352.451129)
			(xy 183.403028 -352.427503) (xy 183.485362 -352.411631) (xy 183.568833 -352.403656) (xy 183.610758 -352.403156)
			(xy 183.611774 -352.403156) (xy 183.648831 -352.403571) (xy 183.72268 -352.409833) (xy 183.795742 -352.422272)
			(xy 183.867502 -352.440802) (xy 183.902604 -352.452686) (xy 183.910801 -352.4552) (xy 183.927935 -352.4552)
			(xy 183.936132 -352.452686) (xy 183.964337 -352.443048) (xy 184.021791 -352.42716) (xy 184.05094 -352.420936)
			(xy 184.060579 -352.41851) (xy 184.077071 -352.407448) (xy 184.088123 -352.390948) (xy 184.090564 -352.381312)
			(xy 184.100088 -352.337416) (xy 184.126813 -352.251655) (xy 184.143904 -352.210116) (xy 184.147468 -352.200525)
			(xy 184.147469 -352.180082) (xy 184.143904 -352.170492) (xy 184.126892 -352.12911) (xy 184.100271 -352.043685)
			(xy 184.082363 -351.956018) (xy 184.073351 -351.866996) (xy 184.072784 -351.822258) (xy 184.072784 -351.822004)
			(xy 184.073288 -351.779656) (xy 184.081339 -351.695342) (xy 184.097368 -351.612176) (xy 184.121229 -351.530909)
			(xy 184.152708 -351.452279) (xy 184.191519 -351.376998) (xy 184.237309 -351.305746) (xy 184.289665 -351.23917)
			(xy 184.348113 -351.177872) (xy 184.412123 -351.122407) (xy 184.481115 -351.073278) (xy 184.554465 -351.030929)
			(xy 184.631508 -350.995745) (xy 184.711547 -350.968043) (xy 184.793856 -350.948075) (xy 184.877691 -350.936022)
			(xy 184.962292 -350.931992) (xy 185.046893 -350.936022) (xy 185.130728 -350.948075) (xy 185.213037 -350.968043)
			(xy 185.293076 -350.995745) (xy 185.370119 -351.030929) (xy 185.443469 -351.073278) (xy 185.512461 -351.122407)
			(xy 185.576471 -351.177872) (xy 185.634919 -351.23917) (xy 185.687275 -351.305746) (xy 185.733065 -351.376998)
			(xy 185.771876 -351.452279) (xy 185.803355 -351.530909) (xy 185.827216 -351.612176) (xy 185.843245 -351.695342)
			(xy 185.851296 -351.779656) (xy 185.8518 -351.822004) (xy 185.8518 -351.822258) (xy 185.851234 -351.866996)
			(xy 185.842218 -351.956018) (xy 185.824312 -352.043685) (xy 185.797698 -352.129113) (xy 185.78068 -352.170492)
			(xy 185.777112 -352.180082) (xy 185.777113 -352.200525) (xy 185.78068 -352.210116) (xy 185.797704 -352.251527)
			(xy 185.824339 -352.337015) (xy 185.842246 -352.424746) (xy 185.851245 -352.513834) (xy 185.8518 -352.558604)
			(xy 185.85116 -352.609084) (xy 185.839825 -352.709404) (xy 185.829194 -352.758756) (xy 185.826997 -352.771225)
			(xy 185.833664 -352.795617) (xy 185.841894 -352.805238) (xy 185.882534 -352.847656) (xy 185.889646 -352.846132)
			(xy 185.898412 -352.843862) (xy 185.913646 -352.834103) (xy 185.919364 -352.827082) (xy 185.944527 -352.794419)
			(xy 185.999939 -352.733355) (xy 186.060764 -352.67768) (xy 186.126478 -352.627872) (xy 186.196519 -352.584357)
			(xy 186.270286 -352.547509) (xy 186.347146 -352.517645) (xy 186.426439 -352.49502) (xy 186.507485 -352.479828)
			(xy 186.589589 -352.472201) (xy 186.630818 -352.471736) (xy 186.671925 -352.472195) (xy 186.753788 -352.479781)
			(xy 186.834603 -352.494887) (xy 186.913679 -352.517383) (xy 186.990343 -352.547078) (xy 187.06394 -352.583719)
			(xy 187.133844 -352.626993) (xy 187.199457 -352.676531) (xy 187.260221 -352.73191) (xy 187.315617 -352.792659)
			(xy 187.365173 -352.85826) (xy 187.408465 -352.928152) (xy 187.445126 -353.001739) (xy 187.474841 -353.078395)
			(xy 187.497359 -353.157466) (xy 187.512486 -353.238276) (xy 187.519078 -353.3092) (xy 191.056256 -353.3092)
			(xy 191.060246 -353.225443) (xy 191.07218 -353.142444) (xy 191.091948 -353.060956) (xy 191.119373 -352.981715)
			(xy 191.154206 -352.90544) (xy 191.196132 -352.832822) (xy 191.244771 -352.764518) (xy 191.299682 -352.701146)
			(xy 191.360368 -352.643281) (xy 191.42628 -352.591447) (xy 191.49682 -352.546112) (xy 191.57135 -352.507688)
			(xy 191.649196 -352.476522) (xy 191.729651 -352.452897) (xy 191.811988 -352.437027) (xy 191.89546 -352.429055)
			(xy 191.937386 -352.428556) (xy 191.938402 -352.428556) (xy 191.975459 -352.428963) (xy 192.049308 -352.435227)
			(xy 192.12237 -352.447669) (xy 192.194131 -352.466201) (xy 192.229232 -352.478086) (xy 192.237429 -352.4806)
			(xy 192.254563 -352.4806) (xy 192.26276 -352.478086) (xy 192.290041 -352.468747) (xy 192.345585 -352.453243)
			(xy 192.373758 -352.447098) (xy 192.383527 -352.444576) (xy 192.400163 -352.433196) (xy 192.411142 -352.416293)
			(xy 192.413382 -352.406458) (xy 192.422838 -352.357349) (xy 192.451357 -352.261489) (xy 192.470278 -352.215196)
			(xy 192.473919 -352.205632) (xy 192.474045 -352.185185) (xy 192.470532 -352.175572) (xy 192.453515 -352.134192)
			(xy 192.426895 -352.048766) (xy 192.408989 -351.961099) (xy 192.399978 -351.872077) (xy 192.399412 -351.827338)
			(xy 192.399412 -351.827084) (xy 192.399916 -351.784736) (xy 192.407967 -351.700422) (xy 192.423996 -351.617256)
			(xy 192.447857 -351.535989) (xy 192.479336 -351.457359) (xy 192.518147 -351.382078) (xy 192.563937 -351.310826)
			(xy 192.616293 -351.24425) (xy 192.674741 -351.182952) (xy 192.738751 -351.127487) (xy 192.807743 -351.078358)
			(xy 192.881093 -351.036009) (xy 192.958136 -351.000825) (xy 193.038175 -350.973123) (xy 193.120484 -350.953155)
			(xy 193.204319 -350.941102) (xy 193.28892 -350.937072) (xy 193.373521 -350.941102) (xy 193.457356 -350.953155)
			(xy 193.539665 -350.973123) (xy 193.619704 -351.000825) (xy 193.696747 -351.036009) (xy 193.770097 -351.078358)
			(xy 193.839089 -351.127487) (xy 193.903099 -351.182952) (xy 193.961547 -351.24425) (xy 194.013903 -351.310826)
			(xy 194.059693 -351.382078) (xy 194.098504 -351.457359) (xy 194.129983 -351.535989) (xy 194.153844 -351.617256)
			(xy 194.169873 -351.700422) (xy 194.177924 -351.784736) (xy 194.178428 -351.827084) (xy 194.178428 -351.827338)
			(xy 194.177853 -351.872076) (xy 194.168839 -351.961098) (xy 194.150936 -352.048765) (xy 194.124325 -352.134193)
			(xy 194.107308 -352.175572) (xy 194.10375 -352.185165) (xy 194.103744 -352.205606) (xy 194.107308 -352.215196)
			(xy 194.12436 -352.256596) (xy 194.150986 -352.342088) (xy 194.165052 -352.41103) (xy 206.449676 -352.41103)
			(xy 206.449676 -351.54743) (xy 206.450162 -351.520179) (xy 206.457918 -351.466231) (xy 206.473273 -351.413936)
			(xy 206.495915 -351.364359) (xy 206.525381 -351.318509) (xy 206.561072 -351.277318) (xy 206.602263 -351.241627)
			(xy 206.648113 -351.212161) (xy 206.69769 -351.189519) (xy 206.749985 -351.174164) (xy 206.803933 -351.166408)
			(xy 206.858435 -351.166408) (xy 206.912383 -351.174164) (xy 206.964678 -351.189519) (xy 207.014255 -351.212161)
			(xy 207.060105 -351.241627) (xy 207.101296 -351.277318) (xy 207.136987 -351.318509) (xy 207.166453 -351.364359)
			(xy 207.189095 -351.413936) (xy 207.20445 -351.466231) (xy 207.212206 -351.520179) (xy 207.212692 -351.54743)
			(xy 207.212692 -352.41103) (xy 207.212206 -352.438281) (xy 207.20445 -352.492229) (xy 207.189095 -352.544524)
			(xy 207.166453 -352.594101) (xy 207.136987 -352.639951) (xy 207.101296 -352.681142) (xy 207.060105 -352.716833)
			(xy 207.014255 -352.746299) (xy 206.964678 -352.768941) (xy 206.912383 -352.784296) (xy 206.858435 -352.792052)
			(xy 206.803933 -352.792052) (xy 206.749985 -352.784296) (xy 206.69769 -352.768941) (xy 206.648113 -352.746299)
			(xy 206.602263 -352.716833) (xy 206.561072 -352.681142) (xy 206.525381 -352.639951) (xy 206.495915 -352.594101)
			(xy 206.473273 -352.544524) (xy 206.457918 -352.492229) (xy 206.450162 -352.438281) (xy 206.449676 -352.41103)
			(xy 194.165052 -352.41103) (xy 194.168886 -352.429823) (xy 194.177877 -352.518913) (xy 194.178428 -352.563684)
			(xy 194.178055 -352.600778) (xy 194.171875 -352.674709) (xy 194.159556 -352.747868) (xy 194.150742 -352.783902)
			(xy 194.149 -352.792252) (xy 194.15051 -352.809229) (xy 194.157543 -352.824754) (xy 194.163188 -352.831146)
			(xy 194.203574 -352.874326) (xy 194.216274 -352.871532) (xy 194.225043 -352.869274) (xy 194.240276 -352.859506)
			(xy 194.245992 -352.852482) (xy 194.271138 -352.819805) (xy 194.326552 -352.758742) (xy 194.387379 -352.703068)
			(xy 194.453095 -352.65326) (xy 194.523138 -352.609746) (xy 194.596907 -352.5729) (xy 194.673768 -352.543037)
			(xy 194.753063 -352.520414) (xy 194.834111 -352.505225) (xy 194.916217 -352.4976) (xy 194.957446 -352.497136)
			(xy 194.998553 -352.497569) (xy 195.080417 -352.505157) (xy 195.161232 -352.520265) (xy 195.240309 -352.542764)
			(xy 195.316973 -352.572461) (xy 195.390571 -352.609104) (xy 195.460474 -352.652379) (xy 195.526087 -352.701919)
			(xy 195.586851 -352.757301) (xy 195.642247 -352.818051) (xy 195.691802 -352.883653) (xy 195.735094 -352.953546)
			(xy 195.744851 -352.973132) (xy 338.849208 -352.973132) (xy 338.849825 -352.926972) (xy 338.859426 -352.835153)
			(xy 338.878488 -352.744823) (xy 338.906804 -352.656953) (xy 338.9249 -352.614484) (xy 338.928699 -352.60454)
			(xy 338.928703 -352.583278) (xy 338.9249 -352.573336) (xy 338.90688 -352.530918) (xy 338.878719 -352.443158)
			(xy 338.859786 -352.352956) (xy 338.850284 -352.26128) (xy 338.849716 -352.215196) (xy 338.850295 -352.1688)
			(xy 338.859941 -352.076512) (xy 338.879138 -351.985728) (xy 338.907678 -351.897435) (xy 338.925916 -351.85477)
			(xy 338.929722 -351.844828) (xy 338.929721 -351.823565) (xy 338.925916 -351.813622) (xy 338.907694 -351.771019)
			(xy 338.879176 -351.682852) (xy 338.859983 -351.592196) (xy 338.850324 -351.500036) (xy 338.849716 -351.453704)
			(xy 338.849716 -351.453196) (xy 338.850148 -351.412092) (xy 338.857734 -351.330235) (xy 338.87284 -351.249427)
			(xy 338.895338 -351.170357) (xy 338.925036 -351.093701) (xy 338.96168 -351.020112) (xy 339.004958 -350.950218)
			(xy 339.0545 -350.884616) (xy 339.109884 -350.823864) (xy 339.170637 -350.768482) (xy 339.236241 -350.718942)
			(xy 339.306137 -350.675666) (xy 339.379727 -350.639025) (xy 339.456384 -350.609329) (xy 339.535454 -350.586834)
			(xy 339.616263 -350.57173) (xy 339.69812 -350.564147) (xy 339.739224 -350.563688) (xy 339.739732 -350.563688)
			(xy 339.786063 -350.564321) (xy 339.87822 -350.573985) (xy 339.968874 -350.593172) (xy 340.057044 -350.621677)
			(xy 340.09965 -350.639888) (xy 340.109592 -350.643694) (xy 340.130856 -350.643694) (xy 340.140798 -350.639888)
			(xy 340.183457 -350.621635) (xy 340.27175 -350.593093) (xy 340.362537 -350.573902) (xy 340.454828 -350.564272)
			(xy 340.501224 -350.563688) (xy 340.547619 -350.564298) (xy 340.639906 -350.573935) (xy 340.73069 -350.593123)
			(xy 340.818984 -350.621654) (xy 340.86165 -350.639888) (xy 340.871592 -350.643694) (xy 340.892856 -350.643694)
			(xy 340.902798 -350.639888) (xy 340.945457 -350.621635) (xy 341.03375 -350.593093) (xy 341.124537 -350.573902)
			(xy 341.216828 -350.564272) (xy 341.263224 -350.563688) (xy 341.309619 -350.564298) (xy 341.401906 -350.573935)
			(xy 341.49269 -350.593123) (xy 341.580984 -350.621654) (xy 341.62365 -350.639888) (xy 341.633592 -350.643694)
			(xy 341.654856 -350.643694) (xy 341.664798 -350.639888) (xy 341.707457 -350.621635) (xy 341.79575 -350.593093)
			(xy 341.886537 -350.573902) (xy 341.978828 -350.564272) (xy 342.025224 -350.563688) (xy 342.071619 -350.564298)
			(xy 342.163906 -350.573935) (xy 342.25469 -350.593123) (xy 342.342984 -350.621654) (xy 342.38565 -350.639888)
			(xy 342.395592 -350.643694) (xy 342.416856 -350.643694) (xy 342.426798 -350.639888) (xy 342.469457 -350.621635)
			(xy 342.55775 -350.593093) (xy 342.648537 -350.573902) (xy 342.740828 -350.564272) (xy 342.787224 -350.563688)
			(xy 342.833689 -350.564308) (xy 342.926112 -350.573988) (xy 343.017025 -350.593241) (xy 343.105438 -350.621857)
			(xy 343.148158 -350.640142) (xy 343.156911 -350.643584) (xy 343.175683 -350.644482) (xy 343.184734 -350.64192)
			(xy 343.230109 -350.62753) (xy 343.323147 -350.607378) (xy 343.417806 -350.597287) (xy 343.465404 -350.596708)
			(xy 343.506508 -350.597148) (xy 343.588364 -350.604734) (xy 343.669172 -350.61984) (xy 343.748241 -350.642338)
			(xy 343.824897 -350.672035) (xy 343.898486 -350.708679) (xy 343.968379 -350.751956) (xy 344.033982 -350.801498)
			(xy 344.094733 -350.856881) (xy 344.150115 -350.917634) (xy 344.199655 -350.983237) (xy 344.242931 -351.053132)
			(xy 344.279573 -351.126721) (xy 344.309269 -351.203378) (xy 344.331765 -351.282448) (xy 344.346869 -351.363255)
			(xy 344.354453 -351.445112) (xy 344.354912 -351.486216) (xy 344.354912 -351.486724) (xy 344.354311 -351.533056)
			(xy 344.344638 -351.625214) (xy 344.325441 -351.715868) (xy 344.296928 -351.804037) (xy 344.278712 -351.846642)
			(xy 344.274897 -351.856581) (xy 344.274903 -351.877848) (xy 344.278712 -351.88779) (xy 344.296962 -351.93045)
			(xy 344.325505 -352.018743) (xy 344.344696 -352.109529) (xy 344.354328 -352.20182) (xy 344.354912 -352.248216)
			(xy 344.354328 -352.294369) (xy 344.344776 -352.386179) (xy 344.325776 -352.476508) (xy 344.297531 -352.564386)
			(xy 344.279474 -352.606864) (xy 344.275648 -352.6168) (xy 344.275662 -352.638069) (xy 344.279474 -352.648012)
			(xy 344.29749 -352.690438) (xy 344.325707 -352.77819) (xy 344.344711 -352.868387) (xy 344.354297 -352.960064)
			(xy 344.354912 -353.006152) (xy 344.354402 -353.047262) (xy 344.34922 -353.1032) (xy 423.453493 -353.1032)
			(xy 423.457484 -353.019415) (xy 423.469422 -352.936388) (xy 423.489198 -352.854872) (xy 423.516634 -352.775605)
			(xy 423.55148 -352.699305) (xy 423.593421 -352.626663) (xy 423.642078 -352.558337) (xy 423.697009 -352.494945)
			(xy 423.757718 -352.437063) (xy 423.823654 -352.385213) (xy 423.89422 -352.339866) (xy 423.968777 -352.301432)
			(xy 424.04665 -352.270259) (xy 424.127133 -352.24663) (xy 424.209499 -352.230759) (xy 424.293 -352.222789)
			(xy 424.33494 -352.222308) (xy 424.372129 -352.222714) (xy 424.446242 -352.228999) (xy 424.519562 -352.241503)
			(xy 424.591568 -352.260139) (xy 424.626786 -352.272092) (xy 424.634983 -352.274606) (xy 424.652117 -352.274606)
			(xy 424.660314 -352.272092) (xy 424.687596 -352.262757) (xy 424.74314 -352.24725) (xy 424.771312 -352.241104)
			(xy 424.781089 -352.238609) (xy 424.797722 -352.227214) (xy 424.808697 -352.210302) (xy 424.810936 -352.200464)
			(xy 424.820391 -352.151355) (xy 424.84891 -352.055495) (xy 424.867832 -352.009202) (xy 424.871403 -351.999613)
			(xy 424.871399 -351.979169) (xy 424.867832 -351.969578) (xy 424.850786 -351.928175) (xy 424.824155 -351.842685)
			(xy 424.806254 -351.754951) (xy 424.797263 -351.665861) (xy 424.796712 -351.62109) (xy 424.797216 -351.578729)
			(xy 424.805269 -351.494392) (xy 424.821303 -351.411202) (xy 424.845171 -351.329912) (xy 424.876659 -351.25126)
			(xy 424.915481 -351.175957) (xy 424.961284 -351.104685) (xy 425.013655 -351.038089) (xy 425.07212 -350.976774)
			(xy 425.136148 -350.921293) (xy 425.20516 -350.87215) (xy 425.27853 -350.82979) (xy 425.355595 -350.794595)
			(xy 425.435657 -350.766886) (xy 425.51799 -350.746912) (xy 425.601849 -350.734855) (xy 425.686474 -350.730824)
			(xy 425.771099 -350.734855) (xy 425.854958 -350.746912) (xy 425.937291 -350.766886) (xy 426.017353 -350.794595)
			(xy 426.094418 -350.82979) (xy 426.167788 -350.87215) (xy 426.2368 -350.921293) (xy 426.300828 -350.976774)
			(xy 426.359293 -351.038089) (xy 426.411664 -351.104685) (xy 426.457467 -351.175957) (xy 426.496289 -351.25126)
			(xy 426.527777 -351.329912) (xy 426.551645 -351.411202) (xy 426.567679 -351.494392) (xy 426.575732 -351.578729)
			(xy 426.576236 -351.62109) (xy 426.575653 -351.665859) (xy 426.566649 -351.754944) (xy 426.548749 -351.842675)
			(xy 426.522136 -351.928167) (xy 426.505116 -351.969578) (xy 426.501559 -351.979171) (xy 426.501555 -351.999611)
			(xy 426.505116 -352.009202) (xy 426.522153 -352.050608) (xy 426.548787 -352.136097) (xy 426.566691 -352.22383)
			(xy 426.575684 -352.312919) (xy 426.576236 -352.35769) (xy 426.575843 -352.394784) (xy 426.569667 -352.468714)
			(xy 426.557358 -352.541873) (xy 426.54855 -352.577908) (xy 426.5467 -352.586267) (xy 426.54815 -352.603318)
			(xy 426.55512 -352.618947) (xy 426.560742 -352.625406) (xy 426.601128 -352.668332) (xy 426.613574 -352.665538)
			(xy 426.622391 -352.663274) (xy 426.637739 -352.653501) (xy 426.643546 -352.646488) (xy 426.66867 -352.613784)
			(xy 426.724067 -352.552685) (xy 426.784882 -352.496976) (xy 426.850593 -352.447136) (xy 426.920635 -352.403592)
			(xy 426.994408 -352.366719) (xy 427.071277 -352.336834) (xy 427.150582 -352.314192) (xy 427.231643 -352.298989)
			(xy 427.313763 -352.291354) (xy 427.355 -352.290888) (xy 427.396111 -352.291352) (xy 427.477981 -352.29894)
			(xy 427.558801 -352.314051) (xy 427.637882 -352.336556) (xy 427.714549 -352.366262) (xy 427.788147 -352.402918)
			(xy 427.858049 -352.446208) (xy 427.923657 -352.495765) (xy 427.984412 -352.551165) (xy 428.039795 -352.611935)
			(xy 428.089333 -352.677557) (xy 428.132604 -352.747471) (xy 428.169239 -352.82108) (xy 428.198924 -352.897755)
			(xy 428.221406 -352.976842) (xy 428.236494 -353.057667) (xy 428.243048 -353.1286) (xy 431.780208 -353.1286)
			(xy 431.784199 -353.04482) (xy 431.796136 -352.961799) (xy 431.815909 -352.880289) (xy 431.843342 -352.801027)
			(xy 431.878184 -352.724732) (xy 431.92012 -352.652094) (xy 431.968771 -352.583771) (xy 432.023696 -352.520381)
			(xy 432.084398 -352.4625) (xy 432.150327 -352.410651) (xy 432.220886 -352.365303) (xy 432.295436 -352.326868)
			(xy 432.373301 -352.295693) (xy 432.453778 -352.27206) (xy 432.536136 -352.256184) (xy 432.619631 -352.248208)
			(xy 432.661568 -352.247708) (xy 432.698757 -352.248106) (xy 432.77287 -352.254393) (xy 432.84619 -352.2669)
			(xy 432.918196 -352.285538) (xy 432.953414 -352.297492) (xy 432.961611 -352.300006) (xy 432.978745 -352.300006)
			(xy 432.986942 -352.297492) (xy 433.014223 -352.288155) (xy 433.069768 -352.27265) (xy 433.09794 -352.266504)
			(xy 433.107722 -352.264025) (xy 433.124353 -352.252622) (xy 433.135327 -352.235704) (xy 433.137564 -352.225864)
			(xy 433.147017 -352.176755) (xy 433.175537 -352.080895) (xy 433.19446 -352.034602) (xy 433.19803 -352.025013)
			(xy 433.198026 -352.004569) (xy 433.19446 -351.994978) (xy 433.177416 -351.953575) (xy 433.150784 -351.868085)
			(xy 433.132882 -351.780351) (xy 433.123891 -351.691261) (xy 433.12334 -351.64649) (xy 433.123844 -351.604129)
			(xy 433.131897 -351.519792) (xy 433.147931 -351.436602) (xy 433.171799 -351.355312) (xy 433.203287 -351.27666)
			(xy 433.242109 -351.201357) (xy 433.287912 -351.130085) (xy 433.340283 -351.063489) (xy 433.398748 -351.002174)
			(xy 433.462776 -350.946693) (xy 433.531788 -350.89755) (xy 433.605158 -350.85519) (xy 433.682223 -350.819995)
			(xy 433.762285 -350.792286) (xy 433.844618 -350.772312) (xy 433.928477 -350.760255) (xy 434.013102 -350.756224)
			(xy 434.097727 -350.760255) (xy 434.181586 -350.772312) (xy 434.263919 -350.792286) (xy 434.343981 -350.819995)
			(xy 434.421046 -350.85519) (xy 434.494416 -350.89755) (xy 434.563428 -350.946693) (xy 434.627456 -351.002174)
			(xy 434.685921 -351.063489) (xy 434.738292 -351.130085) (xy 434.784095 -351.201357) (xy 434.822917 -351.27666)
			(xy 434.854405 -351.355312) (xy 434.878273 -351.436602) (xy 434.894307 -351.519792) (xy 434.90236 -351.604129)
			(xy 434.902864 -351.64649) (xy 434.902279 -351.691259) (xy 434.893275 -351.780343) (xy 434.875376 -351.868074)
			(xy 434.848764 -351.953566) (xy 434.831744 -351.994978) (xy 434.828186 -352.00457) (xy 434.828182 -352.025011)
			(xy 434.831744 -352.034602) (xy 434.848782 -352.076008) (xy 434.875415 -352.161497) (xy 434.893319 -352.24923)
			(xy 434.902312 -352.338319) (xy 434.902864 -352.38309) (xy 434.90247 -352.420184) (xy 434.896295 -352.494114)
			(xy 434.883986 -352.567273) (xy 434.875178 -352.603308) (xy 434.873347 -352.611669) (xy 434.874795 -352.628716)
			(xy 434.881755 -352.644345) (xy 434.88737 -352.650806) (xy 434.927756 -352.693732) (xy 434.940202 -352.690938)
			(xy 434.94901 -352.688645) (xy 434.964363 -352.678893) (xy 434.970174 -352.671888) (xy 434.995281 -352.639171)
			(xy 435.05068 -352.578072) (xy 435.111497 -352.522364) (xy 435.17721 -352.472524) (xy 435.247255 -352.428982)
			(xy 435.321029 -352.39211) (xy 435.3979 -352.362226) (xy 435.477207 -352.339586) (xy 435.558269 -352.324385)
			(xy 435.64039 -352.316753) (xy 435.681628 -352.316288) (xy 435.722739 -352.316726) (xy 435.80461 -352.324316)
			(xy 435.885431 -352.339429) (xy 435.964512 -352.361936) (xy 436.041179 -352.391645) (xy 436.114778 -352.428302)
			(xy 436.184679 -352.471595) (xy 436.250287 -352.521154) (xy 436.311041 -352.576555) (xy 436.366424 -352.637327)
			(xy 436.415962 -352.70295) (xy 436.459233 -352.772865) (xy 436.495867 -352.846475) (xy 436.525552 -352.923151)
			(xy 436.548034 -353.00224) (xy 436.563122 -353.083066) (xy 436.570687 -353.164939) (xy 436.571136 -353.20605)
			(xy 436.570568 -353.25082) (xy 436.561569 -353.339906) (xy 436.543667 -353.427639) (xy 436.517044 -353.513129)
			(xy 436.500016 -353.554538) (xy 436.496425 -353.564121) (xy 436.496444 -353.58457) (xy 436.500016 -353.594162)
			(xy 436.517052 -353.635569) (xy 436.543684 -353.721058) (xy 436.561588 -353.808791) (xy 436.570583 -353.897879)
			(xy 436.571136 -353.94265) (xy 436.570568 -353.98742) (xy 436.561569 -354.076506) (xy 436.543667 -354.164239)
			(xy 436.517044 -354.249729) (xy 436.500016 -354.291138) (xy 436.496425 -354.300721) (xy 436.496444 -354.32117)
			(xy 436.500016 -354.330762) (xy 436.517046 -354.372136) (xy 436.543663 -354.457564) (xy 436.561565 -354.545233)
			(xy 436.570572 -354.634257) (xy 436.571136 -354.678996) (xy 436.571136 -354.67925) (xy 436.57064 -354.720357)
			(xy 436.56306 -354.80222) (xy 436.547959 -354.883035) (xy 436.525468 -354.962112) (xy 436.495777 -355.038776)
			(xy 436.45914 -355.112375) (xy 436.415869 -355.18228) (xy 436.366333 -355.247894) (xy 436.310956 -355.308659)
			(xy 436.250208 -355.364056) (xy 436.184609 -355.413612) (xy 436.114718 -355.456904) (xy 436.041131 -355.493565)
			(xy 435.964475 -355.523279) (xy 435.885405 -355.545796) (xy 435.804595 -355.560921) (xy 435.722735 -355.568527)
			(xy 435.681628 -355.569012) (xy 435.640018 -355.568519) (xy 435.557162 -355.560745) (xy 435.475393 -355.545272)
			(xy 435.395426 -355.522236) (xy 435.317957 -355.491836) (xy 435.243663 -355.454339) (xy 435.208172 -355.432614)
			(xy 435.199049 -355.42742) (xy 435.178322 -355.424214) (xy 435.158043 -355.429561) (xy 435.149498 -355.435662)
			(xy 435.115852 -355.46163) (xy 435.044461 -355.507757) (xy 434.968993 -355.546861) (xy 434.890138 -355.578584)
			(xy 434.808616 -355.602638) (xy 434.72517 -355.618802) (xy 434.640562 -355.626929) (xy 434.598064 -355.627432)
			(xy 434.556953 -355.626982) (xy 434.475084 -355.619391) (xy 434.394263 -355.604278) (xy 434.315183 -355.581771)
			(xy 434.238517 -355.552062) (xy 434.164919 -355.515405) (xy 434.095019 -355.472113) (xy 434.029411 -355.422555)
			(xy 433.968657 -355.367155) (xy 433.913275 -355.306384) (xy 433.863736 -355.240762) (xy 433.820465 -355.170848)
			(xy 433.783831 -355.09724) (xy 433.754145 -355.020565) (xy 433.731661 -354.941477) (xy 433.716572 -354.860653)
			(xy 433.709006 -354.778781) (xy 433.708556 -354.73767) (xy 433.709098 -354.692899) (xy 433.718104 -354.603812)
			(xy 433.736014 -354.51608) (xy 433.762645 -354.430591) (xy 433.779676 -354.389182) (xy 433.783256 -354.379596)
			(xy 433.783245 -354.359149) (xy 433.779676 -354.349558) (xy 433.762646 -354.308149) (xy 433.736013 -354.222661)
			(xy 433.718107 -354.134928) (xy 433.70911 -354.045841) (xy 433.708556 -354.00107) (xy 433.708556 -353.989132)
			(xy 433.682076 -353.983189) (xy 433.629842 -353.968444) (xy 433.604162 -353.959668) (xy 433.595965 -353.957154)
			(xy 433.578831 -353.957154) (xy 433.570634 -353.959668) (xy 433.535422 -353.971642) (xy 433.463417 -353.990292)
			(xy 433.390095 -354.002797) (xy 433.315979 -354.009067) (xy 433.278788 -354.009452) (xy 433.241598 -354.009064)
			(xy 433.167486 -354.002773) (xy 433.094166 -353.990263) (xy 433.02216 -353.971623) (xy 432.986942 -353.959668)
			(xy 432.978745 -353.957154) (xy 432.961611 -353.957154) (xy 432.953414 -353.959668) (xy 432.918203 -353.971647)
			(xy 432.846198 -353.990296) (xy 432.772875 -354.0028) (xy 432.698759 -354.009068) (xy 432.661568 -354.009452)
			(xy 432.619631 -354.008992) (xy 432.536136 -354.001016) (xy 432.453778 -353.98514) (xy 432.373301 -353.961507)
			(xy 432.295436 -353.930332) (xy 432.220886 -353.891897) (xy 432.150327 -353.846549) (xy 432.084398 -353.7947)
			(xy 432.023696 -353.736819) (xy 431.968771 -353.673429) (xy 431.92012 -353.605106) (xy 431.878184 -353.532468)
			(xy 431.843342 -353.456173) (xy 431.815909 -353.376911) (xy 431.796136 -353.295401) (xy 431.784199 -353.21238)
			(xy 431.780208 -353.1286) (xy 428.243048 -353.1286) (xy 428.244059 -353.139539) (xy 428.244508 -353.18065)
			(xy 428.243935 -353.22542) (xy 428.234936 -353.314506) (xy 428.217036 -353.402238) (xy 428.190415 -353.487729)
			(xy 428.173388 -353.529138) (xy 428.169793 -353.53872) (xy 428.169812 -353.559171) (xy 428.173388 -353.568762)
			(xy 428.190428 -353.610167) (xy 428.217058 -353.695657) (xy 428.23496 -353.783391) (xy 428.243955 -353.872479)
			(xy 428.244508 -353.91725) (xy 428.243935 -353.96202) (xy 428.234936 -354.051106) (xy 428.217036 -354.138838)
			(xy 428.190415 -354.224329) (xy 428.173388 -354.265738) (xy 428.169793 -354.27532) (xy 428.169812 -354.295771)
			(xy 428.173388 -354.305362) (xy 428.190417 -354.346737) (xy 428.217034 -354.432165) (xy 428.234937 -354.519833)
			(xy 428.243944 -354.608857) (xy 428.244508 -354.653596) (xy 428.244508 -354.65385) (xy 428.24394 -354.694955)
			(xy 428.23636 -354.776814) (xy 428.221262 -354.857624) (xy 428.198773 -354.936698) (xy 428.169085 -355.013359)
			(xy 428.132451 -355.086955) (xy 428.089184 -355.156857) (xy 428.039654 -355.22247) (xy 427.984281 -355.283233)
			(xy 427.923539 -355.33863) (xy 427.857946 -355.388186) (xy 427.788061 -355.431481) (xy 427.714479 -355.468143)
			(xy 427.63783 -355.497861) (xy 427.558765 -355.520382) (xy 427.47796 -355.535512) (xy 427.396104 -355.543124)
			(xy 427.355 -355.543612) (xy 427.31339 -355.543132) (xy 427.230533 -355.535356) (xy 427.148764 -355.519881)
			(xy 427.068797 -355.496842) (xy 426.991328 -355.46644) (xy 426.917035 -355.42894) (xy 426.881544 -355.407214)
			(xy 426.872433 -355.401996) (xy 426.851698 -355.398798) (xy 426.831415 -355.404156) (xy 426.82287 -355.410262)
			(xy 426.789234 -355.436243) (xy 426.717841 -355.482369) (xy 426.642371 -355.521471) (xy 426.563514 -355.553192)
			(xy 426.481991 -355.577244) (xy 426.398543 -355.593405) (xy 426.313935 -355.60153) (xy 426.271436 -355.602032)
			(xy 426.230327 -355.601513) (xy 426.148459 -355.593929) (xy 426.06764 -355.578822) (xy 425.98856 -355.556321)
			(xy 425.911894 -355.526617) (xy 425.838297 -355.489966) (xy 425.768396 -355.446679) (xy 425.702788 -355.397126)
			(xy 425.642034 -355.341729) (xy 425.58665 -355.280962) (xy 425.537111 -355.215344) (xy 425.49384 -355.145433)
			(xy 425.457204 -355.071828) (xy 425.427518 -354.995156) (xy 425.405034 -354.916071) (xy 425.389944 -354.835249)
			(xy 425.382378 -354.753379) (xy 425.381928 -354.71227) (xy 425.382471 -354.667499) (xy 425.391478 -354.578412)
			(xy 425.409387 -354.49068) (xy 425.436017 -354.40519) (xy 425.453048 -354.363782) (xy 425.45663 -354.354196)
			(xy 425.456619 -354.333749) (xy 425.453048 -354.324158) (xy 425.436017 -354.28275) (xy 425.409384 -354.197261)
			(xy 425.391479 -354.109528) (xy 425.382482 -354.020441) (xy 425.381928 -353.97567) (xy 425.381928 -353.963732)
			(xy 425.35545 -353.957782) (xy 425.303215 -353.943042) (xy 425.277534 -353.934268) (xy 425.269337 -353.931754)
			(xy 425.252203 -353.931754) (xy 425.244006 -353.934268) (xy 425.208787 -353.946222) (xy 425.136785 -353.964878)
			(xy 425.063465 -353.977388) (xy 424.98935 -353.983664) (xy 424.95216 -353.984052) (xy 424.914971 -353.983643)
			(xy 424.840858 -353.977359) (xy 424.767539 -353.964855) (xy 424.695532 -353.94622) (xy 424.660314 -353.934268)
			(xy 424.652117 -353.931754) (xy 424.634983 -353.931754) (xy 424.626786 -353.934268) (xy 424.591569 -353.946227)
			(xy 424.519566 -353.964882) (xy 424.446245 -353.977391) (xy 424.37213 -353.983665) (xy 424.33494 -353.984052)
			(xy 424.293 -353.983611) (xy 424.209499 -353.975641) (xy 424.127133 -353.95977) (xy 424.04665 -353.936141)
			(xy 423.968777 -353.904968) (xy 423.89422 -353.866534) (xy 423.823654 -353.821187) (xy 423.757718 -353.769337)
			(xy 423.697009 -353.711455) (xy 423.642078 -353.648063) (xy 423.593421 -353.579737) (xy 423.55148 -353.507095)
			(xy 423.516634 -353.430795) (xy 423.489198 -353.351528) (xy 423.469422 -353.270012) (xy 423.457484 -353.186985)
			(xy 423.453493 -353.1032) (xy 344.34922 -353.1032) (xy 344.346818 -353.129131) (xy 344.331712 -353.20995)
			(xy 344.309211 -353.289031) (xy 344.279508 -353.365698) (xy 344.242856 -353.439296) (xy 344.199569 -353.509197)
			(xy 344.150015 -353.574806) (xy 344.094618 -353.635561) (xy 344.03385 -353.690944) (xy 343.968231 -353.740483)
			(xy 343.898319 -353.783755) (xy 343.824713 -353.82039) (xy 343.748039 -353.850075) (xy 343.668954 -353.872558)
			(xy 343.58813 -353.887646) (xy 343.50626 -353.895211) (xy 343.46515 -353.89566) (xy 343.421566 -353.895134)
			(xy 343.334811 -353.886653) (xy 343.249302 -353.869729) (xy 343.165858 -353.844524) (xy 343.085279 -353.81128)
			(xy 343.046558 -353.791266) (xy 343.035092 -353.785848) (xy 343.009764 -353.785848) (xy 342.998298 -353.791266)
			(xy 342.959077 -353.812027) (xy 342.877306 -353.846516) (xy 342.792508 -353.872694) (xy 342.705525 -353.890299)
			(xy 342.617221 -353.899159) (xy 342.572848 -353.899724) (xy 342.534532 -353.899341) (xy 342.458179 -353.892813)
			(xy 342.382672 -353.879733) (xy 342.308573 -353.860197) (xy 342.272366 -353.847654) (xy 342.26405 -353.845068)
			(xy 342.246646 -353.845068) (xy 342.23833 -353.847654) (xy 342.202121 -353.860189) (xy 342.128019 -353.879707)
			(xy 342.052513 -353.892787) (xy 341.976163 -353.899332) (xy 341.937848 -353.899724) (xy 341.899532 -353.899341)
			(xy 341.823179 -353.892813) (xy 341.747672 -353.879733) (xy 341.673573 -353.860197) (xy 341.637366 -353.847654)
			(xy 341.62905 -353.845068) (xy 341.611646 -353.845068) (xy 341.60333 -353.847654) (xy 341.567121 -353.860189)
			(xy 341.493019 -353.879707) (xy 341.417513 -353.892787) (xy 341.341163 -353.899332) (xy 341.302848 -353.899724)
			(xy 341.264532 -353.899341) (xy 341.188179 -353.892813) (xy 341.112672 -353.879733) (xy 341.038573 -353.860197)
			(xy 341.002366 -353.847654) (xy 340.99405 -353.845068) (xy 340.976646 -353.845068) (xy 340.96833 -353.847654)
			(xy 340.932121 -353.860189) (xy 340.858019 -353.879707) (xy 340.782513 -353.892787) (xy 340.706163 -353.899332)
			(xy 340.667848 -353.899724) (xy 340.626539 -353.899263) (xy 340.544274 -353.89164) (xy 340.463071 -353.876418)
			(xy 340.38363 -353.853729) (xy 340.306637 -353.823768) (xy 340.232755 -353.786793) (xy 340.19744 -353.765358)
			(xy 340.189803 -353.761082) (xy 340.172701 -353.75742) (xy 340.155358 -353.759679) (xy 340.147402 -353.763326)
			(xy 340.109501 -353.782381) (xy 340.030769 -353.813979) (xy 339.949386 -353.837938) (xy 339.866091 -353.85404)
			(xy 339.781642 -353.862138) (xy 339.739224 -353.86264) (xy 339.73897 -353.86264) (xy 339.697862 -353.862216)
			(xy 339.615997 -353.854629) (xy 339.535181 -353.839522) (xy 339.456103 -353.817024) (xy 339.379438 -353.787327)
			(xy 339.30584 -353.750684) (xy 339.235936 -353.707408) (xy 339.170322 -353.657867) (xy 339.109558 -353.602485)
			(xy 339.054162 -353.541734) (xy 339.004606 -353.476131) (xy 338.961314 -353.406237) (xy 338.924655 -353.332646)
			(xy 338.89494 -353.255988) (xy 338.872425 -353.176916) (xy 338.857299 -353.096103) (xy 338.849693 -353.01424)
			(xy 338.849208 -352.973132) (xy 195.744851 -352.973132) (xy 195.771754 -353.027135) (xy 195.80147 -353.103792)
			(xy 195.823987 -353.182863) (xy 195.839114 -353.263674) (xy 195.846722 -353.345537) (xy 195.847208 -353.386644)
			(xy 195.846646 -353.431414) (xy 195.837635 -353.520499) (xy 195.81973 -353.60823) (xy 195.793111 -353.693721)
			(xy 195.776088 -353.735132) (xy 195.772497 -353.744715) (xy 195.772513 -353.765165) (xy 195.776088 -353.774756)
			(xy 195.793114 -353.816166) (xy 195.81975 -353.901654) (xy 195.837657 -353.989386) (xy 195.846654 -354.078474)
			(xy 195.847208 -354.123244) (xy 195.846646 -354.168014) (xy 195.837635 -354.257099) (xy 195.81973 -354.34483)
			(xy 195.793111 -354.430321) (xy 195.776088 -354.471732) (xy 195.772497 -354.481315) (xy 195.772513 -354.501765)
			(xy 195.776088 -354.511356) (xy 195.793114 -354.552766) (xy 195.81975 -354.638254) (xy 195.837657 -354.725986)
			(xy 195.846654 -354.815074) (xy 195.847208 -354.859844) (xy 195.84679 -354.900955) (xy 195.839198 -354.982827)
			(xy 195.824083 -355.063648) (xy 195.801575 -355.14273) (xy 195.771864 -355.219398) (xy 195.742079 -355.279198)
			(xy 285.476188 -355.279198) (xy 285.476597 -355.238082) (xy 285.484185 -355.1562) (xy 285.499295 -355.075367)
			(xy 285.5218 -354.996274) (xy 285.551507 -354.919594) (xy 285.588163 -354.845983) (xy 285.631455 -354.776069)
			(xy 285.681013 -354.710447) (xy 285.736414 -354.649677) (xy 285.797187 -354.594279) (xy 285.862811 -354.544725)
			(xy 285.932729 -354.501438) (xy 286.006342 -354.464786) (xy 286.083023 -354.435084) (xy 286.162118 -354.412584)
			(xy 286.242951 -354.397477) (xy 286.324834 -354.389894) (xy 286.36595 -354.389436) (xy 286.404239 -354.389856)
			(xy 286.480533 -354.39646) (xy 286.555976 -354.409605) (xy 286.630007 -354.429194) (xy 286.666178 -354.44176)
			(xy 286.674615 -354.444411) (xy 286.692285 -354.444411) (xy 286.700722 -354.44176) (xy 286.736903 -354.429226)
			(xy 286.810935 -354.409651) (xy 286.886373 -354.396501) (xy 286.962662 -354.389874) (xy 287.00095 -354.389436)
			(xy 287.039239 -354.389856) (xy 287.115533 -354.39646) (xy 287.190976 -354.409605) (xy 287.265007 -354.429194)
			(xy 287.301178 -354.44176) (xy 287.309615 -354.444411) (xy 287.327285 -354.444411) (xy 287.335722 -354.44176)
			(xy 287.371903 -354.429226) (xy 287.445935 -354.409651) (xy 287.521373 -354.396501) (xy 287.597662 -354.389874)
			(xy 287.63595 -354.389436) (xy 287.674239 -354.389856) (xy 287.750533 -354.39646) (xy 287.825976 -354.409605)
			(xy 287.900007 -354.429194) (xy 287.936178 -354.44176) (xy 287.944615 -354.444411) (xy 287.962285 -354.444411)
			(xy 287.970722 -354.44176) (xy 288.006903 -354.429226) (xy 288.080935 -354.409651) (xy 288.156373 -354.396501)
			(xy 288.232662 -354.389874) (xy 288.27095 -354.389436) (xy 288.309239 -354.389856) (xy 288.385533 -354.39646)
			(xy 288.460976 -354.409605) (xy 288.535007 -354.429194) (xy 288.571178 -354.44176) (xy 288.579615 -354.444411)
			(xy 288.597285 -354.444411) (xy 288.605722 -354.44176) (xy 288.641903 -354.429226) (xy 288.715935 -354.409651)
			(xy 288.791373 -354.396501) (xy 288.867662 -354.389874) (xy 288.90595 -354.389436) (xy 288.947064 -354.389946)
			(xy 289.028942 -354.397529) (xy 289.10977 -354.412634) (xy 289.18886 -354.435133) (xy 289.265537 -354.464834)
			(xy 289.339146 -354.501483) (xy 289.409059 -354.544768) (xy 289.47468 -354.594319) (xy 289.535449 -354.649714)
			(xy 289.590847 -354.71048) (xy 289.640402 -354.776098) (xy 289.683691 -354.846009) (xy 289.720345 -354.919615)
			(xy 289.75005 -354.99629) (xy 289.772554 -355.075379) (xy 289.787664 -355.156207) (xy 289.795251 -355.238084)
			(xy 289.795712 -355.279198) (xy 289.795298 -355.318061) (xy 289.788487 -355.395488) (xy 289.77495 -355.472025)
			(xy 289.75479 -355.547092) (xy 289.741864 -355.583744) (xy 289.739034 -355.592628) (xy 289.739308 -355.611259)
			(xy 289.742372 -355.620066) (xy 289.757559 -355.659473) (xy 289.781314 -355.740522) (xy 289.797291 -355.823456)
			(xy 289.805346 -355.907529) (xy 289.805872 -355.949758) (xy 289.805454 -355.988048) (xy 289.79885 -356.064341)
			(xy 289.785704 -356.139784) (xy 289.766114 -356.213815) (xy 289.753548 -356.249986) (xy 289.750918 -356.258428)
			(xy 289.750905 -356.276094) (xy 289.753548 -356.28453) (xy 289.766084 -356.32071) (xy 289.785659 -356.394742)
			(xy 289.798808 -356.470181) (xy 289.805435 -356.54647) (xy 289.805872 -356.584758) (xy 289.805362 -356.625872)
			(xy 289.797778 -356.707749) (xy 289.782672 -356.788578) (xy 289.760173 -356.867667) (xy 289.730472 -356.944344)
			(xy 289.693822 -357.017952) (xy 289.650537 -357.087865) (xy 289.600986 -357.153486) (xy 289.545592 -357.214255)
			(xy 289.484826 -357.269653) (xy 289.419208 -357.319208) (xy 289.349298 -357.362497) (xy 289.275691 -357.399151)
			(xy 289.199017 -357.428856) (xy 289.119928 -357.45136) (xy 289.039101 -357.466471) (xy 288.957224 -357.474059)
			(xy 288.91611 -357.47452) (xy 288.87782 -357.474114) (xy 288.801526 -357.467506) (xy 288.726084 -357.454357)
			(xy 288.652053 -357.434764) (xy 288.615882 -357.422196) (xy 288.607445 -357.419545) (xy 288.589775 -357.419545)
			(xy 288.581338 -357.422196) (xy 288.54516 -357.434739) (xy 288.471127 -357.454312) (xy 288.395688 -357.46746)
			(xy 288.319398 -357.474084) (xy 288.28111 -357.47452) (xy 288.24282 -357.474114) (xy 288.166526 -357.467506)
			(xy 288.091084 -357.454357) (xy 288.017053 -357.434764) (xy 287.980882 -357.422196) (xy 287.972445 -357.419545)
			(xy 287.954775 -357.419545) (xy 287.946338 -357.422196) (xy 287.91016 -357.434739) (xy 287.836127 -357.454312)
			(xy 287.760688 -357.46746) (xy 287.684398 -357.474084) (xy 287.64611 -357.47452) (xy 287.60782 -357.474114)
			(xy 287.531526 -357.467506) (xy 287.456084 -357.454357) (xy 287.382053 -357.434764) (xy 287.345882 -357.422196)
			(xy 287.337445 -357.419545) (xy 287.319775 -357.419545) (xy 287.311338 -357.422196) (xy 287.27516 -357.434739)
			(xy 287.201127 -357.454312) (xy 287.125688 -357.46746) (xy 287.049398 -357.474084) (xy 287.01111 -357.47452)
			(xy 286.97282 -357.474114) (xy 286.896526 -357.467506) (xy 286.821084 -357.454357) (xy 286.747053 -357.434764)
			(xy 286.710882 -357.422196) (xy 286.702445 -357.419545) (xy 286.684775 -357.419545) (xy 286.676338 -357.422196)
			(xy 286.64016 -357.434739) (xy 286.566127 -357.454312) (xy 286.490688 -357.46746) (xy 286.414398 -357.474084)
			(xy 286.37611 -357.47452) (xy 286.334994 -357.474092) (xy 286.253113 -357.466505) (xy 286.172281 -357.451395)
			(xy 286.093188 -357.428892) (xy 286.016509 -357.399186) (xy 285.942899 -357.362532) (xy 285.872984 -357.319241)
			(xy 285.807362 -357.269685) (xy 285.746593 -357.214284) (xy 285.691195 -357.153513) (xy 285.641641 -357.08789)
			(xy 285.598353 -357.017973) (xy 285.561701 -356.944361) (xy 285.531998 -356.867681) (xy 285.509497 -356.788588)
			(xy 285.49439 -356.707755) (xy 285.486807 -356.625874) (xy 285.486348 -356.584758) (xy 285.48677 -356.546469)
			(xy 285.493373 -356.470175) (xy 285.506518 -356.394732) (xy 285.526107 -356.320701) (xy 285.538672 -356.28453)
			(xy 285.541343 -356.276098) (xy 285.541329 -356.258423) (xy 285.538672 -356.249986) (xy 285.526141 -356.213804)
			(xy 285.506565 -356.139773) (xy 285.493414 -356.064334) (xy 285.486786 -355.988046) (xy 285.486348 -355.949758)
			(xy 285.486781 -355.910896) (xy 285.493587 -355.833469) (xy 285.507119 -355.756932) (xy 285.527272 -355.681865)
			(xy 285.540196 -355.645212) (xy 285.542998 -355.636321) (xy 285.542744 -355.617697) (xy 285.539688 -355.60889)
			(xy 285.524486 -355.569489) (xy 285.500735 -355.488437) (xy 285.484763 -355.405502) (xy 285.476712 -355.321427)
			(xy 285.476188 -355.279198) (xy 195.742079 -355.279198) (xy 195.735206 -355.292996) (xy 195.691912 -355.362897)
			(xy 195.642352 -355.428505) (xy 195.586949 -355.48926) (xy 195.526176 -355.544642) (xy 195.460551 -355.59418)
			(xy 195.390636 -355.637451) (xy 195.317025 -355.674085) (xy 195.240348 -355.703769) (xy 195.161258 -355.726251)
			(xy 195.080432 -355.741339) (xy 194.998557 -355.748903) (xy 194.957446 -355.749352) (xy 194.915842 -355.74888)
			(xy 194.832994 -355.741147) (xy 194.75123 -355.725716) (xy 194.671262 -355.702722) (xy 194.593789 -355.672366)
			(xy 194.519488 -355.634911) (xy 194.48399 -355.613208) (xy 194.474858 -355.608031) (xy 194.454138 -355.60482)
			(xy 194.433861 -355.61016) (xy 194.425316 -355.616256) (xy 194.391667 -355.642178) (xy 194.320293 -355.688236)
			(xy 194.244854 -355.727283) (xy 194.166037 -355.758962) (xy 194.08456 -355.782986) (xy 194.001164 -355.799135)
			(xy 193.916608 -355.807262) (xy 193.874136 -355.807772) (xy 193.873882 -355.807772) (xy 193.832775 -355.807305)
			(xy 193.750912 -355.799719) (xy 193.670098 -355.784614) (xy 193.591023 -355.762118) (xy 193.514359 -355.732423)
			(xy 193.440762 -355.695782) (xy 193.370859 -355.652509) (xy 193.305245 -355.602971) (xy 193.244482 -355.547592)
			(xy 193.189086 -355.486844) (xy 193.13953 -355.421244) (xy 193.096237 -355.351353) (xy 193.059577 -355.277766)
			(xy 193.029861 -355.201111) (xy 193.007343 -355.122041) (xy 192.992215 -355.041231) (xy 192.984607 -354.959371)
			(xy 192.98412 -354.918264) (xy 192.984683 -354.873494) (xy 192.993693 -354.784409) (xy 193.011598 -354.696678)
			(xy 193.038217 -354.611187) (xy 193.05524 -354.569776) (xy 193.058825 -354.560191) (xy 193.058812 -354.539743)
			(xy 193.05524 -354.530152) (xy 193.03824 -354.4888) (xy 193.011628 -354.403438) (xy 192.99372 -354.315836)
			(xy 192.984697 -354.226879) (xy 192.98412 -354.182172) (xy 192.98412 -354.181156) (xy 192.984374 -354.169726)
			(xy 192.957895 -354.163781) (xy 192.90566 -354.149038) (xy 192.87998 -354.140262) (xy 192.871783 -354.137748)
			(xy 192.854649 -354.137748) (xy 192.846452 -354.140262) (xy 192.811236 -354.152209) (xy 192.739226 -354.170796)
			(xy 192.665903 -354.183236) (xy 192.591792 -354.18944) (xy 192.554606 -354.189792) (xy 192.517422 -354.189422)
			(xy 192.443314 -354.1832) (xy 192.369994 -354.170758) (xy 192.297983 -354.152184) (xy 192.26276 -354.140262)
			(xy 192.254563 -354.137748) (xy 192.237429 -354.137748) (xy 192.229232 -354.140262) (xy 192.19413 -354.15215)
			(xy 192.122374 -354.1707) (xy 192.049311 -354.183146) (xy 191.97546 -354.189399) (xy 191.938402 -354.189792)
			(xy 191.937386 -354.189792) (xy 191.89546 -354.189345) (xy 191.811988 -354.181373) (xy 191.729651 -354.165503)
			(xy 191.649196 -354.141878) (xy 191.57135 -354.110712) (xy 191.49682 -354.072288) (xy 191.42628 -354.026953)
			(xy 191.360368 -353.975119) (xy 191.299682 -353.917254) (xy 191.244771 -353.853882) (xy 191.196132 -353.785578)
			(xy 191.154206 -353.71296) (xy 191.119373 -353.636685) (xy 191.091948 -353.557444) (xy 191.07218 -353.475956)
			(xy 191.060246 -353.392957) (xy 191.056256 -353.3092) (xy 187.519078 -353.3092) (xy 187.520094 -353.320137)
			(xy 187.52058 -353.361244) (xy 187.52002 -353.406014) (xy 187.511009 -353.495099) (xy 187.493104 -353.58283)
			(xy 187.466484 -353.668321) (xy 187.44946 -353.709732) (xy 187.44587 -353.719315) (xy 187.445886 -353.739765)
			(xy 187.44946 -353.749356) (xy 187.466484 -353.790767) (xy 187.493121 -353.876254) (xy 187.511029 -353.963986)
			(xy 187.520026 -354.053074) (xy 187.52058 -354.097844) (xy 187.52002 -354.142614) (xy 187.511009 -354.231699)
			(xy 187.493104 -354.31943) (xy 187.466484 -354.404921) (xy 187.44946 -354.446332) (xy 187.44587 -354.455915)
			(xy 187.445886 -354.476365) (xy 187.44946 -354.485956) (xy 187.466484 -354.527367) (xy 187.493121 -354.612854)
			(xy 187.511029 -354.700586) (xy 187.520026 -354.789674) (xy 187.52058 -354.834444) (xy 187.520189 -354.875556)
			(xy 187.512597 -354.957429) (xy 187.497482 -355.038252) (xy 187.474973 -355.117336) (xy 187.445261 -355.194004)
			(xy 187.408601 -355.267604) (xy 187.365306 -355.337506) (xy 187.315744 -355.403115) (xy 187.260339 -355.46387)
			(xy 187.199564 -355.519252) (xy 187.133937 -355.56879) (xy 187.064019 -355.61206) (xy 186.990406 -355.648693)
			(xy 186.913727 -355.678376) (xy 186.834635 -355.700857) (xy 186.753806 -355.715942) (xy 186.67193 -355.723505)
			(xy 186.630818 -355.723952) (xy 186.589214 -355.723494) (xy 186.506365 -355.715758) (xy 186.424601 -355.700325)
			(xy 186.344633 -355.677328) (xy 186.267161 -355.646969) (xy 186.192859 -355.609513) (xy 186.157362 -355.587808)
			(xy 186.148243 -355.582606) (xy 186.127514 -355.579404) (xy 186.107233 -355.584754) (xy 186.098688 -355.590856)
			(xy 186.065049 -355.616791) (xy 185.993673 -355.662848) (xy 185.918232 -355.701893) (xy 185.839413 -355.73357)
			(xy 185.757935 -355.757592) (xy 185.674537 -355.773739) (xy 185.589981 -355.781864) (xy 185.547508 -355.782372)
			(xy 185.547254 -355.782372) (xy 185.506147 -355.781931) (xy 185.424283 -355.774343) (xy 185.343469 -355.759235)
			(xy 185.264393 -355.736737) (xy 185.187729 -355.70704) (xy 185.114132 -355.670398) (xy 185.044229 -355.627122)
			(xy 184.978615 -355.577583) (xy 184.917852 -355.522202) (xy 184.862456 -355.461452) (xy 184.812901 -355.395851)
			(xy 184.769609 -355.325959) (xy 184.732948 -355.252371) (xy 184.703232 -355.175714) (xy 184.680715 -355.096644)
			(xy 184.665587 -355.015833) (xy 184.657979 -354.933971) (xy 184.657492 -354.892864) (xy 184.658057 -354.848094)
			(xy 184.667066 -354.759009) (xy 184.684971 -354.671278) (xy 184.711589 -354.585787) (xy 184.728612 -354.544376)
			(xy 184.732199 -354.534792) (xy 184.732185 -354.514343) (xy 184.728612 -354.504752) (xy 184.711616 -354.463398)
			(xy 184.685002 -354.378037) (xy 184.667093 -354.290435) (xy 184.658069 -354.201478) (xy 184.657492 -354.156772)
			(xy 184.657492 -354.155756) (xy 184.657746 -354.144326) (xy 184.631266 -354.138384) (xy 184.579032 -354.123639)
			(xy 184.553352 -354.114862) (xy 184.545155 -354.112348) (xy 184.528021 -354.112348) (xy 184.519824 -354.114862)
			(xy 184.484602 -354.126789) (xy 184.412594 -354.145381) (xy 184.339273 -354.157827) (xy 184.265163 -354.164037)
			(xy 184.227978 -354.164392) (xy 184.190794 -354.16403) (xy 184.116686 -354.157806) (xy 184.043366 -354.145361)
			(xy 183.971355 -354.126785) (xy 183.936132 -354.114862) (xy 183.927935 -354.112348) (xy 183.910801 -354.112348)
			(xy 183.902604 -354.114862) (xy 183.867505 -354.126757) (xy 183.795747 -354.145305) (xy 183.722684 -354.157749)
			(xy 183.648832 -354.164001) (xy 183.611774 -354.164392) (xy 183.610758 -354.164392) (xy 183.568833 -354.163944)
			(xy 183.485362 -354.155969) (xy 183.403028 -354.140097) (xy 183.322575 -354.11647) (xy 183.244732 -354.085304)
			(xy 183.170204 -354.046879) (xy 183.099666 -354.001544) (xy 183.033756 -353.949709) (xy 182.973072 -353.891844)
			(xy 182.918163 -353.828473) (xy 182.869527 -353.760169) (xy 182.827603 -353.687552) (xy 182.792771 -353.611278)
			(xy 182.765347 -353.532039) (xy 182.745579 -353.450553) (xy 182.733646 -353.367555) (xy 182.729656 -353.2838)
			(xy 78.346936 -353.2838) (xy 78.321217 -353.348042) (xy 78.282395 -353.423345) (xy 78.236592 -353.494617)
			(xy 78.184221 -353.561213) (xy 78.125756 -353.622528) (xy 78.061728 -353.678009) (xy 77.992716 -353.727152)
			(xy 77.919346 -353.769512) (xy 77.842281 -353.804707) (xy 77.762219 -353.832416) (xy 77.679886 -353.85239)
			(xy 77.596027 -353.864447) (xy 77.511402 -353.868479) (xy 77.426777 -353.864447) (xy 77.342918 -353.85239)
			(xy 77.260585 -353.832416) (xy 77.180523 -353.804707) (xy 77.103458 -353.769512) (xy 77.030088 -353.727152)
			(xy 76.961076 -353.678009) (xy 76.897048 -353.622528) (xy 76.838583 -353.561213) (xy 76.786212 -353.494617)
			(xy 76.740409 -353.423345) (xy 76.701587 -353.348042) (xy 76.670099 -353.26939) (xy 76.646231 -353.1881)
			(xy 76.630197 -353.10491) (xy 76.622144 -353.020573) (xy 76.62164 -352.978212) (xy 76.622159 -352.935266)
			(xy 76.630462 -352.849776) (xy 76.646954 -352.765482) (xy 76.671481 -352.683166) (xy 76.687172 -352.643186)
			(xy 76.690418 -352.63393) (xy 76.690431 -352.614336) (xy 76.687172 -352.605086) (xy 76.671432 -352.565089)
			(xy 76.646875 -352.482712) (xy 76.630388 -352.398348) (xy 76.622124 -352.312786) (xy 76.62164 -352.269806)
			(xy 76.622244 -352.224161) (xy 76.631638 -352.133355) (xy 76.650266 -352.043985) (xy 76.66355 -352.000312)
			(xy 76.665996 -351.9913) (xy 76.664956 -351.972672) (xy 76.661518 -351.96399) (xy 76.642856 -351.920903)
			(xy 76.61365 -351.831658) (xy 76.594004 -351.739834) (xy 76.584137 -351.646451) (xy 76.58354 -351.5995)
			(xy 75.70064 -351.5995) (xy 75.701144 -351.637854) (xy 75.70053 -351.683499) (xy 75.691141 -351.774304)
			(xy 75.672516 -351.863674) (xy 75.659234 -351.907348) (xy 75.65681 -351.916364) (xy 75.657836 -351.934988)
			(xy 75.661266 -351.94367) (xy 75.679947 -351.986749) (xy 75.709149 -352.075997) (xy 75.728789 -352.167824)
			(xy 75.738651 -352.261208) (xy 75.739244 -352.30816) (xy 75.738798 -352.348493) (xy 75.731529 -352.428831)
			(xy 75.71702 -352.508181) (xy 75.69539 -352.585893) (xy 75.666817 -352.661328) (xy 75.649582 -352.697796)
			(xy 75.645066 -352.708391) (xy 75.645063 -352.731399) (xy 75.649582 -352.741992) (xy 75.666819 -352.778431)
			(xy 75.69537 -352.853821) (xy 75.716991 -352.931483) (xy 75.731505 -353.010781) (xy 75.738793 -353.091066)
			(xy 75.739244 -353.131374) (xy 75.73874 -353.173735) (xy 75.730687 -353.258072) (xy 75.714653 -353.341262)
			(xy 75.690785 -353.422552) (xy 75.659297 -353.501204) (xy 75.620475 -353.576507) (xy 75.574672 -353.647779)
			(xy 75.522301 -353.714375) (xy 75.463836 -353.77569) (xy 75.399808 -353.831171) (xy 75.330796 -353.880314)
			(xy 75.257426 -353.922674) (xy 75.180361 -353.957869) (xy 75.100299 -353.985578) (xy 75.017966 -354.005552)
			(xy 74.934107 -354.017609) (xy 74.849482 -354.021641) (xy 74.764857 -354.017609) (xy 74.680998 -354.005552)
			(xy 74.598665 -353.985578) (xy 74.518603 -353.957869) (xy 74.441538 -353.922674) (xy 74.368168 -353.880314)
			(xy 74.299156 -353.831171) (xy 74.235128 -353.77569) (xy 74.176663 -353.714375) (xy 74.124292 -353.647779)
			(xy 74.078489 -353.576507) (xy 74.039667 -353.501204) (xy 74.008179 -353.422552) (xy 73.984311 -353.341262)
			(xy 73.968277 -353.258072) (xy 73.960224 -353.173735) (xy 73.95972 -353.131374) (xy 73.960164 -353.091034)
			(xy 73.96747 -353.010685) (xy 73.982028 -352.931329) (xy 74.003719 -352.85362) (xy 74.032363 -352.778196)
			(xy 74.049636 -352.741738) (xy 74.054225 -352.731091) (xy 74.054231 -352.707932) (xy 74.049636 -352.697288)
			(xy 74.032445 -352.660861) (xy 74.003936 -352.58552) (xy 73.98236 -352.50791) (xy 73.967893 -352.428665)
			(xy 73.960655 -352.348437) (xy 73.960228 -352.30816) (xy 73.960797 -352.262521) (xy 73.970094 -352.171718)
			(xy 73.988639 -352.082344) (xy 74.001884 -352.038666) (xy 74.004352 -352.029659) (xy 74.003297 -352.011026)
			(xy 73.999852 -352.002344) (xy 73.981136 -351.959272) (xy 73.95186 -351.870033) (xy 73.932154 -351.778206)
			(xy 73.922237 -351.684813) (xy 73.92162 -351.637854) (xy 2.509012 -351.637854) (xy 2.509012 -358.071674)
			(xy 14.438884 -358.071674) (xy 14.438884 -357.208074) (xy 14.43937 -357.180805) (xy 14.447132 -357.126821)
			(xy 14.462497 -357.074491) (xy 14.485154 -357.024881) (xy 14.51464 -356.979) (xy 14.550355 -356.937783)
			(xy 14.591572 -356.902068) (xy 14.637453 -356.872582) (xy 14.687063 -356.849925) (xy 14.739393 -356.83456)
			(xy 14.793377 -356.826798) (xy 14.847915 -356.826798) (xy 14.901899 -356.83456) (xy 14.954229 -356.849925)
			(xy 15.003839 -356.872582) (xy 15.04972 -356.902068) (xy 15.090937 -356.937783) (xy 15.126652 -356.979)
			(xy 15.156138 -357.024881) (xy 15.178795 -357.074491) (xy 15.19416 -357.126821) (xy 15.201922 -357.180805)
			(xy 15.202408 -357.208074) (xy 15.202408 -358.071674) (xy 15.201922 -358.098943) (xy 15.19416 -358.152927)
			(xy 15.178795 -358.205257) (xy 15.156138 -358.254867) (xy 15.126652 -358.300748) (xy 15.090937 -358.341965)
			(xy 15.04972 -358.37768) (xy 15.003839 -358.407166) (xy 14.954229 -358.429823) (xy 14.901899 -358.445188)
			(xy 14.847915 -358.45295) (xy 14.793377 -358.45295) (xy 14.739393 -358.445188) (xy 14.687063 -358.429823)
			(xy 14.637453 -358.407166) (xy 14.591572 -358.37768) (xy 14.550355 -358.341965) (xy 14.51464 -358.300748)
			(xy 14.485154 -358.254867) (xy 14.462497 -358.205257) (xy 14.447132 -358.152927) (xy 14.43937 -358.098943)
			(xy 14.438884 -358.071674) (xy 2.509012 -358.071674) (xy 2.509012 -358.549194) (xy 40.47998 -358.549194)
			(xy 40.480352 -358.511134) (xy 40.486825 -358.435291) (xy 40.499758 -358.360279) (xy 40.519056 -358.286646)
			(xy 40.544577 -358.214933) (xy 40.55999 -358.180132) (xy 40.563435 -358.171803) (xy 40.56487 -358.153848)
			(xy 40.562784 -358.14508) (xy 40.551663 -358.104882) (xy 40.536092 -358.022938) (xy 40.528245 -357.939897)
			(xy 40.527732 -357.898192) (xy 40.528135 -357.859902) (xy 40.534744 -357.783608) (xy 40.547894 -357.708165)
			(xy 40.567488 -357.634135) (xy 40.580056 -357.597964) (xy 40.58271 -357.589528) (xy 40.582708 -357.571857)
			(xy 40.580056 -357.56342) (xy 40.567506 -357.527245) (xy 40.547935 -357.453211) (xy 40.53479 -357.37777)
			(xy 40.528167 -357.30148) (xy 40.527732 -357.263192) (xy 40.528236 -357.220831) (xy 40.536289 -357.136494)
			(xy 40.552323 -357.053304) (xy 40.576191 -356.972014) (xy 40.607679 -356.893362) (xy 40.646501 -356.818059)
			(xy 40.692304 -356.746787) (xy 40.744675 -356.680191) (xy 40.80314 -356.618876) (xy 40.867168 -356.563395)
			(xy 40.93618 -356.514252) (xy 41.00955 -356.471892) (xy 41.086615 -356.436697) (xy 41.166677 -356.408988)
			(xy 41.24901 -356.389014) (xy 41.332869 -356.376957) (xy 41.417494 -356.372926) (xy 41.502119 -356.376957)
			(xy 41.585978 -356.389014) (xy 41.668311 -356.408988) (xy 41.748373 -356.436697) (xy 41.825438 -356.471892)
			(xy 41.898808 -356.514252) (xy 41.96782 -356.563395) (xy 42.031848 -356.618876) (xy 42.090313 -356.680191)
			(xy 42.142684 -356.746787) (xy 42.188487 -356.818059) (xy 42.227309 -356.893362) (xy 42.258797 -356.972014)
			(xy 42.282665 -357.053304) (xy 42.298699 -357.136494) (xy 42.306752 -357.220831) (xy 42.307256 -357.263192)
			(xy 42.306849 -357.301482) (xy 42.300241 -357.377776) (xy 42.287093 -357.453218) (xy 42.2675 -357.527249)
			(xy 42.254932 -357.56342) (xy 42.252286 -357.571858) (xy 42.252283 -357.589527) (xy 42.254932 -357.597964)
			(xy 42.267477 -357.634141) (xy 42.28705 -357.708174) (xy 42.300196 -357.783614) (xy 42.30682 -357.859904)
			(xy 42.307256 -357.898192) (xy 42.306876 -357.936251) (xy 42.300404 -358.012094) (xy 42.287473 -358.087107)
			(xy 42.268177 -358.160739) (xy 42.242658 -358.232452) (xy 42.227246 -358.267254) (xy 42.223809 -358.275586)
			(xy 42.222368 -358.293538) (xy 42.224452 -358.302306) (xy 42.23557 -358.342505) (xy 42.251142 -358.424449)
			(xy 42.258991 -358.507489) (xy 42.259032 -358.51084) (xy 43.046396 -358.51084) (xy 43.046759 -358.47278)
			(xy 43.053225 -358.396935) (xy 43.066156 -358.321921) (xy 43.085458 -358.248289) (xy 43.110988 -358.176577)
			(xy 43.126406 -358.141778) (xy 43.129746 -358.133421) (xy 43.131033 -358.115482) (xy 43.128946 -358.106726)
			(xy 43.117873 -358.066521) (xy 43.102375 -357.984574) (xy 43.094614 -357.901538) (xy 43.094148 -357.859838)
			(xy 43.094524 -357.821522) (xy 43.101053 -357.745169) (xy 43.114136 -357.669662) (xy 43.133673 -357.595562)
			(xy 43.146218 -357.559356) (xy 43.148787 -357.551035) (xy 43.148799 -357.533636) (xy 43.146218 -357.52532)
			(xy 43.13374 -357.489193) (xy 43.114246 -357.415282) (xy 43.101158 -357.339973) (xy 43.094573 -357.263819)
			(xy 43.094148 -357.2256) (xy 43.094148 -357.224838) (xy 43.094652 -357.18249) (xy 43.102703 -357.098176)
			(xy 43.118732 -357.01501) (xy 43.142593 -356.933743) (xy 43.174072 -356.855113) (xy 43.212883 -356.779832)
			(xy 43.258673 -356.70858) (xy 43.311029 -356.642004) (xy 43.369477 -356.580706) (xy 43.433487 -356.525241)
			(xy 43.502479 -356.476112) (xy 43.575829 -356.433763) (xy 43.652872 -356.398579) (xy 43.732911 -356.370877)
			(xy 43.81522 -356.350909) (xy 43.899055 -356.338856) (xy 43.983656 -356.334826) (xy 44.068257 -356.338856)
			(xy 44.152092 -356.350909) (xy 44.234401 -356.370877) (xy 44.31444 -356.398579) (xy 44.391483 -356.433763)
			(xy 44.464833 -356.476112) (xy 44.533825 -356.525241) (xy 44.597835 -356.580706) (xy 44.656283 -356.642004)
			(xy 44.708639 -356.70858) (xy 44.754429 -356.779832) (xy 44.79324 -356.855113) (xy 44.824719 -356.933743)
			(xy 44.84858 -357.01501) (xy 44.864609 -357.098176) (xy 44.87266 -357.18249) (xy 44.873164 -357.224838)
			(xy 44.873164 -357.2256) (xy 44.87277 -357.263821) (xy 44.866201 -357.339979) (xy 44.853113 -357.415292)
			(xy 44.833602 -357.489202) (xy 44.821094 -357.52532) (xy 44.818487 -357.533631) (xy 44.818499 -357.55104)
			(xy 44.821094 -357.559356) (xy 44.833623 -357.595567) (xy 44.853143 -357.669669) (xy 44.866225 -357.745173)
			(xy 44.872771 -357.821523) (xy 44.873164 -357.859838) (xy 44.872788 -357.897898) (xy 44.866324 -357.973742)
			(xy 44.853395 -358.048756) (xy 44.837736 -358.108504) (xy 46.991016 -358.108504) (xy 46.991397 -358.070445)
			(xy 46.997869 -357.994602) (xy 47.0108 -357.919589) (xy 47.030096 -357.845957) (xy 47.055615 -357.774244)
			(xy 47.071026 -357.739442) (xy 47.074466 -357.731111) (xy 47.075906 -357.713158) (xy 47.07382 -357.70439)
			(xy 47.0627 -357.664192) (xy 47.047129 -357.582247) (xy 47.039281 -357.499207) (xy 47.038768 -357.457502)
			(xy 47.039173 -357.419212) (xy 47.045781 -357.342918) (xy 47.05893 -357.267476) (xy 47.078524 -357.193445)
			(xy 47.091092 -357.157274) (xy 47.09374 -357.148837) (xy 47.093741 -357.131167) (xy 47.091092 -357.12273)
			(xy 47.078546 -357.086553) (xy 47.058974 -357.01252) (xy 47.045827 -356.93708) (xy 47.039204 -356.86079)
			(xy 47.038768 -356.822502) (xy 47.0392 -356.781386) (xy 47.046788 -356.699506) (xy 47.061898 -356.618674)
			(xy 47.084402 -356.539582) (xy 47.114108 -356.462904) (xy 47.150762 -356.389293) (xy 47.194052 -356.319379)
			(xy 47.243609 -356.253758) (xy 47.299008 -356.192989) (xy 47.359779 -356.137591) (xy 47.425402 -356.088036)
			(xy 47.495318 -356.044749) (xy 47.568929 -356.008097) (xy 47.645609 -355.978393) (xy 47.724702 -355.955891)
			(xy 47.805533 -355.940784) (xy 47.887414 -355.933199) (xy 47.92853 -355.93274) (xy 47.969637 -355.933252)
			(xy 48.051499 -355.940877) (xy 48.132307 -355.956023) (xy 48.211373 -355.97856) (xy 48.288023 -356.008296)
			(xy 48.325024 -356.026212) (xy 48.335846 -356.030917) (xy 48.359414 -356.030917) (xy 48.370236 -356.026212)
			(xy 48.407247 -356.008316) (xy 48.483894 -355.978575) (xy 48.562957 -355.956031) (xy 48.643763 -355.940876)
			(xy 48.725623 -355.93324) (xy 48.76673 -355.93274) (xy 48.80502 -355.933136) (xy 48.881314 -355.939747)
			(xy 48.956757 -355.952899) (xy 49.030787 -355.972495) (xy 49.066958 -355.985064) (xy 49.075395 -355.987715)
			(xy 49.093065 -355.987715) (xy 49.101502 -355.985064) (xy 49.137675 -355.972508) (xy 49.21171 -355.952938)
			(xy 49.287151 -355.939795) (xy 49.363442 -355.933174) (xy 49.40173 -355.93274) (xy 49.44002 -355.933136)
			(xy 49.516314 -355.939747) (xy 49.591757 -355.952899) (xy 49.665787 -355.972495) (xy 49.701958 -355.985064)
			(xy 49.710395 -355.987715) (xy 49.728065 -355.987715) (xy 49.736502 -355.985064) (xy 49.772675 -355.972508)
			(xy 49.84671 -355.952938) (xy 49.922151 -355.939795) (xy 49.998442 -355.933174) (xy 50.03673 -355.93274)
			(xy 50.07502 -355.933136) (xy 50.151314 -355.939747) (xy 50.226757 -355.952899) (xy 50.300787 -355.972495)
			(xy 50.336958 -355.985064) (xy 50.345395 -355.987715) (xy 50.363065 -355.987715) (xy 50.371502 -355.985064)
			(xy 50.407675 -355.972508) (xy 50.48171 -355.952938) (xy 50.557151 -355.939795) (xy 50.633442 -355.933174)
			(xy 50.67173 -355.93274) (xy 50.712845 -355.933184) (xy 50.794723 -355.940774) (xy 50.875552 -355.955886)
			(xy 50.954642 -355.978392) (xy 51.031318 -356.008098) (xy 51.104926 -356.044753) (xy 51.174838 -356.088043)
			(xy 51.240458 -356.137599) (xy 51.301225 -356.192997) (xy 51.356622 -356.253767) (xy 51.406175 -356.319388)
			(xy 51.449463 -356.389302) (xy 51.486115 -356.462911) (xy 51.515819 -356.539588) (xy 51.538321 -356.618679)
			(xy 51.55343 -356.699508) (xy 51.561017 -356.781387) (xy 51.561492 -356.822502) (xy 51.561091 -356.860792)
			(xy 51.554482 -356.937086) (xy 51.541332 -357.012529) (xy 51.521737 -357.086559) (xy 51.509168 -357.12273)
			(xy 51.506515 -357.131166) (xy 51.506516 -357.148837) (xy 51.509168 -357.157274) (xy 51.521713 -357.193451)
			(xy 51.541286 -357.267484) (xy 51.554433 -357.342924) (xy 51.561057 -357.419214) (xy 51.561492 -357.457502)
			(xy 51.561112 -357.495561) (xy 51.55464 -357.571404) (xy 51.541708 -357.646417) (xy 51.522413 -357.720049)
			(xy 51.496894 -357.791762) (xy 51.481482 -357.826564) (xy 51.478039 -357.834894) (xy 51.476603 -357.852848)
			(xy 51.478688 -357.861616) (xy 51.48981 -357.901814) (xy 51.50538 -357.983758) (xy 51.513227 -358.066799)
			(xy 51.51374 -358.108504) (xy 51.513251 -358.149614) (xy 51.505664 -358.231482) (xy 51.490553 -358.312301)
			(xy 51.468049 -358.391381) (xy 51.438343 -358.468047) (xy 51.401689 -358.541644) (xy 51.3584 -358.611544)
			(xy 51.308844 -358.677152) (xy 51.253446 -358.737906) (xy 51.192678 -358.793289) (xy 51.127058 -358.842827)
			(xy 51.057146 -358.886099) (xy 50.98354 -358.922734) (xy 50.906867 -358.952421) (xy 50.827781 -358.974905)
			(xy 50.746958 -358.989995) (xy 50.665088 -358.997562) (xy 50.623978 -358.998012) (xy 50.585661 -358.99765)
			(xy 50.509308 -358.991116) (xy 50.433801 -358.97803) (xy 50.359702 -358.958488) (xy 50.323496 -358.945942)
			(xy 50.31518 -358.943356) (xy 50.297776 -358.943356) (xy 50.28946 -358.945942) (xy 50.253248 -358.958468)
			(xy 50.179147 -358.977989) (xy 50.103642 -358.991071) (xy 50.027293 -358.997619) (xy 49.988978 -358.998012)
			(xy 49.950661 -358.99765) (xy 49.874308 -358.991116) (xy 49.798801 -358.97803) (xy 49.724702 -358.958488)
			(xy 49.688496 -358.945942) (xy 49.68018 -358.943356) (xy 49.662776 -358.943356) (xy 49.65446 -358.945942)
			(xy 49.618248 -358.958468) (xy 49.544147 -358.977989) (xy 49.468642 -358.991071) (xy 49.392293 -358.997619)
			(xy 49.353978 -358.998012) (xy 49.315661 -358.99765) (xy 49.239308 -358.991116) (xy 49.163801 -358.97803)
			(xy 49.089702 -358.958488) (xy 49.053496 -358.945942) (xy 49.04518 -358.943356) (xy 49.027776 -358.943356)
			(xy 49.01946 -358.945942) (xy 48.983339 -358.95844) (xy 48.909426 -358.977928) (xy 48.834115 -358.99101)
			(xy 48.757959 -358.99759) (xy 48.71974 -358.998012) (xy 48.718978 -358.998012) (xy 48.677876 -358.99753)
			(xy 48.596022 -358.989953) (xy 48.515216 -358.974857) (xy 48.436148 -358.95237) (xy 48.359491 -358.922685)
			(xy 48.322484 -358.904794) (xy 48.311662 -358.900089) (xy 48.288094 -358.900089) (xy 48.277272 -358.904794)
			(xy 48.240271 -358.922698) (xy 48.163612 -358.952379) (xy 48.084542 -358.974864) (xy 48.003735 -358.98996)
			(xy 47.92188 -358.997539) (xy 47.880778 -358.998012) (xy 47.839669 -358.997608) (xy 47.757803 -358.990022)
			(xy 47.676986 -358.974915) (xy 47.597907 -358.952416) (xy 47.52124 -358.922719) (xy 47.447641 -358.886075)
			(xy 47.377735 -358.842798) (xy 47.312121 -358.793256) (xy 47.251356 -358.737873) (xy 47.19596 -358.677119)
			(xy 47.146405 -358.611515) (xy 47.103114 -358.541618) (xy 47.066455 -358.468026) (xy 47.036742 -358.391366)
			(xy 47.014227 -358.312292) (xy 46.999104 -358.231477) (xy 46.9915 -358.149612) (xy 46.991016 -358.108504)
			(xy 44.837736 -358.108504) (xy 44.834097 -358.122388) (xy 44.808571 -358.1941) (xy 44.793154 -358.2289)
			(xy 44.789778 -358.237249) (xy 44.788481 -358.255202) (xy 44.790614 -358.263952) (xy 44.801704 -358.304153)
			(xy 44.817195 -358.386101) (xy 44.82495 -358.46914) (xy 44.825412 -358.51084) (xy 44.824852 -358.556303)
			(xy 44.815599 -358.646758) (xy 44.797171 -358.735798) (xy 44.78401 -358.779318) (xy 44.78146 -358.788893)
			(xy 44.783017 -358.808626) (xy 44.787058 -358.817672) (xy 44.805431 -358.855048) (xy 44.835897 -358.932566)
			(xy 44.858991 -359.012591) (xy 44.87451 -359.094423) (xy 44.882318 -359.177347) (xy 44.882816 -359.218992)
			(xy 44.882816 -359.219246) (xy 44.882312 -359.261594) (xy 44.874261 -359.345908) (xy 44.858232 -359.429074)
			(xy 44.834371 -359.510341) (xy 44.802892 -359.588971) (xy 44.764081 -359.664252) (xy 44.718291 -359.735504)
			(xy 44.665935 -359.80208) (xy 44.607487 -359.863378) (xy 44.543477 -359.918843) (xy 44.474485 -359.967972)
			(xy 44.401135 -360.010321) (xy 44.324092 -360.045505) (xy 44.244053 -360.073207) (xy 44.161744 -360.093175)
			(xy 44.077909 -360.105228) (xy 43.993308 -360.109259) (xy 43.908707 -360.105228) (xy 43.824872 -360.093175)
			(xy 43.742563 -360.073207) (xy 43.662524 -360.045505) (xy 43.585481 -360.010321) (xy 43.512131 -359.967972)
			(xy 43.443139 -359.918843) (xy 43.379129 -359.863378) (xy 43.320681 -359.80208) (xy 43.268325 -359.735504)
			(xy 43.222535 -359.664252) (xy 43.183724 -359.588971) (xy 43.152245 -359.510341) (xy 43.128384 -359.429074)
			(xy 43.112355 -359.345908) (xy 43.104304 -359.261594) (xy 43.1038 -359.219246) (xy 43.104356 -359.173782)
			(xy 43.113611 -359.083328) (xy 43.13204 -358.994288) (xy 43.145202 -358.950768) (xy 43.147759 -358.941194)
			(xy 43.146197 -358.921461) (xy 43.142154 -358.912414) (xy 43.123767 -358.875016) (xy 43.093286 -358.797449)
			(xy 43.070189 -358.717372) (xy 43.054676 -358.635487) (xy 43.046883 -358.552511) (xy 43.046396 -358.51084)
			(xy 42.259032 -358.51084) (xy 42.259504 -358.549194) (xy 42.258889 -358.594663) (xy 42.249552 -358.685121)
			(xy 42.231047 -358.774157) (xy 42.217848 -358.817672) (xy 42.215273 -358.827242) (xy 42.216849 -358.846979)
			(xy 42.220896 -358.856026) (xy 42.239309 -358.893418) (xy 42.269845 -358.970977) (xy 42.292996 -359.051051)
			(xy 42.308559 -359.132939) (xy 42.316398 -359.215923) (xy 42.316908 -359.2576) (xy 42.316404 -359.299961)
			(xy 42.308351 -359.384298) (xy 42.292317 -359.467488) (xy 42.268449 -359.548778) (xy 42.236961 -359.62743)
			(xy 42.198139 -359.702733) (xy 42.152336 -359.774005) (xy 42.099965 -359.840601) (xy 42.0415 -359.901916)
			(xy 41.977472 -359.957397) (xy 41.90846 -360.00654) (xy 41.83509 -360.0489) (xy 41.758025 -360.084095)
			(xy 41.677963 -360.111804) (xy 41.59563 -360.131778) (xy 41.511771 -360.143835) (xy 41.427146 -360.147867)
			(xy 41.342521 -360.143835) (xy 41.258662 -360.131778) (xy 41.176329 -360.111804) (xy 41.096267 -360.084095)
			(xy 41.019202 -360.0489) (xy 40.945832 -360.00654) (xy 40.87682 -359.957397) (xy 40.812792 -359.901916)
			(xy 40.754327 -359.840601) (xy 40.701956 -359.774005) (xy 40.656153 -359.702733) (xy 40.617331 -359.62743)
			(xy 40.585843 -359.548778) (xy 40.561975 -359.467488) (xy 40.545941 -359.384298) (xy 40.537888 -359.299961)
			(xy 40.537384 -359.2576) (xy 40.537998 -359.212131) (xy 40.547335 -359.121673) (xy 40.565841 -359.032637)
			(xy 40.57904 -358.989122) (xy 40.581619 -358.979553) (xy 40.580041 -358.959815) (xy 40.575992 -358.950768)
			(xy 40.557613 -358.91336) (xy 40.527071 -358.835806) (xy 40.503913 -358.755736) (xy 40.488342 -358.673851)
			(xy 40.480494 -358.59087) (xy 40.47998 -358.549194) (xy 2.509012 -358.549194) (xy 2.509012 -361.825848)
			(xy 5.986007 -361.825848) (xy 5.986007 -361.696708) (xy 5.993957 -361.567813) (xy 6.009827 -361.439653)
			(xy 6.033556 -361.312712) (xy 6.065055 -361.187473) (xy 6.104204 -361.06441) (xy 6.150855 -360.943991)
			(xy 6.20483 -360.826672) (xy 6.265925 -360.712898) (xy 6.333908 -360.603101) (xy 6.408522 -360.497698)
			(xy 6.489483 -360.397088) (xy 6.576483 -360.301653) (xy 6.669194 -360.211754) (xy 6.767264 -360.127733)
			(xy 6.870319 -360.049909) (xy 6.97797 -359.978577) (xy 7.089809 -359.914007) (xy 7.20541 -359.856445)
			(xy 7.324335 -359.806108) (xy 7.446134 -359.763188) (xy 7.570344 -359.727847) (xy 7.696493 -359.70022)
			(xy 7.824105 -359.680411) (xy 7.952694 -359.668495) (xy 8.081772 -359.664519) (xy 8.21085 -359.668495)
			(xy 8.339439 -359.680411) (xy 8.467051 -359.70022) (xy 8.5932 -359.727847) (xy 8.71741 -359.763188)
			(xy 8.839209 -359.806108) (xy 8.958134 -359.856445) (xy 9.073735 -359.914007) (xy 9.185574 -359.978577)
			(xy 9.293225 -360.049909) (xy 9.39628 -360.127733) (xy 9.49435 -360.211754) (xy 9.587061 -360.301653)
			(xy 9.674061 -360.397088) (xy 9.689764 -360.416602) (xy 12.542012 -360.416602) (xy 12.542012 -359.553002)
			(xy 12.542498 -359.525751) (xy 12.550254 -359.471803) (xy 12.565609 -359.419508) (xy 12.588251 -359.369931)
			(xy 12.617717 -359.324081) (xy 12.653408 -359.28289) (xy 12.694599 -359.247199) (xy 12.740449 -359.217733)
			(xy 12.790026 -359.195091) (xy 12.842321 -359.179736) (xy 12.896269 -359.17198) (xy 12.950771 -359.17198)
			(xy 13.004719 -359.179736) (xy 13.057014 -359.195091) (xy 13.106591 -359.217733) (xy 13.152441 -359.247199)
			(xy 13.193632 -359.28289) (xy 13.229323 -359.324081) (xy 13.258789 -359.369931) (xy 13.281431 -359.419508)
			(xy 13.296786 -359.471803) (xy 13.304542 -359.525751) (xy 13.305028 -359.553002) (xy 13.305028 -360.416602)
			(xy 13.304542 -360.443853) (xy 13.296786 -360.497801) (xy 13.281431 -360.550096) (xy 13.258789 -360.599673)
			(xy 13.229323 -360.645523) (xy 13.193632 -360.686714) (xy 13.152441 -360.722405) (xy 13.106591 -360.751871)
			(xy 13.057014 -360.774513) (xy 13.004719 -360.789868) (xy 12.950771 -360.797624) (xy 12.896269 -360.797624)
			(xy 12.842321 -360.789868) (xy 12.790026 -360.774513) (xy 12.740449 -360.751871) (xy 12.694599 -360.722405)
			(xy 12.653408 -360.686714) (xy 12.617717 -360.645523) (xy 12.588251 -360.599673) (xy 12.565609 -360.550096)
			(xy 12.550254 -360.497801) (xy 12.542498 -360.443853) (xy 12.542012 -360.416602) (xy 9.689764 -360.416602)
			(xy 9.755022 -360.497698) (xy 9.829636 -360.603101) (xy 9.897619 -360.712898) (xy 9.958714 -360.826672)
			(xy 10.012689 -360.943991) (xy 10.05934 -361.06441) (xy 10.098489 -361.187473) (xy 10.129988 -361.312712)
			(xy 10.153717 -361.439653) (xy 10.169587 -361.567813) (xy 10.177537 -361.696708) (xy 10.178034 -361.761278)
			(xy 10.177537 -361.825848) (xy 10.169587 -361.954743) (xy 10.153717 -362.082903) (xy 10.129988 -362.209844)
			(xy 10.098489 -362.335083) (xy 10.079022 -362.396278) (xy 165.733984 -362.396278) (xy 165.733984 -361.532678)
			(xy 165.73447 -361.505409) (xy 165.742232 -361.451425) (xy 165.757597 -361.399095) (xy 165.780254 -361.349485)
			(xy 165.80974 -361.303604) (xy 165.845455 -361.262387) (xy 165.886672 -361.226672) (xy 165.932553 -361.197186)
			(xy 165.982163 -361.174529) (xy 166.034493 -361.159164) (xy 166.088477 -361.151402) (xy 166.143015 -361.151402)
			(xy 166.196999 -361.159164) (xy 166.249329 -361.174529) (xy 166.298939 -361.197186) (xy 166.34482 -361.226672)
			(xy 166.386037 -361.262387) (xy 166.421752 -361.303604) (xy 166.451238 -361.349485) (xy 166.473895 -361.399095)
			(xy 166.48926 -361.451425) (xy 166.497022 -361.505409) (xy 166.497508 -361.532678) (xy 166.497508 -362.234988)
			(xy 185.144664 -362.234988) (xy 185.144664 -362.23448) (xy 185.145268 -362.188148) (xy 185.154941 -362.09599)
			(xy 185.174137 -362.005336) (xy 185.202649 -361.917167) (xy 185.220864 -361.874562) (xy 185.224678 -361.864622)
			(xy 185.224673 -361.843356) (xy 185.220864 -361.833414) (xy 185.202614 -361.790754) (xy 185.174071 -361.702461)
			(xy 185.15488 -361.611675) (xy 185.145248 -361.519384) (xy 185.144664 -361.472988) (xy 185.145245 -361.426592)
			(xy 185.154891 -361.334304) (xy 185.174088 -361.24352) (xy 185.202626 -361.155227) (xy 185.220864 -361.112562)
			(xy 185.224678 -361.102622) (xy 185.224673 -361.081356) (xy 185.220864 -361.071414) (xy 185.202636 -361.028813)
			(xy 185.17412 -360.940645) (xy 185.154929 -360.849989) (xy 185.145271 -360.757828) (xy 185.144664 -360.711496)
			(xy 185.144664 -360.710988) (xy 185.145155 -360.669886) (xy 185.152741 -360.588033) (xy 185.167846 -360.507229)
			(xy 185.190343 -360.428164) (xy 185.220039 -360.351511) (xy 185.25668 -360.277925) (xy 185.299955 -360.208034)
			(xy 185.349493 -360.142434) (xy 185.404873 -360.081684) (xy 185.465622 -360.026303) (xy 185.531221 -359.976764)
			(xy 185.601111 -359.933488) (xy 185.674696 -359.896845) (xy 185.751348 -359.867148) (xy 185.830414 -359.84465)
			(xy 185.911217 -359.829543) (xy 185.99307 -359.821956) (xy 186.034172 -359.82148) (xy 186.03468 -359.82148)
			(xy 186.081011 -359.822097) (xy 186.173169 -359.831765) (xy 186.263823 -359.850958) (xy 186.351992 -359.879466)
			(xy 186.394598 -359.89768) (xy 186.40454 -359.901486) (xy 186.425804 -359.901486) (xy 186.435746 -359.89768)
			(xy 186.478352 -359.879466) (xy 186.566519 -359.850947) (xy 186.657173 -359.831752) (xy 186.749332 -359.822089)
			(xy 186.795664 -359.82148) (xy 186.796172 -359.82148) (xy 186.837274 -359.821979) (xy 186.919129 -359.829561)
			(xy 186.999934 -359.844664) (xy 187.079001 -359.867158) (xy 187.155656 -359.896852) (xy 187.229243 -359.933492)
			(xy 187.299136 -359.976765) (xy 187.364738 -360.026303) (xy 187.425489 -360.081682) (xy 187.480872 -360.142431)
			(xy 187.530412 -360.208031) (xy 187.573689 -360.277922) (xy 187.610332 -360.351508) (xy 187.640029 -360.428161)
			(xy 187.662527 -360.507227) (xy 187.677633 -360.588032) (xy 187.685219 -360.669886) (xy 187.68568 -360.710988)
			(xy 187.68568 -360.711496) (xy 187.685072 -360.757828) (xy 187.684417 -360.764074) (xy 211.161635 -360.764074)
			(xy 211.16566 -360.621882) (xy 211.177723 -360.480146) (xy 211.197786 -360.33932) (xy 211.225784 -360.199854)
			(xy 211.261628 -360.062195) (xy 211.305202 -359.926785) (xy 211.356367 -359.794057) (xy 211.41496 -359.664436)
			(xy 211.480791 -359.538338) (xy 211.553652 -359.416166) (xy 211.633307 -359.298312) (xy 211.719503 -359.185153)
			(xy 211.811962 -359.077051) (xy 211.91039 -358.974354) (xy 212.014469 -358.87739) (xy 212.123868 -358.78647)
			(xy 212.238236 -358.701884) (xy 212.357205 -358.623904) (xy 212.480396 -358.55278) (xy 212.607413 -358.488739)
			(xy 212.73785 -358.431987) (xy 212.871289 -358.382705) (xy 213.007302 -358.341051) (xy 213.145454 -358.307159)
			(xy 213.285303 -358.281138) (xy 213.426399 -358.26307) (xy 213.568291 -358.253013) (xy 213.710526 -358.251)
			(xy 213.852646 -358.257037) (xy 213.994197 -358.271105) (xy 214.134726 -358.293159) (xy 214.273781 -358.323128)
			(xy 214.410919 -358.360916) (xy 214.545699 -358.406402) (xy 214.67769 -358.45944) (xy 214.806469 -358.519861)
			(xy 214.931623 -358.58747) (xy 215.052751 -358.662052) (xy 215.169467 -358.743368) (xy 215.281395 -358.831156)
			(xy 215.388177 -358.925136) (xy 215.489471 -359.025006) (xy 215.584952 -359.130448) (xy 215.674316 -359.241122)
			(xy 215.757274 -359.356675) (xy 215.833563 -359.476736) (xy 215.902937 -359.600921) (xy 215.965174 -359.728832)
			(xy 216.020075 -359.860059) (xy 216.067463 -359.994182) (xy 216.107188 -360.130771) (xy 216.139121 -360.269389)
			(xy 216.163162 -360.409591) (xy 216.179231 -360.550929) (xy 216.187279 -360.69295) (xy 216.187782 -360.764074)
			(xy 255.611635 -360.764074) (xy 255.61566 -360.621882) (xy 255.627723 -360.480146) (xy 255.647786 -360.33932)
			(xy 255.675784 -360.199854) (xy 255.711628 -360.062195) (xy 255.755202 -359.926785) (xy 255.806367 -359.794057)
			(xy 255.86496 -359.664436) (xy 255.930791 -359.538338) (xy 256.003652 -359.416166) (xy 256.083307 -359.298312)
			(xy 256.169503 -359.185153) (xy 256.261962 -359.077051) (xy 256.36039 -358.974354) (xy 256.464469 -358.87739)
			(xy 256.573868 -358.78647) (xy 256.688236 -358.701884) (xy 256.807205 -358.623904) (xy 256.930396 -358.55278)
			(xy 257.057413 -358.488739) (xy 257.18785 -358.431987) (xy 257.321289 -358.382705) (xy 257.457302 -358.341051)
			(xy 257.595454 -358.307159) (xy 257.735303 -358.281138) (xy 257.876399 -358.26307) (xy 258.018291 -358.253013)
			(xy 258.160526 -358.251) (xy 258.302646 -358.257037) (xy 258.444197 -358.271105) (xy 258.584726 -358.293159)
			(xy 258.723781 -358.323128) (xy 258.860919 -358.360916) (xy 258.995699 -358.406402) (xy 259.12769 -358.45944)
			(xy 259.256469 -358.519861) (xy 259.381623 -358.58747) (xy 259.502751 -358.662052) (xy 259.619467 -358.743368)
			(xy 259.652996 -358.769666) (xy 294.901627 -358.769666) (xy 294.905632 -358.663917) (xy 294.917622 -358.558774)
			(xy 294.937531 -358.454839) (xy 294.965242 -358.352707) (xy 295.000599 -358.252963) (xy 295.043397 -358.156179)
			(xy 295.093393 -358.062909) (xy 295.1503 -357.973688) (xy 295.213791 -357.889025) (xy 295.283503 -357.809407)
			(xy 295.359037 -357.735289) (xy 295.43996 -357.667096) (xy 295.525809 -357.605218) (xy 295.616092 -357.550011)
			(xy 295.710291 -357.501789) (xy 295.807868 -357.460829) (xy 295.908263 -357.427367) (xy 296.010901 -357.401593)
			(xy 296.115194 -357.383655) (xy 296.220545 -357.373656) (xy 296.326351 -357.371653) (xy 296.432005 -357.377658)
			(xy 296.536902 -357.391637) (xy 296.640442 -357.413508) (xy 296.742031 -357.443148) (xy 296.841088 -357.480386)
			(xy 296.937045 -357.525008) (xy 297.029352 -357.57676) (xy 297.117481 -357.635345) (xy 297.200927 -357.700427)
			(xy 297.279211 -357.771633) (xy 297.351886 -357.848556) (xy 297.418536 -357.930756) (xy 297.478778 -358.01776)
			(xy 297.532267 -358.109071) (xy 297.578698 -358.204166) (xy 297.617803 -358.3025) (xy 297.64936 -358.403511)
			(xy 297.673187 -358.506618) (xy 297.689148 -358.611232) (xy 297.697152 -358.716754) (xy 297.697652 -358.769666)
			(xy 297.697152 -358.822578) (xy 297.689148 -358.9281) (xy 297.673187 -359.032714) (xy 297.64936 -359.135821)
			(xy 297.617803 -359.236832) (xy 297.578698 -359.335166) (xy 297.532267 -359.430261) (xy 297.478778 -359.521572)
			(xy 297.418536 -359.608576) (xy 297.351886 -359.690776) (xy 297.279211 -359.767699) (xy 297.200927 -359.838905)
			(xy 297.117481 -359.903987) (xy 297.029352 -359.962572) (xy 296.937045 -360.014324) (xy 296.841088 -360.058946)
			(xy 296.742031 -360.096184) (xy 296.640442 -360.125824) (xy 296.536902 -360.147695) (xy 296.432005 -360.161674)
			(xy 296.326351 -360.167679) (xy 296.220545 -360.165676) (xy 296.115194 -360.155677) (xy 296.010901 -360.137739)
			(xy 295.908263 -360.111965) (xy 295.807868 -360.078503) (xy 295.710291 -360.037543) (xy 295.616092 -359.989321)
			(xy 295.525809 -359.934114) (xy 295.43996 -359.872236) (xy 295.359037 -359.804043) (xy 295.283503 -359.729925)
			(xy 295.213791 -359.650307) (xy 295.1503 -359.565644) (xy 295.093393 -359.476423) (xy 295.043397 -359.383153)
			(xy 295.000599 -359.286369) (xy 294.965242 -359.186625) (xy 294.937531 -359.084493) (xy 294.917622 -358.980558)
			(xy 294.905632 -358.875415) (xy 294.901627 -358.769666) (xy 259.652996 -358.769666) (xy 259.731395 -358.831156)
			(xy 259.838177 -358.925136) (xy 259.939471 -359.025006) (xy 260.034952 -359.130448) (xy 260.124316 -359.241122)
			(xy 260.207274 -359.356675) (xy 260.283563 -359.476736) (xy 260.352937 -359.600921) (xy 260.415174 -359.728832)
			(xy 260.470075 -359.860059) (xy 260.517463 -359.994182) (xy 260.557188 -360.130771) (xy 260.589121 -360.269389)
			(xy 260.613162 -360.409591) (xy 260.629231 -360.550929) (xy 260.637279 -360.69295) (xy 260.637782 -360.764074)
			(xy 260.637279 -360.835198) (xy 260.629231 -360.977219) (xy 260.613162 -361.118557) (xy 260.589121 -361.258759)
			(xy 260.557188 -361.397377) (xy 260.517463 -361.533966) (xy 260.470075 -361.668089) (xy 260.415174 -361.799316)
			(xy 260.401302 -361.827826) (xy 430.615097 -361.827826) (xy 430.619102 -361.722077) (xy 430.631092 -361.616934)
			(xy 430.651001 -361.512999) (xy 430.678712 -361.410867) (xy 430.714069 -361.311123) (xy 430.756867 -361.214339)
			(xy 430.806863 -361.121069) (xy 430.86377 -361.031848) (xy 430.927261 -360.947185) (xy 430.996973 -360.867567)
			(xy 431.072507 -360.793449) (xy 431.15343 -360.725256) (xy 431.239279 -360.663378) (xy 431.329562 -360.608171)
			(xy 431.423761 -360.559949) (xy 431.521338 -360.518989) (xy 431.621733 -360.485527) (xy 431.724371 -360.459753)
			(xy 431.828664 -360.441815) (xy 431.934015 -360.431816) (xy 432.039821 -360.429813) (xy 432.145475 -360.435818)
			(xy 432.250372 -360.449797) (xy 432.353912 -360.471668) (xy 432.455501 -360.501308) (xy 432.554558 -360.538546)
			(xy 432.650515 -360.583168) (xy 432.742822 -360.63492) (xy 432.830951 -360.693505) (xy 432.914397 -360.758587)
			(xy 432.992681 -360.829793) (xy 433.065356 -360.906716) (xy 433.132006 -360.988916) (xy 433.192248 -361.07592)
			(xy 433.245737 -361.167231) (xy 433.292168 -361.262326) (xy 433.331273 -361.36066) (xy 433.36283 -361.461671)
			(xy 433.370787 -361.496102) (xy 434.579776 -361.496102) (xy 434.580404 -361.4497) (xy 434.590093 -361.357403)
			(xy 434.609347 -361.266617) (xy 434.637954 -361.178332) (xy 434.65623 -361.135676) (xy 434.660038 -361.125734)
			(xy 434.660039 -361.10447) (xy 434.65623 -361.094528) (xy 434.637968 -361.051867) (xy 434.609375 -360.963579)
			(xy 434.590118 -360.872796) (xy 434.580405 -360.780503) (xy 434.579776 -360.734102) (xy 434.580404 -360.6877)
			(xy 434.590093 -360.595403) (xy 434.609347 -360.504617) (xy 434.637954 -360.416332) (xy 434.65623 -360.373676)
			(xy 434.660038 -360.363734) (xy 434.660039 -360.34247) (xy 434.65623 -360.332528) (xy 434.637968 -360.289867)
			(xy 434.609375 -360.201579) (xy 434.590118 -360.110796) (xy 434.580405 -360.018503) (xy 434.579776 -359.972102)
			(xy 434.5802 -359.930986) (xy 434.587788 -359.849105) (xy 434.602898 -359.768273) (xy 434.625402 -359.68918)
			(xy 434.655109 -359.612502) (xy 434.691763 -359.538891) (xy 434.735054 -359.468977) (xy 434.784611 -359.403355)
			(xy 434.840011 -359.342586) (xy 434.900783 -359.287188) (xy 434.966406 -359.237634) (xy 435.036323 -359.194346)
			(xy 435.109935 -359.157694) (xy 435.186615 -359.127991) (xy 435.265708 -359.10549) (xy 435.346541 -359.090383)
			(xy 435.428422 -359.082799) (xy 435.469538 -359.08234) (xy 435.51594 -359.082957) (xy 435.608238 -359.09265)
			(xy 435.699023 -359.111907) (xy 435.787308 -359.140517) (xy 435.829964 -359.158794) (xy 435.839906 -359.1626)
			(xy 435.86117 -359.1626) (xy 435.871112 -359.158794) (xy 435.913767 -359.140517) (xy 436.002057 -359.111928)
			(xy 436.092842 -359.092675) (xy 436.185137 -359.082967) (xy 436.231538 -359.08234) (xy 436.272653 -359.082777)
			(xy 436.354532 -359.090367) (xy 436.435361 -359.10548) (xy 436.514451 -359.127986) (xy 436.591127 -359.157693)
			(xy 436.664735 -359.194349) (xy 436.734647 -359.237639) (xy 436.800266 -359.287195) (xy 436.861034 -359.342595)
			(xy 436.91643 -359.403364) (xy 436.965984 -359.468986) (xy 437.009271 -359.5389) (xy 437.045923 -359.61251)
			(xy 437.075627 -359.689187) (xy 437.098129 -359.768278) (xy 437.113238 -359.849108) (xy 437.120825 -359.930987)
			(xy 437.1213 -359.972102) (xy 437.120676 -360.018504) (xy 437.110985 -360.110802) (xy 437.091731 -360.201587)
			(xy 437.063122 -360.289872) (xy 437.044846 -360.332528) (xy 437.041037 -360.34247) (xy 437.041038 -360.363734)
			(xy 437.044846 -360.373676) (xy 437.063108 -360.416337) (xy 437.091701 -360.504625) (xy 437.110959 -360.595408)
			(xy 437.120671 -360.687701) (xy 437.1213 -360.734102) (xy 437.120676 -360.780504) (xy 437.110985 -360.872802)
			(xy 437.091731 -360.963587) (xy 437.063122 -361.051872) (xy 437.044846 -361.094528) (xy 437.041037 -361.10447)
			(xy 437.041038 -361.125734) (xy 437.044846 -361.135676) (xy 437.063108 -361.178337) (xy 437.091701 -361.266625)
			(xy 437.110959 -361.357408) (xy 437.120671 -361.449701) (xy 437.1213 -361.496102) (xy 437.120789 -361.537215)
			(xy 437.113202 -361.619091) (xy 437.098093 -361.699917) (xy 437.075592 -361.779004) (xy 437.045889 -361.855678)
			(xy 437.009238 -361.929285) (xy 436.965952 -361.999196) (xy 436.916401 -362.064814) (xy 436.861007 -362.125581)
			(xy 436.800242 -362.180978) (xy 436.734625 -362.230532) (xy 436.664716 -362.273821) (xy 436.591111 -362.310474)
			(xy 436.514439 -362.34018) (xy 436.435352 -362.362685) (xy 436.354526 -362.377797) (xy 436.272651 -362.385387)
			(xy 436.231538 -362.385864) (xy 436.185135 -362.385256) (xy 436.092838 -362.37556) (xy 436.002052 -362.356301)
			(xy 435.913768 -362.327688) (xy 435.871112 -362.30941) (xy 435.86117 -362.305604) (xy 435.839906 -362.305604)
			(xy 435.829964 -362.30941) (xy 435.787299 -362.327662) (xy 435.699012 -362.356257) (xy 435.608231 -362.375517)
			(xy 435.515939 -362.385233) (xy 435.469538 -362.385864) (xy 435.428424 -362.385365) (xy 435.346546 -362.377782)
			(xy 435.265717 -362.362675) (xy 435.186627 -362.340175) (xy 435.10995 -362.310473) (xy 435.036341 -362.273823)
			(xy 434.966428 -362.230538) (xy 434.900807 -362.180986) (xy 434.840038 -362.12559) (xy 434.78464 -362.064824)
			(xy 434.735085 -361.999205) (xy 434.691796 -361.929294) (xy 434.655143 -361.855686) (xy 434.625438 -361.779011)
			(xy 434.602934 -361.699922) (xy 434.587824 -361.619094) (xy 434.580237 -361.537216) (xy 434.579776 -361.496102)
			(xy 433.370787 -361.496102) (xy 433.386657 -361.564778) (xy 433.402618 -361.669392) (xy 433.410622 -361.774914)
			(xy 433.411122 -361.827826) (xy 433.410622 -361.880738) (xy 433.402618 -361.98626) (xy 433.386657 -362.090874)
			(xy 433.36283 -362.193981) (xy 433.331273 -362.294992) (xy 433.292168 -362.393326) (xy 433.245737 -362.488421)
			(xy 433.192248 -362.579732) (xy 433.132006 -362.666736) (xy 433.065356 -362.748936) (xy 432.992681 -362.825859)
			(xy 432.914397 -362.897065) (xy 432.830951 -362.962147) (xy 432.742822 -363.020732) (xy 432.650515 -363.072484)
			(xy 432.554558 -363.117106) (xy 432.455501 -363.154344) (xy 432.353912 -363.183984) (xy 432.250372 -363.205855)
			(xy 432.145475 -363.219834) (xy 432.039821 -363.225839) (xy 431.934015 -363.223836) (xy 431.828664 -363.213837)
			(xy 431.724371 -363.195899) (xy 431.621733 -363.170125) (xy 431.521338 -363.136663) (xy 431.423761 -363.095703)
			(xy 431.329562 -363.047481) (xy 431.239279 -362.992274) (xy 431.15343 -362.930396) (xy 431.072507 -362.862203)
			(xy 430.996973 -362.788085) (xy 430.927261 -362.708467) (xy 430.86377 -362.623804) (xy 430.806863 -362.534583)
			(xy 430.756867 -362.441313) (xy 430.714069 -362.344529) (xy 430.678712 -362.244785) (xy 430.651001 -362.142653)
			(xy 430.631092 -362.038718) (xy 430.619102 -361.933575) (xy 430.615097 -361.827826) (xy 260.401302 -361.827826)
			(xy 260.352937 -361.927227) (xy 260.283563 -362.051412) (xy 260.207274 -362.171473) (xy 260.124316 -362.287026)
			(xy 260.034952 -362.3977) (xy 259.939471 -362.503142) (xy 259.838177 -362.603012) (xy 259.731395 -362.696992)
			(xy 259.619467 -362.78478) (xy 259.502751 -362.866096) (xy 259.381623 -362.940678) (xy 259.256469 -363.008287)
			(xy 259.12769 -363.068708) (xy 258.995699 -363.121746) (xy 258.860919 -363.167232) (xy 258.723781 -363.20502)
			(xy 258.584726 -363.234989) (xy 258.444197 -363.257043) (xy 258.302646 -363.271111) (xy 258.160526 -363.277148)
			(xy 258.018291 -363.275135) (xy 257.876399 -363.265078) (xy 257.735303 -363.24701) (xy 257.595454 -363.220989)
			(xy 257.457302 -363.187097) (xy 257.321289 -363.145443) (xy 257.18785 -363.096161) (xy 257.057413 -363.039409)
			(xy 256.930396 -362.975368) (xy 256.807205 -362.904244) (xy 256.688236 -362.826264) (xy 256.573868 -362.741678)
			(xy 256.464469 -362.650758) (xy 256.36039 -362.553794) (xy 256.261962 -362.451097) (xy 256.169503 -362.342995)
			(xy 256.083307 -362.229836) (xy 256.003652 -362.111982) (xy 255.930791 -361.98981) (xy 255.86496 -361.863712)
			(xy 255.806367 -361.734091) (xy 255.755202 -361.601363) (xy 255.711628 -361.465953) (xy 255.675784 -361.328294)
			(xy 255.647786 -361.188828) (xy 255.627723 -361.048002) (xy 255.61566 -360.906266) (xy 255.611635 -360.764074)
			(xy 216.187782 -360.764074) (xy 216.187279 -360.835198) (xy 216.179231 -360.977219) (xy 216.163162 -361.118557)
			(xy 216.139121 -361.258759) (xy 216.107188 -361.397377) (xy 216.067463 -361.533966) (xy 216.020075 -361.668089)
			(xy 215.965174 -361.799316) (xy 215.902937 -361.927227) (xy 215.833563 -362.051412) (xy 215.757274 -362.171473)
			(xy 215.674316 -362.287026) (xy 215.584952 -362.3977) (xy 215.489471 -362.503142) (xy 215.388177 -362.603012)
			(xy 215.281395 -362.696992) (xy 215.169467 -362.78478) (xy 215.052751 -362.866096) (xy 214.931623 -362.940678)
			(xy 214.806469 -363.008287) (xy 214.67769 -363.068708) (xy 214.545699 -363.121746) (xy 214.410919 -363.167232)
			(xy 214.273781 -363.20502) (xy 214.134726 -363.234989) (xy 213.994197 -363.257043) (xy 213.852646 -363.271111)
			(xy 213.710526 -363.277148) (xy 213.568291 -363.275135) (xy 213.426399 -363.265078) (xy 213.285303 -363.24701)
			(xy 213.145454 -363.220989) (xy 213.007302 -363.187097) (xy 212.871289 -363.145443) (xy 212.73785 -363.096161)
			(xy 212.607413 -363.039409) (xy 212.480396 -362.975368) (xy 212.357205 -362.904244) (xy 212.238236 -362.826264)
			(xy 212.123868 -362.741678) (xy 212.014469 -362.650758) (xy 211.91039 -362.553794) (xy 211.811962 -362.451097)
			(xy 211.719503 -362.342995) (xy 211.633307 -362.229836) (xy 211.553652 -362.111982) (xy 211.480791 -361.98981)
			(xy 211.41496 -361.863712) (xy 211.356367 -361.734091) (xy 211.305202 -361.601363) (xy 211.261628 -361.465953)
			(xy 211.225784 -361.328294) (xy 211.197786 -361.188828) (xy 211.177723 -361.048002) (xy 211.16566 -360.906266)
			(xy 211.161635 -360.764074) (xy 187.684417 -360.764074) (xy 187.675402 -360.849986) (xy 187.656207 -360.94064)
			(xy 187.627695 -361.028809) (xy 187.60948 -361.071414) (xy 187.605683 -361.081359) (xy 187.605679 -361.10262)
			(xy 187.60948 -361.112562) (xy 187.627719 -361.155227) (xy 187.656265 -361.243518) (xy 187.67546 -361.334302)
			(xy 187.685094 -361.426592) (xy 187.68568 -361.472988) (xy 187.685095 -361.519384) (xy 187.675451 -361.611672)
			(xy 187.656256 -361.702456) (xy 187.627718 -361.790749) (xy 187.60948 -361.833414) (xy 187.605683 -361.843359)
			(xy 187.605679 -361.86462) (xy 187.60948 -361.874562) (xy 187.627696 -361.917167) (xy 187.656216 -362.005334)
			(xy 187.67541 -362.095988) (xy 187.685071 -362.188148) (xy 187.68568 -362.23448) (xy 187.68568 -362.234988)
			(xy 187.685236 -362.276092) (xy 187.677652 -362.357949) (xy 187.664078 -362.430568) (xy 190.281567 -362.430568)
			(xy 190.285572 -362.324819) (xy 190.297562 -362.219676) (xy 190.317471 -362.115741) (xy 190.345182 -362.013609)
			(xy 190.380539 -361.913865) (xy 190.423337 -361.817081) (xy 190.473333 -361.723811) (xy 190.53024 -361.63459)
			(xy 190.593731 -361.549927) (xy 190.663443 -361.470309) (xy 190.738977 -361.396191) (xy 190.8199 -361.327998)
			(xy 190.905749 -361.26612) (xy 190.996032 -361.210913) (xy 191.090231 -361.162691) (xy 191.187808 -361.121731)
			(xy 191.288203 -361.088269) (xy 191.390841 -361.062495) (xy 191.495134 -361.044557) (xy 191.600485 -361.034558)
			(xy 191.706291 -361.032555) (xy 191.811945 -361.03856) (xy 191.916842 -361.052539) (xy 192.020382 -361.07441)
			(xy 192.121971 -361.10405) (xy 192.221028 -361.141288) (xy 192.316985 -361.18591) (xy 192.409292 -361.237662)
			(xy 192.497421 -361.296247) (xy 192.580867 -361.361329) (xy 192.659151 -361.432535) (xy 192.731826 -361.509458)
			(xy 192.798476 -361.591658) (xy 192.858718 -361.678662) (xy 192.912207 -361.769973) (xy 192.958638 -361.865068)
			(xy 192.997743 -361.963402) (xy 193.0293 -362.064413) (xy 193.053127 -362.16752) (xy 193.069088 -362.272134)
			(xy 193.077092 -362.377656) (xy 193.077592 -362.430568) (xy 193.077092 -362.48348) (xy 193.069088 -362.589002)
			(xy 193.053127 -362.693616) (xy 193.0293 -362.796723) (xy 192.997743 -362.897734) (xy 192.958638 -362.996068)
			(xy 192.912207 -363.091163) (xy 192.858718 -363.182474) (xy 192.798476 -363.269478) (xy 192.731826 -363.351678)
			(xy 192.659151 -363.428601) (xy 192.580867 -363.499807) (xy 192.497421 -363.564889) (xy 192.409292 -363.623474)
			(xy 192.316985 -363.675226) (xy 192.221028 -363.719848) (xy 192.121971 -363.757086) (xy 192.020382 -363.786726)
			(xy 191.916842 -363.808597) (xy 191.811945 -363.822576) (xy 191.706291 -363.828581) (xy 191.600485 -363.826578)
			(xy 191.495134 -363.816579) (xy 191.390841 -363.798641) (xy 191.288203 -363.772867) (xy 191.187808 -363.739405)
			(xy 191.090231 -363.698445) (xy 190.996032 -363.650223) (xy 190.905749 -363.595016) (xy 190.8199 -363.533138)
			(xy 190.738977 -363.464945) (xy 190.663443 -363.390827) (xy 190.593731 -363.311209) (xy 190.53024 -363.226546)
			(xy 190.473333 -363.137325) (xy 190.423337 -363.044055) (xy 190.380539 -362.947271) (xy 190.345182 -362.847527)
			(xy 190.317471 -362.745395) (xy 190.297562 -362.64146) (xy 190.285572 -362.536317) (xy 190.281567 -362.430568)
			(xy 187.664078 -362.430568) (xy 187.662547 -362.438757) (xy 187.64005 -362.517826) (xy 187.610354 -362.594483)
			(xy 187.573711 -362.668072) (xy 187.530434 -362.737966) (xy 187.480892 -362.803569) (xy 187.425509 -362.86432)
			(xy 187.364756 -362.919703) (xy 187.299153 -362.969243) (xy 187.229258 -363.012519) (xy 187.155668 -363.04916)
			(xy 187.079011 -363.078856) (xy 186.999941 -363.101351) (xy 186.919133 -363.116454) (xy 186.837276 -363.124037)
			(xy 186.796172 -363.124496) (xy 186.795664 -363.124496) (xy 186.749333 -363.123866) (xy 186.657176 -363.114202)
			(xy 186.566521 -363.095013) (xy 186.478352 -363.066508) (xy 186.435746 -363.048296) (xy 186.425804 -363.04449)
			(xy 186.40454 -363.04449) (xy 186.394598 -363.048296) (xy 186.351999 -363.066527) (xy 186.26383 -363.095042)
			(xy 186.173173 -363.114232) (xy 186.081013 -363.123889) (xy 186.03468 -363.124496) (xy 186.034172 -363.124496)
			(xy 185.993069 -363.12406) (xy 185.911213 -363.116473) (xy 185.830407 -363.101365) (xy 185.751339 -363.078866)
			(xy 185.674684 -363.049167) (xy 185.601097 -363.012522) (xy 185.531204 -362.969244) (xy 185.465603 -362.919702)
			(xy 185.404853 -362.864319) (xy 185.349472 -362.803566) (xy 185.299933 -362.737963) (xy 185.256658 -362.668068)
			(xy 185.220017 -362.594479) (xy 185.190322 -362.517823) (xy 185.167826 -362.438755) (xy 185.152722 -362.357947)
			(xy 185.145138 -362.276091) (xy 185.144664 -362.234988) (xy 166.497508 -362.234988) (xy 166.497508 -362.396278)
			(xy 166.497022 -362.423547) (xy 166.48926 -362.477531) (xy 166.473895 -362.529861) (xy 166.451238 -362.579471)
			(xy 166.421752 -362.625352) (xy 166.386037 -362.666569) (xy 166.34482 -362.702284) (xy 166.298939 -362.73177)
			(xy 166.249329 -362.754427) (xy 166.196999 -362.769792) (xy 166.143015 -362.777554) (xy 166.088477 -362.777554)
			(xy 166.034493 -362.769792) (xy 165.982163 -362.754427) (xy 165.932553 -362.73177) (xy 165.886672 -362.702284)
			(xy 165.845455 -362.666569) (xy 165.80974 -362.625352) (xy 165.780254 -362.579471) (xy 165.757597 -362.529861)
			(xy 165.742232 -362.477531) (xy 165.73447 -362.423547) (xy 165.733984 -362.396278) (xy 10.079022 -362.396278)
			(xy 10.05934 -362.458146) (xy 10.012689 -362.578565) (xy 9.958714 -362.695884) (xy 9.897619 -362.809658)
			(xy 9.829636 -362.919455) (xy 9.755022 -363.024858) (xy 9.674061 -363.125468) (xy 9.587061 -363.220903)
			(xy 9.49435 -363.310802) (xy 9.39628 -363.394823) (xy 9.293225 -363.472647) (xy 9.185574 -363.543979)
			(xy 9.073735 -363.608549) (xy 8.958134 -363.666111) (xy 8.839209 -363.716448) (xy 8.71741 -363.759368)
			(xy 8.5932 -363.794709) (xy 8.467051 -363.822336) (xy 8.339439 -363.842145) (xy 8.21085 -363.854061)
			(xy 8.081772 -363.858038) (xy 7.952694 -363.854061) (xy 7.824105 -363.842145) (xy 7.696493 -363.822336)
			(xy 7.570344 -363.794709) (xy 7.446134 -363.759368) (xy 7.324335 -363.716448) (xy 7.20541 -363.666111)
			(xy 7.089809 -363.608549) (xy 6.97797 -363.543979) (xy 6.870319 -363.472647) (xy 6.767264 -363.394823)
			(xy 6.669194 -363.310802) (xy 6.576483 -363.220903) (xy 6.489483 -363.125468) (xy 6.408522 -363.024858)
			(xy 6.333908 -362.919455) (xy 6.265925 -362.809658) (xy 6.20483 -362.695884) (xy 6.150855 -362.578565)
			(xy 6.104204 -362.458146) (xy 6.065055 -362.335083) (xy 6.033556 -362.209844) (xy 6.009827 -362.082903)
			(xy 5.993957 -361.954743) (xy 5.986007 -361.825848) (xy 2.509012 -361.825848) (xy 2.509012 -369.062565)
			(xy 44.335754 -369.062565) (xy 44.335754 -369.008035) (xy 44.343514 -368.95406) (xy 44.358876 -368.901738)
			(xy 44.381527 -368.852135) (xy 44.411006 -368.806259) (xy 44.446714 -368.765046) (xy 44.487923 -368.729334)
			(xy 44.533794 -368.699849) (xy 44.583395 -368.677192) (xy 44.635715 -368.661824) (xy 44.689689 -368.654057)
			(xy 44.716954 -368.653568) (xy 45.580554 -368.653568) (xy 45.607829 -368.653968) (xy 45.661825 -368.661726)
			(xy 45.714168 -368.677089) (xy 45.763791 -368.699746) (xy 45.809684 -368.729235) (xy 45.850912 -368.764955)
			(xy 45.886638 -368.80618) (xy 45.916132 -368.852069) (xy 45.938795 -368.901689) (xy 45.954164 -368.95403)
			(xy 45.961928 -369.008025) (xy 45.961928 -369.062565) (xy 51.142954 -369.062565) (xy 51.142954 -369.008035)
			(xy 51.150714 -368.95406) (xy 51.166076 -368.901738) (xy 51.188727 -368.852135) (xy 51.218206 -368.806259)
			(xy 51.253914 -368.765046) (xy 51.295123 -368.729334) (xy 51.340994 -368.699849) (xy 51.390595 -368.677192)
			(xy 51.442915 -368.661824) (xy 51.496889 -368.654057) (xy 51.524154 -368.653568) (xy 52.387754 -368.653568)
			(xy 52.415029 -368.653968) (xy 52.469025 -368.661726) (xy 52.521368 -368.677089) (xy 52.570991 -368.699746)
			(xy 52.616884 -368.729235) (xy 52.658112 -368.764955) (xy 52.693838 -368.80618) (xy 52.723332 -368.852069)
			(xy 52.745995 -368.901689) (xy 52.761364 -368.95403) (xy 52.769128 -369.008025) (xy 52.769128 -369.062565)
			(xy 57.950154 -369.062565) (xy 57.950154 -369.008035) (xy 57.957914 -368.95406) (xy 57.973276 -368.901738)
			(xy 57.995927 -368.852135) (xy 58.025406 -368.806259) (xy 58.061114 -368.765046) (xy 58.102323 -368.729334)
			(xy 58.148194 -368.699849) (xy 58.197795 -368.677192) (xy 58.250115 -368.661824) (xy 58.304089 -368.654057)
			(xy 58.331354 -368.653568) (xy 59.194954 -368.653568) (xy 59.222229 -368.653968) (xy 59.276225 -368.661726)
			(xy 59.328568 -368.677089) (xy 59.378191 -368.699746) (xy 59.424084 -368.729235) (xy 59.465312 -368.764955)
			(xy 59.501038 -368.80618) (xy 59.530532 -368.852069) (xy 59.553195 -368.901689) (xy 59.568564 -368.95403)
			(xy 59.576328 -369.008025) (xy 59.576328 -369.062565) (xy 64.757354 -369.062565) (xy 64.757354 -369.008035)
			(xy 64.765114 -368.95406) (xy 64.780476 -368.901738) (xy 64.803127 -368.852135) (xy 64.832606 -368.806259)
			(xy 64.868314 -368.765046) (xy 64.909523 -368.729334) (xy 64.955394 -368.699849) (xy 65.004995 -368.677192)
			(xy 65.057315 -368.661824) (xy 65.111289 -368.654057) (xy 65.138554 -368.653568) (xy 66.002154 -368.653568)
			(xy 66.029429 -368.653968) (xy 66.083425 -368.661726) (xy 66.135768 -368.677089) (xy 66.185391 -368.699746)
			(xy 66.231284 -368.729235) (xy 66.272512 -368.764955) (xy 66.308238 -368.80618) (xy 66.337732 -368.852069)
			(xy 66.360395 -368.901689) (xy 66.375764 -368.95403) (xy 66.383528 -369.008025) (xy 66.383528 -369.062565)
			(xy 68.160954 -369.062565) (xy 68.160954 -369.008035) (xy 68.168714 -368.95406) (xy 68.184076 -368.901738)
			(xy 68.206727 -368.852135) (xy 68.236206 -368.806259) (xy 68.271914 -368.765046) (xy 68.313123 -368.729334)
			(xy 68.358994 -368.699849) (xy 68.408595 -368.677192) (xy 68.460915 -368.661824) (xy 68.514889 -368.654057)
			(xy 68.542154 -368.653568) (xy 69.405754 -368.653568) (xy 69.433029 -368.653968) (xy 69.487025 -368.661726)
			(xy 69.539368 -368.677089) (xy 69.588991 -368.699746) (xy 69.634884 -368.729235) (xy 69.676112 -368.764955)
			(xy 69.711838 -368.80618) (xy 69.741332 -368.852069) (xy 69.763995 -368.901689) (xy 69.779364 -368.95403)
			(xy 69.787128 -369.008025) (xy 69.787128 -369.062569) (xy 76.863431 -369.062569) (xy 76.863431 -369.008031)
			(xy 76.871193 -368.954048) (xy 76.886558 -368.90172) (xy 76.909214 -368.85211) (xy 76.9387 -368.80623)
			(xy 76.974414 -368.765013) (xy 77.015632 -368.729298) (xy 77.061512 -368.699813) (xy 77.111121 -368.677157)
			(xy 77.16345 -368.661793) (xy 77.217433 -368.654031) (xy 77.244702 -368.653568) (xy 78.108302 -368.653568)
			(xy 78.135573 -368.653995) (xy 78.189561 -368.661757) (xy 78.241894 -368.677124) (xy 78.291508 -368.699782)
			(xy 78.337393 -368.72927) (xy 78.378613 -368.764988) (xy 78.414331 -368.806209) (xy 78.443819 -368.852093)
			(xy 78.466477 -368.901707) (xy 78.481843 -368.954041) (xy 78.489606 -369.008029) (xy 78.489606 -369.062569)
			(xy 83.670631 -369.062569) (xy 83.670631 -369.008031) (xy 83.678393 -368.954048) (xy 83.693758 -368.90172)
			(xy 83.716414 -368.85211) (xy 83.7459 -368.80623) (xy 83.781614 -368.765013) (xy 83.822832 -368.729298)
			(xy 83.868712 -368.699813) (xy 83.918321 -368.677157) (xy 83.97065 -368.661793) (xy 84.024633 -368.654031)
			(xy 84.051902 -368.653568) (xy 84.915502 -368.653568) (xy 84.942773 -368.653995) (xy 84.996761 -368.661757)
			(xy 85.049094 -368.677124) (xy 85.098708 -368.699782) (xy 85.144593 -368.72927) (xy 85.185813 -368.764988)
			(xy 85.221531 -368.806209) (xy 85.251019 -368.852093) (xy 85.273677 -368.901707) (xy 85.289043 -368.954041)
			(xy 85.296806 -369.008029) (xy 85.296806 -369.062569) (xy 90.477831 -369.062569) (xy 90.477831 -369.008031)
			(xy 90.485593 -368.954048) (xy 90.500958 -368.90172) (xy 90.523614 -368.85211) (xy 90.5531 -368.80623)
			(xy 90.588814 -368.765013) (xy 90.630032 -368.729298) (xy 90.675912 -368.699813) (xy 90.725521 -368.677157)
			(xy 90.77785 -368.661793) (xy 90.831833 -368.654031) (xy 90.859102 -368.653568) (xy 91.722702 -368.653568)
			(xy 91.749973 -368.653995) (xy 91.803961 -368.661757) (xy 91.856294 -368.677124) (xy 91.905908 -368.699782)
			(xy 91.951793 -368.72927) (xy 91.993013 -368.764988) (xy 92.028731 -368.806209) (xy 92.058219 -368.852093)
			(xy 92.080877 -368.901707) (xy 92.096243 -368.954041) (xy 92.104006 -369.008029) (xy 92.104006 -369.062569)
			(xy 97.285031 -369.062569) (xy 97.285031 -369.008031) (xy 97.292793 -368.954048) (xy 97.308158 -368.90172)
			(xy 97.330814 -368.85211) (xy 97.3603 -368.80623) (xy 97.396014 -368.765013) (xy 97.437232 -368.729298)
			(xy 97.483112 -368.699813) (xy 97.532721 -368.677157) (xy 97.58505 -368.661793) (xy 97.639033 -368.654031)
			(xy 97.666302 -368.653568) (xy 98.529902 -368.653568) (xy 98.557173 -368.653995) (xy 98.611161 -368.661757)
			(xy 98.663494 -368.677124) (xy 98.713108 -368.699782) (xy 98.758993 -368.72927) (xy 98.800213 -368.764988)
			(xy 98.835931 -368.806209) (xy 98.865419 -368.852093) (xy 98.888077 -368.901707) (xy 98.903443 -368.954041)
			(xy 98.911206 -369.008029) (xy 98.911206 -369.062569) (xy 100.688631 -369.062569) (xy 100.688631 -369.008031)
			(xy 100.696393 -368.954048) (xy 100.711758 -368.90172) (xy 100.734414 -368.85211) (xy 100.7639 -368.80623)
			(xy 100.799614 -368.765013) (xy 100.840832 -368.729298) (xy 100.886712 -368.699813) (xy 100.936321 -368.677157)
			(xy 100.98865 -368.661793) (xy 101.042633 -368.654031) (xy 101.069902 -368.653568) (xy 101.933502 -368.653568)
			(xy 101.960773 -368.653995) (xy 102.014761 -368.661757) (xy 102.067094 -368.677124) (xy 102.116708 -368.699782)
			(xy 102.162593 -368.72927) (xy 102.203813 -368.764988) (xy 102.239531 -368.806209) (xy 102.269019 -368.852093)
			(xy 102.291677 -368.901707) (xy 102.307043 -368.954041) (xy 102.314806 -369.008029) (xy 102.314806 -369.062567)
			(xy 111.435654 -369.062567) (xy 111.435654 -369.008033) (xy 111.443415 -368.954054) (xy 111.458779 -368.901729)
			(xy 111.481433 -368.852123) (xy 111.510917 -368.806246) (xy 111.546629 -368.765031) (xy 111.587842 -368.729319)
			(xy 111.633719 -368.699835) (xy 111.683325 -368.677181) (xy 111.73565 -368.661816) (xy 111.789629 -368.654055)
			(xy 111.816896 -368.653568) (xy 112.680496 -368.653568) (xy 112.707769 -368.653971) (xy 112.761761 -368.661734)
			(xy 112.814098 -368.677101) (xy 112.863716 -368.69976) (xy 112.909603 -368.72925) (xy 112.950827 -368.76497)
			(xy 112.986548 -368.806193) (xy 113.016038 -368.852081) (xy 113.038698 -368.901698) (xy 113.054066 -368.954035)
			(xy 113.061828 -369.008027) (xy 113.061828 -369.062567) (xy 118.242854 -369.062567) (xy 118.242854 -369.008033)
			(xy 118.250615 -368.954054) (xy 118.265979 -368.901729) (xy 118.288633 -368.852123) (xy 118.318117 -368.806246)
			(xy 118.353829 -368.765031) (xy 118.395042 -368.729319) (xy 118.440919 -368.699835) (xy 118.490525 -368.677181)
			(xy 118.54285 -368.661816) (xy 118.596829 -368.654055) (xy 118.624096 -368.653568) (xy 119.487696 -368.653568)
			(xy 119.514969 -368.653971) (xy 119.568961 -368.661734) (xy 119.621298 -368.677101) (xy 119.670916 -368.69976)
			(xy 119.716803 -368.72925) (xy 119.758027 -368.76497) (xy 119.793748 -368.806193) (xy 119.823238 -368.852081)
			(xy 119.845898 -368.901698) (xy 119.861266 -368.954035) (xy 119.869028 -369.008027) (xy 119.869028 -369.062567)
			(xy 125.050054 -369.062567) (xy 125.050054 -369.008033) (xy 125.057815 -368.954054) (xy 125.073179 -368.901729)
			(xy 125.095833 -368.852123) (xy 125.125317 -368.806246) (xy 125.161029 -368.765031) (xy 125.202242 -368.729319)
			(xy 125.248119 -368.699835) (xy 125.297725 -368.677181) (xy 125.35005 -368.661816) (xy 125.404029 -368.654055)
			(xy 125.431296 -368.653568) (xy 126.294896 -368.653568) (xy 126.322169 -368.653971) (xy 126.376161 -368.661734)
			(xy 126.428498 -368.677101) (xy 126.478116 -368.69976) (xy 126.524003 -368.72925) (xy 126.565227 -368.76497)
			(xy 126.600948 -368.806193) (xy 126.630438 -368.852081) (xy 126.653098 -368.901698) (xy 126.668466 -368.954035)
			(xy 126.676228 -369.008027) (xy 126.676228 -369.062567) (xy 131.857254 -369.062567) (xy 131.857254 -369.008033)
			(xy 131.865015 -368.954054) (xy 131.880379 -368.901729) (xy 131.903033 -368.852123) (xy 131.932517 -368.806246)
			(xy 131.968229 -368.765031) (xy 132.009442 -368.729319) (xy 132.055319 -368.699835) (xy 132.104925 -368.677181)
			(xy 132.15725 -368.661816) (xy 132.211229 -368.654055) (xy 132.238496 -368.653568) (xy 133.102096 -368.653568)
			(xy 133.129369 -368.653971) (xy 133.183361 -368.661734) (xy 133.235698 -368.677101) (xy 133.285316 -368.69976)
			(xy 133.331203 -368.72925) (xy 133.372427 -368.76497) (xy 133.408148 -368.806193) (xy 133.437638 -368.852081)
			(xy 133.460298 -368.901698) (xy 133.475666 -368.954035) (xy 133.483428 -369.008027) (xy 133.483428 -369.062567)
			(xy 135.260854 -369.062567) (xy 135.260854 -369.008033) (xy 135.268615 -368.954054) (xy 135.283979 -368.901729)
			(xy 135.306633 -368.852123) (xy 135.336117 -368.806246) (xy 135.371829 -368.765031) (xy 135.413042 -368.729319)
			(xy 135.458919 -368.699835) (xy 135.508525 -368.677181) (xy 135.56085 -368.661816) (xy 135.614829 -368.654055)
			(xy 135.642096 -368.653568) (xy 136.505696 -368.653568) (xy 136.532969 -368.653971) (xy 136.586961 -368.661734)
			(xy 136.639298 -368.677101) (xy 136.688916 -368.69976) (xy 136.734803 -368.72925) (xy 136.776027 -368.76497)
			(xy 136.811748 -368.806193) (xy 136.841238 -368.852081) (xy 136.863898 -368.901698) (xy 136.879266 -368.954035)
			(xy 136.887028 -369.008027) (xy 136.887028 -369.062573) (xy 136.879266 -369.116565) (xy 136.863898 -369.168902)
			(xy 136.841238 -369.218519) (xy 136.811748 -369.264407) (xy 136.776027 -369.30563) (xy 136.734803 -369.34135)
			(xy 136.688916 -369.37084) (xy 136.639298 -369.393499) (xy 136.586961 -369.408866) (xy 136.532969 -369.416629)
			(xy 136.505696 -369.417092) (xy 135.642096 -369.417092) (xy 135.614829 -369.416545) (xy 135.56085 -369.408784)
			(xy 135.508525 -369.393419) (xy 135.458919 -369.370765) (xy 135.413042 -369.341281) (xy 135.371829 -369.305569)
			(xy 135.336117 -369.264354) (xy 135.306633 -369.218477) (xy 135.283979 -369.168871) (xy 135.268615 -369.116546)
			(xy 135.260854 -369.062567) (xy 133.483428 -369.062567) (xy 133.483428 -369.062573) (xy 133.475666 -369.116565)
			(xy 133.460298 -369.168902) (xy 133.437638 -369.218519) (xy 133.408148 -369.264407) (xy 133.372427 -369.30563)
			(xy 133.331203 -369.34135) (xy 133.285316 -369.37084) (xy 133.235698 -369.393499) (xy 133.183361 -369.408866)
			(xy 133.129369 -369.416629) (xy 133.102096 -369.417092) (xy 132.238496 -369.417092) (xy 132.211229 -369.416545)
			(xy 132.15725 -369.408784) (xy 132.104925 -369.393419) (xy 132.055319 -369.370765) (xy 132.009442 -369.341281)
			(xy 131.968229 -369.305569) (xy 131.932517 -369.264354) (xy 131.903033 -369.218477) (xy 131.880379 -369.168871)
			(xy 131.865015 -369.116546) (xy 131.857254 -369.062567) (xy 126.676228 -369.062567) (xy 126.676228 -369.062573)
			(xy 126.668466 -369.116565) (xy 126.653098 -369.168902) (xy 126.630438 -369.218519) (xy 126.600948 -369.264407)
			(xy 126.565227 -369.30563) (xy 126.524003 -369.34135) (xy 126.478116 -369.37084) (xy 126.428498 -369.393499)
			(xy 126.376161 -369.408866) (xy 126.322169 -369.416629) (xy 126.294896 -369.417092) (xy 125.431296 -369.417092)
			(xy 125.404029 -369.416545) (xy 125.35005 -369.408784) (xy 125.297725 -369.393419) (xy 125.248119 -369.370765)
			(xy 125.202242 -369.341281) (xy 125.161029 -369.305569) (xy 125.125317 -369.264354) (xy 125.095833 -369.218477)
			(xy 125.073179 -369.168871) (xy 125.057815 -369.116546) (xy 125.050054 -369.062567) (xy 119.869028 -369.062567)
			(xy 119.869028 -369.062573) (xy 119.861266 -369.116565) (xy 119.845898 -369.168902) (xy 119.823238 -369.218519)
			(xy 119.793748 -369.264407) (xy 119.758027 -369.30563) (xy 119.716803 -369.34135) (xy 119.670916 -369.37084)
			(xy 119.621298 -369.393499) (xy 119.568961 -369.408866) (xy 119.514969 -369.416629) (xy 119.487696 -369.417092)
			(xy 118.624096 -369.417092) (xy 118.596829 -369.416545) (xy 118.54285 -369.408784) (xy 118.490525 -369.393419)
			(xy 118.440919 -369.370765) (xy 118.395042 -369.341281) (xy 118.353829 -369.305569) (xy 118.318117 -369.264354)
			(xy 118.288633 -369.218477) (xy 118.265979 -369.168871) (xy 118.250615 -369.116546) (xy 118.242854 -369.062567)
			(xy 113.061828 -369.062567) (xy 113.061828 -369.062573) (xy 113.054066 -369.116565) (xy 113.038698 -369.168902)
			(xy 113.016038 -369.218519) (xy 112.986548 -369.264407) (xy 112.950827 -369.30563) (xy 112.909603 -369.34135)
			(xy 112.863716 -369.37084) (xy 112.814098 -369.393499) (xy 112.761761 -369.408866) (xy 112.707769 -369.416629)
			(xy 112.680496 -369.417092) (xy 111.816896 -369.417092) (xy 111.789629 -369.416545) (xy 111.73565 -369.408784)
			(xy 111.683325 -369.393419) (xy 111.633719 -369.370765) (xy 111.587842 -369.341281) (xy 111.546629 -369.305569)
			(xy 111.510917 -369.264354) (xy 111.481433 -369.218477) (xy 111.458779 -369.168871) (xy 111.443415 -369.116546)
			(xy 111.435654 -369.062567) (xy 102.314806 -369.062567) (xy 102.314806 -369.062571) (xy 102.307043 -369.116559)
			(xy 102.291677 -369.168893) (xy 102.269019 -369.218507) (xy 102.239531 -369.264391) (xy 102.203813 -369.305612)
			(xy 102.162593 -369.34133) (xy 102.116708 -369.370818) (xy 102.067094 -369.393476) (xy 102.014761 -369.408843)
			(xy 101.960773 -369.416605) (xy 101.933502 -369.417092) (xy 101.069902 -369.417092) (xy 101.042633 -369.416569)
			(xy 100.98865 -369.408807) (xy 100.936321 -369.393443) (xy 100.886712 -369.370787) (xy 100.840832 -369.341302)
			(xy 100.799614 -369.305587) (xy 100.7639 -369.26437) (xy 100.734414 -369.21849) (xy 100.711758 -369.16888)
			(xy 100.696393 -369.116552) (xy 100.688631 -369.062569) (xy 98.911206 -369.062569) (xy 98.911206 -369.062571)
			(xy 98.903443 -369.116559) (xy 98.888077 -369.168893) (xy 98.865419 -369.218507) (xy 98.835931 -369.264391)
			(xy 98.800213 -369.305612) (xy 98.758993 -369.34133) (xy 98.713108 -369.370818) (xy 98.663494 -369.393476)
			(xy 98.611161 -369.408843) (xy 98.557173 -369.416605) (xy 98.529902 -369.417092) (xy 97.666302 -369.417092)
			(xy 97.639033 -369.416569) (xy 97.58505 -369.408807) (xy 97.532721 -369.393443) (xy 97.483112 -369.370787)
			(xy 97.437232 -369.341302) (xy 97.396014 -369.305587) (xy 97.3603 -369.26437) (xy 97.330814 -369.21849)
			(xy 97.308158 -369.16888) (xy 97.292793 -369.116552) (xy 97.285031 -369.062569) (xy 92.104006 -369.062569)
			(xy 92.104006 -369.062571) (xy 92.096243 -369.116559) (xy 92.080877 -369.168893) (xy 92.058219 -369.218507)
			(xy 92.028731 -369.264391) (xy 91.993013 -369.305612) (xy 91.951793 -369.34133) (xy 91.905908 -369.370818)
			(xy 91.856294 -369.393476) (xy 91.803961 -369.408843) (xy 91.749973 -369.416605) (xy 91.722702 -369.417092)
			(xy 90.859102 -369.417092) (xy 90.831833 -369.416569) (xy 90.77785 -369.408807) (xy 90.725521 -369.393443)
			(xy 90.675912 -369.370787) (xy 90.630032 -369.341302) (xy 90.588814 -369.305587) (xy 90.5531 -369.26437)
			(xy 90.523614 -369.21849) (xy 90.500958 -369.16888) (xy 90.485593 -369.116552) (xy 90.477831 -369.062569)
			(xy 85.296806 -369.062569) (xy 85.296806 -369.062571) (xy 85.289043 -369.116559) (xy 85.273677 -369.168893)
			(xy 85.251019 -369.218507) (xy 85.221531 -369.264391) (xy 85.185813 -369.305612) (xy 85.144593 -369.34133)
			(xy 85.098708 -369.370818) (xy 85.049094 -369.393476) (xy 84.996761 -369.408843) (xy 84.942773 -369.416605)
			(xy 84.915502 -369.417092) (xy 84.051902 -369.417092) (xy 84.024633 -369.416569) (xy 83.97065 -369.408807)
			(xy 83.918321 -369.393443) (xy 83.868712 -369.370787) (xy 83.822832 -369.341302) (xy 83.781614 -369.305587)
			(xy 83.7459 -369.26437) (xy 83.716414 -369.21849) (xy 83.693758 -369.16888) (xy 83.678393 -369.116552)
			(xy 83.670631 -369.062569) (xy 78.489606 -369.062569) (xy 78.489606 -369.062571) (xy 78.481843 -369.116559)
			(xy 78.466477 -369.168893) (xy 78.443819 -369.218507) (xy 78.414331 -369.264391) (xy 78.378613 -369.305612)
			(xy 78.337393 -369.34133) (xy 78.291508 -369.370818) (xy 78.241894 -369.393476) (xy 78.189561 -369.408843)
			(xy 78.135573 -369.416605) (xy 78.108302 -369.417092) (xy 77.244702 -369.417092) (xy 77.217433 -369.416569)
			(xy 77.16345 -369.408807) (xy 77.111121 -369.393443) (xy 77.061512 -369.370787) (xy 77.015632 -369.341302)
			(xy 76.974414 -369.305587) (xy 76.9387 -369.26437) (xy 76.909214 -369.21849) (xy 76.886558 -369.16888)
			(xy 76.871193 -369.116552) (xy 76.863431 -369.062569) (xy 69.787128 -369.062569) (xy 69.787128 -369.062575)
			(xy 69.779364 -369.11657) (xy 69.763995 -369.168911) (xy 69.741332 -369.218531) (xy 69.711838 -369.26442)
			(xy 69.676112 -369.305645) (xy 69.634884 -369.341365) (xy 69.588991 -369.370854) (xy 69.539368 -369.393511)
			(xy 69.487025 -369.408874) (xy 69.433029 -369.416632) (xy 69.405754 -369.417092) (xy 68.542154 -369.417092)
			(xy 68.514889 -369.416543) (xy 68.460915 -369.408776) (xy 68.408595 -369.393408) (xy 68.358994 -369.370751)
			(xy 68.313123 -369.341266) (xy 68.271914 -369.305554) (xy 68.236206 -369.264341) (xy 68.206727 -369.218465)
			(xy 68.184076 -369.168862) (xy 68.168714 -369.11654) (xy 68.160954 -369.062565) (xy 66.383528 -369.062565)
			(xy 66.383528 -369.062575) (xy 66.375764 -369.11657) (xy 66.360395 -369.168911) (xy 66.337732 -369.218531)
			(xy 66.308238 -369.26442) (xy 66.272512 -369.305645) (xy 66.231284 -369.341365) (xy 66.185391 -369.370854)
			(xy 66.135768 -369.393511) (xy 66.083425 -369.408874) (xy 66.029429 -369.416632) (xy 66.002154 -369.417092)
			(xy 65.138554 -369.417092) (xy 65.111289 -369.416543) (xy 65.057315 -369.408776) (xy 65.004995 -369.393408)
			(xy 64.955394 -369.370751) (xy 64.909523 -369.341266) (xy 64.868314 -369.305554) (xy 64.832606 -369.264341)
			(xy 64.803127 -369.218465) (xy 64.780476 -369.168862) (xy 64.765114 -369.11654) (xy 64.757354 -369.062565)
			(xy 59.576328 -369.062565) (xy 59.576328 -369.062575) (xy 59.568564 -369.11657) (xy 59.553195 -369.168911)
			(xy 59.530532 -369.218531) (xy 59.501038 -369.26442) (xy 59.465312 -369.305645) (xy 59.424084 -369.341365)
			(xy 59.378191 -369.370854) (xy 59.328568 -369.393511) (xy 59.276225 -369.408874) (xy 59.222229 -369.416632)
			(xy 59.194954 -369.417092) (xy 58.331354 -369.417092) (xy 58.304089 -369.416543) (xy 58.250115 -369.408776)
			(xy 58.197795 -369.393408) (xy 58.148194 -369.370751) (xy 58.102323 -369.341266) (xy 58.061114 -369.305554)
			(xy 58.025406 -369.264341) (xy 57.995927 -369.218465) (xy 57.973276 -369.168862) (xy 57.957914 -369.11654)
			(xy 57.950154 -369.062565) (xy 52.769128 -369.062565) (xy 52.769128 -369.062575) (xy 52.761364 -369.11657)
			(xy 52.745995 -369.168911) (xy 52.723332 -369.218531) (xy 52.693838 -369.26442) (xy 52.658112 -369.305645)
			(xy 52.616884 -369.341365) (xy 52.570991 -369.370854) (xy 52.521368 -369.393511) (xy 52.469025 -369.408874)
			(xy 52.415029 -369.416632) (xy 52.387754 -369.417092) (xy 51.524154 -369.417092) (xy 51.496889 -369.416543)
			(xy 51.442915 -369.408776) (xy 51.390595 -369.393408) (xy 51.340994 -369.370751) (xy 51.295123 -369.341266)
			(xy 51.253914 -369.305554) (xy 51.218206 -369.264341) (xy 51.188727 -369.218465) (xy 51.166076 -369.168862)
			(xy 51.150714 -369.11654) (xy 51.142954 -369.062565) (xy 45.961928 -369.062565) (xy 45.961928 -369.062575)
			(xy 45.954164 -369.11657) (xy 45.938795 -369.168911) (xy 45.916132 -369.218531) (xy 45.886638 -369.26442)
			(xy 45.850912 -369.305645) (xy 45.809684 -369.341365) (xy 45.763791 -369.370854) (xy 45.714168 -369.393511)
			(xy 45.661825 -369.408874) (xy 45.607829 -369.416632) (xy 45.580554 -369.417092) (xy 44.716954 -369.417092)
			(xy 44.689689 -369.416543) (xy 44.635715 -369.408776) (xy 44.583395 -369.393408) (xy 44.533794 -369.370751)
			(xy 44.487923 -369.341266) (xy 44.446714 -369.305554) (xy 44.411006 -369.264341) (xy 44.381527 -369.218465)
			(xy 44.358876 -369.168862) (xy 44.343514 -369.11654) (xy 44.335754 -369.062565) (xy 2.509012 -369.062565)
			(xy 2.509012 -370.206778) (xy 138.3665 -370.206778) (xy 138.3665 -369.343178) (xy 138.366986 -369.315909)
			(xy 138.374748 -369.261925) (xy 138.390113 -369.209595) (xy 138.41277 -369.159985) (xy 138.442256 -369.114104)
			(xy 138.477971 -369.072887) (xy 138.519188 -369.037172) (xy 138.565069 -369.007686) (xy 138.614679 -368.985029)
			(xy 138.667009 -368.969664) (xy 138.720993 -368.961902) (xy 138.775531 -368.961902) (xy 138.829515 -368.969664)
			(xy 138.881845 -368.985029) (xy 138.931455 -369.007686) (xy 138.977336 -369.037172) (xy 139.006648 -369.062571)
			(xy 143.963332 -369.062571) (xy 143.963332 -369.008029) (xy 143.971094 -368.954043) (xy 143.986461 -368.901711)
			(xy 144.009121 -368.852098) (xy 144.03861 -368.806216) (xy 144.074329 -368.764998) (xy 144.115551 -368.729284)
			(xy 144.161437 -368.699799) (xy 144.211052 -368.677146) (xy 144.263386 -368.661785) (xy 144.317373 -368.654028)
			(xy 144.344644 -368.653568) (xy 145.208244 -368.653568) (xy 145.235513 -368.653998) (xy 145.289497 -368.661765)
			(xy 145.341825 -368.677135) (xy 145.391433 -368.699796) (xy 145.437312 -368.729285) (xy 145.478528 -368.765003)
			(xy 145.514241 -368.806223) (xy 145.543725 -368.852105) (xy 145.56638 -368.901716) (xy 145.581744 -368.954047)
			(xy 145.589506 -369.00803) (xy 145.589506 -369.06257) (xy 145.589506 -369.062571) (xy 150.770532 -369.062571)
			(xy 150.770532 -369.008029) (xy 150.778294 -368.954043) (xy 150.793661 -368.901711) (xy 150.816321 -368.852098)
			(xy 150.84581 -368.806216) (xy 150.881529 -368.764998) (xy 150.922751 -368.729284) (xy 150.968637 -368.699799)
			(xy 151.018252 -368.677146) (xy 151.070586 -368.661785) (xy 151.124573 -368.654028) (xy 151.151844 -368.653568)
			(xy 152.015444 -368.653568) (xy 152.042713 -368.653998) (xy 152.096697 -368.661765) (xy 152.149025 -368.677135)
			(xy 152.198633 -368.699796) (xy 152.244512 -368.729285) (xy 152.285728 -368.765003) (xy 152.321441 -368.806223)
			(xy 152.350925 -368.852105) (xy 152.37358 -368.901716) (xy 152.388944 -368.954047) (xy 152.396706 -369.00803)
			(xy 152.396706 -369.06257) (xy 152.396706 -369.062571) (xy 157.577732 -369.062571) (xy 157.577732 -369.008029)
			(xy 157.585494 -368.954043) (xy 157.600861 -368.901711) (xy 157.623521 -368.852098) (xy 157.65301 -368.806216)
			(xy 157.688729 -368.764998) (xy 157.729951 -368.729284) (xy 157.775837 -368.699799) (xy 157.825452 -368.677146)
			(xy 157.877786 -368.661785) (xy 157.931773 -368.654028) (xy 157.959044 -368.653568) (xy 158.822644 -368.653568)
			(xy 158.849913 -368.653998) (xy 158.903897 -368.661765) (xy 158.956225 -368.677135) (xy 159.005833 -368.699796)
			(xy 159.051712 -368.729285) (xy 159.092928 -368.765003) (xy 159.128641 -368.806223) (xy 159.158125 -368.852105)
			(xy 159.18078 -368.901716) (xy 159.196144 -368.954047) (xy 159.203906 -369.00803) (xy 159.203906 -369.06257)
			(xy 159.203906 -369.062571) (xy 164.384932 -369.062571) (xy 164.384932 -369.008029) (xy 164.392694 -368.954043)
			(xy 164.408061 -368.901711) (xy 164.430721 -368.852098) (xy 164.46021 -368.806216) (xy 164.495929 -368.764998)
			(xy 164.537151 -368.729284) (xy 164.583037 -368.699799) (xy 164.632652 -368.677146) (xy 164.684986 -368.661785)
			(xy 164.738973 -368.654028) (xy 164.766244 -368.653568) (xy 165.629844 -368.653568) (xy 165.657113 -368.653998)
			(xy 165.711097 -368.661765) (xy 165.763425 -368.677135) (xy 165.813033 -368.699796) (xy 165.858912 -368.729285)
			(xy 165.900128 -368.765003) (xy 165.935841 -368.806223) (xy 165.965325 -368.852105) (xy 165.98798 -368.901716)
			(xy 166.003344 -368.954047) (xy 166.011106 -369.00803) (xy 166.011106 -369.06257) (xy 166.011106 -369.062571)
			(xy 167.788532 -369.062571) (xy 167.788532 -369.008029) (xy 167.796294 -368.954043) (xy 167.811661 -368.901711)
			(xy 167.834321 -368.852098) (xy 167.86381 -368.806216) (xy 167.899529 -368.764998) (xy 167.940751 -368.729284)
			(xy 167.986637 -368.699799) (xy 168.036252 -368.677146) (xy 168.088586 -368.661785) (xy 168.142573 -368.654028)
			(xy 168.169844 -368.653568) (xy 169.033444 -368.653568) (xy 169.060713 -368.653998) (xy 169.114697 -368.661765)
			(xy 169.167025 -368.677135) (xy 169.216633 -368.699796) (xy 169.262512 -368.729285) (xy 169.303728 -368.765003)
			(xy 169.339441 -368.806223) (xy 169.368925 -368.852105) (xy 169.39158 -368.901716) (xy 169.406944 -368.954047)
			(xy 169.414706 -369.00803) (xy 169.414706 -369.06257) (xy 169.406944 -369.116553) (xy 169.39158 -369.168884)
			(xy 169.368925 -369.218495) (xy 169.339441 -369.264377) (xy 169.303728 -369.305597) (xy 169.262512 -369.341315)
			(xy 169.216633 -369.370804) (xy 169.167025 -369.393465) (xy 169.114697 -369.408835) (xy 169.060713 -369.416602)
			(xy 169.033444 -369.417092) (xy 168.169844 -369.417092) (xy 168.142573 -369.416572) (xy 168.088586 -369.408815)
			(xy 168.036252 -369.393454) (xy 167.986637 -369.370801) (xy 167.940751 -369.341316) (xy 167.899529 -369.305602)
			(xy 167.86381 -369.264384) (xy 167.834321 -369.218502) (xy 167.811661 -369.168889) (xy 167.796294 -369.116557)
			(xy 167.788532 -369.062571) (xy 166.011106 -369.062571) (xy 166.003344 -369.116553) (xy 165.98798 -369.168884)
			(xy 165.965325 -369.218495) (xy 165.935841 -369.264377) (xy 165.900128 -369.305597) (xy 165.858912 -369.341315)
			(xy 165.813033 -369.370804) (xy 165.763425 -369.393465) (xy 165.711097 -369.408835) (xy 165.657113 -369.416602)
			(xy 165.629844 -369.417092) (xy 164.766244 -369.417092) (xy 164.738973 -369.416572) (xy 164.684986 -369.408815)
			(xy 164.632652 -369.393454) (xy 164.583037 -369.370801) (xy 164.537151 -369.341316) (xy 164.495929 -369.305602)
			(xy 164.46021 -369.264384) (xy 164.430721 -369.218502) (xy 164.408061 -369.168889) (xy 164.392694 -369.116557)
			(xy 164.384932 -369.062571) (xy 159.203906 -369.062571) (xy 159.196144 -369.116553) (xy 159.18078 -369.168884)
			(xy 159.158125 -369.218495) (xy 159.128641 -369.264377) (xy 159.092928 -369.305597) (xy 159.051712 -369.341315)
			(xy 159.005833 -369.370804) (xy 158.956225 -369.393465) (xy 158.903897 -369.408835) (xy 158.849913 -369.416602)
			(xy 158.822644 -369.417092) (xy 157.959044 -369.417092) (xy 157.931773 -369.416572) (xy 157.877786 -369.408815)
			(xy 157.825452 -369.393454) (xy 157.775837 -369.370801) (xy 157.729951 -369.341316) (xy 157.688729 -369.305602)
			(xy 157.65301 -369.264384) (xy 157.623521 -369.218502) (xy 157.600861 -369.168889) (xy 157.585494 -369.116557)
			(xy 157.577732 -369.062571) (xy 152.396706 -369.062571) (xy 152.388944 -369.116553) (xy 152.37358 -369.168884)
			(xy 152.350925 -369.218495) (xy 152.321441 -369.264377) (xy 152.285728 -369.305597) (xy 152.244512 -369.341315)
			(xy 152.198633 -369.370804) (xy 152.149025 -369.393465) (xy 152.096697 -369.408835) (xy 152.042713 -369.416602)
			(xy 152.015444 -369.417092) (xy 151.151844 -369.417092) (xy 151.124573 -369.416572) (xy 151.070586 -369.408815)
			(xy 151.018252 -369.393454) (xy 150.968637 -369.370801) (xy 150.922751 -369.341316) (xy 150.881529 -369.305602)
			(xy 150.84581 -369.264384) (xy 150.816321 -369.218502) (xy 150.793661 -369.168889) (xy 150.778294 -369.116557)
			(xy 150.770532 -369.062571) (xy 145.589506 -369.062571) (xy 145.581744 -369.116553) (xy 145.56638 -369.168884)
			(xy 145.543725 -369.218495) (xy 145.514241 -369.264377) (xy 145.478528 -369.305597) (xy 145.437312 -369.341315)
			(xy 145.391433 -369.370804) (xy 145.341825 -369.393465) (xy 145.289497 -369.408835) (xy 145.235513 -369.416602)
			(xy 145.208244 -369.417092) (xy 144.344644 -369.417092) (xy 144.317373 -369.416572) (xy 144.263386 -369.408815)
			(xy 144.211052 -369.393454) (xy 144.161437 -369.370801) (xy 144.115551 -369.341316) (xy 144.074329 -369.305602)
			(xy 144.03861 -369.264384) (xy 144.009121 -369.218502) (xy 143.986461 -369.168889) (xy 143.971094 -369.116557)
			(xy 143.963332 -369.062571) (xy 139.006648 -369.062571) (xy 139.018553 -369.072887) (xy 139.054268 -369.114104)
			(xy 139.083754 -369.159985) (xy 139.106411 -369.209595) (xy 139.121776 -369.261925) (xy 139.129538 -369.315909)
			(xy 139.130024 -369.343178) (xy 139.130024 -370.206778) (xy 139.129538 -370.234047) (xy 139.121776 -370.288031)
			(xy 139.106411 -370.340361) (xy 139.083754 -370.389971) (xy 139.071223 -370.40947) (xy 141.572996 -370.40947)
			(xy 141.572996 -369.54587) (xy 141.573482 -369.518619) (xy 141.581238 -369.464671) (xy 141.596593 -369.412376)
			(xy 141.619235 -369.362799) (xy 141.648701 -369.316949) (xy 141.684392 -369.275758) (xy 141.725583 -369.240067)
			(xy 141.771433 -369.210601) (xy 141.82101 -369.187959) (xy 141.873305 -369.172604) (xy 141.927253 -369.164848)
			(xy 141.981755 -369.164848) (xy 142.035703 -369.172604) (xy 142.087998 -369.187959) (xy 142.137575 -369.210601)
			(xy 142.183425 -369.240067) (xy 142.224616 -369.275758) (xy 142.260307 -369.316949) (xy 142.289773 -369.362799)
			(xy 142.312415 -369.412376) (xy 142.32777 -369.464671) (xy 142.335526 -369.518619) (xy 142.336012 -369.54587)
			(xy 142.336012 -369.62565) (xy 175.203103 -369.62565) (xy 175.203103 -369.57115) (xy 175.210859 -369.517206)
			(xy 175.226214 -369.464914) (xy 175.248854 -369.41534) (xy 175.278318 -369.369493) (xy 175.314008 -369.328305)
			(xy 175.355196 -369.292616) (xy 175.401044 -369.263152) (xy 175.450618 -369.240512) (xy 175.50291 -369.225158)
			(xy 175.556854 -369.217403) (xy 175.584104 -369.21694) (xy 176.447704 -369.21694) (xy 176.474958 -369.21733)
			(xy 176.528913 -369.225088) (xy 176.581213 -369.240446) (xy 176.630796 -369.26309) (xy 176.676652 -369.29256)
			(xy 176.717847 -369.328256) (xy 176.753543 -369.369451) (xy 176.783012 -369.415307) (xy 176.805656 -369.46489)
			(xy 176.821013 -369.517191) (xy 176.82877 -369.571146) (xy 176.82877 -369.625654) (xy 176.821013 -369.679609)
			(xy 176.805656 -369.73191) (xy 176.783012 -369.781493) (xy 176.753543 -369.827349) (xy 176.717847 -369.868544)
			(xy 176.676652 -369.90424) (xy 176.630796 -369.93371) (xy 176.581213 -369.956354) (xy 176.528913 -369.971712)
			(xy 176.474958 -369.97947) (xy 176.447704 -369.979956) (xy 175.584104 -369.979956) (xy 175.556854 -369.979397)
			(xy 175.50291 -369.971642) (xy 175.450618 -369.956288) (xy 175.401044 -369.933648) (xy 175.355196 -369.904184)
			(xy 175.314008 -369.868495) (xy 175.278318 -369.827307) (xy 175.248854 -369.78146) (xy 175.226214 -369.731886)
			(xy 175.210859 -369.679594) (xy 175.203103 -369.62565) (xy 142.336012 -369.62565) (xy 142.336012 -370.40947)
			(xy 142.335526 -370.436721) (xy 142.32777 -370.490669) (xy 142.312415 -370.542964) (xy 142.289773 -370.592541)
			(xy 142.260307 -370.638391) (xy 142.224616 -370.679582) (xy 142.183425 -370.715273) (xy 142.137575 -370.744739)
			(xy 142.087998 -370.767381) (xy 142.035703 -370.782736) (xy 141.981755 -370.790492) (xy 141.927253 -370.790492)
			(xy 141.873305 -370.782736) (xy 141.82101 -370.767381) (xy 141.771433 -370.744739) (xy 141.725583 -370.715273)
			(xy 141.684392 -370.679582) (xy 141.648701 -370.638391) (xy 141.619235 -370.592541) (xy 141.596593 -370.542964)
			(xy 141.581238 -370.490669) (xy 141.573482 -370.436721) (xy 141.572996 -370.40947) (xy 139.071223 -370.40947)
			(xy 139.054268 -370.435852) (xy 139.018553 -370.477069) (xy 138.977336 -370.512784) (xy 138.931455 -370.54227)
			(xy 138.881845 -370.564927) (xy 138.829515 -370.580292) (xy 138.775531 -370.588054) (xy 138.720993 -370.588054)
			(xy 138.667009 -370.580292) (xy 138.614679 -370.564927) (xy 138.565069 -370.54227) (xy 138.519188 -370.512784)
			(xy 138.477971 -370.477069) (xy 138.442256 -370.435852) (xy 138.41277 -370.389971) (xy 138.390113 -370.340361)
			(xy 138.374748 -370.288031) (xy 138.366986 -370.234047) (xy 138.3665 -370.206778) (xy 2.509012 -370.206778)
			(xy 2.509012 -371.526365) (xy 42.633954 -371.526365) (xy 42.633954 -371.471835) (xy 42.641714 -371.41786)
			(xy 42.657076 -371.365538) (xy 42.679727 -371.315935) (xy 42.709206 -371.270059) (xy 42.744914 -371.228846)
			(xy 42.786123 -371.193134) (xy 42.831994 -371.163649) (xy 42.881595 -371.140992) (xy 42.933915 -371.125624)
			(xy 42.987889 -371.117857) (xy 43.015154 -371.117368) (xy 43.878754 -371.117368) (xy 43.906029 -371.117768)
			(xy 43.960025 -371.125526) (xy 44.012368 -371.140889) (xy 44.061991 -371.163546) (xy 44.107884 -371.193035)
			(xy 44.149112 -371.228755) (xy 44.184838 -371.26998) (xy 44.214332 -371.315869) (xy 44.236995 -371.365489)
			(xy 44.252364 -371.41783) (xy 44.260128 -371.471825) (xy 44.260128 -371.526365) (xy 49.441154 -371.526365)
			(xy 49.441154 -371.471835) (xy 49.448914 -371.41786) (xy 49.464276 -371.365538) (xy 49.486927 -371.315935)
			(xy 49.516406 -371.270059) (xy 49.552114 -371.228846) (xy 49.593323 -371.193134) (xy 49.639194 -371.163649)
			(xy 49.688795 -371.140992) (xy 49.741115 -371.125624) (xy 49.795089 -371.117857) (xy 49.822354 -371.117368)
			(xy 50.685954 -371.117368) (xy 50.713229 -371.117768) (xy 50.767225 -371.125526) (xy 50.819568 -371.140889)
			(xy 50.869191 -371.163546) (xy 50.915084 -371.193035) (xy 50.956312 -371.228755) (xy 50.992038 -371.26998)
			(xy 51.021532 -371.315869) (xy 51.044195 -371.365489) (xy 51.059564 -371.41783) (xy 51.067328 -371.471825)
			(xy 51.067328 -371.526365) (xy 56.248354 -371.526365) (xy 56.248354 -371.471835) (xy 56.256114 -371.41786)
			(xy 56.271476 -371.365538) (xy 56.294127 -371.315935) (xy 56.323606 -371.270059) (xy 56.359314 -371.228846)
			(xy 56.400523 -371.193134) (xy 56.446394 -371.163649) (xy 56.495995 -371.140992) (xy 56.548315 -371.125624)
			(xy 56.602289 -371.117857) (xy 56.629554 -371.117368) (xy 57.493154 -371.117368) (xy 57.520429 -371.117768)
			(xy 57.574425 -371.125526) (xy 57.626768 -371.140889) (xy 57.676391 -371.163546) (xy 57.722284 -371.193035)
			(xy 57.763512 -371.228755) (xy 57.799238 -371.26998) (xy 57.828732 -371.315869) (xy 57.851395 -371.365489)
			(xy 57.866764 -371.41783) (xy 57.874528 -371.471825) (xy 57.874528 -371.526365) (xy 63.055554 -371.526365)
			(xy 63.055554 -371.471835) (xy 63.063314 -371.41786) (xy 63.078676 -371.365538) (xy 63.101327 -371.315935)
			(xy 63.130806 -371.270059) (xy 63.166514 -371.228846) (xy 63.207723 -371.193134) (xy 63.253594 -371.163649)
			(xy 63.303195 -371.140992) (xy 63.355515 -371.125624) (xy 63.409489 -371.117857) (xy 63.436754 -371.117368)
			(xy 64.300354 -371.117368) (xy 64.327629 -371.117768) (xy 64.381625 -371.125526) (xy 64.433968 -371.140889)
			(xy 64.483591 -371.163546) (xy 64.529484 -371.193035) (xy 64.570712 -371.228755) (xy 64.606438 -371.26998)
			(xy 64.635932 -371.315869) (xy 64.658595 -371.365489) (xy 64.673964 -371.41783) (xy 64.681728 -371.471825)
			(xy 64.681728 -371.526369) (xy 75.161631 -371.526369) (xy 75.161631 -371.471831) (xy 75.169393 -371.417848)
			(xy 75.184758 -371.36552) (xy 75.207414 -371.31591) (xy 75.2369 -371.27003) (xy 75.272614 -371.228813)
			(xy 75.313832 -371.193098) (xy 75.359712 -371.163613) (xy 75.409321 -371.140957) (xy 75.46165 -371.125593)
			(xy 75.515633 -371.117831) (xy 75.542902 -371.117368) (xy 76.406502 -371.117368) (xy 76.433773 -371.117795)
			(xy 76.487761 -371.125557) (xy 76.540094 -371.140924) (xy 76.589708 -371.163582) (xy 76.635593 -371.19307)
			(xy 76.676813 -371.228788) (xy 76.712531 -371.270009) (xy 76.742019 -371.315893) (xy 76.764677 -371.365507)
			(xy 76.780043 -371.417841) (xy 76.787806 -371.471829) (xy 76.787806 -371.526369) (xy 81.968831 -371.526369)
			(xy 81.968831 -371.471831) (xy 81.976593 -371.417848) (xy 81.991958 -371.36552) (xy 82.014614 -371.31591)
			(xy 82.0441 -371.27003) (xy 82.079814 -371.228813) (xy 82.121032 -371.193098) (xy 82.166912 -371.163613)
			(xy 82.216521 -371.140957) (xy 82.26885 -371.125593) (xy 82.322833 -371.117831) (xy 82.350102 -371.117368)
			(xy 83.213702 -371.117368) (xy 83.240973 -371.117795) (xy 83.294961 -371.125557) (xy 83.347294 -371.140924)
			(xy 83.396908 -371.163582) (xy 83.442793 -371.19307) (xy 83.484013 -371.228788) (xy 83.519731 -371.270009)
			(xy 83.549219 -371.315893) (xy 83.571877 -371.365507) (xy 83.587243 -371.417841) (xy 83.595006 -371.471829)
			(xy 83.595006 -371.526369) (xy 88.776031 -371.526369) (xy 88.776031 -371.471831) (xy 88.783793 -371.417848)
			(xy 88.799158 -371.36552) (xy 88.821814 -371.31591) (xy 88.8513 -371.27003) (xy 88.887014 -371.228813)
			(xy 88.928232 -371.193098) (xy 88.974112 -371.163613) (xy 89.023721 -371.140957) (xy 89.07605 -371.125593)
			(xy 89.130033 -371.117831) (xy 89.157302 -371.117368) (xy 90.020902 -371.117368) (xy 90.048173 -371.117795)
			(xy 90.102161 -371.125557) (xy 90.154494 -371.140924) (xy 90.204108 -371.163582) (xy 90.249993 -371.19307)
			(xy 90.291213 -371.228788) (xy 90.326931 -371.270009) (xy 90.356419 -371.315893) (xy 90.379077 -371.365507)
			(xy 90.394443 -371.417841) (xy 90.402206 -371.471829) (xy 90.402206 -371.526369) (xy 95.583231 -371.526369)
			(xy 95.583231 -371.471831) (xy 95.590993 -371.417848) (xy 95.606358 -371.36552) (xy 95.629014 -371.31591)
			(xy 95.6585 -371.27003) (xy 95.694214 -371.228813) (xy 95.735432 -371.193098) (xy 95.781312 -371.163613)
			(xy 95.830921 -371.140957) (xy 95.88325 -371.125593) (xy 95.937233 -371.117831) (xy 95.964502 -371.117368)
			(xy 96.828102 -371.117368) (xy 96.855373 -371.117795) (xy 96.909361 -371.125557) (xy 96.961694 -371.140924)
			(xy 97.011308 -371.163582) (xy 97.057193 -371.19307) (xy 97.098413 -371.228788) (xy 97.134131 -371.270009)
			(xy 97.163619 -371.315893) (xy 97.186277 -371.365507) (xy 97.201643 -371.417841) (xy 97.209406 -371.471829)
			(xy 97.209406 -371.526367) (xy 109.733854 -371.526367) (xy 109.733854 -371.471833) (xy 109.741615 -371.417854)
			(xy 109.756979 -371.365529) (xy 109.779633 -371.315923) (xy 109.809117 -371.270046) (xy 109.844829 -371.228831)
			(xy 109.886042 -371.193119) (xy 109.931919 -371.163635) (xy 109.981525 -371.140981) (xy 110.03385 -371.125616)
			(xy 110.087829 -371.117855) (xy 110.115096 -371.117368) (xy 110.978696 -371.117368) (xy 111.005969 -371.117771)
			(xy 111.059961 -371.125534) (xy 111.112298 -371.140901) (xy 111.161916 -371.16356) (xy 111.207803 -371.19305)
			(xy 111.249027 -371.22877) (xy 111.284748 -371.269993) (xy 111.314238 -371.315881) (xy 111.336898 -371.365498)
			(xy 111.352266 -371.417835) (xy 111.360028 -371.471827) (xy 111.360028 -371.526367) (xy 116.541054 -371.526367)
			(xy 116.541054 -371.471833) (xy 116.548815 -371.417854) (xy 116.564179 -371.365529) (xy 116.586833 -371.315923)
			(xy 116.616317 -371.270046) (xy 116.652029 -371.228831) (xy 116.693242 -371.193119) (xy 116.739119 -371.163635)
			(xy 116.788725 -371.140981) (xy 116.84105 -371.125616) (xy 116.895029 -371.117855) (xy 116.922296 -371.117368)
			(xy 117.785896 -371.117368) (xy 117.813169 -371.117771) (xy 117.867161 -371.125534) (xy 117.919498 -371.140901)
			(xy 117.969116 -371.16356) (xy 118.015003 -371.19305) (xy 118.056227 -371.22877) (xy 118.091948 -371.269993)
			(xy 118.121438 -371.315881) (xy 118.144098 -371.365498) (xy 118.159466 -371.417835) (xy 118.167228 -371.471827)
			(xy 118.167228 -371.526367) (xy 123.348254 -371.526367) (xy 123.348254 -371.471833) (xy 123.356015 -371.417854)
			(xy 123.371379 -371.365529) (xy 123.394033 -371.315923) (xy 123.423517 -371.270046) (xy 123.459229 -371.228831)
			(xy 123.500442 -371.193119) (xy 123.546319 -371.163635) (xy 123.595925 -371.140981) (xy 123.64825 -371.125616)
			(xy 123.702229 -371.117855) (xy 123.729496 -371.117368) (xy 124.593096 -371.117368) (xy 124.620369 -371.117771)
			(xy 124.674361 -371.125534) (xy 124.726698 -371.140901) (xy 124.776316 -371.16356) (xy 124.822203 -371.19305)
			(xy 124.863427 -371.22877) (xy 124.899148 -371.269993) (xy 124.928638 -371.315881) (xy 124.951298 -371.365498)
			(xy 124.966666 -371.417835) (xy 124.974428 -371.471827) (xy 124.974428 -371.526367) (xy 130.155454 -371.526367)
			(xy 130.155454 -371.471833) (xy 130.163215 -371.417854) (xy 130.178579 -371.365529) (xy 130.201233 -371.315923)
			(xy 130.230717 -371.270046) (xy 130.266429 -371.228831) (xy 130.307642 -371.193119) (xy 130.353519 -371.163635)
			(xy 130.403125 -371.140981) (xy 130.45545 -371.125616) (xy 130.509429 -371.117855) (xy 130.536696 -371.117368)
			(xy 131.400296 -371.117368) (xy 131.427569 -371.117771) (xy 131.481561 -371.125534) (xy 131.533898 -371.140901)
			(xy 131.583516 -371.16356) (xy 131.629403 -371.19305) (xy 131.670627 -371.22877) (xy 131.706348 -371.269993)
			(xy 131.735838 -371.315881) (xy 131.758498 -371.365498) (xy 131.773866 -371.417835) (xy 131.781628 -371.471827)
			(xy 131.781628 -371.526371) (xy 142.261532 -371.526371) (xy 142.261532 -371.471829) (xy 142.269294 -371.417843)
			(xy 142.284661 -371.365511) (xy 142.307321 -371.315898) (xy 142.33681 -371.270016) (xy 142.372529 -371.228798)
			(xy 142.413751 -371.193084) (xy 142.459637 -371.163599) (xy 142.509252 -371.140946) (xy 142.561586 -371.125585)
			(xy 142.615573 -371.117828) (xy 142.642844 -371.117368) (xy 143.506444 -371.117368) (xy 143.533713 -371.117798)
			(xy 143.587697 -371.125565) (xy 143.640025 -371.140935) (xy 143.689633 -371.163596) (xy 143.735512 -371.193085)
			(xy 143.776728 -371.228803) (xy 143.812441 -371.270023) (xy 143.841925 -371.315905) (xy 143.86458 -371.365516)
			(xy 143.879944 -371.417847) (xy 143.887706 -371.47183) (xy 143.887706 -371.52637) (xy 143.887706 -371.526371)
			(xy 149.068732 -371.526371) (xy 149.068732 -371.471829) (xy 149.076494 -371.417843) (xy 149.091861 -371.365511)
			(xy 149.114521 -371.315898) (xy 149.14401 -371.270016) (xy 149.179729 -371.228798) (xy 149.220951 -371.193084)
			(xy 149.266837 -371.163599) (xy 149.316452 -371.140946) (xy 149.368786 -371.125585) (xy 149.422773 -371.117828)
			(xy 149.450044 -371.117368) (xy 150.313644 -371.117368) (xy 150.340913 -371.117798) (xy 150.394897 -371.125565)
			(xy 150.447225 -371.140935) (xy 150.496833 -371.163596) (xy 150.542712 -371.193085) (xy 150.583928 -371.228803)
			(xy 150.619641 -371.270023) (xy 150.649125 -371.315905) (xy 150.67178 -371.365516) (xy 150.687144 -371.417847)
			(xy 150.694906 -371.47183) (xy 150.694906 -371.52637) (xy 150.694906 -371.526371) (xy 155.875932 -371.526371)
			(xy 155.875932 -371.471829) (xy 155.883694 -371.417843) (xy 155.899061 -371.365511) (xy 155.921721 -371.315898)
			(xy 155.95121 -371.270016) (xy 155.986929 -371.228798) (xy 156.028151 -371.193084) (xy 156.074037 -371.163599)
			(xy 156.123652 -371.140946) (xy 156.175986 -371.125585) (xy 156.229973 -371.117828) (xy 156.257244 -371.117368)
			(xy 157.120844 -371.117368) (xy 157.148113 -371.117798) (xy 157.202097 -371.125565) (xy 157.254425 -371.140935)
			(xy 157.304033 -371.163596) (xy 157.349912 -371.193085) (xy 157.391128 -371.228803) (xy 157.426841 -371.270023)
			(xy 157.456325 -371.315905) (xy 157.47898 -371.365516) (xy 157.494344 -371.417847) (xy 157.502106 -371.47183)
			(xy 157.502106 -371.52637) (xy 157.502106 -371.526371) (xy 162.683132 -371.526371) (xy 162.683132 -371.471829)
			(xy 162.690894 -371.417843) (xy 162.706261 -371.365511) (xy 162.728921 -371.315898) (xy 162.75841 -371.270016)
			(xy 162.794129 -371.228798) (xy 162.835351 -371.193084) (xy 162.881237 -371.163599) (xy 162.930852 -371.140946)
			(xy 162.983186 -371.125585) (xy 163.037173 -371.117828) (xy 163.064444 -371.117368) (xy 163.928044 -371.117368)
			(xy 163.955313 -371.117798) (xy 164.009297 -371.125565) (xy 164.061625 -371.140935) (xy 164.111233 -371.163596)
			(xy 164.157112 -371.193085) (xy 164.198328 -371.228803) (xy 164.234041 -371.270023) (xy 164.263525 -371.315905)
			(xy 164.28618 -371.365516) (xy 164.301544 -371.417847) (xy 164.309306 -371.47183) (xy 164.309306 -371.52637)
			(xy 164.301544 -371.580353) (xy 164.28618 -371.632684) (xy 164.263525 -371.682295) (xy 164.234041 -371.728177)
			(xy 164.198328 -371.769397) (xy 164.157112 -371.805115) (xy 164.111233 -371.834604) (xy 164.061625 -371.857265)
			(xy 164.009297 -371.872635) (xy 163.955313 -371.880402) (xy 163.928044 -371.880892) (xy 163.064444 -371.880892)
			(xy 163.037173 -371.880372) (xy 162.983186 -371.872615) (xy 162.930852 -371.857254) (xy 162.881237 -371.834601)
			(xy 162.835351 -371.805116) (xy 162.794129 -371.769402) (xy 162.75841 -371.728184) (xy 162.728921 -371.682302)
			(xy 162.706261 -371.632689) (xy 162.690894 -371.580357) (xy 162.683132 -371.526371) (xy 157.502106 -371.526371)
			(xy 157.494344 -371.580353) (xy 157.47898 -371.632684) (xy 157.456325 -371.682295) (xy 157.426841 -371.728177)
			(xy 157.391128 -371.769397) (xy 157.349912 -371.805115) (xy 157.304033 -371.834604) (xy 157.254425 -371.857265)
			(xy 157.202097 -371.872635) (xy 157.148113 -371.880402) (xy 157.120844 -371.880892) (xy 156.257244 -371.880892)
			(xy 156.229973 -371.880372) (xy 156.175986 -371.872615) (xy 156.123652 -371.857254) (xy 156.074037 -371.834601)
			(xy 156.028151 -371.805116) (xy 155.986929 -371.769402) (xy 155.95121 -371.728184) (xy 155.921721 -371.682302)
			(xy 155.899061 -371.632689) (xy 155.883694 -371.580357) (xy 155.875932 -371.526371) (xy 150.694906 -371.526371)
			(xy 150.687144 -371.580353) (xy 150.67178 -371.632684) (xy 150.649125 -371.682295) (xy 150.619641 -371.728177)
			(xy 150.583928 -371.769397) (xy 150.542712 -371.805115) (xy 150.496833 -371.834604) (xy 150.447225 -371.857265)
			(xy 150.394897 -371.872635) (xy 150.340913 -371.880402) (xy 150.313644 -371.880892) (xy 149.450044 -371.880892)
			(xy 149.422773 -371.880372) (xy 149.368786 -371.872615) (xy 149.316452 -371.857254) (xy 149.266837 -371.834601)
			(xy 149.220951 -371.805116) (xy 149.179729 -371.769402) (xy 149.14401 -371.728184) (xy 149.114521 -371.682302)
			(xy 149.091861 -371.632689) (xy 149.076494 -371.580357) (xy 149.068732 -371.526371) (xy 143.887706 -371.526371)
			(xy 143.879944 -371.580353) (xy 143.86458 -371.632684) (xy 143.841925 -371.682295) (xy 143.812441 -371.728177)
			(xy 143.776728 -371.769397) (xy 143.735512 -371.805115) (xy 143.689633 -371.834604) (xy 143.640025 -371.857265)
			(xy 143.587697 -371.872635) (xy 143.533713 -371.880402) (xy 143.506444 -371.880892) (xy 142.642844 -371.880892)
			(xy 142.615573 -371.880372) (xy 142.561586 -371.872615) (xy 142.509252 -371.857254) (xy 142.459637 -371.834601)
			(xy 142.413751 -371.805116) (xy 142.372529 -371.769402) (xy 142.33681 -371.728184) (xy 142.307321 -371.682302)
			(xy 142.284661 -371.632689) (xy 142.269294 -371.580357) (xy 142.261532 -371.526371) (xy 131.781628 -371.526371)
			(xy 131.781628 -371.526373) (xy 131.773866 -371.580365) (xy 131.758498 -371.632702) (xy 131.735838 -371.682319)
			(xy 131.706348 -371.728207) (xy 131.670627 -371.76943) (xy 131.629403 -371.80515) (xy 131.583516 -371.83464)
			(xy 131.533898 -371.857299) (xy 131.481561 -371.872666) (xy 131.427569 -371.880429) (xy 131.400296 -371.880892)
			(xy 130.536696 -371.880892) (xy 130.509429 -371.880345) (xy 130.45545 -371.872584) (xy 130.403125 -371.857219)
			(xy 130.353519 -371.834565) (xy 130.307642 -371.805081) (xy 130.266429 -371.769369) (xy 130.230717 -371.728154)
			(xy 130.201233 -371.682277) (xy 130.178579 -371.632671) (xy 130.163215 -371.580346) (xy 130.155454 -371.526367)
			(xy 124.974428 -371.526367) (xy 124.974428 -371.526373) (xy 124.966666 -371.580365) (xy 124.951298 -371.632702)
			(xy 124.928638 -371.682319) (xy 124.899148 -371.728207) (xy 124.863427 -371.76943) (xy 124.822203 -371.80515)
			(xy 124.776316 -371.83464) (xy 124.726698 -371.857299) (xy 124.674361 -371.872666) (xy 124.620369 -371.880429)
			(xy 124.593096 -371.880892) (xy 123.729496 -371.880892) (xy 123.702229 -371.880345) (xy 123.64825 -371.872584)
			(xy 123.595925 -371.857219) (xy 123.546319 -371.834565) (xy 123.500442 -371.805081) (xy 123.459229 -371.769369)
			(xy 123.423517 -371.728154) (xy 123.394033 -371.682277) (xy 123.371379 -371.632671) (xy 123.356015 -371.580346)
			(xy 123.348254 -371.526367) (xy 118.167228 -371.526367) (xy 118.167228 -371.526373) (xy 118.159466 -371.580365)
			(xy 118.144098 -371.632702) (xy 118.121438 -371.682319) (xy 118.091948 -371.728207) (xy 118.056227 -371.76943)
			(xy 118.015003 -371.80515) (xy 117.969116 -371.83464) (xy 117.919498 -371.857299) (xy 117.867161 -371.872666)
			(xy 117.813169 -371.880429) (xy 117.785896 -371.880892) (xy 116.922296 -371.880892) (xy 116.895029 -371.880345)
			(xy 116.84105 -371.872584) (xy 116.788725 -371.857219) (xy 116.739119 -371.834565) (xy 116.693242 -371.805081)
			(xy 116.652029 -371.769369) (xy 116.616317 -371.728154) (xy 116.586833 -371.682277) (xy 116.564179 -371.632671)
			(xy 116.548815 -371.580346) (xy 116.541054 -371.526367) (xy 111.360028 -371.526367) (xy 111.360028 -371.526373)
			(xy 111.352266 -371.580365) (xy 111.336898 -371.632702) (xy 111.314238 -371.682319) (xy 111.284748 -371.728207)
			(xy 111.249027 -371.76943) (xy 111.207803 -371.80515) (xy 111.161916 -371.83464) (xy 111.112298 -371.857299)
			(xy 111.059961 -371.872666) (xy 111.005969 -371.880429) (xy 110.978696 -371.880892) (xy 110.115096 -371.880892)
			(xy 110.087829 -371.880345) (xy 110.03385 -371.872584) (xy 109.981525 -371.857219) (xy 109.931919 -371.834565)
			(xy 109.886042 -371.805081) (xy 109.844829 -371.769369) (xy 109.809117 -371.728154) (xy 109.779633 -371.682277)
			(xy 109.756979 -371.632671) (xy 109.741615 -371.580346) (xy 109.733854 -371.526367) (xy 97.209406 -371.526367)
			(xy 97.209406 -371.526371) (xy 97.201643 -371.580359) (xy 97.186277 -371.632693) (xy 97.163619 -371.682307)
			(xy 97.134131 -371.728191) (xy 97.098413 -371.769412) (xy 97.057193 -371.80513) (xy 97.011308 -371.834618)
			(xy 96.961694 -371.857276) (xy 96.909361 -371.872643) (xy 96.855373 -371.880405) (xy 96.828102 -371.880892)
			(xy 95.964502 -371.880892) (xy 95.937233 -371.880369) (xy 95.88325 -371.872607) (xy 95.830921 -371.857243)
			(xy 95.781312 -371.834587) (xy 95.735432 -371.805102) (xy 95.694214 -371.769387) (xy 95.6585 -371.72817)
			(xy 95.629014 -371.68229) (xy 95.606358 -371.63268) (xy 95.590993 -371.580352) (xy 95.583231 -371.526369)
			(xy 90.402206 -371.526369) (xy 90.402206 -371.526371) (xy 90.394443 -371.580359) (xy 90.379077 -371.632693)
			(xy 90.356419 -371.682307) (xy 90.326931 -371.728191) (xy 90.291213 -371.769412) (xy 90.249993 -371.80513)
			(xy 90.204108 -371.834618) (xy 90.154494 -371.857276) (xy 90.102161 -371.872643) (xy 90.048173 -371.880405)
			(xy 90.020902 -371.880892) (xy 89.157302 -371.880892) (xy 89.130033 -371.880369) (xy 89.07605 -371.872607)
			(xy 89.023721 -371.857243) (xy 88.974112 -371.834587) (xy 88.928232 -371.805102) (xy 88.887014 -371.769387)
			(xy 88.8513 -371.72817) (xy 88.821814 -371.68229) (xy 88.799158 -371.63268) (xy 88.783793 -371.580352)
			(xy 88.776031 -371.526369) (xy 83.595006 -371.526369) (xy 83.595006 -371.526371) (xy 83.587243 -371.580359)
			(xy 83.571877 -371.632693) (xy 83.549219 -371.682307) (xy 83.519731 -371.728191) (xy 83.484013 -371.769412)
			(xy 83.442793 -371.80513) (xy 83.396908 -371.834618) (xy 83.347294 -371.857276) (xy 83.294961 -371.872643)
			(xy 83.240973 -371.880405) (xy 83.213702 -371.880892) (xy 82.350102 -371.880892) (xy 82.322833 -371.880369)
			(xy 82.26885 -371.872607) (xy 82.216521 -371.857243) (xy 82.166912 -371.834587) (xy 82.121032 -371.805102)
			(xy 82.079814 -371.769387) (xy 82.0441 -371.72817) (xy 82.014614 -371.68229) (xy 81.991958 -371.63268)
			(xy 81.976593 -371.580352) (xy 81.968831 -371.526369) (xy 76.787806 -371.526369) (xy 76.787806 -371.526371)
			(xy 76.780043 -371.580359) (xy 76.764677 -371.632693) (xy 76.742019 -371.682307) (xy 76.712531 -371.728191)
			(xy 76.676813 -371.769412) (xy 76.635593 -371.80513) (xy 76.589708 -371.834618) (xy 76.540094 -371.857276)
			(xy 76.487761 -371.872643) (xy 76.433773 -371.880405) (xy 76.406502 -371.880892) (xy 75.542902 -371.880892)
			(xy 75.515633 -371.880369) (xy 75.46165 -371.872607) (xy 75.409321 -371.857243) (xy 75.359712 -371.834587)
			(xy 75.313832 -371.805102) (xy 75.272614 -371.769387) (xy 75.2369 -371.72817) (xy 75.207414 -371.68229)
			(xy 75.184758 -371.63268) (xy 75.169393 -371.580352) (xy 75.161631 -371.526369) (xy 64.681728 -371.526369)
			(xy 64.681728 -371.526375) (xy 64.673964 -371.58037) (xy 64.658595 -371.632711) (xy 64.635932 -371.682331)
			(xy 64.606438 -371.72822) (xy 64.570712 -371.769445) (xy 64.529484 -371.805165) (xy 64.483591 -371.834654)
			(xy 64.433968 -371.857311) (xy 64.381625 -371.872674) (xy 64.327629 -371.880432) (xy 64.300354 -371.880892)
			(xy 63.436754 -371.880892) (xy 63.409489 -371.880343) (xy 63.355515 -371.872576) (xy 63.303195 -371.857208)
			(xy 63.253594 -371.834551) (xy 63.207723 -371.805066) (xy 63.166514 -371.769354) (xy 63.130806 -371.728141)
			(xy 63.101327 -371.682265) (xy 63.078676 -371.632662) (xy 63.063314 -371.58034) (xy 63.055554 -371.526365)
			(xy 57.874528 -371.526365) (xy 57.874528 -371.526375) (xy 57.866764 -371.58037) (xy 57.851395 -371.632711)
			(xy 57.828732 -371.682331) (xy 57.799238 -371.72822) (xy 57.763512 -371.769445) (xy 57.722284 -371.805165)
			(xy 57.676391 -371.834654) (xy 57.626768 -371.857311) (xy 57.574425 -371.872674) (xy 57.520429 -371.880432)
			(xy 57.493154 -371.880892) (xy 56.629554 -371.880892) (xy 56.602289 -371.880343) (xy 56.548315 -371.872576)
			(xy 56.495995 -371.857208) (xy 56.446394 -371.834551) (xy 56.400523 -371.805066) (xy 56.359314 -371.769354)
			(xy 56.323606 -371.728141) (xy 56.294127 -371.682265) (xy 56.271476 -371.632662) (xy 56.256114 -371.58034)
			(xy 56.248354 -371.526365) (xy 51.067328 -371.526365) (xy 51.067328 -371.526375) (xy 51.059564 -371.58037)
			(xy 51.044195 -371.632711) (xy 51.021532 -371.682331) (xy 50.992038 -371.72822) (xy 50.956312 -371.769445)
			(xy 50.915084 -371.805165) (xy 50.869191 -371.834654) (xy 50.819568 -371.857311) (xy 50.767225 -371.872674)
			(xy 50.713229 -371.880432) (xy 50.685954 -371.880892) (xy 49.822354 -371.880892) (xy 49.795089 -371.880343)
			(xy 49.741115 -371.872576) (xy 49.688795 -371.857208) (xy 49.639194 -371.834551) (xy 49.593323 -371.805066)
			(xy 49.552114 -371.769354) (xy 49.516406 -371.728141) (xy 49.486927 -371.682265) (xy 49.464276 -371.632662)
			(xy 49.448914 -371.58034) (xy 49.441154 -371.526365) (xy 44.260128 -371.526365) (xy 44.260128 -371.526375)
			(xy 44.252364 -371.58037) (xy 44.236995 -371.632711) (xy 44.214332 -371.682331) (xy 44.184838 -371.72822)
			(xy 44.149112 -371.769445) (xy 44.107884 -371.805165) (xy 44.061991 -371.834654) (xy 44.012368 -371.857311)
			(xy 43.960025 -371.872674) (xy 43.906029 -371.880432) (xy 43.878754 -371.880892) (xy 43.015154 -371.880892)
			(xy 42.987889 -371.880343) (xy 42.933915 -371.872576) (xy 42.881595 -371.857208) (xy 42.831994 -371.834551)
			(xy 42.786123 -371.805066) (xy 42.744914 -371.769354) (xy 42.709206 -371.728141) (xy 42.679727 -371.682265)
			(xy 42.657076 -371.632662) (xy 42.641714 -371.58034) (xy 42.633954 -371.526365) (xy 2.509012 -371.526365)
			(xy 2.509012 -376.489976) (xy 31.068784 -376.489976) (xy 31.072756 -376.311733) (xy 31.084664 -376.133844)
			(xy 31.104485 -375.956662) (xy 31.132179 -375.780538) (xy 31.167691 -375.605823) (xy 31.210951 -375.432864)
			(xy 31.261873 -375.262003) (xy 31.320356 -375.093581) (xy 31.386283 -374.927931) (xy 31.459524 -374.765382)
			(xy 31.539934 -374.606257) (xy 31.627352 -374.450872) (xy 31.721605 -374.299536) (xy 31.822506 -374.152548)
			(xy 31.929855 -374.010201) (xy 32.043438 -373.872778) (xy 32.163031 -373.740551) (xy 32.288395 -373.613782)
			(xy 32.419282 -373.492724) (xy 32.555431 -373.377617) (xy 32.696573 -373.268689) (xy 32.842428 -373.166157)
			(xy 32.992705 -373.070223) (xy 33.147106 -372.98108) (xy 33.305325 -372.898903) (xy 33.467048 -372.823855)
			(xy 33.631953 -372.756087) (xy 33.799714 -372.695731) (xy 33.969997 -372.642909) (xy 34.142464 -372.597725)
			(xy 34.316772 -372.560268) (xy 34.492576 -372.530614) (xy 34.669526 -372.508821) (xy 34.847272 -372.494931)
			(xy 35.025459 -372.488974) (xy 35.203736 -372.49096) (xy 35.381747 -372.500886) (xy 35.559139 -372.518732)
			(xy 35.735559 -372.544462) (xy 35.910659 -372.578026) (xy 36.08409 -372.619356) (xy 36.255507 -372.668372)
			(xy 36.42457 -372.724974) (xy 36.590945 -372.789052) (xy 36.754299 -372.860478) (xy 36.91431 -372.93911)
			(xy 37.070659 -373.024791) (xy 37.223036 -373.117353) (xy 37.371139 -373.21661) (xy 37.514673 -373.322367)
			(xy 37.653353 -373.434412) (xy 37.786904 -373.552524) (xy 37.915061 -373.676468) (xy 38.03757 -373.805998)
			(xy 38.154187 -373.940857) (xy 38.193125 -373.990165) (xy 47.739354 -373.990165) (xy 47.739354 -373.935635)
			(xy 47.747114 -373.88166) (xy 47.762476 -373.829338) (xy 47.785127 -373.779735) (xy 47.814606 -373.733859)
			(xy 47.850314 -373.692646) (xy 47.891523 -373.656934) (xy 47.937394 -373.627449) (xy 47.986995 -373.604792)
			(xy 48.039315 -373.589424) (xy 48.093289 -373.581657) (xy 48.120554 -373.581168) (xy 48.984154 -373.581168)
			(xy 49.011429 -373.581568) (xy 49.065425 -373.589326) (xy 49.117768 -373.604689) (xy 49.167391 -373.627346)
			(xy 49.213284 -373.656835) (xy 49.254512 -373.692555) (xy 49.290238 -373.73378) (xy 49.319732 -373.779669)
			(xy 49.342395 -373.829289) (xy 49.357764 -373.88163) (xy 49.365528 -373.935625) (xy 49.365528 -373.990165)
			(xy 54.546554 -373.990165) (xy 54.546554 -373.935635) (xy 54.554314 -373.88166) (xy 54.569676 -373.829338)
			(xy 54.592327 -373.779735) (xy 54.621806 -373.733859) (xy 54.657514 -373.692646) (xy 54.698723 -373.656934)
			(xy 54.744594 -373.627449) (xy 54.794195 -373.604792) (xy 54.846515 -373.589424) (xy 54.900489 -373.581657)
			(xy 54.927754 -373.581168) (xy 55.791354 -373.581168) (xy 55.818629 -373.581568) (xy 55.872625 -373.589326)
			(xy 55.924968 -373.604689) (xy 55.974591 -373.627346) (xy 56.020484 -373.656835) (xy 56.061712 -373.692555)
			(xy 56.097438 -373.73378) (xy 56.126932 -373.779669) (xy 56.149595 -373.829289) (xy 56.164964 -373.88163)
			(xy 56.172728 -373.935625) (xy 56.172728 -373.990165) (xy 61.353754 -373.990165) (xy 61.353754 -373.935635)
			(xy 61.361514 -373.88166) (xy 61.376876 -373.829338) (xy 61.399527 -373.779735) (xy 61.429006 -373.733859)
			(xy 61.464714 -373.692646) (xy 61.505923 -373.656934) (xy 61.551794 -373.627449) (xy 61.601395 -373.604792)
			(xy 61.653715 -373.589424) (xy 61.707689 -373.581657) (xy 61.734954 -373.581168) (xy 62.598554 -373.581168)
			(xy 62.625829 -373.581568) (xy 62.679825 -373.589326) (xy 62.732168 -373.604689) (xy 62.781791 -373.627346)
			(xy 62.827684 -373.656835) (xy 62.868912 -373.692555) (xy 62.904638 -373.73378) (xy 62.934132 -373.779669)
			(xy 62.956795 -373.829289) (xy 62.972164 -373.88163) (xy 62.979928 -373.935625) (xy 62.979928 -373.990169)
			(xy 80.267031 -373.990169) (xy 80.267031 -373.935631) (xy 80.274793 -373.881648) (xy 80.290158 -373.82932)
			(xy 80.312814 -373.77971) (xy 80.3423 -373.73383) (xy 80.378014 -373.692613) (xy 80.419232 -373.656898)
			(xy 80.465112 -373.627413) (xy 80.514721 -373.604757) (xy 80.56705 -373.589393) (xy 80.621033 -373.581631)
			(xy 80.648302 -373.581168) (xy 81.511902 -373.581168) (xy 81.539173 -373.581595) (xy 81.593161 -373.589357)
			(xy 81.645494 -373.604724) (xy 81.695108 -373.627382) (xy 81.740993 -373.65687) (xy 81.782213 -373.692588)
			(xy 81.817931 -373.733809) (xy 81.847419 -373.779693) (xy 81.870077 -373.829307) (xy 81.885443 -373.881641)
			(xy 81.893206 -373.935629) (xy 81.893206 -373.990169) (xy 87.074231 -373.990169) (xy 87.074231 -373.935631)
			(xy 87.081993 -373.881648) (xy 87.097358 -373.82932) (xy 87.120014 -373.77971) (xy 87.1495 -373.73383)
			(xy 87.185214 -373.692613) (xy 87.226432 -373.656898) (xy 87.272312 -373.627413) (xy 87.321921 -373.604757)
			(xy 87.37425 -373.589393) (xy 87.428233 -373.581631) (xy 87.455502 -373.581168) (xy 88.319102 -373.581168)
			(xy 88.346373 -373.581595) (xy 88.400361 -373.589357) (xy 88.452694 -373.604724) (xy 88.502308 -373.627382)
			(xy 88.548193 -373.65687) (xy 88.589413 -373.692588) (xy 88.625131 -373.733809) (xy 88.654619 -373.779693)
			(xy 88.677277 -373.829307) (xy 88.692643 -373.881641) (xy 88.700406 -373.935629) (xy 88.700406 -373.990169)
			(xy 93.881431 -373.990169) (xy 93.881431 -373.935631) (xy 93.889193 -373.881648) (xy 93.904558 -373.82932)
			(xy 93.927214 -373.77971) (xy 93.9567 -373.73383) (xy 93.992414 -373.692613) (xy 94.033632 -373.656898)
			(xy 94.079512 -373.627413) (xy 94.129121 -373.604757) (xy 94.18145 -373.589393) (xy 94.235433 -373.581631)
			(xy 94.262702 -373.581168) (xy 95.126302 -373.581168) (xy 95.153573 -373.581595) (xy 95.207561 -373.589357)
			(xy 95.259894 -373.604724) (xy 95.309508 -373.627382) (xy 95.355393 -373.65687) (xy 95.396613 -373.692588)
			(xy 95.432331 -373.733809) (xy 95.461819 -373.779693) (xy 95.484477 -373.829307) (xy 95.499843 -373.881641)
			(xy 95.507606 -373.935629) (xy 95.507606 -373.990167) (xy 114.839254 -373.990167) (xy 114.839254 -373.935633)
			(xy 114.847015 -373.881654) (xy 114.862379 -373.829329) (xy 114.885033 -373.779723) (xy 114.914517 -373.733846)
			(xy 114.950229 -373.692631) (xy 114.991442 -373.656919) (xy 115.037319 -373.627435) (xy 115.086925 -373.604781)
			(xy 115.13925 -373.589416) (xy 115.193229 -373.581655) (xy 115.220496 -373.581168) (xy 116.084096 -373.581168)
			(xy 116.111369 -373.581571) (xy 116.165361 -373.589334) (xy 116.217698 -373.604701) (xy 116.267316 -373.62736)
			(xy 116.313203 -373.65685) (xy 116.354427 -373.69257) (xy 116.390148 -373.733793) (xy 116.419638 -373.779681)
			(xy 116.442298 -373.829298) (xy 116.457666 -373.881635) (xy 116.465428 -373.935627) (xy 116.465428 -373.990167)
			(xy 121.646454 -373.990167) (xy 121.646454 -373.935633) (xy 121.654215 -373.881654) (xy 121.669579 -373.829329)
			(xy 121.692233 -373.779723) (xy 121.721717 -373.733846) (xy 121.757429 -373.692631) (xy 121.798642 -373.656919)
			(xy 121.844519 -373.627435) (xy 121.894125 -373.604781) (xy 121.94645 -373.589416) (xy 122.000429 -373.581655)
			(xy 122.027696 -373.581168) (xy 122.891296 -373.581168) (xy 122.918569 -373.581571) (xy 122.972561 -373.589334)
			(xy 123.024898 -373.604701) (xy 123.074516 -373.62736) (xy 123.120403 -373.65685) (xy 123.161627 -373.69257)
			(xy 123.197348 -373.733793) (xy 123.226838 -373.779681) (xy 123.249498 -373.829298) (xy 123.264866 -373.881635)
			(xy 123.272628 -373.935627) (xy 123.272628 -373.990167) (xy 128.453654 -373.990167) (xy 128.453654 -373.935633)
			(xy 128.461415 -373.881654) (xy 128.476779 -373.829329) (xy 128.499433 -373.779723) (xy 128.528917 -373.733846)
			(xy 128.564629 -373.692631) (xy 128.605842 -373.656919) (xy 128.651719 -373.627435) (xy 128.701325 -373.604781)
			(xy 128.75365 -373.589416) (xy 128.807629 -373.581655) (xy 128.834896 -373.581168) (xy 129.698496 -373.581168)
			(xy 129.725769 -373.581571) (xy 129.779761 -373.589334) (xy 129.832098 -373.604701) (xy 129.881716 -373.62736)
			(xy 129.927603 -373.65685) (xy 129.968827 -373.69257) (xy 130.004548 -373.733793) (xy 130.034038 -373.779681)
			(xy 130.056698 -373.829298) (xy 130.072066 -373.881635) (xy 130.079828 -373.935627) (xy 130.079828 -373.990171)
			(xy 147.366932 -373.990171) (xy 147.366932 -373.935629) (xy 147.374694 -373.881643) (xy 147.390061 -373.829311)
			(xy 147.412721 -373.779698) (xy 147.44221 -373.733816) (xy 147.477929 -373.692598) (xy 147.519151 -373.656884)
			(xy 147.565037 -373.627399) (xy 147.614652 -373.604746) (xy 147.666986 -373.589385) (xy 147.720973 -373.581628)
			(xy 147.748244 -373.581168) (xy 148.611844 -373.581168) (xy 148.639113 -373.581598) (xy 148.693097 -373.589365)
			(xy 148.745425 -373.604735) (xy 148.795033 -373.627396) (xy 148.840912 -373.656885) (xy 148.882128 -373.692603)
			(xy 148.917841 -373.733823) (xy 148.947325 -373.779705) (xy 148.96998 -373.829316) (xy 148.985344 -373.881647)
			(xy 148.993106 -373.93563) (xy 148.993106 -373.99017) (xy 148.993106 -373.990171) (xy 154.174132 -373.990171)
			(xy 154.174132 -373.935629) (xy 154.181894 -373.881643) (xy 154.197261 -373.829311) (xy 154.219921 -373.779698)
			(xy 154.24941 -373.733816) (xy 154.285129 -373.692598) (xy 154.326351 -373.656884) (xy 154.372237 -373.627399)
			(xy 154.421852 -373.604746) (xy 154.474186 -373.589385) (xy 154.528173 -373.581628) (xy 154.555444 -373.581168)
			(xy 155.419044 -373.581168) (xy 155.446313 -373.581598) (xy 155.500297 -373.589365) (xy 155.552625 -373.604735)
			(xy 155.602233 -373.627396) (xy 155.648112 -373.656885) (xy 155.689328 -373.692603) (xy 155.725041 -373.733823)
			(xy 155.754525 -373.779705) (xy 155.77718 -373.829316) (xy 155.792544 -373.881647) (xy 155.800306 -373.93563)
			(xy 155.800306 -373.99017) (xy 155.800306 -373.990171) (xy 160.981332 -373.990171) (xy 160.981332 -373.935629)
			(xy 160.989094 -373.881643) (xy 161.004461 -373.829311) (xy 161.027121 -373.779698) (xy 161.05661 -373.733816)
			(xy 161.092329 -373.692598) (xy 161.133551 -373.656884) (xy 161.179437 -373.627399) (xy 161.229052 -373.604746)
			(xy 161.281386 -373.589385) (xy 161.335373 -373.581628) (xy 161.362644 -373.581168) (xy 162.226244 -373.581168)
			(xy 162.253513 -373.581598) (xy 162.307497 -373.589365) (xy 162.359825 -373.604735) (xy 162.409433 -373.627396)
			(xy 162.455312 -373.656885) (xy 162.496528 -373.692603) (xy 162.532241 -373.733823) (xy 162.561725 -373.779705)
			(xy 162.58438 -373.829316) (xy 162.599744 -373.881647) (xy 162.607506 -373.93563) (xy 162.607506 -373.99017)
			(xy 162.599744 -374.044153) (xy 162.58438 -374.096484) (xy 162.561725 -374.146095) (xy 162.532241 -374.191977)
			(xy 162.496528 -374.233197) (xy 162.455312 -374.268915) (xy 162.409433 -374.298404) (xy 162.359825 -374.321065)
			(xy 162.307497 -374.336435) (xy 162.253513 -374.344202) (xy 162.226244 -374.344692) (xy 161.362644 -374.344692)
			(xy 161.335373 -374.344172) (xy 161.281386 -374.336415) (xy 161.229052 -374.321054) (xy 161.179437 -374.298401)
			(xy 161.133551 -374.268916) (xy 161.092329 -374.233202) (xy 161.05661 -374.191984) (xy 161.027121 -374.146102)
			(xy 161.004461 -374.096489) (xy 160.989094 -374.044157) (xy 160.981332 -373.990171) (xy 155.800306 -373.990171)
			(xy 155.792544 -374.044153) (xy 155.77718 -374.096484) (xy 155.754525 -374.146095) (xy 155.725041 -374.191977)
			(xy 155.689328 -374.233197) (xy 155.648112 -374.268915) (xy 155.602233 -374.298404) (xy 155.552625 -374.321065)
			(xy 155.500297 -374.336435) (xy 155.446313 -374.344202) (xy 155.419044 -374.344692) (xy 154.555444 -374.344692)
			(xy 154.528173 -374.344172) (xy 154.474186 -374.336415) (xy 154.421852 -374.321054) (xy 154.372237 -374.298401)
			(xy 154.326351 -374.268916) (xy 154.285129 -374.233202) (xy 154.24941 -374.191984) (xy 154.219921 -374.146102)
			(xy 154.197261 -374.096489) (xy 154.181894 -374.044157) (xy 154.174132 -373.990171) (xy 148.993106 -373.990171)
			(xy 148.985344 -374.044153) (xy 148.96998 -374.096484) (xy 148.947325 -374.146095) (xy 148.917841 -374.191977)
			(xy 148.882128 -374.233197) (xy 148.840912 -374.268915) (xy 148.795033 -374.298404) (xy 148.745425 -374.321065)
			(xy 148.693097 -374.336435) (xy 148.639113 -374.344202) (xy 148.611844 -374.344692) (xy 147.748244 -374.344692)
			(xy 147.720973 -374.344172) (xy 147.666986 -374.336415) (xy 147.614652 -374.321054) (xy 147.565037 -374.298401)
			(xy 147.519151 -374.268916) (xy 147.477929 -374.233202) (xy 147.44221 -374.191984) (xy 147.412721 -374.146102)
			(xy 147.390061 -374.096489) (xy 147.374694 -374.044157) (xy 147.366932 -373.990171) (xy 130.079828 -373.990171)
			(xy 130.079828 -373.990173) (xy 130.072066 -374.044165) (xy 130.056698 -374.096502) (xy 130.034038 -374.146119)
			(xy 130.004548 -374.192007) (xy 129.968827 -374.23323) (xy 129.927603 -374.26895) (xy 129.881716 -374.29844)
			(xy 129.832098 -374.321099) (xy 129.779761 -374.336466) (xy 129.725769 -374.344229) (xy 129.698496 -374.344692)
			(xy 128.834896 -374.344692) (xy 128.807629 -374.344145) (xy 128.75365 -374.336384) (xy 128.701325 -374.321019)
			(xy 128.651719 -374.298365) (xy 128.605842 -374.268881) (xy 128.564629 -374.233169) (xy 128.528917 -374.191954)
			(xy 128.499433 -374.146077) (xy 128.476779 -374.096471) (xy 128.461415 -374.044146) (xy 128.453654 -373.990167)
			(xy 123.272628 -373.990167) (xy 123.272628 -373.990173) (xy 123.264866 -374.044165) (xy 123.249498 -374.096502)
			(xy 123.226838 -374.146119) (xy 123.197348 -374.192007) (xy 123.161627 -374.23323) (xy 123.120403 -374.26895)
			(xy 123.074516 -374.29844) (xy 123.024898 -374.321099) (xy 122.972561 -374.336466) (xy 122.918569 -374.344229)
			(xy 122.891296 -374.344692) (xy 122.027696 -374.344692) (xy 122.000429 -374.344145) (xy 121.94645 -374.336384)
			(xy 121.894125 -374.321019) (xy 121.844519 -374.298365) (xy 121.798642 -374.268881) (xy 121.757429 -374.233169)
			(xy 121.721717 -374.191954) (xy 121.692233 -374.146077) (xy 121.669579 -374.096471) (xy 121.654215 -374.044146)
			(xy 121.646454 -373.990167) (xy 116.465428 -373.990167) (xy 116.465428 -373.990173) (xy 116.457666 -374.044165)
			(xy 116.442298 -374.096502) (xy 116.419638 -374.146119) (xy 116.390148 -374.192007) (xy 116.354427 -374.23323)
			(xy 116.313203 -374.26895) (xy 116.267316 -374.29844) (xy 116.217698 -374.321099) (xy 116.165361 -374.336466)
			(xy 116.111369 -374.344229) (xy 116.084096 -374.344692) (xy 115.220496 -374.344692) (xy 115.193229 -374.344145)
			(xy 115.13925 -374.336384) (xy 115.086925 -374.321019) (xy 115.037319 -374.298365) (xy 114.991442 -374.268881)
			(xy 114.950229 -374.233169) (xy 114.914517 -374.191954) (xy 114.885033 -374.146077) (xy 114.862379 -374.096471)
			(xy 114.847015 -374.044146) (xy 114.839254 -373.990167) (xy 95.507606 -373.990167) (xy 95.507606 -373.990171)
			(xy 95.499843 -374.044159) (xy 95.484477 -374.096493) (xy 95.461819 -374.146107) (xy 95.432331 -374.191991)
			(xy 95.396613 -374.233212) (xy 95.355393 -374.26893) (xy 95.309508 -374.298418) (xy 95.259894 -374.321076)
			(xy 95.207561 -374.336443) (xy 95.153573 -374.344205) (xy 95.126302 -374.344692) (xy 94.262702 -374.344692)
			(xy 94.235433 -374.344169) (xy 94.18145 -374.336407) (xy 94.129121 -374.321043) (xy 94.079512 -374.298387)
			(xy 94.033632 -374.268902) (xy 93.992414 -374.233187) (xy 93.9567 -374.19197) (xy 93.927214 -374.14609)
			(xy 93.904558 -374.09648) (xy 93.889193 -374.044152) (xy 93.881431 -373.990169) (xy 88.700406 -373.990169)
			(xy 88.700406 -373.990171) (xy 88.692643 -374.044159) (xy 88.677277 -374.096493) (xy 88.654619 -374.146107)
			(xy 88.625131 -374.191991) (xy 88.589413 -374.233212) (xy 88.548193 -374.26893) (xy 88.502308 -374.298418)
			(xy 88.452694 -374.321076) (xy 88.400361 -374.336443) (xy 88.346373 -374.344205) (xy 88.319102 -374.344692)
			(xy 87.455502 -374.344692) (xy 87.428233 -374.344169) (xy 87.37425 -374.336407) (xy 87.321921 -374.321043)
			(xy 87.272312 -374.298387) (xy 87.226432 -374.268902) (xy 87.185214 -374.233187) (xy 87.1495 -374.19197)
			(xy 87.120014 -374.14609) (xy 87.097358 -374.09648) (xy 87.081993 -374.044152) (xy 87.074231 -373.990169)
			(xy 81.893206 -373.990169) (xy 81.893206 -373.990171) (xy 81.885443 -374.044159) (xy 81.870077 -374.096493)
			(xy 81.847419 -374.146107) (xy 81.817931 -374.191991) (xy 81.782213 -374.233212) (xy 81.740993 -374.26893)
			(xy 81.695108 -374.298418) (xy 81.645494 -374.321076) (xy 81.593161 -374.336443) (xy 81.539173 -374.344205)
			(xy 81.511902 -374.344692) (xy 80.648302 -374.344692) (xy 80.621033 -374.344169) (xy 80.56705 -374.336407)
			(xy 80.514721 -374.321043) (xy 80.465112 -374.298387) (xy 80.419232 -374.268902) (xy 80.378014 -374.233187)
			(xy 80.3423 -374.19197) (xy 80.312814 -374.14609) (xy 80.290158 -374.09648) (xy 80.274793 -374.044152)
			(xy 80.267031 -373.990169) (xy 62.979928 -373.990169) (xy 62.979928 -373.990175) (xy 62.972164 -374.04417)
			(xy 62.956795 -374.096511) (xy 62.934132 -374.146131) (xy 62.904638 -374.19202) (xy 62.868912 -374.233245)
			(xy 62.827684 -374.268965) (xy 62.781791 -374.298454) (xy 62.732168 -374.321111) (xy 62.679825 -374.336474)
			(xy 62.625829 -374.344232) (xy 62.598554 -374.344692) (xy 61.734954 -374.344692) (xy 61.707689 -374.344143)
			(xy 61.653715 -374.336376) (xy 61.601395 -374.321008) (xy 61.551794 -374.298351) (xy 61.505923 -374.268866)
			(xy 61.464714 -374.233154) (xy 61.429006 -374.191941) (xy 61.399527 -374.146065) (xy 61.376876 -374.096462)
			(xy 61.361514 -374.04414) (xy 61.353754 -373.990165) (xy 56.172728 -373.990165) (xy 56.172728 -373.990175)
			(xy 56.164964 -374.04417) (xy 56.149595 -374.096511) (xy 56.126932 -374.146131) (xy 56.097438 -374.19202)
			(xy 56.061712 -374.233245) (xy 56.020484 -374.268965) (xy 55.974591 -374.298454) (xy 55.924968 -374.321111)
			(xy 55.872625 -374.336474) (xy 55.818629 -374.344232) (xy 55.791354 -374.344692) (xy 54.927754 -374.344692)
			(xy 54.900489 -374.344143) (xy 54.846515 -374.336376) (xy 54.794195 -374.321008) (xy 54.744594 -374.298351)
			(xy 54.698723 -374.268866) (xy 54.657514 -374.233154) (xy 54.621806 -374.191941) (xy 54.592327 -374.146065)
			(xy 54.569676 -374.096462) (xy 54.554314 -374.04414) (xy 54.546554 -373.990165) (xy 49.365528 -373.990165)
			(xy 49.365528 -373.990175) (xy 49.357764 -374.04417) (xy 49.342395 -374.096511) (xy 49.319732 -374.146131)
			(xy 49.290238 -374.19202) (xy 49.254512 -374.233245) (xy 49.213284 -374.268965) (xy 49.167391 -374.298454)
			(xy 49.117768 -374.321111) (xy 49.065425 -374.336474) (xy 49.011429 -374.344232) (xy 48.984154 -374.344692)
			(xy 48.120554 -374.344692) (xy 48.093289 -374.344143) (xy 48.039315 -374.336376) (xy 47.986995 -374.321008)
			(xy 47.937394 -374.298351) (xy 47.891523 -374.268866) (xy 47.850314 -374.233154) (xy 47.814606 -374.191941)
			(xy 47.785127 -374.146065) (xy 47.762476 -374.096462) (xy 47.747114 -374.04414) (xy 47.739354 -373.990165)
			(xy 38.193125 -373.990165) (xy 38.26468 -374.080777) (xy 38.368831 -374.22548) (xy 38.466433 -374.374679)
			(xy 38.557291 -374.528078) (xy 38.641225 -374.685372) (xy 38.71807 -374.846248) (xy 38.787671 -375.010389)
			(xy 38.849892 -375.177466) (xy 38.904608 -375.34715) (xy 38.95171 -375.519103) (xy 38.991106 -375.692983)
			(xy 39.022717 -375.868446) (xy 39.046481 -376.045142) (xy 39.062349 -376.222722) (xy 39.070291 -376.400832)
			(xy 39.070788 -376.489976) (xy 39.070291 -376.57912) (xy 39.062349 -376.75723) (xy 39.05568 -376.83186)
			(xy 41.04894 -376.83186) (xy 41.04894 -375.96826) (xy 41.049426 -375.940991) (xy 41.057188 -375.887007)
			(xy 41.072553 -375.834677) (xy 41.09521 -375.785067) (xy 41.124696 -375.739186) (xy 41.160411 -375.697969)
			(xy 41.201628 -375.662254) (xy 41.247509 -375.632768) (xy 41.297119 -375.610111) (xy 41.349449 -375.594746)
			(xy 41.403433 -375.586984) (xy 41.457971 -375.586984) (xy 41.511955 -375.594746) (xy 41.564285 -375.610111)
			(xy 41.613895 -375.632768) (xy 41.659776 -375.662254) (xy 41.700993 -375.697969) (xy 41.736708 -375.739186)
			(xy 41.766194 -375.785067) (xy 41.788851 -375.834677) (xy 41.804216 -375.887007) (xy 41.811978 -375.940991)
			(xy 41.812464 -375.96826) (xy 41.812464 -376.83186) (xy 41.811978 -376.859129) (xy 41.804216 -376.913113)
			(xy 41.791381 -376.956828) (xy 70.895972 -376.956828) (xy 70.895972 -376.093228) (xy 70.896458 -376.065959)
			(xy 70.90422 -376.011975) (xy 70.919585 -375.959645) (xy 70.942242 -375.910035) (xy 70.971728 -375.864154)
			(xy 71.007443 -375.822937) (xy 71.04866 -375.787222) (xy 71.094541 -375.757736) (xy 71.144151 -375.735079)
			(xy 71.196481 -375.719714) (xy 71.250465 -375.711952) (xy 71.305003 -375.711952) (xy 71.358987 -375.719714)
			(xy 71.411317 -375.735079) (xy 71.460927 -375.757736) (xy 71.506808 -375.787222) (xy 71.548025 -375.822937)
			(xy 71.58374 -375.864154) (xy 71.613226 -375.910035) (xy 71.635883 -375.959645) (xy 71.651248 -376.011975)
			(xy 71.65901 -376.065959) (xy 71.659496 -376.093228) (xy 71.659496 -376.83186) (xy 73.576688 -376.83186)
			(xy 73.576688 -375.96826) (xy 73.577174 -375.940991) (xy 73.584936 -375.887007) (xy 73.600301 -375.834677)
			(xy 73.622958 -375.785067) (xy 73.652444 -375.739186) (xy 73.688159 -375.697969) (xy 73.729376 -375.662254)
			(xy 73.775257 -375.632768) (xy 73.824867 -375.610111) (xy 73.877197 -375.594746) (xy 73.931181 -375.586984)
			(xy 73.985719 -375.586984) (xy 74.039703 -375.594746) (xy 74.092033 -375.610111) (xy 74.141643 -375.632768)
			(xy 74.187524 -375.662254) (xy 74.228741 -375.697969) (xy 74.264456 -375.739186) (xy 74.293942 -375.785067)
			(xy 74.316599 -375.834677) (xy 74.331964 -375.887007) (xy 74.339726 -375.940991) (xy 74.340212 -375.96826)
			(xy 74.340212 -376.83186) (xy 74.339726 -376.859129) (xy 74.331964 -376.913113) (xy 74.319129 -376.956828)
			(xy 103.42372 -376.956828) (xy 103.42372 -376.093228) (xy 103.424206 -376.065959) (xy 103.431968 -376.011975)
			(xy 103.447333 -375.959645) (xy 103.46999 -375.910035) (xy 103.499476 -375.864154) (xy 103.535191 -375.822937)
			(xy 103.576408 -375.787222) (xy 103.622289 -375.757736) (xy 103.671899 -375.735079) (xy 103.724229 -375.719714)
			(xy 103.778213 -375.711952) (xy 103.832751 -375.711952) (xy 103.886735 -375.719714) (xy 103.939065 -375.735079)
			(xy 103.988675 -375.757736) (xy 104.034556 -375.787222) (xy 104.075773 -375.822937) (xy 104.111488 -375.864154)
			(xy 104.140974 -375.910035) (xy 104.163631 -375.959645) (xy 104.178996 -376.011975) (xy 104.186758 -376.065959)
			(xy 104.187244 -376.093228) (xy 104.187244 -376.83186) (xy 108.149136 -376.83186) (xy 108.149136 -375.96826)
			(xy 108.149622 -375.941009) (xy 108.157378 -375.887061) (xy 108.172733 -375.834766) (xy 108.195375 -375.785189)
			(xy 108.224841 -375.739339) (xy 108.260532 -375.698148) (xy 108.301723 -375.662457) (xy 108.347573 -375.632991)
			(xy 108.39715 -375.610349) (xy 108.449445 -375.594994) (xy 108.503393 -375.587238) (xy 108.557895 -375.587238)
			(xy 108.611843 -375.594994) (xy 108.664138 -375.610349) (xy 108.713715 -375.632991) (xy 108.759565 -375.662457)
			(xy 108.800756 -375.698148) (xy 108.836447 -375.739339) (xy 108.865913 -375.785189) (xy 108.888555 -375.834766)
			(xy 108.90391 -375.887061) (xy 108.911666 -375.941009) (xy 108.912152 -375.96826) (xy 108.912152 -376.83186)
			(xy 108.911666 -376.859111) (xy 108.90391 -376.913059) (xy 108.891058 -376.956828) (xy 137.996168 -376.956828)
			(xy 137.996168 -376.093228) (xy 137.996654 -376.065977) (xy 138.00441 -376.012029) (xy 138.019765 -375.959734)
			(xy 138.042407 -375.910157) (xy 138.071873 -375.864307) (xy 138.107564 -375.823116) (xy 138.148755 -375.787425)
			(xy 138.194605 -375.757959) (xy 138.244182 -375.735317) (xy 138.296477 -375.719962) (xy 138.350425 -375.712206)
			(xy 138.404927 -375.712206) (xy 138.458875 -375.719962) (xy 138.51117 -375.735317) (xy 138.560747 -375.757959)
			(xy 138.606597 -375.787425) (xy 138.647788 -375.823116) (xy 138.683479 -375.864307) (xy 138.712945 -375.910157)
			(xy 138.735587 -375.959734) (xy 138.750942 -376.012029) (xy 138.758698 -376.065977) (xy 138.759184 -376.093228)
			(xy 138.759184 -376.83186) (xy 140.676884 -376.83186) (xy 140.676884 -375.96826) (xy 140.67737 -375.941009)
			(xy 140.685126 -375.887061) (xy 140.700481 -375.834766) (xy 140.723123 -375.785189) (xy 140.752589 -375.739339)
			(xy 140.78828 -375.698148) (xy 140.829471 -375.662457) (xy 140.875321 -375.632991) (xy 140.924898 -375.610349)
			(xy 140.977193 -375.594994) (xy 141.031141 -375.587238) (xy 141.085643 -375.587238) (xy 141.139591 -375.594994)
			(xy 141.191886 -375.610349) (xy 141.241463 -375.632991) (xy 141.287313 -375.662457) (xy 141.328504 -375.698148)
			(xy 141.364195 -375.739339) (xy 141.393661 -375.785189) (xy 141.416303 -375.834766) (xy 141.431658 -375.887061)
			(xy 141.439414 -375.941009) (xy 141.4399 -375.96826) (xy 141.4399 -376.83186) (xy 141.439414 -376.859111)
			(xy 141.431658 -376.913059) (xy 141.418806 -376.956828) (xy 170.523916 -376.956828) (xy 170.523916 -376.093228)
			(xy 170.524402 -376.065977) (xy 170.532158 -376.012029) (xy 170.547513 -375.959734) (xy 170.570155 -375.910157)
			(xy 170.599621 -375.864307) (xy 170.635312 -375.823116) (xy 170.676503 -375.787425) (xy 170.722353 -375.757959)
			(xy 170.77193 -375.735317) (xy 170.824225 -375.719962) (xy 170.878173 -375.712206) (xy 170.932675 -375.712206)
			(xy 170.986623 -375.719962) (xy 171.038918 -375.735317) (xy 171.088495 -375.757959) (xy 171.134345 -375.787425)
			(xy 171.175536 -375.823116) (xy 171.211227 -375.864307) (xy 171.240693 -375.910157) (xy 171.263335 -375.959734)
			(xy 171.27869 -376.012029) (xy 171.286446 -376.065977) (xy 171.286932 -376.093228) (xy 171.286932 -376.489976)
			(xy 173.498776 -376.489976) (xy 173.502748 -376.311733) (xy 173.514656 -376.133844) (xy 173.534477 -375.956662)
			(xy 173.562171 -375.780538) (xy 173.597683 -375.605823) (xy 173.640943 -375.432864) (xy 173.691865 -375.262003)
			(xy 173.750348 -375.093581) (xy 173.816275 -374.927931) (xy 173.889516 -374.765382) (xy 173.969926 -374.606257)
			(xy 174.057344 -374.450872) (xy 174.151597 -374.299536) (xy 174.252498 -374.152548) (xy 174.359847 -374.010201)
			(xy 174.47343 -373.872778) (xy 174.593023 -373.740551) (xy 174.718387 -373.613782) (xy 174.849274 -373.492724)
			(xy 174.985423 -373.377617) (xy 175.126565 -373.268689) (xy 175.27242 -373.166157) (xy 175.422697 -373.070223)
			(xy 175.577098 -372.98108) (xy 175.735317 -372.898903) (xy 175.89704 -372.823855) (xy 176.061945 -372.756087)
			(xy 176.229706 -372.695731) (xy 176.399989 -372.642909) (xy 176.572456 -372.597725) (xy 176.746764 -372.560268)
			(xy 176.922568 -372.530614) (xy 177.099518 -372.508821) (xy 177.277264 -372.494931) (xy 177.455451 -372.488974)
			(xy 177.633728 -372.49096) (xy 177.811739 -372.500886) (xy 177.989131 -372.518732) (xy 178.165551 -372.544462)
			(xy 178.340651 -372.578026) (xy 178.514082 -372.619356) (xy 178.685499 -372.668372) (xy 178.854562 -372.724974)
			(xy 179.020937 -372.789052) (xy 179.184291 -372.860478) (xy 179.344302 -372.93911) (xy 179.500651 -373.024791)
			(xy 179.653028 -373.117353) (xy 179.801131 -373.21661) (xy 179.944665 -373.322367) (xy 180.083345 -373.434412)
			(xy 180.216896 -373.552524) (xy 180.345053 -373.676468) (xy 180.467562 -373.805998) (xy 180.584179 -373.940857)
			(xy 180.596796 -373.956834) (xy 282.853384 -373.956834) (xy 282.853384 -373.093234) (xy 282.85387 -373.065983)
			(xy 282.861626 -373.012035) (xy 282.876981 -372.95974) (xy 282.899623 -372.910163) (xy 282.929089 -372.864313)
			(xy 282.96478 -372.823122) (xy 283.005971 -372.787431) (xy 283.051821 -372.757965) (xy 283.101398 -372.735323)
			(xy 283.153693 -372.719968) (xy 283.207641 -372.712212) (xy 283.262143 -372.712212) (xy 283.316091 -372.719968)
			(xy 283.368386 -372.735323) (xy 283.417963 -372.757965) (xy 283.463813 -372.787431) (xy 283.505004 -372.823122)
			(xy 283.540695 -372.864313) (xy 283.570161 -372.910163) (xy 283.592803 -372.95974) (xy 283.608158 -373.012035)
			(xy 283.615914 -373.065983) (xy 283.6164 -373.093234) (xy 283.6164 -373.956834) (xy 283.615914 -373.984085)
			(xy 283.608158 -374.038033) (xy 283.592803 -374.090328) (xy 283.570161 -374.139905) (xy 283.540695 -374.185755)
			(xy 283.505004 -374.226946) (xy 283.463813 -374.262637) (xy 283.417963 -374.292103) (xy 283.368386 -374.314745)
			(xy 283.316091 -374.3301) (xy 283.262143 -374.337856) (xy 283.207641 -374.337856) (xy 283.153693 -374.3301)
			(xy 283.101398 -374.314745) (xy 283.051821 -374.292103) (xy 283.005971 -374.262637) (xy 282.96478 -374.226946)
			(xy 282.929089 -374.185755) (xy 282.899623 -374.139905) (xy 282.876981 -374.090328) (xy 282.861626 -374.038033)
			(xy 282.85387 -373.984085) (xy 282.853384 -373.956834) (xy 180.596796 -373.956834) (xy 180.694672 -374.080777)
			(xy 180.798823 -374.22548) (xy 180.896425 -374.374679) (xy 180.987283 -374.528078) (xy 181.071217 -374.685372)
			(xy 181.148062 -374.846248) (xy 181.217663 -375.010389) (xy 181.279884 -375.177466) (xy 181.3346 -375.34715)
			(xy 181.381702 -375.519103) (xy 181.421098 -375.692983) (xy 181.452709 -375.868446) (xy 181.476473 -376.045142)
			(xy 181.492341 -376.222722) (xy 181.500283 -376.400832) (xy 181.50078 -376.489976) (xy 181.500283 -376.57912)
			(xy 181.492341 -376.75723) (xy 181.476473 -376.93481) (xy 181.452709 -377.111506) (xy 181.421098 -377.286969)
			(xy 181.381702 -377.460849) (xy 181.3346 -377.632802) (xy 181.319901 -377.678385) (xy 193.900548 -377.678385)
			(xy 193.900548 -377.593663) (xy 193.908601 -377.509326) (xy 193.924635 -377.426136) (xy 193.948503 -377.344846)
			(xy 193.979991 -377.266194) (xy 194.018813 -377.190891) (xy 194.064616 -377.119619) (xy 194.116987 -377.053023)
			(xy 194.175452 -376.991708) (xy 194.23948 -376.936227) (xy 194.308492 -376.887084) (xy 194.381862 -376.844724)
			(xy 194.458927 -376.809529) (xy 194.538989 -376.78182) (xy 194.621322 -376.761846) (xy 194.705181 -376.749789)
			(xy 194.789806 -376.745758) (xy 194.874431 -376.749789) (xy 194.95829 -376.761846) (xy 195.040623 -376.78182)
			(xy 195.120685 -376.809529) (xy 195.19775 -376.844724) (xy 195.27112 -376.887084) (xy 195.340132 -376.936227)
			(xy 195.40416 -376.991708) (xy 195.462625 -377.053023) (xy 195.514996 -377.119619) (xy 195.560799 -377.190891)
			(xy 195.599621 -377.266194) (xy 195.631109 -377.344846) (xy 195.654977 -377.426136) (xy 195.671011 -377.509326)
			(xy 195.679064 -377.593663) (xy 195.679568 -377.636024) (xy 195.679064 -377.678385) (xy 195.671011 -377.762722)
			(xy 195.654977 -377.845912) (xy 195.631109 -377.927202) (xy 195.599621 -378.005854) (xy 195.560799 -378.081157)
			(xy 195.514996 -378.152429) (xy 195.47531 -378.202895) (xy 199.443082 -378.202895) (xy 199.443082 -378.118173)
			(xy 199.451135 -378.033836) (xy 199.467169 -377.950646) (xy 199.491037 -377.869356) (xy 199.522525 -377.790704)
			(xy 199.561347 -377.715401) (xy 199.60715 -377.644129) (xy 199.659521 -377.577533) (xy 199.717986 -377.516218)
			(xy 199.782014 -377.460737) (xy 199.851026 -377.411594) (xy 199.924396 -377.369234) (xy 200.001461 -377.334039)
			(xy 200.081523 -377.30633) (xy 200.163856 -377.286356) (xy 200.247715 -377.274299) (xy 200.33234 -377.270268)
			(xy 200.416965 -377.274299) (xy 200.500824 -377.286356) (xy 200.583157 -377.30633) (xy 200.663219 -377.334039)
			(xy 200.740284 -377.369234) (xy 200.813654 -377.411594) (xy 200.859958 -377.444567) (xy 300.335454 -377.444567)
			(xy 300.335454 -377.390033) (xy 300.343215 -377.336054) (xy 300.358579 -377.283729) (xy 300.381233 -377.234123)
			(xy 300.410717 -377.188246) (xy 300.446429 -377.147031) (xy 300.487642 -377.111319) (xy 300.533519 -377.081835)
			(xy 300.583125 -377.059181) (xy 300.63545 -377.043816) (xy 300.689429 -377.036055) (xy 300.716696 -377.035568)
			(xy 301.580296 -377.035568) (xy 301.607569 -377.035971) (xy 301.661561 -377.043734) (xy 301.713898 -377.059101)
			(xy 301.763516 -377.08176) (xy 301.809403 -377.11125) (xy 301.850627 -377.14697) (xy 301.886348 -377.188193)
			(xy 301.915838 -377.234081) (xy 301.938498 -377.283698) (xy 301.953866 -377.336035) (xy 301.961628 -377.390027)
			(xy 301.961628 -377.444567) (xy 307.142654 -377.444567) (xy 307.142654 -377.390033) (xy 307.150415 -377.336054)
			(xy 307.165779 -377.283729) (xy 307.188433 -377.234123) (xy 307.217917 -377.188246) (xy 307.253629 -377.147031)
			(xy 307.294842 -377.111319) (xy 307.340719 -377.081835) (xy 307.390325 -377.059181) (xy 307.44265 -377.043816)
			(xy 307.496629 -377.036055) (xy 307.523896 -377.035568) (xy 308.387496 -377.035568) (xy 308.414769 -377.035971)
			(xy 308.468761 -377.043734) (xy 308.521098 -377.059101) (xy 308.570716 -377.08176) (xy 308.616603 -377.11125)
			(xy 308.657827 -377.14697) (xy 308.693548 -377.188193) (xy 308.723038 -377.234081) (xy 308.745698 -377.283698)
			(xy 308.761066 -377.336035) (xy 308.768828 -377.390027) (xy 308.768828 -377.444567) (xy 313.949854 -377.444567)
			(xy 313.949854 -377.390033) (xy 313.957615 -377.336054) (xy 313.972979 -377.283729) (xy 313.995633 -377.234123)
			(xy 314.025117 -377.188246) (xy 314.060829 -377.147031) (xy 314.102042 -377.111319) (xy 314.147919 -377.081835)
			(xy 314.197525 -377.059181) (xy 314.24985 -377.043816) (xy 314.303829 -377.036055) (xy 314.331096 -377.035568)
			(xy 315.194696 -377.035568) (xy 315.221969 -377.035971) (xy 315.275961 -377.043734) (xy 315.328298 -377.059101)
			(xy 315.377916 -377.08176) (xy 315.423803 -377.11125) (xy 315.465027 -377.14697) (xy 315.500748 -377.188193)
			(xy 315.530238 -377.234081) (xy 315.552898 -377.283698) (xy 315.568266 -377.336035) (xy 315.576028 -377.390027)
			(xy 315.576028 -377.444567) (xy 320.757054 -377.444567) (xy 320.757054 -377.390033) (xy 320.764815 -377.336054)
			(xy 320.780179 -377.283729) (xy 320.802833 -377.234123) (xy 320.832317 -377.188246) (xy 320.868029 -377.147031)
			(xy 320.909242 -377.111319) (xy 320.955119 -377.081835) (xy 321.004725 -377.059181) (xy 321.05705 -377.043816)
			(xy 321.111029 -377.036055) (xy 321.138296 -377.035568) (xy 322.001896 -377.035568) (xy 322.029169 -377.035971)
			(xy 322.083161 -377.043734) (xy 322.135498 -377.059101) (xy 322.185116 -377.08176) (xy 322.231003 -377.11125)
			(xy 322.272227 -377.14697) (xy 322.307948 -377.188193) (xy 322.337438 -377.234081) (xy 322.360098 -377.283698)
			(xy 322.375466 -377.336035) (xy 322.383228 -377.390027) (xy 322.383228 -377.444567) (xy 324.160654 -377.444567)
			(xy 324.160654 -377.390033) (xy 324.168415 -377.336054) (xy 324.183779 -377.283729) (xy 324.206433 -377.234123)
			(xy 324.235917 -377.188246) (xy 324.271629 -377.147031) (xy 324.312842 -377.111319) (xy 324.358719 -377.081835)
			(xy 324.408325 -377.059181) (xy 324.46065 -377.043816) (xy 324.514629 -377.036055) (xy 324.541896 -377.035568)
			(xy 325.405496 -377.035568) (xy 325.432769 -377.035971) (xy 325.486761 -377.043734) (xy 325.539098 -377.059101)
			(xy 325.588716 -377.08176) (xy 325.634603 -377.11125) (xy 325.675827 -377.14697) (xy 325.711548 -377.188193)
			(xy 325.741038 -377.234081) (xy 325.763698 -377.283698) (xy 325.779066 -377.336035) (xy 325.786828 -377.390027)
			(xy 325.786828 -377.444571) (xy 332.863132 -377.444571) (xy 332.863132 -377.390029) (xy 332.870894 -377.336043)
			(xy 332.886261 -377.283711) (xy 332.908921 -377.234098) (xy 332.93841 -377.188216) (xy 332.974129 -377.146998)
			(xy 333.015351 -377.111284) (xy 333.061237 -377.081799) (xy 333.110852 -377.059146) (xy 333.163186 -377.043785)
			(xy 333.217173 -377.036028) (xy 333.244444 -377.035568) (xy 334.108044 -377.035568) (xy 334.135313 -377.035998)
			(xy 334.189297 -377.043765) (xy 334.241625 -377.059135) (xy 334.291233 -377.081796) (xy 334.337112 -377.111285)
			(xy 334.378328 -377.147003) (xy 334.414041 -377.188223) (xy 334.443525 -377.234105) (xy 334.46618 -377.283716)
			(xy 334.481544 -377.336047) (xy 334.489306 -377.39003) (xy 334.489306 -377.44457) (xy 334.489306 -377.444571)
			(xy 339.670332 -377.444571) (xy 339.670332 -377.390029) (xy 339.678094 -377.336043) (xy 339.693461 -377.283711)
			(xy 339.716121 -377.234098) (xy 339.74561 -377.188216) (xy 339.781329 -377.146998) (xy 339.822551 -377.111284)
			(xy 339.868437 -377.081799) (xy 339.918052 -377.059146) (xy 339.970386 -377.043785) (xy 340.024373 -377.036028)
			(xy 340.051644 -377.035568) (xy 340.915244 -377.035568) (xy 340.942513 -377.035998) (xy 340.996497 -377.043765)
			(xy 341.048825 -377.059135) (xy 341.098433 -377.081796) (xy 341.144312 -377.111285) (xy 341.185528 -377.147003)
			(xy 341.221241 -377.188223) (xy 341.250725 -377.234105) (xy 341.27338 -377.283716) (xy 341.288744 -377.336047)
			(xy 341.296506 -377.39003) (xy 341.296506 -377.44457) (xy 341.296506 -377.444571) (xy 346.477532 -377.444571)
			(xy 346.477532 -377.390029) (xy 346.485294 -377.336043) (xy 346.500661 -377.283711) (xy 346.523321 -377.234098)
			(xy 346.55281 -377.188216) (xy 346.588529 -377.146998) (xy 346.629751 -377.111284) (xy 346.675637 -377.081799)
			(xy 346.725252 -377.059146) (xy 346.777586 -377.043785) (xy 346.831573 -377.036028) (xy 346.858844 -377.035568)
			(xy 347.722444 -377.035568) (xy 347.749713 -377.035998) (xy 347.803697 -377.043765) (xy 347.856025 -377.059135)
			(xy 347.905633 -377.081796) (xy 347.951512 -377.111285) (xy 347.992728 -377.147003) (xy 348.028441 -377.188223)
			(xy 348.057925 -377.234105) (xy 348.08058 -377.283716) (xy 348.095944 -377.336047) (xy 348.103706 -377.39003)
			(xy 348.103706 -377.44457) (xy 348.103706 -377.444571) (xy 353.284732 -377.444571) (xy 353.284732 -377.390029)
			(xy 353.292494 -377.336043) (xy 353.307861 -377.283711) (xy 353.330521 -377.234098) (xy 353.36001 -377.188216)
			(xy 353.395729 -377.146998) (xy 353.436951 -377.111284) (xy 353.482837 -377.081799) (xy 353.532452 -377.059146)
			(xy 353.584786 -377.043785) (xy 353.638773 -377.036028) (xy 353.666044 -377.035568) (xy 354.529644 -377.035568)
			(xy 354.556913 -377.035998) (xy 354.610897 -377.043765) (xy 354.663225 -377.059135) (xy 354.712833 -377.081796)
			(xy 354.758712 -377.111285) (xy 354.799928 -377.147003) (xy 354.835641 -377.188223) (xy 354.865125 -377.234105)
			(xy 354.88778 -377.283716) (xy 354.903144 -377.336047) (xy 354.910906 -377.39003) (xy 354.910906 -377.44457)
			(xy 354.910906 -377.444571) (xy 356.688332 -377.444571) (xy 356.688332 -377.390029) (xy 356.696094 -377.336043)
			(xy 356.711461 -377.283711) (xy 356.734121 -377.234098) (xy 356.76361 -377.188216) (xy 356.799329 -377.146998)
			(xy 356.840551 -377.111284) (xy 356.886437 -377.081799) (xy 356.936052 -377.059146) (xy 356.988386 -377.043785)
			(xy 357.042373 -377.036028) (xy 357.069644 -377.035568) (xy 357.933244 -377.035568) (xy 357.960513 -377.035998)
			(xy 358.014497 -377.043765) (xy 358.066825 -377.059135) (xy 358.116433 -377.081796) (xy 358.162312 -377.111285)
			(xy 358.203528 -377.147003) (xy 358.239241 -377.188223) (xy 358.268725 -377.234105) (xy 358.29138 -377.283716)
			(xy 358.306744 -377.336047) (xy 358.314506 -377.39003) (xy 358.314506 -377.444567) (xy 367.435654 -377.444567)
			(xy 367.435654 -377.390033) (xy 367.443415 -377.336054) (xy 367.458779 -377.28373) (xy 367.481433 -377.234124)
			(xy 367.510916 -377.188247) (xy 367.546627 -377.147033) (xy 367.587841 -377.11132) (xy 367.633717 -377.081837)
			(xy 367.683322 -377.059182) (xy 367.735647 -377.043817) (xy 367.789625 -377.036055) (xy 367.816892 -377.035568)
			(xy 368.680492 -377.035568) (xy 368.707766 -377.035971) (xy 368.761757 -377.043733) (xy 368.814095 -377.0591)
			(xy 368.863713 -377.081759) (xy 368.909602 -377.111248) (xy 368.950826 -377.146968) (xy 368.986547 -377.188192)
			(xy 369.016038 -377.23408) (xy 369.038698 -377.283697) (xy 369.054065 -377.336035) (xy 369.061828 -377.390026)
			(xy 369.061828 -377.444567) (xy 374.242854 -377.444567) (xy 374.242854 -377.390033) (xy 374.250615 -377.336054)
			(xy 374.265979 -377.28373) (xy 374.288633 -377.234124) (xy 374.318116 -377.188247) (xy 374.353827 -377.147033)
			(xy 374.395041 -377.11132) (xy 374.440917 -377.081837) (xy 374.490522 -377.059182) (xy 374.542847 -377.043817)
			(xy 374.596825 -377.036055) (xy 374.624092 -377.035568) (xy 375.487692 -377.035568) (xy 375.514966 -377.035971)
			(xy 375.568957 -377.043733) (xy 375.621295 -377.0591) (xy 375.670913 -377.081759) (xy 375.716802 -377.111248)
			(xy 375.758026 -377.146968) (xy 375.793747 -377.188192) (xy 375.823238 -377.23408) (xy 375.845898 -377.283697)
			(xy 375.861265 -377.336035) (xy 375.869028 -377.390026) (xy 375.869028 -377.444567) (xy 381.050054 -377.444567)
			(xy 381.050054 -377.390033) (xy 381.057815 -377.336054) (xy 381.073179 -377.28373) (xy 381.095833 -377.234124)
			(xy 381.125316 -377.188247) (xy 381.161027 -377.147033) (xy 381.202241 -377.11132) (xy 381.248117 -377.081837)
			(xy 381.297722 -377.059182) (xy 381.350047 -377.043817) (xy 381.404025 -377.036055) (xy 381.431292 -377.035568)
			(xy 382.294892 -377.035568) (xy 382.322166 -377.035971) (xy 382.376157 -377.043733) (xy 382.428495 -377.0591)
			(xy 382.478113 -377.081759) (xy 382.524002 -377.111248) (xy 382.565226 -377.146968) (xy 382.600947 -377.188192)
			(xy 382.630438 -377.23408) (xy 382.653098 -377.283697) (xy 382.668465 -377.336035) (xy 382.676228 -377.390026)
			(xy 382.676228 -377.444567) (xy 387.857254 -377.444567) (xy 387.857254 -377.390033) (xy 387.865015 -377.336054)
			(xy 387.880379 -377.28373) (xy 387.903033 -377.234124) (xy 387.932516 -377.188247) (xy 387.968227 -377.147033)
			(xy 388.009441 -377.11132) (xy 388.055317 -377.081837) (xy 388.104922 -377.059182) (xy 388.157247 -377.043817)
			(xy 388.211225 -377.036055) (xy 388.238492 -377.035568) (xy 389.102092 -377.035568) (xy 389.129366 -377.035971)
			(xy 389.183357 -377.043733) (xy 389.235695 -377.0591) (xy 389.285313 -377.081759) (xy 389.331202 -377.111248)
			(xy 389.372426 -377.146968) (xy 389.408147 -377.188192) (xy 389.437638 -377.23408) (xy 389.460298 -377.283697)
			(xy 389.475665 -377.336035) (xy 389.483428 -377.390026) (xy 389.483428 -377.444567) (xy 391.260854 -377.444567)
			(xy 391.260854 -377.390033) (xy 391.268615 -377.336054) (xy 391.283979 -377.28373) (xy 391.306633 -377.234124)
			(xy 391.336116 -377.188247) (xy 391.371827 -377.147033) (xy 391.413041 -377.11132) (xy 391.458917 -377.081837)
			(xy 391.508522 -377.059182) (xy 391.560847 -377.043817) (xy 391.614825 -377.036055) (xy 391.642092 -377.035568)
			(xy 392.505692 -377.035568) (xy 392.532966 -377.035971) (xy 392.586957 -377.043733) (xy 392.639295 -377.0591)
			(xy 392.688913 -377.081759) (xy 392.734802 -377.111248) (xy 392.776026 -377.146968) (xy 392.811747 -377.188192)
			(xy 392.841238 -377.23408) (xy 392.863898 -377.283697) (xy 392.879265 -377.336035) (xy 392.887028 -377.390026)
			(xy 392.887028 -377.444571) (xy 399.963332 -377.444571) (xy 399.963332 -377.390029) (xy 399.971094 -377.336043)
			(xy 399.986461 -377.283711) (xy 400.00912 -377.234099) (xy 400.038609 -377.188217) (xy 400.074328 -377.147)
			(xy 400.11555 -377.111285) (xy 400.161435 -377.081801) (xy 400.211049 -377.059147) (xy 400.263382 -377.043786)
			(xy 400.317369 -377.036029) (xy 400.34464 -377.035568) (xy 401.20824 -377.035568) (xy 401.23551 -377.035997)
			(xy 401.289493 -377.043764) (xy 401.341822 -377.059134) (xy 401.391431 -377.081794) (xy 401.437311 -377.111284)
			(xy 401.478527 -377.147002) (xy 401.51424 -377.188222) (xy 401.543725 -377.234104) (xy 401.56638 -377.283716)
			(xy 401.581744 -377.336046) (xy 401.589506 -377.39003) (xy 401.589506 -377.44457) (xy 401.589506 -377.444571)
			(xy 406.770532 -377.444571) (xy 406.770532 -377.390029) (xy 406.778294 -377.336043) (xy 406.793661 -377.283711)
			(xy 406.81632 -377.234099) (xy 406.845809 -377.188217) (xy 406.881528 -377.147) (xy 406.92275 -377.111285)
			(xy 406.968635 -377.081801) (xy 407.018249 -377.059147) (xy 407.070582 -377.043786) (xy 407.124569 -377.036029)
			(xy 407.15184 -377.035568) (xy 408.01544 -377.035568) (xy 408.04271 -377.035997) (xy 408.096693 -377.043764)
			(xy 408.149022 -377.059134) (xy 408.198631 -377.081794) (xy 408.244511 -377.111284) (xy 408.285727 -377.147002)
			(xy 408.32144 -377.188222) (xy 408.350925 -377.234104) (xy 408.37358 -377.283716) (xy 408.388944 -377.336046)
			(xy 408.396706 -377.39003) (xy 408.396706 -377.44457) (xy 408.396706 -377.444571) (xy 413.577732 -377.444571)
			(xy 413.577732 -377.390029) (xy 413.585494 -377.336043) (xy 413.600861 -377.283711) (xy 413.62352 -377.234099)
			(xy 413.653009 -377.188217) (xy 413.688728 -377.147) (xy 413.72995 -377.111285) (xy 413.775835 -377.081801)
			(xy 413.825449 -377.059147) (xy 413.877782 -377.043786) (xy 413.931769 -377.036029) (xy 413.95904 -377.035568)
			(xy 414.82264 -377.035568) (xy 414.84991 -377.035997) (xy 414.903893 -377.043764) (xy 414.956222 -377.059134)
			(xy 415.005831 -377.081794) (xy 415.051711 -377.111284) (xy 415.092927 -377.147002) (xy 415.12864 -377.188222)
			(xy 415.158125 -377.234104) (xy 415.18078 -377.283716) (xy 415.196144 -377.336046) (xy 415.203906 -377.39003)
			(xy 415.203906 -377.44457) (xy 415.203906 -377.444571) (xy 420.384932 -377.444571) (xy 420.384932 -377.390029)
			(xy 420.392694 -377.336043) (xy 420.408061 -377.283711) (xy 420.43072 -377.234099) (xy 420.460209 -377.188217)
			(xy 420.495928 -377.147) (xy 420.53715 -377.111285) (xy 420.583035 -377.081801) (xy 420.632649 -377.059147)
			(xy 420.684982 -377.043786) (xy 420.738969 -377.036029) (xy 420.76624 -377.035568) (xy 421.62984 -377.035568)
			(xy 421.65711 -377.035997) (xy 421.711093 -377.043764) (xy 421.763422 -377.059134) (xy 421.813031 -377.081794)
			(xy 421.858911 -377.111284) (xy 421.900127 -377.147002) (xy 421.93584 -377.188222) (xy 421.965325 -377.234104)
			(xy 421.98798 -377.283716) (xy 422.003344 -377.336046) (xy 422.011106 -377.39003) (xy 422.011106 -377.44457)
			(xy 422.011106 -377.444571) (xy 423.788532 -377.444571) (xy 423.788532 -377.390029) (xy 423.796294 -377.336043)
			(xy 423.811661 -377.283711) (xy 423.83432 -377.234099) (xy 423.863809 -377.188217) (xy 423.899528 -377.147)
			(xy 423.94075 -377.111285) (xy 423.986635 -377.081801) (xy 424.036249 -377.059147) (xy 424.088582 -377.043786)
			(xy 424.142569 -377.036029) (xy 424.16984 -377.035568) (xy 425.03344 -377.035568) (xy 425.06071 -377.035997)
			(xy 425.114693 -377.043764) (xy 425.167022 -377.059134) (xy 425.216631 -377.081794) (xy 425.262511 -377.111284)
			(xy 425.303727 -377.147002) (xy 425.33944 -377.188222) (xy 425.368925 -377.234104) (xy 425.39158 -377.283716)
			(xy 425.406944 -377.336046) (xy 425.414706 -377.39003) (xy 425.414706 -377.44457) (xy 425.406944 -377.498554)
			(xy 425.39158 -377.550884) (xy 425.368925 -377.600496) (xy 425.33944 -377.646378) (xy 425.303727 -377.687598)
			(xy 425.262511 -377.723316) (xy 425.216631 -377.752806) (xy 425.167022 -377.775466) (xy 425.114693 -377.790836)
			(xy 425.06071 -377.798603) (xy 425.03344 -377.799092) (xy 424.16984 -377.799092) (xy 424.142569 -377.798571)
			(xy 424.088582 -377.790814) (xy 424.036249 -377.775453) (xy 423.986635 -377.752799) (xy 423.94075 -377.723315)
			(xy 423.899528 -377.6876) (xy 423.863809 -377.646383) (xy 423.83432 -377.600501) (xy 423.811661 -377.550889)
			(xy 423.796294 -377.498557) (xy 423.788532 -377.444571) (xy 422.011106 -377.444571) (xy 422.003344 -377.498554)
			(xy 421.98798 -377.550884) (xy 421.965325 -377.600496) (xy 421.93584 -377.646378) (xy 421.900127 -377.687598)
			(xy 421.858911 -377.723316) (xy 421.813031 -377.752806) (xy 421.763422 -377.775466) (xy 421.711093 -377.790836)
			(xy 421.65711 -377.798603) (xy 421.62984 -377.799092) (xy 420.76624 -377.799092) (xy 420.738969 -377.798571)
			(xy 420.684982 -377.790814) (xy 420.632649 -377.775453) (xy 420.583035 -377.752799) (xy 420.53715 -377.723315)
			(xy 420.495928 -377.6876) (xy 420.460209 -377.646383) (xy 420.43072 -377.600501) (xy 420.408061 -377.550889)
			(xy 420.392694 -377.498557) (xy 420.384932 -377.444571) (xy 415.203906 -377.444571) (xy 415.196144 -377.498554)
			(xy 415.18078 -377.550884) (xy 415.158125 -377.600496) (xy 415.12864 -377.646378) (xy 415.092927 -377.687598)
			(xy 415.051711 -377.723316) (xy 415.005831 -377.752806) (xy 414.956222 -377.775466) (xy 414.903893 -377.790836)
			(xy 414.84991 -377.798603) (xy 414.82264 -377.799092) (xy 413.95904 -377.799092) (xy 413.931769 -377.798571)
			(xy 413.877782 -377.790814) (xy 413.825449 -377.775453) (xy 413.775835 -377.752799) (xy 413.72995 -377.723315)
			(xy 413.688728 -377.6876) (xy 413.653009 -377.646383) (xy 413.62352 -377.600501) (xy 413.600861 -377.550889)
			(xy 413.585494 -377.498557) (xy 413.577732 -377.444571) (xy 408.396706 -377.444571) (xy 408.388944 -377.498554)
			(xy 408.37358 -377.550884) (xy 408.350925 -377.600496) (xy 408.32144 -377.646378) (xy 408.285727 -377.687598)
			(xy 408.244511 -377.723316) (xy 408.198631 -377.752806) (xy 408.149022 -377.775466) (xy 408.096693 -377.790836)
			(xy 408.04271 -377.798603) (xy 408.01544 -377.799092) (xy 407.15184 -377.799092) (xy 407.124569 -377.798571)
			(xy 407.070582 -377.790814) (xy 407.018249 -377.775453) (xy 406.968635 -377.752799) (xy 406.92275 -377.723315)
			(xy 406.881528 -377.6876) (xy 406.845809 -377.646383) (xy 406.81632 -377.600501) (xy 406.793661 -377.550889)
			(xy 406.778294 -377.498557) (xy 406.770532 -377.444571) (xy 401.589506 -377.444571) (xy 401.581744 -377.498554)
			(xy 401.56638 -377.550884) (xy 401.543725 -377.600496) (xy 401.51424 -377.646378) (xy 401.478527 -377.687598)
			(xy 401.437311 -377.723316) (xy 401.391431 -377.752806) (xy 401.341822 -377.775466) (xy 401.289493 -377.790836)
			(xy 401.23551 -377.798603) (xy 401.20824 -377.799092) (xy 400.34464 -377.799092) (xy 400.317369 -377.798571)
			(xy 400.263382 -377.790814) (xy 400.211049 -377.775453) (xy 400.161435 -377.752799) (xy 400.11555 -377.723315)
			(xy 400.074328 -377.6876) (xy 400.038609 -377.646383) (xy 400.00912 -377.600501) (xy 399.986461 -377.550889)
			(xy 399.971094 -377.498557) (xy 399.963332 -377.444571) (xy 392.887028 -377.444571) (xy 392.887028 -377.444574)
			(xy 392.879265 -377.498565) (xy 392.863898 -377.550903) (xy 392.841238 -377.60052) (xy 392.811747 -377.646408)
			(xy 392.776026 -377.687632) (xy 392.734802 -377.723352) (xy 392.688913 -377.752841) (xy 392.639295 -377.7755)
			(xy 392.586957 -377.790867) (xy 392.532966 -377.798629) (xy 392.505692 -377.799092) (xy 391.642092 -377.799092)
			(xy 391.614825 -377.798545) (xy 391.560847 -377.790783) (xy 391.508522 -377.775418) (xy 391.458917 -377.752763)
			(xy 391.413041 -377.72328) (xy 391.371827 -377.687567) (xy 391.336116 -377.646353) (xy 391.306633 -377.600476)
			(xy 391.283979 -377.55087) (xy 391.268615 -377.498546) (xy 391.260854 -377.444567) (xy 389.483428 -377.444567)
			(xy 389.483428 -377.444574) (xy 389.475665 -377.498565) (xy 389.460298 -377.550903) (xy 389.437638 -377.60052)
			(xy 389.408147 -377.646408) (xy 389.372426 -377.687632) (xy 389.331202 -377.723352) (xy 389.285313 -377.752841)
			(xy 389.235695 -377.7755) (xy 389.183357 -377.790867) (xy 389.129366 -377.798629) (xy 389.102092 -377.799092)
			(xy 388.238492 -377.799092) (xy 388.211225 -377.798545) (xy 388.157247 -377.790783) (xy 388.104922 -377.775418)
			(xy 388.055317 -377.752763) (xy 388.009441 -377.72328) (xy 387.968227 -377.687567) (xy 387.932516 -377.646353)
			(xy 387.903033 -377.600476) (xy 387.880379 -377.55087) (xy 387.865015 -377.498546) (xy 387.857254 -377.444567)
			(xy 382.676228 -377.444567) (xy 382.676228 -377.444574) (xy 382.668465 -377.498565) (xy 382.653098 -377.550903)
			(xy 382.630438 -377.60052) (xy 382.600947 -377.646408) (xy 382.565226 -377.687632) (xy 382.524002 -377.723352)
			(xy 382.478113 -377.752841) (xy 382.428495 -377.7755) (xy 382.376157 -377.790867) (xy 382.322166 -377.798629)
			(xy 382.294892 -377.799092) (xy 381.431292 -377.799092) (xy 381.404025 -377.798545) (xy 381.350047 -377.790783)
			(xy 381.297722 -377.775418) (xy 381.248117 -377.752763) (xy 381.202241 -377.72328) (xy 381.161027 -377.687567)
			(xy 381.125316 -377.646353) (xy 381.095833 -377.600476) (xy 381.073179 -377.55087) (xy 381.057815 -377.498546)
			(xy 381.050054 -377.444567) (xy 375.869028 -377.444567) (xy 375.869028 -377.444574) (xy 375.861265 -377.498565)
			(xy 375.845898 -377.550903) (xy 375.823238 -377.60052) (xy 375.793747 -377.646408) (xy 375.758026 -377.687632)
			(xy 375.716802 -377.723352) (xy 375.670913 -377.752841) (xy 375.621295 -377.7755) (xy 375.568957 -377.790867)
			(xy 375.514966 -377.798629) (xy 375.487692 -377.799092) (xy 374.624092 -377.799092) (xy 374.596825 -377.798545)
			(xy 374.542847 -377.790783) (xy 374.490522 -377.775418) (xy 374.440917 -377.752763) (xy 374.395041 -377.72328)
			(xy 374.353827 -377.687567) (xy 374.318116 -377.646353) (xy 374.288633 -377.600476) (xy 374.265979 -377.55087)
			(xy 374.250615 -377.498546) (xy 374.242854 -377.444567) (xy 369.061828 -377.444567) (xy 369.061828 -377.444574)
			(xy 369.054065 -377.498565) (xy 369.038698 -377.550903) (xy 369.016038 -377.60052) (xy 368.986547 -377.646408)
			(xy 368.950826 -377.687632) (xy 368.909602 -377.723352) (xy 368.863713 -377.752841) (xy 368.814095 -377.7755)
			(xy 368.761757 -377.790867) (xy 368.707766 -377.798629) (xy 368.680492 -377.799092) (xy 367.816892 -377.799092)
			(xy 367.789625 -377.798545) (xy 367.735647 -377.790783) (xy 367.683322 -377.775418) (xy 367.633717 -377.752763)
			(xy 367.587841 -377.72328) (xy 367.546627 -377.687567) (xy 367.510916 -377.646353) (xy 367.481433 -377.600476)
			(xy 367.458779 -377.55087) (xy 367.443415 -377.498546) (xy 367.435654 -377.444567) (xy 358.314506 -377.444567)
			(xy 358.314506 -377.44457) (xy 358.306744 -377.498553) (xy 358.29138 -377.550884) (xy 358.268725 -377.600495)
			(xy 358.239241 -377.646377) (xy 358.203528 -377.687597) (xy 358.162312 -377.723315) (xy 358.116433 -377.752804)
			(xy 358.066825 -377.775465) (xy 358.014497 -377.790835) (xy 357.960513 -377.798602) (xy 357.933244 -377.799092)
			(xy 357.069644 -377.799092) (xy 357.042373 -377.798572) (xy 356.988386 -377.790815) (xy 356.936052 -377.775454)
			(xy 356.886437 -377.752801) (xy 356.840551 -377.723316) (xy 356.799329 -377.687602) (xy 356.76361 -377.646384)
			(xy 356.734121 -377.600502) (xy 356.711461 -377.550889) (xy 356.696094 -377.498557) (xy 356.688332 -377.444571)
			(xy 354.910906 -377.444571) (xy 354.903144 -377.498553) (xy 354.88778 -377.550884) (xy 354.865125 -377.600495)
			(xy 354.835641 -377.646377) (xy 354.799928 -377.687597) (xy 354.758712 -377.723315) (xy 354.712833 -377.752804)
			(xy 354.663225 -377.775465) (xy 354.610897 -377.790835) (xy 354.556913 -377.798602) (xy 354.529644 -377.799092)
			(xy 353.666044 -377.799092) (xy 353.638773 -377.798572) (xy 353.584786 -377.790815) (xy 353.532452 -377.775454)
			(xy 353.482837 -377.752801) (xy 353.436951 -377.723316) (xy 353.395729 -377.687602) (xy 353.36001 -377.646384)
			(xy 353.330521 -377.600502) (xy 353.307861 -377.550889) (xy 353.292494 -377.498557) (xy 353.284732 -377.444571)
			(xy 348.103706 -377.444571) (xy 348.095944 -377.498553) (xy 348.08058 -377.550884) (xy 348.057925 -377.600495)
			(xy 348.028441 -377.646377) (xy 347.992728 -377.687597) (xy 347.951512 -377.723315) (xy 347.905633 -377.752804)
			(xy 347.856025 -377.775465) (xy 347.803697 -377.790835) (xy 347.749713 -377.798602) (xy 347.722444 -377.799092)
			(xy 346.858844 -377.799092) (xy 346.831573 -377.798572) (xy 346.777586 -377.790815) (xy 346.725252 -377.775454)
			(xy 346.675637 -377.752801) (xy 346.629751 -377.723316) (xy 346.588529 -377.687602) (xy 346.55281 -377.646384)
			(xy 346.523321 -377.600502) (xy 346.500661 -377.550889) (xy 346.485294 -377.498557) (xy 346.477532 -377.444571)
			(xy 341.296506 -377.444571) (xy 341.288744 -377.498553) (xy 341.27338 -377.550884) (xy 341.250725 -377.600495)
			(xy 341.221241 -377.646377) (xy 341.185528 -377.687597) (xy 341.144312 -377.723315) (xy 341.098433 -377.752804)
			(xy 341.048825 -377.775465) (xy 340.996497 -377.790835) (xy 340.942513 -377.798602) (xy 340.915244 -377.799092)
			(xy 340.051644 -377.799092) (xy 340.024373 -377.798572) (xy 339.970386 -377.790815) (xy 339.918052 -377.775454)
			(xy 339.868437 -377.752801) (xy 339.822551 -377.723316) (xy 339.781329 -377.687602) (xy 339.74561 -377.646384)
			(xy 339.716121 -377.600502) (xy 339.693461 -377.550889) (xy 339.678094 -377.498557) (xy 339.670332 -377.444571)
			(xy 334.489306 -377.444571) (xy 334.481544 -377.498553) (xy 334.46618 -377.550884) (xy 334.443525 -377.600495)
			(xy 334.414041 -377.646377) (xy 334.378328 -377.687597) (xy 334.337112 -377.723315) (xy 334.291233 -377.752804)
			(xy 334.241625 -377.775465) (xy 334.189297 -377.790835) (xy 334.135313 -377.798602) (xy 334.108044 -377.799092)
			(xy 333.244444 -377.799092) (xy 333.217173 -377.798572) (xy 333.163186 -377.790815) (xy 333.110852 -377.775454)
			(xy 333.061237 -377.752801) (xy 333.015351 -377.723316) (xy 332.974129 -377.687602) (xy 332.93841 -377.646384)
			(xy 332.908921 -377.600502) (xy 332.886261 -377.550889) (xy 332.870894 -377.498557) (xy 332.863132 -377.444571)
			(xy 325.786828 -377.444571) (xy 325.786828 -377.444573) (xy 325.779066 -377.498565) (xy 325.763698 -377.550902)
			(xy 325.741038 -377.600519) (xy 325.711548 -377.646407) (xy 325.675827 -377.68763) (xy 325.634603 -377.72335)
			(xy 325.588716 -377.75284) (xy 325.539098 -377.775499) (xy 325.486761 -377.790866) (xy 325.432769 -377.798629)
			(xy 325.405496 -377.799092) (xy 324.541896 -377.799092) (xy 324.514629 -377.798545) (xy 324.46065 -377.790784)
			(xy 324.408325 -377.775419) (xy 324.358719 -377.752765) (xy 324.312842 -377.723281) (xy 324.271629 -377.687569)
			(xy 324.235917 -377.646354) (xy 324.206433 -377.600477) (xy 324.183779 -377.550871) (xy 324.168415 -377.498546)
			(xy 324.160654 -377.444567) (xy 322.383228 -377.444567) (xy 322.383228 -377.444573) (xy 322.375466 -377.498565)
			(xy 322.360098 -377.550902) (xy 322.337438 -377.600519) (xy 322.307948 -377.646407) (xy 322.272227 -377.68763)
			(xy 322.231003 -377.72335) (xy 322.185116 -377.75284) (xy 322.135498 -377.775499) (xy 322.083161 -377.790866)
			(xy 322.029169 -377.798629) (xy 322.001896 -377.799092) (xy 321.138296 -377.799092) (xy 321.111029 -377.798545)
			(xy 321.05705 -377.790784) (xy 321.004725 -377.775419) (xy 320.955119 -377.752765) (xy 320.909242 -377.723281)
			(xy 320.868029 -377.687569) (xy 320.832317 -377.646354) (xy 320.802833 -377.600477) (xy 320.780179 -377.550871)
			(xy 320.764815 -377.498546) (xy 320.757054 -377.444567) (xy 315.576028 -377.444567) (xy 315.576028 -377.444573)
			(xy 315.568266 -377.498565) (xy 315.552898 -377.550902) (xy 315.530238 -377.600519) (xy 315.500748 -377.646407)
			(xy 315.465027 -377.68763) (xy 315.423803 -377.72335) (xy 315.377916 -377.75284) (xy 315.328298 -377.775499)
			(xy 315.275961 -377.790866) (xy 315.221969 -377.798629) (xy 315.194696 -377.799092) (xy 314.331096 -377.799092)
			(xy 314.303829 -377.798545) (xy 314.24985 -377.790784) (xy 314.197525 -377.775419) (xy 314.147919 -377.752765)
			(xy 314.102042 -377.723281) (xy 314.060829 -377.687569) (xy 314.025117 -377.646354) (xy 313.995633 -377.600477)
			(xy 313.972979 -377.550871) (xy 313.957615 -377.498546) (xy 313.949854 -377.444567) (xy 308.768828 -377.444567)
			(xy 308.768828 -377.444573) (xy 308.761066 -377.498565) (xy 308.745698 -377.550902) (xy 308.723038 -377.600519)
			(xy 308.693548 -377.646407) (xy 308.657827 -377.68763) (xy 308.616603 -377.72335) (xy 308.570716 -377.75284)
			(xy 308.521098 -377.775499) (xy 308.468761 -377.790866) (xy 308.414769 -377.798629) (xy 308.387496 -377.799092)
			(xy 307.523896 -377.799092) (xy 307.496629 -377.798545) (xy 307.44265 -377.790784) (xy 307.390325 -377.775419)
			(xy 307.340719 -377.752765) (xy 307.294842 -377.723281) (xy 307.253629 -377.687569) (xy 307.217917 -377.646354)
			(xy 307.188433 -377.600477) (xy 307.165779 -377.550871) (xy 307.150415 -377.498546) (xy 307.142654 -377.444567)
			(xy 301.961628 -377.444567) (xy 301.961628 -377.444573) (xy 301.953866 -377.498565) (xy 301.938498 -377.550902)
			(xy 301.915838 -377.600519) (xy 301.886348 -377.646407) (xy 301.850627 -377.68763) (xy 301.809403 -377.72335)
			(xy 301.763516 -377.75284) (xy 301.713898 -377.775499) (xy 301.661561 -377.790866) (xy 301.607569 -377.798629)
			(xy 301.580296 -377.799092) (xy 300.716696 -377.799092) (xy 300.689429 -377.798545) (xy 300.63545 -377.790784)
			(xy 300.583125 -377.775419) (xy 300.533519 -377.752765) (xy 300.487642 -377.723281) (xy 300.446429 -377.687569)
			(xy 300.410717 -377.646354) (xy 300.381233 -377.600477) (xy 300.358579 -377.550871) (xy 300.343215 -377.498546)
			(xy 300.335454 -377.444567) (xy 200.859958 -377.444567) (xy 200.882666 -377.460737) (xy 200.946694 -377.516218)
			(xy 201.005159 -377.577533) (xy 201.05753 -377.644129) (xy 201.103333 -377.715401) (xy 201.142155 -377.790704)
			(xy 201.173643 -377.869356) (xy 201.197511 -377.950646) (xy 201.213545 -378.033836) (xy 201.221598 -378.118173)
			(xy 201.222102 -378.160534) (xy 201.221598 -378.202895) (xy 201.213545 -378.287232) (xy 201.197511 -378.370422)
			(xy 201.173643 -378.451712) (xy 201.142155 -378.530364) (xy 201.103333 -378.605667) (xy 201.05753 -378.676939)
			(xy 201.005159 -378.743535) (xy 200.946694 -378.80485) (xy 200.882666 -378.860331) (xy 200.813654 -378.909474)
			(xy 200.740284 -378.951834) (xy 200.663219 -378.987029) (xy 200.583157 -379.014738) (xy 200.500824 -379.034712)
			(xy 200.416965 -379.046769) (xy 200.33234 -379.050801) (xy 200.247715 -379.046769) (xy 200.163856 -379.034712)
			(xy 200.081523 -379.014738) (xy 200.001461 -378.987029) (xy 199.924396 -378.951834) (xy 199.851026 -378.909474)
			(xy 199.782014 -378.860331) (xy 199.717986 -378.80485) (xy 199.659521 -378.743535) (xy 199.60715 -378.676939)
			(xy 199.561347 -378.605667) (xy 199.522525 -378.530364) (xy 199.491037 -378.451712) (xy 199.467169 -378.370422)
			(xy 199.451135 -378.287232) (xy 199.443082 -378.202895) (xy 195.47531 -378.202895) (xy 195.462625 -378.219025)
			(xy 195.40416 -378.28034) (xy 195.340132 -378.335821) (xy 195.27112 -378.384964) (xy 195.19775 -378.427324)
			(xy 195.120685 -378.462519) (xy 195.040623 -378.490228) (xy 194.95829 -378.510202) (xy 194.874431 -378.522259)
			(xy 194.789806 -378.526291) (xy 194.705181 -378.522259) (xy 194.621322 -378.510202) (xy 194.538989 -378.490228)
			(xy 194.458927 -378.462519) (xy 194.381862 -378.427324) (xy 194.308492 -378.384964) (xy 194.23948 -378.335821)
			(xy 194.175452 -378.28034) (xy 194.116987 -378.219025) (xy 194.064616 -378.152429) (xy 194.018813 -378.081157)
			(xy 193.979991 -378.005854) (xy 193.948503 -377.927202) (xy 193.924635 -377.845912) (xy 193.908601 -377.762722)
			(xy 193.900548 -377.678385) (xy 181.319901 -377.678385) (xy 181.279884 -377.802486) (xy 181.217663 -377.969563)
			(xy 181.148062 -378.133704) (xy 181.071217 -378.29458) (xy 180.987283 -378.451874) (xy 180.896425 -378.605273)
			(xy 180.798823 -378.754472) (xy 180.694672 -378.899175) (xy 180.584179 -379.039095) (xy 180.467562 -379.173954)
			(xy 180.345053 -379.303484) (xy 180.216896 -379.427428) (xy 180.083345 -379.54554) (xy 179.944665 -379.657585)
			(xy 179.801131 -379.763342) (xy 179.653028 -379.862599) (xy 179.577684 -379.908367) (xy 298.633654 -379.908367)
			(xy 298.633654 -379.853833) (xy 298.641415 -379.799854) (xy 298.656779 -379.747529) (xy 298.679433 -379.697923)
			(xy 298.708917 -379.652046) (xy 298.744629 -379.610831) (xy 298.785842 -379.575119) (xy 298.831719 -379.545635)
			(xy 298.881325 -379.522981) (xy 298.93365 -379.507616) (xy 298.987629 -379.499855) (xy 299.014896 -379.499368)
			(xy 299.878496 -379.499368) (xy 299.905769 -379.499771) (xy 299.959761 -379.507534) (xy 300.012098 -379.522901)
			(xy 300.061716 -379.54556) (xy 300.107603 -379.57505) (xy 300.148827 -379.61077) (xy 300.184548 -379.651993)
			(xy 300.214038 -379.697881) (xy 300.236698 -379.747498) (xy 300.252066 -379.799835) (xy 300.259828 -379.853827)
			(xy 300.259828 -379.908367) (xy 305.440854 -379.908367) (xy 305.440854 -379.853833) (xy 305.448615 -379.799854)
			(xy 305.463979 -379.747529) (xy 305.486633 -379.697923) (xy 305.516117 -379.652046) (xy 305.551829 -379.610831)
			(xy 305.593042 -379.575119) (xy 305.638919 -379.545635) (xy 305.688525 -379.522981) (xy 305.74085 -379.507616)
			(xy 305.794829 -379.499855) (xy 305.822096 -379.499368) (xy 306.685696 -379.499368) (xy 306.712969 -379.499771)
			(xy 306.766961 -379.507534) (xy 306.819298 -379.522901) (xy 306.868916 -379.54556) (xy 306.914803 -379.57505)
			(xy 306.956027 -379.61077) (xy 306.991748 -379.651993) (xy 307.021238 -379.697881) (xy 307.043898 -379.747498)
			(xy 307.059266 -379.799835) (xy 307.067028 -379.853827) (xy 307.067028 -379.908367) (xy 312.248054 -379.908367)
			(xy 312.248054 -379.853833) (xy 312.255815 -379.799854) (xy 312.271179 -379.747529) (xy 312.293833 -379.697923)
			(xy 312.323317 -379.652046) (xy 312.359029 -379.610831) (xy 312.400242 -379.575119) (xy 312.446119 -379.545635)
			(xy 312.495725 -379.522981) (xy 312.54805 -379.507616) (xy 312.602029 -379.499855) (xy 312.629296 -379.499368)
			(xy 313.492896 -379.499368) (xy 313.520169 -379.499771) (xy 313.574161 -379.507534) (xy 313.626498 -379.522901)
			(xy 313.676116 -379.54556) (xy 313.722003 -379.57505) (xy 313.763227 -379.61077) (xy 313.798948 -379.651993)
			(xy 313.828438 -379.697881) (xy 313.851098 -379.747498) (xy 313.866466 -379.799835) (xy 313.874228 -379.853827)
			(xy 313.874228 -379.908367) (xy 319.055254 -379.908367) (xy 319.055254 -379.853833) (xy 319.063015 -379.799854)
			(xy 319.078379 -379.747529) (xy 319.101033 -379.697923) (xy 319.130517 -379.652046) (xy 319.166229 -379.610831)
			(xy 319.207442 -379.575119) (xy 319.253319 -379.545635) (xy 319.302925 -379.522981) (xy 319.35525 -379.507616)
			(xy 319.409229 -379.499855) (xy 319.436496 -379.499368) (xy 320.300096 -379.499368) (xy 320.327369 -379.499771)
			(xy 320.381361 -379.507534) (xy 320.433698 -379.522901) (xy 320.483316 -379.54556) (xy 320.529203 -379.57505)
			(xy 320.570427 -379.61077) (xy 320.606148 -379.651993) (xy 320.635638 -379.697881) (xy 320.658298 -379.747498)
			(xy 320.673666 -379.799835) (xy 320.681428 -379.853827) (xy 320.681428 -379.908371) (xy 331.161332 -379.908371)
			(xy 331.161332 -379.853829) (xy 331.169094 -379.799843) (xy 331.184461 -379.747511) (xy 331.207121 -379.697898)
			(xy 331.23661 -379.652016) (xy 331.272329 -379.610798) (xy 331.313551 -379.575084) (xy 331.359437 -379.545599)
			(xy 331.409052 -379.522946) (xy 331.461386 -379.507585) (xy 331.515373 -379.499828) (xy 331.542644 -379.499368)
			(xy 332.406244 -379.499368) (xy 332.433513 -379.499798) (xy 332.487497 -379.507565) (xy 332.539825 -379.522935)
			(xy 332.589433 -379.545596) (xy 332.635312 -379.575085) (xy 332.676528 -379.610803) (xy 332.712241 -379.652023)
			(xy 332.741725 -379.697905) (xy 332.76438 -379.747516) (xy 332.779744 -379.799847) (xy 332.787506 -379.85383)
			(xy 332.787506 -379.90837) (xy 332.787506 -379.908371) (xy 337.968532 -379.908371) (xy 337.968532 -379.853829)
			(xy 337.976294 -379.799843) (xy 337.991661 -379.747511) (xy 338.014321 -379.697898) (xy 338.04381 -379.652016)
			(xy 338.079529 -379.610798) (xy 338.120751 -379.575084) (xy 338.166637 -379.545599) (xy 338.216252 -379.522946)
			(xy 338.268586 -379.507585) (xy 338.322573 -379.499828) (xy 338.349844 -379.499368) (xy 339.213444 -379.499368)
			(xy 339.240713 -379.499798) (xy 339.294697 -379.507565) (xy 339.347025 -379.522935) (xy 339.396633 -379.545596)
			(xy 339.442512 -379.575085) (xy 339.483728 -379.610803) (xy 339.519441 -379.652023) (xy 339.548925 -379.697905)
			(xy 339.57158 -379.747516) (xy 339.586944 -379.799847) (xy 339.594706 -379.85383) (xy 339.594706 -379.90837)
			(xy 339.594706 -379.908371) (xy 344.775732 -379.908371) (xy 344.775732 -379.853829) (xy 344.783494 -379.799843)
			(xy 344.798861 -379.747511) (xy 344.821521 -379.697898) (xy 344.85101 -379.652016) (xy 344.886729 -379.610798)
			(xy 344.927951 -379.575084) (xy 344.973837 -379.545599) (xy 345.023452 -379.522946) (xy 345.075786 -379.507585)
			(xy 345.129773 -379.499828) (xy 345.157044 -379.499368) (xy 346.020644 -379.499368) (xy 346.047913 -379.499798)
			(xy 346.101897 -379.507565) (xy 346.154225 -379.522935) (xy 346.203833 -379.545596) (xy 346.249712 -379.575085)
			(xy 346.290928 -379.610803) (xy 346.326641 -379.652023) (xy 346.356125 -379.697905) (xy 346.37878 -379.747516)
			(xy 346.394144 -379.799847) (xy 346.401906 -379.85383) (xy 346.401906 -379.90837) (xy 346.401906 -379.908371)
			(xy 351.582932 -379.908371) (xy 351.582932 -379.853829) (xy 351.590694 -379.799843) (xy 351.606061 -379.747511)
			(xy 351.628721 -379.697898) (xy 351.65821 -379.652016) (xy 351.693929 -379.610798) (xy 351.735151 -379.575084)
			(xy 351.781037 -379.545599) (xy 351.830652 -379.522946) (xy 351.882986 -379.507585) (xy 351.936973 -379.499828)
			(xy 351.964244 -379.499368) (xy 352.827844 -379.499368) (xy 352.855113 -379.499798) (xy 352.909097 -379.507565)
			(xy 352.961425 -379.522935) (xy 353.011033 -379.545596) (xy 353.056912 -379.575085) (xy 353.098128 -379.610803)
			(xy 353.133841 -379.652023) (xy 353.163325 -379.697905) (xy 353.18598 -379.747516) (xy 353.201344 -379.799847)
			(xy 353.209106 -379.85383) (xy 353.209106 -379.908367) (xy 365.733854 -379.908367) (xy 365.733854 -379.853833)
			(xy 365.741615 -379.799854) (xy 365.756979 -379.74753) (xy 365.779633 -379.697924) (xy 365.809116 -379.652047)
			(xy 365.844827 -379.610833) (xy 365.886041 -379.57512) (xy 365.931917 -379.545637) (xy 365.981522 -379.522982)
			(xy 366.033847 -379.507617) (xy 366.087825 -379.499855) (xy 366.115092 -379.499368) (xy 366.978692 -379.499368)
			(xy 367.005966 -379.499771) (xy 367.059957 -379.507533) (xy 367.112295 -379.5229) (xy 367.161913 -379.545559)
			(xy 367.207802 -379.575048) (xy 367.249026 -379.610768) (xy 367.284747 -379.651992) (xy 367.314238 -379.69788)
			(xy 367.336898 -379.747497) (xy 367.352265 -379.799835) (xy 367.360028 -379.853826) (xy 367.360028 -379.908367)
			(xy 372.541054 -379.908367) (xy 372.541054 -379.853833) (xy 372.548815 -379.799854) (xy 372.564179 -379.74753)
			(xy 372.586833 -379.697924) (xy 372.616316 -379.652047) (xy 372.652027 -379.610833) (xy 372.693241 -379.57512)
			(xy 372.739117 -379.545637) (xy 372.788722 -379.522982) (xy 372.841047 -379.507617) (xy 372.895025 -379.499855)
			(xy 372.922292 -379.499368) (xy 373.785892 -379.499368) (xy 373.813166 -379.499771) (xy 373.867157 -379.507533)
			(xy 373.919495 -379.5229) (xy 373.969113 -379.545559) (xy 374.015002 -379.575048) (xy 374.056226 -379.610768)
			(xy 374.091947 -379.651992) (xy 374.121438 -379.69788) (xy 374.144098 -379.747497) (xy 374.159465 -379.799835)
			(xy 374.167228 -379.853826) (xy 374.167228 -379.908367) (xy 379.348254 -379.908367) (xy 379.348254 -379.853833)
			(xy 379.356015 -379.799854) (xy 379.371379 -379.74753) (xy 379.394033 -379.697924) (xy 379.423516 -379.652047)
			(xy 379.459227 -379.610833) (xy 379.500441 -379.57512) (xy 379.546317 -379.545637) (xy 379.595922 -379.522982)
			(xy 379.648247 -379.507617) (xy 379.702225 -379.499855) (xy 379.729492 -379.499368) (xy 380.593092 -379.499368)
			(xy 380.620366 -379.499771) (xy 380.674357 -379.507533) (xy 380.726695 -379.5229) (xy 380.776313 -379.545559)
			(xy 380.822202 -379.575048) (xy 380.863426 -379.610768) (xy 380.899147 -379.651992) (xy 380.928638 -379.69788)
			(xy 380.951298 -379.747497) (xy 380.966665 -379.799835) (xy 380.974428 -379.853826) (xy 380.974428 -379.908367)
			(xy 386.155454 -379.908367) (xy 386.155454 -379.853833) (xy 386.163215 -379.799854) (xy 386.178579 -379.74753)
			(xy 386.201233 -379.697924) (xy 386.230716 -379.652047) (xy 386.266427 -379.610833) (xy 386.307641 -379.57512)
			(xy 386.353517 -379.545637) (xy 386.403122 -379.522982) (xy 386.455447 -379.507617) (xy 386.509425 -379.499855)
			(xy 386.536692 -379.499368) (xy 387.400292 -379.499368) (xy 387.427566 -379.499771) (xy 387.481557 -379.507533)
			(xy 387.533895 -379.5229) (xy 387.583513 -379.545559) (xy 387.629402 -379.575048) (xy 387.670626 -379.610768)
			(xy 387.706347 -379.651992) (xy 387.735838 -379.69788) (xy 387.758498 -379.747497) (xy 387.773865 -379.799835)
			(xy 387.781628 -379.853826) (xy 387.781628 -379.908371) (xy 398.261532 -379.908371) (xy 398.261532 -379.853829)
			(xy 398.269294 -379.799843) (xy 398.284661 -379.747511) (xy 398.30732 -379.697899) (xy 398.336809 -379.652017)
			(xy 398.372528 -379.6108) (xy 398.41375 -379.575085) (xy 398.459635 -379.545601) (xy 398.509249 -379.522947)
			(xy 398.561582 -379.507586) (xy 398.615569 -379.499829) (xy 398.64284 -379.499368) (xy 399.50644 -379.499368)
			(xy 399.53371 -379.499797) (xy 399.587693 -379.507564) (xy 399.640022 -379.522934) (xy 399.689631 -379.545594)
			(xy 399.735511 -379.575084) (xy 399.776727 -379.610802) (xy 399.81244 -379.652022) (xy 399.841925 -379.697904)
			(xy 399.86458 -379.747516) (xy 399.879944 -379.799846) (xy 399.887706 -379.85383) (xy 399.887706 -379.90837)
			(xy 399.887706 -379.908371) (xy 405.068732 -379.908371) (xy 405.068732 -379.853829) (xy 405.076494 -379.799843)
			(xy 405.091861 -379.747511) (xy 405.11452 -379.697899) (xy 405.144009 -379.652017) (xy 405.179728 -379.6108)
			(xy 405.22095 -379.575085) (xy 405.266835 -379.545601) (xy 405.316449 -379.522947) (xy 405.368782 -379.507586)
			(xy 405.422769 -379.499829) (xy 405.45004 -379.499368) (xy 406.31364 -379.499368) (xy 406.34091 -379.499797)
			(xy 406.394893 -379.507564) (xy 406.447222 -379.522934) (xy 406.496831 -379.545594) (xy 406.542711 -379.575084)
			(xy 406.583927 -379.610802) (xy 406.61964 -379.652022) (xy 406.649125 -379.697904) (xy 406.67178 -379.747516)
			(xy 406.687144 -379.799846) (xy 406.694906 -379.85383) (xy 406.694906 -379.90837) (xy 406.694906 -379.908371)
			(xy 411.875932 -379.908371) (xy 411.875932 -379.853829) (xy 411.883694 -379.799843) (xy 411.899061 -379.747511)
			(xy 411.92172 -379.697899) (xy 411.951209 -379.652017) (xy 411.986928 -379.6108) (xy 412.02815 -379.575085)
			(xy 412.074035 -379.545601) (xy 412.123649 -379.522947) (xy 412.175982 -379.507586) (xy 412.229969 -379.499829)
			(xy 412.25724 -379.499368) (xy 413.12084 -379.499368) (xy 413.14811 -379.499797) (xy 413.202093 -379.507564)
			(xy 413.254422 -379.522934) (xy 413.304031 -379.545594) (xy 413.349911 -379.575084) (xy 413.391127 -379.610802)
			(xy 413.42684 -379.652022) (xy 413.456325 -379.697904) (xy 413.47898 -379.747516) (xy 413.494344 -379.799846)
			(xy 413.502106 -379.85383) (xy 413.502106 -379.90837) (xy 413.502106 -379.908371) (xy 418.683132 -379.908371)
			(xy 418.683132 -379.853829) (xy 418.690894 -379.799843) (xy 418.706261 -379.747511) (xy 418.72892 -379.697899)
			(xy 418.758409 -379.652017) (xy 418.794128 -379.6108) (xy 418.83535 -379.575085) (xy 418.881235 -379.545601)
			(xy 418.930849 -379.522947) (xy 418.983182 -379.507586) (xy 419.037169 -379.499829) (xy 419.06444 -379.499368)
			(xy 419.92804 -379.499368) (xy 419.95531 -379.499797) (xy 420.009293 -379.507564) (xy 420.061622 -379.522934)
			(xy 420.111231 -379.545594) (xy 420.157111 -379.575084) (xy 420.198327 -379.610802) (xy 420.23404 -379.652022)
			(xy 420.263525 -379.697904) (xy 420.28618 -379.747516) (xy 420.301544 -379.799846) (xy 420.309306 -379.85383)
			(xy 420.309306 -379.90837) (xy 420.301544 -379.962354) (xy 420.28618 -380.014684) (xy 420.263525 -380.064296)
			(xy 420.23404 -380.110178) (xy 420.198327 -380.151398) (xy 420.157111 -380.187116) (xy 420.111231 -380.216606)
			(xy 420.061622 -380.239266) (xy 420.009293 -380.254636) (xy 419.95531 -380.262403) (xy 419.92804 -380.262892)
			(xy 419.06444 -380.262892) (xy 419.037169 -380.262371) (xy 418.983182 -380.254614) (xy 418.930849 -380.239253)
			(xy 418.881235 -380.216599) (xy 418.83535 -380.187115) (xy 418.794128 -380.1514) (xy 418.758409 -380.110183)
			(xy 418.72892 -380.064301) (xy 418.706261 -380.014689) (xy 418.690894 -379.962357) (xy 418.683132 -379.908371)
			(xy 413.502106 -379.908371) (xy 413.494344 -379.962354) (xy 413.47898 -380.014684) (xy 413.456325 -380.064296)
			(xy 413.42684 -380.110178) (xy 413.391127 -380.151398) (xy 413.349911 -380.187116) (xy 413.304031 -380.216606)
			(xy 413.254422 -380.239266) (xy 413.202093 -380.254636) (xy 413.14811 -380.262403) (xy 413.12084 -380.262892)
			(xy 412.25724 -380.262892) (xy 412.229969 -380.262371) (xy 412.175982 -380.254614) (xy 412.123649 -380.239253)
			(xy 412.074035 -380.216599) (xy 412.02815 -380.187115) (xy 411.986928 -380.1514) (xy 411.951209 -380.110183)
			(xy 411.92172 -380.064301) (xy 411.899061 -380.014689) (xy 411.883694 -379.962357) (xy 411.875932 -379.908371)
			(xy 406.694906 -379.908371) (xy 406.687144 -379.962354) (xy 406.67178 -380.014684) (xy 406.649125 -380.064296)
			(xy 406.61964 -380.110178) (xy 406.583927 -380.151398) (xy 406.542711 -380.187116) (xy 406.496831 -380.216606)
			(xy 406.447222 -380.239266) (xy 406.394893 -380.254636) (xy 406.34091 -380.262403) (xy 406.31364 -380.262892)
			(xy 405.45004 -380.262892) (xy 405.422769 -380.262371) (xy 405.368782 -380.254614) (xy 405.316449 -380.239253)
			(xy 405.266835 -380.216599) (xy 405.22095 -380.187115) (xy 405.179728 -380.1514) (xy 405.144009 -380.110183)
			(xy 405.11452 -380.064301) (xy 405.091861 -380.014689) (xy 405.076494 -379.962357) (xy 405.068732 -379.908371)
			(xy 399.887706 -379.908371) (xy 399.879944 -379.962354) (xy 399.86458 -380.014684) (xy 399.841925 -380.064296)
			(xy 399.81244 -380.110178) (xy 399.776727 -380.151398) (xy 399.735511 -380.187116) (xy 399.689631 -380.216606)
			(xy 399.640022 -380.239266) (xy 399.587693 -380.254636) (xy 399.53371 -380.262403) (xy 399.50644 -380.262892)
			(xy 398.64284 -380.262892) (xy 398.615569 -380.262371) (xy 398.561582 -380.254614) (xy 398.509249 -380.239253)
			(xy 398.459635 -380.216599) (xy 398.41375 -380.187115) (xy 398.372528 -380.1514) (xy 398.336809 -380.110183)
			(xy 398.30732 -380.064301) (xy 398.284661 -380.014689) (xy 398.269294 -379.962357) (xy 398.261532 -379.908371)
			(xy 387.781628 -379.908371) (xy 387.781628 -379.908374) (xy 387.773865 -379.962365) (xy 387.758498 -380.014703)
			(xy 387.735838 -380.06432) (xy 387.706347 -380.110208) (xy 387.670626 -380.151432) (xy 387.629402 -380.187152)
			(xy 387.583513 -380.216641) (xy 387.533895 -380.2393) (xy 387.481557 -380.254667) (xy 387.427566 -380.262429)
			(xy 387.400292 -380.262892) (xy 386.536692 -380.262892) (xy 386.509425 -380.262345) (xy 386.455447 -380.254583)
			(xy 386.403122 -380.239218) (xy 386.353517 -380.216563) (xy 386.307641 -380.18708) (xy 386.266427 -380.151367)
			(xy 386.230716 -380.110153) (xy 386.201233 -380.064276) (xy 386.178579 -380.01467) (xy 386.163215 -379.962346)
			(xy 386.155454 -379.908367) (xy 380.974428 -379.908367) (xy 380.974428 -379.908374) (xy 380.966665 -379.962365)
			(xy 380.951298 -380.014703) (xy 380.928638 -380.06432) (xy 380.899147 -380.110208) (xy 380.863426 -380.151432)
			(xy 380.822202 -380.187152) (xy 380.776313 -380.216641) (xy 380.726695 -380.2393) (xy 380.674357 -380.254667)
			(xy 380.620366 -380.262429) (xy 380.593092 -380.262892) (xy 379.729492 -380.262892) (xy 379.702225 -380.262345)
			(xy 379.648247 -380.254583) (xy 379.595922 -380.239218) (xy 379.546317 -380.216563) (xy 379.500441 -380.18708)
			(xy 379.459227 -380.151367) (xy 379.423516 -380.110153) (xy 379.394033 -380.064276) (xy 379.371379 -380.01467)
			(xy 379.356015 -379.962346) (xy 379.348254 -379.908367) (xy 374.167228 -379.908367) (xy 374.167228 -379.908374)
			(xy 374.159465 -379.962365) (xy 374.144098 -380.014703) (xy 374.121438 -380.06432) (xy 374.091947 -380.110208)
			(xy 374.056226 -380.151432) (xy 374.015002 -380.187152) (xy 373.969113 -380.216641) (xy 373.919495 -380.2393)
			(xy 373.867157 -380.254667) (xy 373.813166 -380.262429) (xy 373.785892 -380.262892) (xy 372.922292 -380.262892)
			(xy 372.895025 -380.262345) (xy 372.841047 -380.254583) (xy 372.788722 -380.239218) (xy 372.739117 -380.216563)
			(xy 372.693241 -380.18708) (xy 372.652027 -380.151367) (xy 372.616316 -380.110153) (xy 372.586833 -380.064276)
			(xy 372.564179 -380.01467) (xy 372.548815 -379.962346) (xy 372.541054 -379.908367) (xy 367.360028 -379.908367)
			(xy 367.360028 -379.908374) (xy 367.352265 -379.962365) (xy 367.336898 -380.014703) (xy 367.314238 -380.06432)
			(xy 367.284747 -380.110208) (xy 367.249026 -380.151432) (xy 367.207802 -380.187152) (xy 367.161913 -380.216641)
			(xy 367.112295 -380.2393) (xy 367.059957 -380.254667) (xy 367.005966 -380.262429) (xy 366.978692 -380.262892)
			(xy 366.115092 -380.262892) (xy 366.087825 -380.262345) (xy 366.033847 -380.254583) (xy 365.981522 -380.239218)
			(xy 365.931917 -380.216563) (xy 365.886041 -380.18708) (xy 365.844827 -380.151367) (xy 365.809116 -380.110153)
			(xy 365.779633 -380.064276) (xy 365.756979 -380.01467) (xy 365.741615 -379.962346) (xy 365.733854 -379.908367)
			(xy 353.209106 -379.908367) (xy 353.209106 -379.90837) (xy 353.201344 -379.962353) (xy 353.18598 -380.014684)
			(xy 353.163325 -380.064295) (xy 353.133841 -380.110177) (xy 353.098128 -380.151397) (xy 353.056912 -380.187115)
			(xy 353.011033 -380.216604) (xy 352.961425 -380.239265) (xy 352.909097 -380.254635) (xy 352.855113 -380.262402)
			(xy 352.827844 -380.262892) (xy 351.964244 -380.262892) (xy 351.936973 -380.262372) (xy 351.882986 -380.254615)
			(xy 351.830652 -380.239254) (xy 351.781037 -380.216601) (xy 351.735151 -380.187116) (xy 351.693929 -380.151402)
			(xy 351.65821 -380.110184) (xy 351.628721 -380.064302) (xy 351.606061 -380.014689) (xy 351.590694 -379.962357)
			(xy 351.582932 -379.908371) (xy 346.401906 -379.908371) (xy 346.394144 -379.962353) (xy 346.37878 -380.014684)
			(xy 346.356125 -380.064295) (xy 346.326641 -380.110177) (xy 346.290928 -380.151397) (xy 346.249712 -380.187115)
			(xy 346.203833 -380.216604) (xy 346.154225 -380.239265) (xy 346.101897 -380.254635) (xy 346.047913 -380.262402)
			(xy 346.020644 -380.262892) (xy 345.157044 -380.262892) (xy 345.129773 -380.262372) (xy 345.075786 -380.254615)
			(xy 345.023452 -380.239254) (xy 344.973837 -380.216601) (xy 344.927951 -380.187116) (xy 344.886729 -380.151402)
			(xy 344.85101 -380.110184) (xy 344.821521 -380.064302) (xy 344.798861 -380.014689) (xy 344.783494 -379.962357)
			(xy 344.775732 -379.908371) (xy 339.594706 -379.908371) (xy 339.586944 -379.962353) (xy 339.57158 -380.014684)
			(xy 339.548925 -380.064295) (xy 339.519441 -380.110177) (xy 339.483728 -380.151397) (xy 339.442512 -380.187115)
			(xy 339.396633 -380.216604) (xy 339.347025 -380.239265) (xy 339.294697 -380.254635) (xy 339.240713 -380.262402)
			(xy 339.213444 -380.262892) (xy 338.349844 -380.262892) (xy 338.322573 -380.262372) (xy 338.268586 -380.254615)
			(xy 338.216252 -380.239254) (xy 338.166637 -380.216601) (xy 338.120751 -380.187116) (xy 338.079529 -380.151402)
			(xy 338.04381 -380.110184) (xy 338.014321 -380.064302) (xy 337.991661 -380.014689) (xy 337.976294 -379.962357)
			(xy 337.968532 -379.908371) (xy 332.787506 -379.908371) (xy 332.779744 -379.962353) (xy 332.76438 -380.014684)
			(xy 332.741725 -380.064295) (xy 332.712241 -380.110177) (xy 332.676528 -380.151397) (xy 332.635312 -380.187115)
			(xy 332.589433 -380.216604) (xy 332.539825 -380.239265) (xy 332.487497 -380.254635) (xy 332.433513 -380.262402)
			(xy 332.406244 -380.262892) (xy 331.542644 -380.262892) (xy 331.515373 -380.262372) (xy 331.461386 -380.254615)
			(xy 331.409052 -380.239254) (xy 331.359437 -380.216601) (xy 331.313551 -380.187116) (xy 331.272329 -380.151402)
			(xy 331.23661 -380.110184) (xy 331.207121 -380.064302) (xy 331.184461 -380.014689) (xy 331.169094 -379.962357)
			(xy 331.161332 -379.908371) (xy 320.681428 -379.908371) (xy 320.681428 -379.908373) (xy 320.673666 -379.962365)
			(xy 320.658298 -380.014702) (xy 320.635638 -380.064319) (xy 320.606148 -380.110207) (xy 320.570427 -380.15143)
			(xy 320.529203 -380.18715) (xy 320.483316 -380.21664) (xy 320.433698 -380.239299) (xy 320.381361 -380.254666)
			(xy 320.327369 -380.262429) (xy 320.300096 -380.262892) (xy 319.436496 -380.262892) (xy 319.409229 -380.262345)
			(xy 319.35525 -380.254584) (xy 319.302925 -380.239219) (xy 319.253319 -380.216565) (xy 319.207442 -380.187081)
			(xy 319.166229 -380.151369) (xy 319.130517 -380.110154) (xy 319.101033 -380.064277) (xy 319.078379 -380.014671)
			(xy 319.063015 -379.962346) (xy 319.055254 -379.908367) (xy 313.874228 -379.908367) (xy 313.874228 -379.908373)
			(xy 313.866466 -379.962365) (xy 313.851098 -380.014702) (xy 313.828438 -380.064319) (xy 313.798948 -380.110207)
			(xy 313.763227 -380.15143) (xy 313.722003 -380.18715) (xy 313.676116 -380.21664) (xy 313.626498 -380.239299)
			(xy 313.574161 -380.254666) (xy 313.520169 -380.262429) (xy 313.492896 -380.262892) (xy 312.629296 -380.262892)
			(xy 312.602029 -380.262345) (xy 312.54805 -380.254584) (xy 312.495725 -380.239219) (xy 312.446119 -380.216565)
			(xy 312.400242 -380.187081) (xy 312.359029 -380.151369) (xy 312.323317 -380.110154) (xy 312.293833 -380.064277)
			(xy 312.271179 -380.014671) (xy 312.255815 -379.962346) (xy 312.248054 -379.908367) (xy 307.067028 -379.908367)
			(xy 307.067028 -379.908373) (xy 307.059266 -379.962365) (xy 307.043898 -380.014702) (xy 307.021238 -380.064319)
			(xy 306.991748 -380.110207) (xy 306.956027 -380.15143) (xy 306.914803 -380.18715) (xy 306.868916 -380.21664)
			(xy 306.819298 -380.239299) (xy 306.766961 -380.254666) (xy 306.712969 -380.262429) (xy 306.685696 -380.262892)
			(xy 305.822096 -380.262892) (xy 305.794829 -380.262345) (xy 305.74085 -380.254584) (xy 305.688525 -380.239219)
			(xy 305.638919 -380.216565) (xy 305.593042 -380.187081) (xy 305.551829 -380.151369) (xy 305.516117 -380.110154)
			(xy 305.486633 -380.064277) (xy 305.463979 -380.014671) (xy 305.448615 -379.962346) (xy 305.440854 -379.908367)
			(xy 300.259828 -379.908367) (xy 300.259828 -379.908373) (xy 300.252066 -379.962365) (xy 300.236698 -380.014702)
			(xy 300.214038 -380.064319) (xy 300.184548 -380.110207) (xy 300.148827 -380.15143) (xy 300.107603 -380.18715)
			(xy 300.061716 -380.21664) (xy 300.012098 -380.239299) (xy 299.959761 -380.254666) (xy 299.905769 -380.262429)
			(xy 299.878496 -380.262892) (xy 299.014896 -380.262892) (xy 298.987629 -380.262345) (xy 298.93365 -380.254584)
			(xy 298.881325 -380.239219) (xy 298.831719 -380.216565) (xy 298.785842 -380.187081) (xy 298.744629 -380.151369)
			(xy 298.708917 -380.110154) (xy 298.679433 -380.064277) (xy 298.656779 -380.014671) (xy 298.641415 -379.962346)
			(xy 298.633654 -379.908367) (xy 179.577684 -379.908367) (xy 179.500651 -379.955161) (xy 179.344302 -380.040842)
			(xy 179.184291 -380.119474) (xy 179.020937 -380.1909) (xy 178.854562 -380.254978) (xy 178.685499 -380.31158)
			(xy 178.514082 -380.360596) (xy 178.340651 -380.401926) (xy 178.165551 -380.43549) (xy 177.989131 -380.46122)
			(xy 177.811739 -380.479066) (xy 177.633728 -380.488992) (xy 177.455451 -380.490978) (xy 177.277264 -380.485021)
			(xy 177.099518 -380.471131) (xy 176.922568 -380.449338) (xy 176.746764 -380.419684) (xy 176.572456 -380.382227)
			(xy 176.399989 -380.337043) (xy 176.229706 -380.284221) (xy 176.061945 -380.223865) (xy 175.89704 -380.156097)
			(xy 175.735317 -380.081049) (xy 175.577098 -379.998872) (xy 175.422697 -379.909729) (xy 175.27242 -379.813795)
			(xy 175.126565 -379.711263) (xy 174.985423 -379.602335) (xy 174.849274 -379.487228) (xy 174.718387 -379.36617)
			(xy 174.593023 -379.239401) (xy 174.47343 -379.107174) (xy 174.359847 -378.969751) (xy 174.252498 -378.827404)
			(xy 174.151597 -378.680416) (xy 174.057344 -378.52908) (xy 173.969926 -378.373695) (xy 173.889516 -378.21457)
			(xy 173.816275 -378.052021) (xy 173.750348 -377.886371) (xy 173.691865 -377.717949) (xy 173.640943 -377.547088)
			(xy 173.597683 -377.374129) (xy 173.562171 -377.199414) (xy 173.534477 -377.02329) (xy 173.514656 -376.846108)
			(xy 173.502748 -376.668219) (xy 173.498776 -376.489976) (xy 171.286932 -376.489976) (xy 171.286932 -376.956828)
			(xy 171.286446 -376.984079) (xy 171.27869 -377.038027) (xy 171.263335 -377.090322) (xy 171.240693 -377.139899)
			(xy 171.211227 -377.185749) (xy 171.175536 -377.22694) (xy 171.134345 -377.262631) (xy 171.088495 -377.292097)
			(xy 171.038918 -377.314739) (xy 170.986623 -377.330094) (xy 170.932675 -377.33785) (xy 170.878173 -377.33785)
			(xy 170.824225 -377.330094) (xy 170.77193 -377.314739) (xy 170.722353 -377.292097) (xy 170.676503 -377.262631)
			(xy 170.635312 -377.22694) (xy 170.599621 -377.185749) (xy 170.570155 -377.139899) (xy 170.547513 -377.090322)
			(xy 170.532158 -377.038027) (xy 170.524402 -376.984079) (xy 170.523916 -376.956828) (xy 141.418806 -376.956828)
			(xy 141.416303 -376.965354) (xy 141.393661 -377.014931) (xy 141.364195 -377.060781) (xy 141.328504 -377.101972)
			(xy 141.287313 -377.137663) (xy 141.241463 -377.167129) (xy 141.191886 -377.189771) (xy 141.139591 -377.205126)
			(xy 141.085643 -377.212882) (xy 141.031141 -377.212882) (xy 140.977193 -377.205126) (xy 140.924898 -377.189771)
			(xy 140.875321 -377.167129) (xy 140.829471 -377.137663) (xy 140.78828 -377.101972) (xy 140.752589 -377.060781)
			(xy 140.723123 -377.014931) (xy 140.700481 -376.965354) (xy 140.685126 -376.913059) (xy 140.67737 -376.859111)
			(xy 140.676884 -376.83186) (xy 138.759184 -376.83186) (xy 138.759184 -376.956828) (xy 138.758698 -376.984079)
			(xy 138.750942 -377.038027) (xy 138.735587 -377.090322) (xy 138.712945 -377.139899) (xy 138.683479 -377.185749)
			(xy 138.647788 -377.22694) (xy 138.606597 -377.262631) (xy 138.560747 -377.292097) (xy 138.51117 -377.314739)
			(xy 138.458875 -377.330094) (xy 138.404927 -377.33785) (xy 138.350425 -377.33785) (xy 138.296477 -377.330094)
			(xy 138.244182 -377.314739) (xy 138.194605 -377.292097) (xy 138.148755 -377.262631) (xy 138.107564 -377.22694)
			(xy 138.071873 -377.185749) (xy 138.042407 -377.139899) (xy 138.019765 -377.090322) (xy 138.00441 -377.038027)
			(xy 137.996654 -376.984079) (xy 137.996168 -376.956828) (xy 108.891058 -376.956828) (xy 108.888555 -376.965354)
			(xy 108.865913 -377.014931) (xy 108.836447 -377.060781) (xy 108.800756 -377.101972) (xy 108.759565 -377.137663)
			(xy 108.713715 -377.167129) (xy 108.664138 -377.189771) (xy 108.611843 -377.205126) (xy 108.557895 -377.212882)
			(xy 108.503393 -377.212882) (xy 108.449445 -377.205126) (xy 108.39715 -377.189771) (xy 108.347573 -377.167129)
			(xy 108.301723 -377.137663) (xy 108.260532 -377.101972) (xy 108.224841 -377.060781) (xy 108.195375 -377.014931)
			(xy 108.172733 -376.965354) (xy 108.157378 -376.913059) (xy 108.149622 -376.859111) (xy 108.149136 -376.83186)
			(xy 104.187244 -376.83186) (xy 104.187244 -376.956828) (xy 104.186758 -376.984097) (xy 104.178996 -377.038081)
			(xy 104.163631 -377.090411) (xy 104.140974 -377.140021) (xy 104.111488 -377.185902) (xy 104.075773 -377.227119)
			(xy 104.034556 -377.262834) (xy 103.988675 -377.29232) (xy 103.939065 -377.314977) (xy 103.886735 -377.330342)
			(xy 103.832751 -377.338104) (xy 103.778213 -377.338104) (xy 103.724229 -377.330342) (xy 103.671899 -377.314977)
			(xy 103.622289 -377.29232) (xy 103.576408 -377.262834) (xy 103.535191 -377.227119) (xy 103.499476 -377.185902)
			(xy 103.46999 -377.140021) (xy 103.447333 -377.090411) (xy 103.431968 -377.038081) (xy 103.424206 -376.984097)
			(xy 103.42372 -376.956828) (xy 74.319129 -376.956828) (xy 74.316599 -376.965443) (xy 74.293942 -377.015053)
			(xy 74.264456 -377.060934) (xy 74.228741 -377.102151) (xy 74.187524 -377.137866) (xy 74.141643 -377.167352)
			(xy 74.092033 -377.190009) (xy 74.039703 -377.205374) (xy 73.985719 -377.213136) (xy 73.931181 -377.213136)
			(xy 73.877197 -377.205374) (xy 73.824867 -377.190009) (xy 73.775257 -377.167352) (xy 73.729376 -377.137866)
			(xy 73.688159 -377.102151) (xy 73.652444 -377.060934) (xy 73.622958 -377.015053) (xy 73.600301 -376.965443)
			(xy 73.584936 -376.913113) (xy 73.577174 -376.859129) (xy 73.576688 -376.83186) (xy 71.659496 -376.83186)
			(xy 71.659496 -376.956828) (xy 71.65901 -376.984097) (xy 71.651248 -377.038081) (xy 71.635883 -377.090411)
			(xy 71.613226 -377.140021) (xy 71.58374 -377.185902) (xy 71.548025 -377.227119) (xy 71.506808 -377.262834)
			(xy 71.460927 -377.29232) (xy 71.411317 -377.314977) (xy 71.358987 -377.330342) (xy 71.305003 -377.338104)
			(xy 71.250465 -377.338104) (xy 71.196481 -377.330342) (xy 71.144151 -377.314977) (xy 71.094541 -377.29232)
			(xy 71.04866 -377.262834) (xy 71.007443 -377.227119) (xy 70.971728 -377.185902) (xy 70.942242 -377.140021)
			(xy 70.919585 -377.090411) (xy 70.90422 -377.038081) (xy 70.896458 -376.984097) (xy 70.895972 -376.956828)
			(xy 41.791381 -376.956828) (xy 41.788851 -376.965443) (xy 41.766194 -377.015053) (xy 41.736708 -377.060934)
			(xy 41.700993 -377.102151) (xy 41.659776 -377.137866) (xy 41.613895 -377.167352) (xy 41.564285 -377.190009)
			(xy 41.511955 -377.205374) (xy 41.457971 -377.213136) (xy 41.403433 -377.213136) (xy 41.349449 -377.205374)
			(xy 41.297119 -377.190009) (xy 41.247509 -377.167352) (xy 41.201628 -377.137866) (xy 41.160411 -377.102151)
			(xy 41.124696 -377.060934) (xy 41.09521 -377.015053) (xy 41.072553 -376.965443) (xy 41.057188 -376.913113)
			(xy 41.049426 -376.859129) (xy 41.04894 -376.83186) (xy 39.05568 -376.83186) (xy 39.046481 -376.93481)
			(xy 39.022717 -377.111506) (xy 38.991106 -377.286969) (xy 38.95171 -377.460849) (xy 38.904608 -377.632802)
			(xy 38.849892 -377.802486) (xy 38.787671 -377.969563) (xy 38.71807 -378.133704) (xy 38.641225 -378.29458)
			(xy 38.557291 -378.451874) (xy 38.466433 -378.605273) (xy 38.368831 -378.754472) (xy 38.26468 -378.899175)
			(xy 38.154187 -379.039095) (xy 38.03757 -379.173954) (xy 37.915061 -379.303484) (xy 37.786904 -379.427428)
			(xy 37.653353 -379.54554) (xy 37.514673 -379.657585) (xy 37.371139 -379.763342) (xy 37.223036 -379.862599)
			(xy 37.070659 -379.955161) (xy 36.91431 -380.040842) (xy 36.754299 -380.119474) (xy 36.590945 -380.1909)
			(xy 36.42457 -380.254978) (xy 36.255507 -380.31158) (xy 36.084678 -380.360428) (xy 70.895972 -380.360428)
			(xy 70.895972 -379.496828) (xy 70.896458 -379.469559) (xy 70.90422 -379.415575) (xy 70.919585 -379.363245)
			(xy 70.942242 -379.313635) (xy 70.971728 -379.267754) (xy 71.007443 -379.226537) (xy 71.04866 -379.190822)
			(xy 71.094541 -379.161336) (xy 71.144151 -379.138679) (xy 71.196481 -379.123314) (xy 71.250465 -379.115552)
			(xy 71.305003 -379.115552) (xy 71.358987 -379.123314) (xy 71.411317 -379.138679) (xy 71.460927 -379.161336)
			(xy 71.506808 -379.190822) (xy 71.548025 -379.226537) (xy 71.58374 -379.267754) (xy 71.613226 -379.313635)
			(xy 71.635883 -379.363245) (xy 71.651248 -379.415575) (xy 71.65901 -379.469559) (xy 71.659496 -379.496828)
			(xy 71.659496 -380.360428) (xy 103.42372 -380.360428) (xy 103.42372 -379.496828) (xy 103.424206 -379.469559)
			(xy 103.431968 -379.415575) (xy 103.447333 -379.363245) (xy 103.46999 -379.313635) (xy 103.499476 -379.267754)
			(xy 103.535191 -379.226537) (xy 103.576408 -379.190822) (xy 103.622289 -379.161336) (xy 103.671899 -379.138679)
			(xy 103.724229 -379.123314) (xy 103.778213 -379.115552) (xy 103.832751 -379.115552) (xy 103.886735 -379.123314)
			(xy 103.939065 -379.138679) (xy 103.988675 -379.161336) (xy 104.034556 -379.190822) (xy 104.075773 -379.226537)
			(xy 104.111488 -379.267754) (xy 104.140974 -379.313635) (xy 104.163631 -379.363245) (xy 104.178996 -379.415575)
			(xy 104.186758 -379.469559) (xy 104.187244 -379.496828) (xy 104.187244 -380.360428) (xy 137.996168 -380.360428)
			(xy 137.996168 -379.496828) (xy 137.996654 -379.469577) (xy 138.00441 -379.415629) (xy 138.019765 -379.363334)
			(xy 138.042407 -379.313757) (xy 138.071873 -379.267907) (xy 138.107564 -379.226716) (xy 138.148755 -379.191025)
			(xy 138.194605 -379.161559) (xy 138.244182 -379.138917) (xy 138.296477 -379.123562) (xy 138.350425 -379.115806)
			(xy 138.404927 -379.115806) (xy 138.458875 -379.123562) (xy 138.51117 -379.138917) (xy 138.560747 -379.161559)
			(xy 138.606597 -379.191025) (xy 138.647788 -379.226716) (xy 138.683479 -379.267907) (xy 138.712945 -379.313757)
			(xy 138.735587 -379.363334) (xy 138.750942 -379.415629) (xy 138.758698 -379.469577) (xy 138.759184 -379.496828)
			(xy 138.759184 -380.360428) (xy 170.523916 -380.360428) (xy 170.523916 -379.496828) (xy 170.524402 -379.469577)
			(xy 170.532158 -379.415629) (xy 170.547513 -379.363334) (xy 170.570155 -379.313757) (xy 170.599621 -379.267907)
			(xy 170.635312 -379.226716) (xy 170.676503 -379.191025) (xy 170.722353 -379.161559) (xy 170.77193 -379.138917)
			(xy 170.824225 -379.123562) (xy 170.878173 -379.115806) (xy 170.932675 -379.115806) (xy 170.986623 -379.123562)
			(xy 171.038918 -379.138917) (xy 171.088495 -379.161559) (xy 171.134345 -379.191025) (xy 171.175536 -379.226716)
			(xy 171.211227 -379.267907) (xy 171.240693 -379.313757) (xy 171.263335 -379.363334) (xy 171.27869 -379.415629)
			(xy 171.286446 -379.469577) (xy 171.286932 -379.496828) (xy 171.286932 -380.360428) (xy 171.286446 -380.387679)
			(xy 171.27869 -380.441627) (xy 171.263335 -380.493922) (xy 171.240693 -380.543499) (xy 171.211227 -380.589349)
			(xy 171.175536 -380.63054) (xy 171.134345 -380.666231) (xy 171.088495 -380.695697) (xy 171.038918 -380.718339)
			(xy 170.986623 -380.733694) (xy 170.932675 -380.74145) (xy 170.878173 -380.74145) (xy 170.824225 -380.733694)
			(xy 170.77193 -380.718339) (xy 170.722353 -380.695697) (xy 170.676503 -380.666231) (xy 170.635312 -380.63054)
			(xy 170.599621 -380.589349) (xy 170.570155 -380.543499) (xy 170.547513 -380.493922) (xy 170.532158 -380.441627)
			(xy 170.524402 -380.387679) (xy 170.523916 -380.360428) (xy 138.759184 -380.360428) (xy 138.758698 -380.387679)
			(xy 138.750942 -380.441627) (xy 138.735587 -380.493922) (xy 138.712945 -380.543499) (xy 138.683479 -380.589349)
			(xy 138.647788 -380.63054) (xy 138.606597 -380.666231) (xy 138.560747 -380.695697) (xy 138.51117 -380.718339)
			(xy 138.458875 -380.733694) (xy 138.404927 -380.74145) (xy 138.350425 -380.74145) (xy 138.296477 -380.733694)
			(xy 138.244182 -380.718339) (xy 138.194605 -380.695697) (xy 138.148755 -380.666231) (xy 138.107564 -380.63054)
			(xy 138.071873 -380.589349) (xy 138.042407 -380.543499) (xy 138.019765 -380.493922) (xy 138.00441 -380.441627)
			(xy 137.996654 -380.387679) (xy 137.996168 -380.360428) (xy 104.187244 -380.360428) (xy 104.186758 -380.387697)
			(xy 104.178996 -380.441681) (xy 104.163631 -380.494011) (xy 104.140974 -380.543621) (xy 104.111488 -380.589502)
			(xy 104.075773 -380.630719) (xy 104.034556 -380.666434) (xy 103.988675 -380.69592) (xy 103.939065 -380.718577)
			(xy 103.886735 -380.733942) (xy 103.832751 -380.741704) (xy 103.778213 -380.741704) (xy 103.724229 -380.733942)
			(xy 103.671899 -380.718577) (xy 103.622289 -380.69592) (xy 103.576408 -380.666434) (xy 103.535191 -380.630719)
			(xy 103.499476 -380.589502) (xy 103.46999 -380.543621) (xy 103.447333 -380.494011) (xy 103.431968 -380.441681)
			(xy 103.424206 -380.387697) (xy 103.42372 -380.360428) (xy 71.659496 -380.360428) (xy 71.65901 -380.387697)
			(xy 71.651248 -380.441681) (xy 71.635883 -380.494011) (xy 71.613226 -380.543621) (xy 71.58374 -380.589502)
			(xy 71.548025 -380.630719) (xy 71.506808 -380.666434) (xy 71.460927 -380.69592) (xy 71.411317 -380.718577)
			(xy 71.358987 -380.733942) (xy 71.305003 -380.741704) (xy 71.250465 -380.741704) (xy 71.196481 -380.733942)
			(xy 71.144151 -380.718577) (xy 71.094541 -380.69592) (xy 71.04866 -380.666434) (xy 71.007443 -380.630719)
			(xy 70.971728 -380.589502) (xy 70.942242 -380.543621) (xy 70.919585 -380.494011) (xy 70.90422 -380.441681)
			(xy 70.896458 -380.387697) (xy 70.895972 -380.360428) (xy 36.084678 -380.360428) (xy 36.08409 -380.360596)
			(xy 35.910659 -380.401926) (xy 35.735559 -380.43549) (xy 35.559139 -380.46122) (xy 35.381747 -380.479066)
			(xy 35.203736 -380.488992) (xy 35.025459 -380.490978) (xy 34.847272 -380.485021) (xy 34.669526 -380.471131)
			(xy 34.492576 -380.449338) (xy 34.316772 -380.419684) (xy 34.142464 -380.382227) (xy 33.969997 -380.337043)
			(xy 33.799714 -380.284221) (xy 33.631953 -380.223865) (xy 33.467048 -380.156097) (xy 33.305325 -380.081049)
			(xy 33.147106 -379.998872) (xy 32.992705 -379.909729) (xy 32.842428 -379.813795) (xy 32.696573 -379.711263)
			(xy 32.555431 -379.602335) (xy 32.419282 -379.487228) (xy 32.288395 -379.36617) (xy 32.163031 -379.239401)
			(xy 32.043438 -379.107174) (xy 31.929855 -378.969751) (xy 31.822506 -378.827404) (xy 31.721605 -378.680416)
			(xy 31.627352 -378.52908) (xy 31.539934 -378.373695) (xy 31.459524 -378.21457) (xy 31.386283 -378.052021)
			(xy 31.320356 -377.886371) (xy 31.261873 -377.717949) (xy 31.210951 -377.547088) (xy 31.167691 -377.374129)
			(xy 31.132179 -377.199414) (xy 31.104485 -377.02329) (xy 31.084664 -376.846108) (xy 31.072756 -376.668219)
			(xy 31.068784 -376.489976) (xy 2.509012 -376.489976) (xy 2.509012 -382.36906) (xy 41.04894 -382.36906)
			(xy 41.04894 -381.50546) (xy 41.049426 -381.478191) (xy 41.057188 -381.424207) (xy 41.072553 -381.371877)
			(xy 41.09521 -381.322267) (xy 41.124696 -381.276386) (xy 41.160411 -381.235169) (xy 41.201628 -381.199454)
			(xy 41.247509 -381.169968) (xy 41.297119 -381.147311) (xy 41.349449 -381.131946) (xy 41.403433 -381.124184)
			(xy 41.457971 -381.124184) (xy 41.511955 -381.131946) (xy 41.564285 -381.147311) (xy 41.613895 -381.169968)
			(xy 41.659776 -381.199454) (xy 41.700993 -381.235169) (xy 41.736708 -381.276386) (xy 41.766194 -381.322267)
			(xy 41.788851 -381.371877) (xy 41.804216 -381.424207) (xy 41.811978 -381.478191) (xy 41.812464 -381.50546)
			(xy 41.812464 -382.36906) (xy 73.576688 -382.36906) (xy 73.576688 -381.50546) (xy 73.577174 -381.478191)
			(xy 73.584936 -381.424207) (xy 73.600301 -381.371877) (xy 73.622958 -381.322267) (xy 73.652444 -381.276386)
			(xy 73.688159 -381.235169) (xy 73.729376 -381.199454) (xy 73.775257 -381.169968) (xy 73.824867 -381.147311)
			(xy 73.877197 -381.131946) (xy 73.931181 -381.124184) (xy 73.985719 -381.124184) (xy 74.039703 -381.131946)
			(xy 74.092033 -381.147311) (xy 74.141643 -381.169968) (xy 74.187524 -381.199454) (xy 74.228741 -381.235169)
			(xy 74.264456 -381.276386) (xy 74.293942 -381.322267) (xy 74.316599 -381.371877) (xy 74.331964 -381.424207)
			(xy 74.339726 -381.478191) (xy 74.340212 -381.50546) (xy 74.340212 -382.36906) (xy 108.149136 -382.36906)
			(xy 108.149136 -381.50546) (xy 108.149622 -381.478209) (xy 108.157378 -381.424261) (xy 108.172733 -381.371966)
			(xy 108.195375 -381.322389) (xy 108.224841 -381.276539) (xy 108.260532 -381.235348) (xy 108.301723 -381.199657)
			(xy 108.347573 -381.170191) (xy 108.39715 -381.147549) (xy 108.449445 -381.132194) (xy 108.503393 -381.124438)
			(xy 108.557895 -381.124438) (xy 108.611843 -381.132194) (xy 108.664138 -381.147549) (xy 108.713715 -381.170191)
			(xy 108.759565 -381.199657) (xy 108.800756 -381.235348) (xy 108.836447 -381.276539) (xy 108.865913 -381.322389)
			(xy 108.888555 -381.371966) (xy 108.90391 -381.424261) (xy 108.911666 -381.478209) (xy 108.912152 -381.50546)
			(xy 108.912152 -382.36906) (xy 140.676884 -382.36906) (xy 140.676884 -381.50546) (xy 140.67737 -381.478209)
			(xy 140.685126 -381.424261) (xy 140.700481 -381.371966) (xy 140.723123 -381.322389) (xy 140.752589 -381.276539)
			(xy 140.78828 -381.235348) (xy 140.829471 -381.199657) (xy 140.875321 -381.170191) (xy 140.924898 -381.147549)
			(xy 140.977193 -381.132194) (xy 141.031141 -381.124438) (xy 141.085643 -381.124438) (xy 141.139591 -381.132194)
			(xy 141.191886 -381.147549) (xy 141.241463 -381.170191) (xy 141.287313 -381.199657) (xy 141.328504 -381.235348)
			(xy 141.364195 -381.276539) (xy 141.393661 -381.322389) (xy 141.416303 -381.371966) (xy 141.431658 -381.424261)
			(xy 141.439414 -381.478209) (xy 141.4399 -381.50546) (xy 141.4399 -382.36906) (xy 141.439414 -382.396311)
			(xy 141.431658 -382.450259) (xy 141.416303 -382.502554) (xy 141.393661 -382.552131) (xy 141.364195 -382.597981)
			(xy 141.328504 -382.639172) (xy 141.287313 -382.674863) (xy 141.241463 -382.704329) (xy 141.191886 -382.726971)
			(xy 141.139591 -382.742326) (xy 141.085643 -382.750082) (xy 141.031141 -382.750082) (xy 140.977193 -382.742326)
			(xy 140.924898 -382.726971) (xy 140.875321 -382.704329) (xy 140.829471 -382.674863) (xy 140.78828 -382.639172)
			(xy 140.752589 -382.597981) (xy 140.723123 -382.552131) (xy 140.700481 -382.502554) (xy 140.685126 -382.450259)
			(xy 140.67737 -382.396311) (xy 140.676884 -382.36906) (xy 108.912152 -382.36906) (xy 108.911666 -382.396311)
			(xy 108.90391 -382.450259) (xy 108.888555 -382.502554) (xy 108.865913 -382.552131) (xy 108.836447 -382.597981)
			(xy 108.800756 -382.639172) (xy 108.759565 -382.674863) (xy 108.713715 -382.704329) (xy 108.664138 -382.726971)
			(xy 108.611843 -382.742326) (xy 108.557895 -382.750082) (xy 108.503393 -382.750082) (xy 108.449445 -382.742326)
			(xy 108.39715 -382.726971) (xy 108.347573 -382.704329) (xy 108.301723 -382.674863) (xy 108.260532 -382.639172)
			(xy 108.224841 -382.597981) (xy 108.195375 -382.552131) (xy 108.172733 -382.502554) (xy 108.157378 -382.450259)
			(xy 108.149622 -382.396311) (xy 108.149136 -382.36906) (xy 74.340212 -382.36906) (xy 74.339726 -382.396329)
			(xy 74.331964 -382.450313) (xy 74.316599 -382.502643) (xy 74.293942 -382.552253) (xy 74.264456 -382.598134)
			(xy 74.228741 -382.639351) (xy 74.187524 -382.675066) (xy 74.141643 -382.704552) (xy 74.092033 -382.727209)
			(xy 74.039703 -382.742574) (xy 73.985719 -382.750336) (xy 73.931181 -382.750336) (xy 73.877197 -382.742574)
			(xy 73.824867 -382.727209) (xy 73.775257 -382.704552) (xy 73.729376 -382.675066) (xy 73.688159 -382.639351)
			(xy 73.652444 -382.598134) (xy 73.622958 -382.552253) (xy 73.600301 -382.502643) (xy 73.584936 -382.450313)
			(xy 73.577174 -382.396329) (xy 73.576688 -382.36906) (xy 41.812464 -382.36906) (xy 41.811978 -382.396329)
			(xy 41.804216 -382.450313) (xy 41.788851 -382.502643) (xy 41.766194 -382.552253) (xy 41.736708 -382.598134)
			(xy 41.700993 -382.639351) (xy 41.659776 -382.675066) (xy 41.613895 -382.704552) (xy 41.564285 -382.727209)
			(xy 41.511955 -382.742574) (xy 41.457971 -382.750336) (xy 41.403433 -382.750336) (xy 41.349449 -382.742574)
			(xy 41.297119 -382.727209) (xy 41.247509 -382.704552) (xy 41.201628 -382.675066) (xy 41.160411 -382.639351)
			(xy 41.124696 -382.598134) (xy 41.09521 -382.552253) (xy 41.072553 -382.502643) (xy 41.057188 -382.450313)
			(xy 41.049426 -382.396329) (xy 41.04894 -382.36906) (xy 2.509012 -382.36906) (xy 2.509012 -385.310888)
			(xy 47.485808 -385.310888) (xy 47.485808 -385.31038) (xy 47.486221 -385.286373) (xy 47.493739 -385.238951)
			(xy 47.508587 -385.19329) (xy 47.530398 -385.150515) (xy 47.558635 -385.111682) (xy 47.592603 -385.077747)
			(xy 47.631463 -385.049546) (xy 47.674258 -385.027775) (xy 47.719933 -385.012971) (xy 47.767362 -385.005498)
			(xy 47.79137 -385.005072) (xy 47.815305 -385.005523) (xy 47.862591 -385.012984) (xy 47.908134 -385.027728)
			(xy 47.950821 -385.049394) (xy 47.989606 -385.077452) (xy 48.023541 -385.111216) (xy 48.051795 -385.149858)
			(xy 48.06315 -385.170934) (xy 48.063658 -385.17195) (xy 48.143964 -385.310888) (xy 48.685704 -385.310888)
			(xy 48.685704 -385.31038) (xy 48.686121 -385.286373) (xy 48.693639 -385.238951) (xy 48.708486 -385.193291)
			(xy 48.730297 -385.150516) (xy 48.758534 -385.111683) (xy 48.792501 -385.077748) (xy 48.831361 -385.049548)
			(xy 48.874155 -385.027777) (xy 48.91983 -385.012972) (xy 48.967259 -385.005498) (xy 48.991266 -385.005072)
			(xy 49.015201 -385.005526) (xy 49.062486 -385.012986) (xy 49.10803 -385.02773) (xy 49.150716 -385.049395)
			(xy 49.189502 -385.077453) (xy 49.223437 -385.111216) (xy 49.251691 -385.149859) (xy 49.263046 -385.170934)
			(xy 49.263554 -385.17195) (xy 49.34386 -385.310888) (xy 49.8856 -385.310888) (xy 49.8856 -385.31038)
			(xy 49.886021 -385.286373) (xy 49.893539 -385.238952) (xy 49.908386 -385.193291) (xy 49.930196 -385.150518)
			(xy 49.958433 -385.111685) (xy 49.992399 -385.07775) (xy 50.031259 -385.049549) (xy 50.074052 -385.027778)
			(xy 50.119727 -385.012973) (xy 50.167155 -385.005499) (xy 50.191162 -385.005072) (xy 50.215097 -385.005529)
			(xy 50.262382 -385.012989) (xy 50.307925 -385.027732) (xy 50.350612 -385.049397) (xy 50.389397 -385.077454)
			(xy 50.423333 -385.111217) (xy 50.451587 -385.149859) (xy 50.462942 -385.170934) (xy 50.46345 -385.17195)
			(xy 50.543756 -385.310888) (xy 51.086004 -385.310888) (xy 51.086004 -385.31038) (xy 51.086444 -385.286388)
			(xy 51.093954 -385.238994) (xy 51.108785 -385.193359) (xy 51.130572 -385.150605) (xy 51.158779 -385.111786)
			(xy 51.192711 -385.077858) (xy 51.231533 -385.049655) (xy 51.274288 -385.027872) (xy 51.319925 -385.013046)
			(xy 51.36732 -385.005542) (xy 51.391312 -385.005072) (xy 51.415246 -385.00557) (xy 51.462529 -385.013022)
			(xy 51.508071 -385.027757) (xy 51.550758 -385.049416) (xy 51.589544 -385.077467) (xy 51.62348 -385.111224)
			(xy 51.651736 -385.149861) (xy 51.663092 -385.170934) (xy 51.6636 -385.17195) (xy 51.743906 -385.310888)
			(xy 52.2859 -385.310888) (xy 52.2859 -385.31038) (xy 52.286344 -385.286388) (xy 52.293854 -385.238995)
			(xy 52.308684 -385.19336) (xy 52.330471 -385.150606) (xy 52.358677 -385.111788) (xy 52.392609 -385.077859)
			(xy 52.43143 -385.049656) (xy 52.474186 -385.027873) (xy 52.519822 -385.013047) (xy 52.567216 -385.005542)
			(xy 52.591208 -385.005072) (xy 52.615141 -385.005573) (xy 52.662424 -385.013024) (xy 52.707967 -385.027759)
			(xy 52.750653 -385.049417) (xy 52.789439 -385.077468) (xy 52.823376 -385.111224) (xy 52.851632 -385.149861)
			(xy 52.862988 -385.170934) (xy 52.863496 -385.17195) (xy 52.943802 -385.310888) (xy 53.485796 -385.310888)
			(xy 53.485796 -385.31038) (xy 53.486221 -385.286373) (xy 53.493738 -385.238952) (xy 53.508585 -385.193292)
			(xy 53.530396 -385.150519) (xy 53.558632 -385.111686) (xy 53.592598 -385.077751) (xy 53.631456 -385.04955)
			(xy 53.67425 -385.027779) (xy 53.719923 -385.012973) (xy 53.767351 -385.005499) (xy 53.791358 -385.005072)
			(xy 53.815293 -385.005532) (xy 53.862578 -385.012992) (xy 53.908121 -385.027734) (xy 53.950807 -385.049398)
			(xy 53.989593 -385.077455) (xy 54.023528 -385.111217) (xy 54.051783 -385.149859) (xy 54.063138 -385.170934)
			(xy 54.063646 -385.17195) (xy 54.143952 -385.310888) (xy 54.685692 -385.310888) (xy 54.685692 -385.31038)
			(xy 54.686121 -385.286374) (xy 54.693638 -385.238953) (xy 54.708485 -385.193293) (xy 54.730295 -385.15052)
			(xy 54.758531 -385.111687) (xy 54.792496 -385.077752) (xy 54.831354 -385.049552) (xy 54.874147 -385.02778)
			(xy 54.91982 -385.012974) (xy 54.967247 -385.005499) (xy 54.991254 -385.005072) (xy 55.015189 -385.005536)
			(xy 55.062474 -385.012994) (xy 55.108017 -385.027736) (xy 55.150703 -385.0494) (xy 55.189489 -385.077456)
			(xy 55.223424 -385.111218) (xy 55.251679 -385.149859) (xy 55.263034 -385.170934) (xy 55.263542 -385.17195)
			(xy 55.343848 -385.310888) (xy 55.885588 -385.310888) (xy 55.885588 -385.31038) (xy 55.886021 -385.286374)
			(xy 55.893538 -385.238954) (xy 55.908385 -385.193294) (xy 55.930194 -385.150521) (xy 55.95843 -385.111689)
			(xy 55.992394 -385.077754) (xy 56.031252 -385.049553) (xy 56.074044 -385.027781) (xy 56.119717 -385.012975)
			(xy 56.167143 -385.0055) (xy 56.19115 -385.005072) (xy 56.215085 -385.005539) (xy 56.262369 -385.012997)
			(xy 56.307912 -385.027738) (xy 56.350599 -385.049401) (xy 56.389384 -385.077457) (xy 56.42332 -385.111218)
			(xy 56.451575 -385.149859) (xy 56.46293 -385.170934) (xy 56.463438 -385.17195) (xy 56.543744 -385.310888)
			(xy 57.085992 -385.310888) (xy 57.085992 -385.31038) (xy 57.086444 -385.286388) (xy 57.093953 -385.238996)
			(xy 57.108783 -385.193362) (xy 57.130569 -385.150609) (xy 57.158775 -385.11179) (xy 57.192706 -385.077862)
			(xy 57.231526 -385.049659) (xy 57.27428 -385.027876) (xy 57.319915 -385.013049) (xy 57.367308 -385.005543)
			(xy 57.3913 -385.005072) (xy 57.391554 -385.005072) (xy 57.415489 -385.005536) (xy 57.462774 -385.012994)
			(xy 57.508317 -385.027736) (xy 57.551003 -385.0494) (xy 57.589789 -385.077456) (xy 57.623724 -385.111218)
			(xy 57.651979 -385.149859) (xy 57.663334 -385.170934) (xy 57.663842 -385.17195) (xy 57.744148 -385.310888)
			(xy 58.285888 -385.310888) (xy 58.285888 -385.31038) (xy 58.286344 -385.286388) (xy 58.293853 -385.238996)
			(xy 58.308683 -385.193362) (xy 58.330469 -385.15061) (xy 58.358674 -385.111792) (xy 58.392604 -385.077863)
			(xy 58.431424 -385.04966) (xy 58.474177 -385.027877) (xy 58.519812 -385.013049) (xy 58.567204 -385.005543)
			(xy 58.591196 -385.005072) (xy 58.59145 -385.005072) (xy 58.615385 -385.005539) (xy 58.662669 -385.012997)
			(xy 58.708212 -385.027738) (xy 58.750899 -385.049401) (xy 58.789684 -385.077457) (xy 58.82362 -385.111218)
			(xy 58.851875 -385.149859) (xy 58.86323 -385.170934) (xy 58.863738 -385.17195) (xy 58.944044 -385.310888)
			(xy 59.485784 -385.310888) (xy 59.485784 -385.31038) (xy 59.486221 -385.286374) (xy 59.493738 -385.238954)
			(xy 59.508584 -385.193295) (xy 59.530394 -385.150522) (xy 59.558628 -385.11169) (xy 59.592593 -385.077755)
			(xy 59.63145 -385.049554) (xy 59.674241 -385.027782) (xy 59.719913 -385.012976) (xy 59.76734 -385.0055)
			(xy 59.791346 -385.005072) (xy 59.7916 -385.005072) (xy 59.815533 -385.00558) (xy 59.862816 -385.01303)
			(xy 59.908358 -385.027764) (xy 59.951044 -385.04942) (xy 59.989831 -385.07747) (xy 60.023768 -385.111226)
			(xy 60.052024 -385.149862) (xy 60.06338 -385.170934) (xy 60.063888 -385.17195) (xy 60.144194 -385.310888)
			(xy 60.68568 -385.310888) (xy 60.68568 -385.31038) (xy 60.686121 -385.286374) (xy 60.693638 -385.238955)
			(xy 60.708484 -385.193296) (xy 60.730293 -385.150524) (xy 60.758527 -385.111692) (xy 60.792491 -385.077757)
			(xy 60.831347 -385.049556) (xy 60.874139 -385.027783) (xy 60.91981 -385.012977) (xy 60.967236 -385.0055)
			(xy 60.991242 -385.005072) (xy 60.991496 -385.005072) (xy 61.015432 -385.005502) (xy 61.062718 -385.012966)
			(xy 61.108262 -385.027714) (xy 61.150949 -385.049384) (xy 61.189734 -385.077445) (xy 61.223668 -385.111212)
			(xy 61.251922 -385.149857) (xy 61.263276 -385.170934) (xy 61.263784 -385.17195) (xy 61.34409 -385.310888)
			(xy 61.885576 -385.310888) (xy 61.885576 -385.31038) (xy 61.886021 -385.286374) (xy 61.893538 -385.238955)
			(xy 61.908383 -385.193297) (xy 61.930192 -385.150525) (xy 61.958426 -385.111693) (xy 61.992389 -385.077758)
			(xy 62.031245 -385.049557) (xy 62.074036 -385.027785) (xy 62.119707 -385.012977) (xy 62.167132 -385.0055)
			(xy 62.191138 -385.005072) (xy 62.191392 -385.005072) (xy 62.215328 -385.005505) (xy 62.262614 -385.012969)
			(xy 62.308158 -385.027716) (xy 62.350844 -385.049385) (xy 62.38963 -385.077446) (xy 62.423564 -385.111212)
			(xy 62.451818 -385.149857) (xy 62.463172 -385.170934) (xy 62.46368 -385.17195) (xy 62.543986 -385.310888)
			(xy 63.08598 -385.310888) (xy 63.08598 -385.31038) (xy 63.086444 -385.286389) (xy 63.093953 -385.238998)
			(xy 63.108782 -385.193364) (xy 63.130567 -385.150612) (xy 63.158771 -385.111795) (xy 63.192701 -385.077866)
			(xy 63.231519 -385.049663) (xy 63.274272 -385.027879) (xy 63.319905 -385.013051) (xy 63.367297 -385.005543)
			(xy 63.391288 -385.005072) (xy 63.391542 -385.005072) (xy 63.415476 -385.005545) (xy 63.462761 -385.013002)
			(xy 63.508303 -385.027742) (xy 63.55099 -385.049404) (xy 63.589776 -385.077459) (xy 63.623712 -385.11122)
			(xy 63.651967 -385.14986) (xy 63.663322 -385.170934) (xy 63.66383 -385.17195) (xy 63.744136 -385.310888)
			(xy 64.285876 -385.310888) (xy 64.285876 -385.31038) (xy 64.286344 -385.286389) (xy 64.293853 -385.238998)
			(xy 64.308682 -385.193365) (xy 64.330467 -385.150614) (xy 64.35867 -385.111796) (xy 64.392599 -385.077868)
			(xy 64.431417 -385.049664) (xy 64.474169 -385.02788) (xy 64.519802 -385.013052) (xy 64.567193 -385.005544)
			(xy 64.591184 -385.005072) (xy 64.591438 -385.005072) (xy 64.615372 -385.005549) (xy 64.662656 -385.013005)
			(xy 64.708199 -385.027744) (xy 64.750886 -385.049406) (xy 64.789672 -385.07746) (xy 64.823607 -385.11122)
			(xy 64.851863 -385.14986) (xy 64.863218 -385.170934) (xy 64.863726 -385.17195) (xy 64.944032 -385.310888)
			(xy 65.485772 -385.310888) (xy 65.485772 -385.31038) (xy 65.486221 -385.286375) (xy 65.493738 -385.238956)
			(xy 65.508583 -385.193298) (xy 65.530391 -385.150526) (xy 65.558625 -385.111694) (xy 65.592588 -385.07776)
			(xy 65.631443 -385.049558) (xy 65.674233 -385.027786) (xy 65.719903 -385.012978) (xy 65.767328 -385.005501)
			(xy 65.791334 -385.005072) (xy 65.791588 -385.005072) (xy 65.815524 -385.005508) (xy 65.86281 -385.012972)
			(xy 65.908353 -385.027718) (xy 65.95104 -385.049387) (xy 65.989825 -385.077447) (xy 66.02376 -385.111213)
			(xy 66.052014 -385.149858) (xy 66.063368 -385.170934) (xy 66.063876 -385.17195) (xy 66.144182 -385.310888)
			(xy 80.013556 -385.310888) (xy 80.013556 -385.31038) (xy 80.014021 -385.286375) (xy 80.021537 -385.238958)
			(xy 80.036382 -385.193302) (xy 80.058188 -385.150531) (xy 80.08642 -385.1117) (xy 80.120381 -385.077765)
			(xy 80.159234 -385.049564) (xy 80.202022 -385.02779) (xy 80.24769 -385.012981) (xy 80.295113 -385.005502)
			(xy 80.319118 -385.005072) (xy 80.343052 -385.005565) (xy 80.390335 -385.013018) (xy 80.435877 -385.027754)
			(xy 80.478564 -385.049413) (xy 80.51735 -385.077465) (xy 80.551287 -385.111223) (xy 80.579542 -385.149861)
			(xy 80.590898 -385.170934) (xy 80.591406 -385.17195) (xy 80.671712 -385.310888) (xy 81.213452 -385.310888)
			(xy 81.213452 -385.31038) (xy 81.213921 -385.286376) (xy 81.221437 -385.238959) (xy 81.236281 -385.193303)
			(xy 81.258088 -385.150532) (xy 81.286319 -385.111701) (xy 81.320279 -385.077767) (xy 81.359132 -385.049565)
			(xy 81.401919 -385.027792) (xy 81.447587 -385.012982) (xy 81.495009 -385.005502) (xy 81.519014 -385.005072)
			(xy 81.542948 -385.005568) (xy 81.590231 -385.013021) (xy 81.635773 -385.027756) (xy 81.67846 -385.049415)
			(xy 81.717246 -385.077466) (xy 81.751182 -385.111224) (xy 81.779438 -385.149861) (xy 81.790794 -385.170934)
			(xy 81.791302 -385.17195) (xy 81.871608 -385.310888) (xy 82.413348 -385.310888) (xy 82.413348 -385.31038)
			(xy 82.413821 -385.286376) (xy 82.421337 -385.238959) (xy 82.436181 -385.193304) (xy 82.457987 -385.150533)
			(xy 82.486218 -385.111702) (xy 82.520178 -385.077768) (xy 82.55903 -385.049567) (xy 82.601816 -385.027793)
			(xy 82.647483 -385.012983) (xy 82.694905 -385.005502) (xy 82.71891 -385.005072) (xy 82.742843 -385.005571)
			(xy 82.790127 -385.013023) (xy 82.835669 -385.027758) (xy 82.878355 -385.049416) (xy 82.917142 -385.077467)
			(xy 82.951078 -385.111224) (xy 82.979334 -385.149861) (xy 82.99069 -385.170934) (xy 82.991198 -385.17195)
			(xy 83.071504 -385.310888) (xy 83.613752 -385.310888) (xy 83.613752 -385.31038) (xy 83.614244 -385.28639)
			(xy 83.621752 -385.239002) (xy 83.63658 -385.193371) (xy 83.658362 -385.150621) (xy 83.686563 -385.111804)
			(xy 83.720489 -385.077876) (xy 83.759304 -385.049673) (xy 83.802052 -385.027887) (xy 83.847682 -385.013057)
			(xy 83.89507 -385.005546) (xy 83.91906 -385.005072) (xy 83.942995 -385.005531) (xy 83.99028 -385.01299)
			(xy 84.035823 -385.027733) (xy 84.07851 -385.049398) (xy 84.117295 -385.077455) (xy 84.151231 -385.111217)
			(xy 84.179485 -385.149859) (xy 84.19084 -385.170934) (xy 84.191348 -385.17195) (xy 84.271654 -385.310888)
			(xy 84.813648 -385.310888) (xy 84.813648 -385.31038) (xy 84.814144 -385.28639) (xy 84.821652 -385.239002)
			(xy 84.836479 -385.193372) (xy 84.858261 -385.150622) (xy 84.886462 -385.111805) (xy 84.920387 -385.077878)
			(xy 84.959201 -385.049674) (xy 85.001949 -385.027888) (xy 85.047579 -385.013057) (xy 85.094966 -385.005546)
			(xy 85.118956 -385.005072) (xy 85.142891 -385.005534) (xy 85.190176 -385.012993) (xy 85.235719 -385.027735)
			(xy 85.278405 -385.049399) (xy 85.317191 -385.077456) (xy 85.351126 -385.111218) (xy 85.379381 -385.149859)
			(xy 85.390736 -385.170934) (xy 85.391244 -385.17195) (xy 85.47155 -385.310888) (xy 86.013544 -385.310888)
			(xy 86.013544 -385.31038) (xy 86.01402 -385.286376) (xy 86.021537 -385.23896) (xy 86.03638 -385.193304)
			(xy 86.058186 -385.150534) (xy 86.086417 -385.111704) (xy 86.120376 -385.07777) (xy 86.159227 -385.049568)
			(xy 86.202014 -385.027794) (xy 86.24768 -385.012984) (xy 86.295102 -385.005503) (xy 86.319106 -385.005072)
			(xy 86.343039 -385.005575) (xy 86.390322 -385.013026) (xy 86.435864 -385.02776) (xy 86.478551 -385.049418)
			(xy 86.517337 -385.077468) (xy 86.551274 -385.111225) (xy 86.57953 -385.149861) (xy 86.590886 -385.170934)
			(xy 86.591394 -385.17195) (xy 86.6717 -385.310888) (xy 87.21344 -385.310888) (xy 87.21344 -385.31038)
			(xy 87.213821 -385.286371) (xy 87.22134 -385.238946) (xy 87.23619 -385.193282) (xy 87.258004 -385.150506)
			(xy 87.286245 -385.111671) (xy 87.320216 -385.077735) (xy 87.359081 -385.049535) (xy 87.40188 -385.027766)
			(xy 87.44756 -385.012965) (xy 87.494993 -385.005496) (xy 87.519002 -385.005072) (xy 87.542935 -385.005578)
			(xy 87.590218 -385.013028) (xy 87.63576 -385.027763) (xy 87.678447 -385.04942) (xy 87.717233 -385.077469)
			(xy 87.75117 -385.111225) (xy 87.779426 -385.149861) (xy 87.790782 -385.170934) (xy 87.79129 -385.17195)
			(xy 87.871596 -385.310888) (xy 88.413336 -385.310888) (xy 88.413336 -385.31038) (xy 88.413721 -385.286371)
			(xy 88.42124 -385.238947) (xy 88.436089 -385.193283) (xy 88.457903 -385.150507) (xy 88.486144 -385.111672)
			(xy 88.520115 -385.077737) (xy 88.558979 -385.049537) (xy 88.601777 -385.027767) (xy 88.647456 -385.012965)
			(xy 88.694889 -385.005496) (xy 88.718898 -385.005072) (xy 88.742834 -385.0055) (xy 88.790121 -385.012965)
			(xy 88.835664 -385.027713) (xy 88.878351 -385.049383) (xy 88.917136 -385.077445) (xy 88.95107 -385.111212)
			(xy 88.979324 -385.149857) (xy 88.990678 -385.170934) (xy 88.991186 -385.17195) (xy 89.071492 -385.310888)
			(xy 89.61374 -385.310888) (xy 89.61374 -385.31038) (xy 89.61412 -385.286384) (xy 89.621631 -385.238983)
			(xy 89.636465 -385.193341) (xy 89.658257 -385.150582) (xy 89.68647 -385.111758) (xy 89.72041 -385.077826)
			(xy 89.75924 -385.049622) (xy 89.802004 -385.027839) (xy 89.847649 -385.013015) (xy 89.895052 -385.005515)
			(xy 89.919048 -385.005072) (xy 89.942983 -385.005541) (xy 89.990267 -385.012998) (xy 90.03581 -385.027739)
			(xy 90.078497 -385.049402) (xy 90.117282 -385.077458) (xy 90.151218 -385.111219) (xy 90.179473 -385.149859)
			(xy 90.190828 -385.170934) (xy 90.191336 -385.17195) (xy 90.271642 -385.310888) (xy 90.813636 -385.310888)
			(xy 90.813636 -385.31038) (xy 90.81402 -385.286384) (xy 90.821531 -385.238984) (xy 90.836365 -385.193342)
			(xy 90.858157 -385.150583) (xy 90.886369 -385.111759) (xy 90.920308 -385.077828) (xy 90.959138 -385.049623)
			(xy 91.001901 -385.02784) (xy 91.047546 -385.013016) (xy 91.094948 -385.005515) (xy 91.118944 -385.005072)
			(xy 91.142878 -385.005544) (xy 91.190163 -385.013001) (xy 91.235706 -385.027741) (xy 91.278392 -385.049404)
			(xy 91.317178 -385.077459) (xy 91.351114 -385.111219) (xy 91.379369 -385.14986) (xy 91.390724 -385.170934)
			(xy 91.391232 -385.17195) (xy 91.471538 -385.310888) (xy 92.013532 -385.310888) (xy 92.013532 -385.31038)
			(xy 92.013921 -385.286372) (xy 92.02144 -385.238947) (xy 92.036289 -385.193284) (xy 92.058102 -385.150508)
			(xy 92.086342 -385.111674) (xy 92.120313 -385.077738) (xy 92.159176 -385.049538) (xy 92.201975 -385.027769)
			(xy 92.247653 -385.012966) (xy 92.295085 -385.005496) (xy 92.319094 -385.005072) (xy 92.34303 -385.005503)
			(xy 92.390316 -385.012968) (xy 92.43586 -385.027715) (xy 92.478547 -385.049385) (xy 92.517332 -385.077446)
			(xy 92.551266 -385.111212) (xy 92.57952 -385.149857) (xy 92.590874 -385.170934) (xy 92.591382 -385.17195)
			(xy 92.671688 -385.310888) (xy 93.213428 -385.310888) (xy 93.213428 -385.31038) (xy 93.213821 -385.286372)
			(xy 93.221339 -385.238948) (xy 93.236188 -385.193285) (xy 93.258002 -385.150509) (xy 93.286241 -385.111675)
			(xy 93.320211 -385.07774) (xy 93.359074 -385.049539) (xy 93.401872 -385.02777) (xy 93.44755 -385.012967)
			(xy 93.494981 -385.005497) (xy 93.51899 -385.005072) (xy 93.542926 -385.005506) (xy 93.590212 -385.01297)
			(xy 93.635756 -385.027717) (xy 93.678442 -385.049386) (xy 93.717227 -385.077447) (xy 93.751162 -385.111213)
			(xy 93.779416 -385.149857) (xy 93.79077 -385.170934) (xy 93.791278 -385.17195) (xy 93.871584 -385.310888)
			(xy 94.413324 -385.310888) (xy 94.413324 -385.31038) (xy 94.413721 -385.286372) (xy 94.421239 -385.238948)
			(xy 94.436088 -385.193286) (xy 94.457901 -385.15051) (xy 94.48614 -385.111676) (xy 94.520109 -385.077741)
			(xy 94.558972 -385.049541) (xy 94.601769 -385.027771) (xy 94.647446 -385.012968) (xy 94.694878 -385.005497)
			(xy 94.718886 -385.005072) (xy 94.742822 -385.00551) (xy 94.790108 -385.012973) (xy 94.835651 -385.027719)
			(xy 94.878338 -385.049388) (xy 94.917123 -385.077448) (xy 94.951058 -385.111213) (xy 94.979312 -385.149858)
			(xy 94.990666 -385.170934) (xy 94.991174 -385.17195) (xy 95.07148 -385.310888) (xy 95.613728 -385.310888)
			(xy 95.613728 -385.31038) (xy 95.61412 -385.286385) (xy 95.621631 -385.238985) (xy 95.636464 -385.193344)
			(xy 95.658255 -385.150585) (xy 95.686467 -385.111762) (xy 95.720405 -385.07783) (xy 95.759233 -385.049626)
			(xy 95.801996 -385.027843) (xy 95.847639 -385.013018) (xy 95.89504 -385.005515) (xy 95.919036 -385.005072)
			(xy 95.94297 -385.00555) (xy 95.990254 -385.013006) (xy 96.035797 -385.027745) (xy 96.078484 -385.049407)
			(xy 96.117269 -385.077461) (xy 96.151205 -385.11122) (xy 96.179461 -385.14986) (xy 96.190816 -385.170934)
			(xy 96.191324 -385.17195) (xy 96.27163 -385.310888) (xy 96.813624 -385.310888) (xy 96.813624 -385.31038)
			(xy 96.81402 -385.286385) (xy 96.821531 -385.238985) (xy 96.836364 -385.193345) (xy 96.858154 -385.150586)
			(xy 96.886366 -385.111764) (xy 96.920303 -385.077832) (xy 96.959131 -385.049627) (xy 97.001893 -385.027844)
			(xy 97.047536 -385.013018) (xy 97.094937 -385.005516) (xy 97.118932 -385.005072) (xy 97.142866 -385.005554)
			(xy 97.19015 -385.013009) (xy 97.235693 -385.027747) (xy 97.278379 -385.049408) (xy 97.317165 -385.077462)
			(xy 97.351101 -385.111221) (xy 97.379357 -385.14986) (xy 97.390712 -385.170934) (xy 97.39122 -385.17195)
			(xy 97.471526 -385.310888) (xy 98.01352 -385.310888) (xy 98.01352 -385.31038) (xy 98.013921 -385.286372)
			(xy 98.021439 -385.238949) (xy 98.036288 -385.193287) (xy 98.0581 -385.150512) (xy 98.086339 -385.111678)
			(xy 98.120308 -385.077742) (xy 98.15917 -385.049542) (xy 98.201966 -385.027772) (xy 98.247643 -385.012969)
			(xy 98.295074 -385.005497) (xy 98.319082 -385.005072) (xy 98.343018 -385.005513) (xy 98.390303 -385.012976)
			(xy 98.435847 -385.027721) (xy 98.478534 -385.049389) (xy 98.517319 -385.077449) (xy 98.551254 -385.111214)
			(xy 98.579508 -385.149858) (xy 98.590862 -385.170934) (xy 98.59137 -385.17195) (xy 98.671676 -385.310888)
			(xy 114.586004 -385.310888) (xy 114.586004 -385.31038) (xy 114.586444 -385.286388) (xy 114.593954 -385.238994)
			(xy 114.608785 -385.193359) (xy 114.630572 -385.150605) (xy 114.658779 -385.111786) (xy 114.692711 -385.077858)
			(xy 114.731533 -385.049655) (xy 114.774288 -385.027872) (xy 114.819925 -385.013046) (xy 114.86732 -385.005542)
			(xy 114.891312 -385.005072) (xy 114.915246 -385.00557) (xy 114.962529 -385.013022) (xy 115.008071 -385.027757)
			(xy 115.050758 -385.049416) (xy 115.089544 -385.077467) (xy 115.12348 -385.111224) (xy 115.151736 -385.149861)
			(xy 115.163092 -385.170934) (xy 115.1636 -385.17195) (xy 115.243906 -385.310888) (xy 115.7859 -385.310888)
			(xy 115.7859 -385.31038) (xy 115.786344 -385.286388) (xy 115.793854 -385.238995) (xy 115.808684 -385.19336)
			(xy 115.830471 -385.150606) (xy 115.858677 -385.111788) (xy 115.892609 -385.077859) (xy 115.93143 -385.049656)
			(xy 115.974186 -385.027873) (xy 116.019822 -385.013047) (xy 116.067216 -385.005542) (xy 116.091208 -385.005072)
			(xy 116.115141 -385.005573) (xy 116.162424 -385.013024) (xy 116.207967 -385.027759) (xy 116.250653 -385.049417)
			(xy 116.289439 -385.077468) (xy 116.323376 -385.111224) (xy 116.351632 -385.149861) (xy 116.362988 -385.170934)
			(xy 116.363496 -385.17195) (xy 116.443802 -385.310888) (xy 116.985796 -385.310888) (xy 116.985796 -385.31038)
			(xy 116.986244 -385.286388) (xy 116.993753 -385.238995) (xy 117.008584 -385.193361) (xy 117.03037 -385.150608)
			(xy 117.058576 -385.111789) (xy 117.092507 -385.077861) (xy 117.131328 -385.049658) (xy 117.174083 -385.027875)
			(xy 117.219719 -385.013048) (xy 117.267112 -385.005542) (xy 117.291104 -385.005072) (xy 117.315037 -385.005576)
			(xy 117.36232 -385.013027) (xy 117.407862 -385.027762) (xy 117.450549 -385.049419) (xy 117.489335 -385.077469)
			(xy 117.523272 -385.111225) (xy 117.551528 -385.149861) (xy 117.562884 -385.170934) (xy 117.563392 -385.17195)
			(xy 117.643698 -385.310888) (xy 118.185692 -385.310888) (xy 118.185692 -385.31038) (xy 118.186121 -385.286374)
			(xy 118.193638 -385.238953) (xy 118.208485 -385.193293) (xy 118.230295 -385.15052) (xy 118.258531 -385.111687)
			(xy 118.292496 -385.077752) (xy 118.331354 -385.049552) (xy 118.374147 -385.02778) (xy 118.41982 -385.012974)
			(xy 118.467247 -385.005499) (xy 118.491254 -385.005072) (xy 118.515189 -385.005536) (xy 118.562474 -385.012994)
			(xy 118.608017 -385.027736) (xy 118.650703 -385.0494) (xy 118.689489 -385.077456) (xy 118.723424 -385.111218)
			(xy 118.751679 -385.149859) (xy 118.763034 -385.170934) (xy 118.763542 -385.17195) (xy 118.843848 -385.310888)
			(xy 119.385588 -385.310888) (xy 119.385588 -385.31038) (xy 119.386021 -385.286374) (xy 119.393538 -385.238954)
			(xy 119.408385 -385.193294) (xy 119.430194 -385.150521) (xy 119.45843 -385.111689) (xy 119.492394 -385.077754)
			(xy 119.531252 -385.049553) (xy 119.574044 -385.027781) (xy 119.619717 -385.012975) (xy 119.667143 -385.0055)
			(xy 119.69115 -385.005072) (xy 119.715085 -385.005539) (xy 119.762369 -385.012997) (xy 119.807912 -385.027738)
			(xy 119.850599 -385.049401) (xy 119.889384 -385.077457) (xy 119.92332 -385.111218) (xy 119.951575 -385.149859)
			(xy 119.96293 -385.170934) (xy 119.963438 -385.17195) (xy 120.043744 -385.310888) (xy 120.585992 -385.310888)
			(xy 120.585992 -385.31038) (xy 120.586444 -385.286388) (xy 120.593953 -385.238996) (xy 120.608783 -385.193362)
			(xy 120.630569 -385.150609) (xy 120.658775 -385.11179) (xy 120.692706 -385.077862) (xy 120.731526 -385.049659)
			(xy 120.77428 -385.027876) (xy 120.819915 -385.013049) (xy 120.867308 -385.005543) (xy 120.8913 -385.005072)
			(xy 120.915233 -385.00558) (xy 120.962516 -385.01303) (xy 121.008058 -385.027764) (xy 121.050744 -385.04942)
			(xy 121.089531 -385.07747) (xy 121.123468 -385.111226) (xy 121.151724 -385.149862) (xy 121.16308 -385.170934)
			(xy 121.163588 -385.17195) (xy 121.243894 -385.310888) (xy 121.785888 -385.310888) (xy 121.785888 -385.31038)
			(xy 121.786344 -385.286388) (xy 121.793853 -385.238996) (xy 121.808683 -385.193362) (xy 121.830469 -385.15061)
			(xy 121.858674 -385.111792) (xy 121.892604 -385.077863) (xy 121.931424 -385.04966) (xy 121.974177 -385.027877)
			(xy 122.019812 -385.013049) (xy 122.067204 -385.005543) (xy 122.091196 -385.005072) (xy 122.115132 -385.005502)
			(xy 122.162418 -385.012966) (xy 122.207962 -385.027714) (xy 122.250649 -385.049384) (xy 122.289434 -385.077445)
			(xy 122.323368 -385.111212) (xy 122.351622 -385.149857) (xy 122.362976 -385.170934) (xy 122.363484 -385.17195)
			(xy 122.44379 -385.310888) (xy 122.985784 -385.310888) (xy 122.985784 -385.31038) (xy 122.986244 -385.286389)
			(xy 122.993753 -385.238997) (xy 123.008583 -385.193363) (xy 123.030368 -385.150611) (xy 123.058573 -385.111793)
			(xy 123.092502 -385.077865) (xy 123.131321 -385.049662) (xy 123.174074 -385.027878) (xy 123.219709 -385.01305)
			(xy 123.267101 -385.005543) (xy 123.291092 -385.005072) (xy 123.315028 -385.005505) (xy 123.362314 -385.012969)
			(xy 123.407858 -385.027716) (xy 123.450544 -385.049385) (xy 123.48933 -385.077446) (xy 123.523264 -385.111212)
			(xy 123.551518 -385.149857) (xy 123.562872 -385.170934) (xy 123.56338 -385.17195) (xy 123.643686 -385.310888)
			(xy 124.18568 -385.310888) (xy 124.18568 -385.31038) (xy 124.186121 -385.286374) (xy 124.193638 -385.238955)
			(xy 124.208484 -385.193296) (xy 124.230293 -385.150524) (xy 124.258527 -385.111692) (xy 124.292491 -385.077757)
			(xy 124.331347 -385.049556) (xy 124.374139 -385.027783) (xy 124.41981 -385.012977) (xy 124.467236 -385.0055)
			(xy 124.491242 -385.005072) (xy 124.515176 -385.005545) (xy 124.562461 -385.013002) (xy 124.608003 -385.027742)
			(xy 124.65069 -385.049404) (xy 124.689476 -385.077459) (xy 124.723412 -385.11122) (xy 124.751667 -385.14986)
			(xy 124.763022 -385.170934) (xy 124.76353 -385.17195) (xy 124.843836 -385.310888) (xy 125.385576 -385.310888)
			(xy 125.385576 -385.31038) (xy 125.386021 -385.286374) (xy 125.393538 -385.238955) (xy 125.408383 -385.193297)
			(xy 125.430192 -385.150525) (xy 125.458426 -385.111693) (xy 125.492389 -385.077758) (xy 125.531245 -385.049557)
			(xy 125.574036 -385.027785) (xy 125.619707 -385.012977) (xy 125.667132 -385.0055) (xy 125.691138 -385.005072)
			(xy 125.715072 -385.005549) (xy 125.762356 -385.013005) (xy 125.807899 -385.027744) (xy 125.850586 -385.049406)
			(xy 125.889372 -385.07746) (xy 125.923307 -385.11122) (xy 125.951563 -385.14986) (xy 125.962918 -385.170934)
			(xy 125.963426 -385.17195) (xy 126.043732 -385.310888) (xy 126.58598 -385.310888) (xy 126.58598 -385.31038)
			(xy 126.586444 -385.286389) (xy 126.593953 -385.238998) (xy 126.608782 -385.193364) (xy 126.630567 -385.150612)
			(xy 126.658771 -385.111795) (xy 126.692701 -385.077866) (xy 126.731519 -385.049663) (xy 126.774272 -385.027879)
			(xy 126.819905 -385.013051) (xy 126.867297 -385.005543) (xy 126.891288 -385.005072) (xy 126.915224 -385.005508)
			(xy 126.96251 -385.012972) (xy 127.008053 -385.027718) (xy 127.05074 -385.049387) (xy 127.089525 -385.077447)
			(xy 127.12346 -385.111213) (xy 127.151714 -385.149858) (xy 127.163068 -385.170934) (xy 127.163576 -385.17195)
			(xy 127.243882 -385.310888) (xy 127.785876 -385.310888) (xy 127.785876 -385.31038) (xy 127.786344 -385.286389)
			(xy 127.793853 -385.238998) (xy 127.808682 -385.193365) (xy 127.830467 -385.150614) (xy 127.85867 -385.111796)
			(xy 127.892599 -385.077868) (xy 127.931417 -385.049664) (xy 127.974169 -385.02788) (xy 128.019802 -385.013052)
			(xy 128.067193 -385.005544) (xy 128.091184 -385.005072) (xy 128.11512 -385.005511) (xy 128.162406 -385.012974)
			(xy 128.207949 -385.02772) (xy 128.250636 -385.049388) (xy 128.289421 -385.077448) (xy 128.323356 -385.111214)
			(xy 128.35161 -385.149858) (xy 128.362964 -385.170934) (xy 128.363472 -385.17195) (xy 128.443778 -385.310888)
			(xy 128.985772 -385.310888) (xy 128.985772 -385.31038) (xy 128.986244 -385.286389) (xy 128.993753 -385.238999)
			(xy 129.008581 -385.193366) (xy 129.030366 -385.150615) (xy 129.058569 -385.111797) (xy 129.092497 -385.077869)
			(xy 129.131315 -385.049666) (xy 129.174066 -385.027881) (xy 129.219699 -385.013053) (xy 129.267089 -385.005544)
			(xy 129.29108 -385.005072) (xy 129.315016 -385.005515) (xy 129.362301 -385.012977) (xy 129.407845 -385.027722)
			(xy 129.450531 -385.04939) (xy 129.489317 -385.077449) (xy 129.523252 -385.111214) (xy 129.551506 -385.149858)
			(xy 129.56286 -385.170934) (xy 129.563368 -385.17195) (xy 129.643674 -385.310888) (xy 130.185668 -385.310888)
			(xy 130.185668 -385.31038) (xy 130.186121 -385.286375) (xy 130.193637 -385.238957) (xy 130.208483 -385.193299)
			(xy 130.230291 -385.150527) (xy 130.258524 -385.111696) (xy 130.292486 -385.077761) (xy 130.331341 -385.04956)
			(xy 130.37413 -385.027787) (xy 130.4198 -385.012979) (xy 130.467224 -385.005501) (xy 130.49123 -385.005072)
			(xy 130.515164 -385.005555) (xy 130.562448 -385.01301) (xy 130.60799 -385.027748) (xy 130.650677 -385.049409)
			(xy 130.689463 -385.077462) (xy 130.723399 -385.111221) (xy 130.751655 -385.14986) (xy 130.76301 -385.170934)
			(xy 130.763518 -385.17195) (xy 130.843824 -385.310888) (xy 131.385564 -385.310888) (xy 131.385564 -385.31038)
			(xy 131.386021 -385.286375) (xy 131.393537 -385.238957) (xy 131.408382 -385.1933) (xy 131.43019 -385.150528)
			(xy 131.458422 -385.111697) (xy 131.492384 -385.077762) (xy 131.531239 -385.049561) (xy 131.574027 -385.027788)
			(xy 131.619697 -385.01298) (xy 131.667121 -385.005501) (xy 131.691126 -385.005072) (xy 131.71506 -385.005558)
			(xy 131.762344 -385.013013) (xy 131.807886 -385.02775) (xy 131.850573 -385.04941) (xy 131.889359 -385.077463)
			(xy 131.923295 -385.111222) (xy 131.951551 -385.14986) (xy 131.962906 -385.170934) (xy 131.963414 -385.17195)
			(xy 132.04372 -385.310888) (xy 132.585968 -385.310888) (xy 132.585968 -385.31038) (xy 132.586444 -385.286389)
			(xy 132.593952 -385.238999) (xy 132.608781 -385.193367) (xy 132.630565 -385.150616) (xy 132.658768 -385.111799)
			(xy 132.692696 -385.077871) (xy 132.731513 -385.049667) (xy 132.774263 -385.027883) (xy 132.819895 -385.013053)
			(xy 132.867285 -385.005544) (xy 132.891276 -385.005072) (xy 132.915211 -385.005518) (xy 132.962497 -385.01298)
			(xy 133.00804 -385.027724) (xy 133.050727 -385.049391) (xy 133.089512 -385.07745) (xy 133.123447 -385.111215)
			(xy 133.151701 -385.149858) (xy 133.163056 -385.170934) (xy 133.163564 -385.17195) (xy 133.24387 -385.310888)
			(xy 147.113752 -385.310888) (xy 147.113752 -385.31038) (xy 147.114244 -385.28639) (xy 147.121752 -385.239002)
			(xy 147.13658 -385.193371) (xy 147.158362 -385.150621) (xy 147.186563 -385.111804) (xy 147.220489 -385.077876)
			(xy 147.259304 -385.049673) (xy 147.302052 -385.027887) (xy 147.347682 -385.013057) (xy 147.39507 -385.005546)
			(xy 147.41906 -385.005072) (xy 147.442995 -385.005531) (xy 147.49028 -385.01299) (xy 147.535823 -385.027733)
			(xy 147.57851 -385.049398) (xy 147.617295 -385.077455) (xy 147.651231 -385.111217) (xy 147.679485 -385.149859)
			(xy 147.69084 -385.170934) (xy 147.691348 -385.17195) (xy 147.771654 -385.310888) (xy 148.313648 -385.310888)
			(xy 148.313648 -385.31038) (xy 148.314144 -385.28639) (xy 148.321652 -385.239002) (xy 148.336479 -385.193372)
			(xy 148.358261 -385.150622) (xy 148.386462 -385.111805) (xy 148.420387 -385.077878) (xy 148.459201 -385.049674)
			(xy 148.501949 -385.027888) (xy 148.547579 -385.013057) (xy 148.594966 -385.005546) (xy 148.618956 -385.005072)
			(xy 148.642891 -385.005534) (xy 148.690176 -385.012993) (xy 148.735719 -385.027735) (xy 148.778405 -385.049399)
			(xy 148.817191 -385.077456) (xy 148.851126 -385.111218) (xy 148.879381 -385.149859) (xy 148.890736 -385.170934)
			(xy 148.891244 -385.17195) (xy 148.97155 -385.310888) (xy 149.513544 -385.310888) (xy 149.513544 -385.31038)
			(xy 149.514044 -385.286391) (xy 149.521552 -385.239003) (xy 149.536379 -385.193373) (xy 149.558161 -385.150623)
			(xy 149.586361 -385.111807) (xy 149.620286 -385.077879) (xy 149.659099 -385.049675) (xy 149.701847 -385.02789)
			(xy 149.747476 -385.013058) (xy 149.794863 -385.005546) (xy 149.818852 -385.005072) (xy 149.842787 -385.005537)
			(xy 149.890071 -385.012995) (xy 149.935614 -385.027737) (xy 149.978301 -385.049401) (xy 150.017087 -385.077457)
			(xy 150.051022 -385.111218) (xy 150.079277 -385.149859) (xy 150.090632 -385.170934) (xy 150.09114 -385.17195)
			(xy 150.171446 -385.310888) (xy 150.71344 -385.310888) (xy 150.71344 -385.31038) (xy 150.713821 -385.286371)
			(xy 150.72134 -385.238946) (xy 150.73619 -385.193282) (xy 150.758004 -385.150506) (xy 150.786245 -385.111671)
			(xy 150.820216 -385.077735) (xy 150.859081 -385.049535) (xy 150.90188 -385.027766) (xy 150.94756 -385.012965)
			(xy 150.994993 -385.005496) (xy 151.019002 -385.005072) (xy 151.042935 -385.005578) (xy 151.090218 -385.013028)
			(xy 151.13576 -385.027763) (xy 151.178447 -385.04942) (xy 151.217233 -385.077469) (xy 151.25117 -385.111225)
			(xy 151.279426 -385.149861) (xy 151.290782 -385.170934) (xy 151.29129 -385.17195) (xy 151.371596 -385.310888)
			(xy 151.913336 -385.310888) (xy 151.913336 -385.31038) (xy 151.913721 -385.286371) (xy 151.92124 -385.238947)
			(xy 151.936089 -385.193283) (xy 151.957903 -385.150507) (xy 151.986144 -385.111672) (xy 152.020115 -385.077737)
			(xy 152.058979 -385.049537) (xy 152.101777 -385.027767) (xy 152.147456 -385.012965) (xy 152.194889 -385.005496)
			(xy 152.218898 -385.005072) (xy 152.242834 -385.0055) (xy 152.290121 -385.012965) (xy 152.335664 -385.027713)
			(xy 152.378351 -385.049383) (xy 152.417136 -385.077445) (xy 152.45107 -385.111212) (xy 152.479324 -385.149857)
			(xy 152.490678 -385.170934) (xy 152.491186 -385.17195) (xy 152.571492 -385.310888) (xy 153.11374 -385.310888)
			(xy 153.11374 -385.31038) (xy 153.11412 -385.286384) (xy 153.121631 -385.238983) (xy 153.136465 -385.193341)
			(xy 153.158257 -385.150582) (xy 153.18647 -385.111758) (xy 153.22041 -385.077826) (xy 153.25924 -385.049622)
			(xy 153.302004 -385.027839) (xy 153.347649 -385.013015) (xy 153.395052 -385.005515) (xy 153.419048 -385.005072)
			(xy 153.442983 -385.005541) (xy 153.490267 -385.012998) (xy 153.53581 -385.027739) (xy 153.578497 -385.049402)
			(xy 153.617282 -385.077458) (xy 153.651218 -385.111219) (xy 153.679473 -385.149859) (xy 153.690828 -385.170934)
			(xy 153.691336 -385.17195) (xy 153.771642 -385.310888) (xy 154.313636 -385.310888) (xy 154.313636 -385.31038)
			(xy 154.31402 -385.286384) (xy 154.321531 -385.238984) (xy 154.336365 -385.193342) (xy 154.358157 -385.150583)
			(xy 154.386369 -385.111759) (xy 154.420308 -385.077828) (xy 154.459138 -385.049623) (xy 154.501901 -385.02784)
			(xy 154.547546 -385.013016) (xy 154.594948 -385.005515) (xy 154.618944 -385.005072) (xy 154.642878 -385.005544)
			(xy 154.690163 -385.013001) (xy 154.735706 -385.027741) (xy 154.778392 -385.049404) (xy 154.817178 -385.077459)
			(xy 154.851114 -385.111219) (xy 154.879369 -385.14986) (xy 154.890724 -385.170934) (xy 154.891232 -385.17195)
			(xy 154.971538 -385.310888) (xy 155.513532 -385.310888) (xy 155.513532 -385.31038) (xy 155.51392 -385.286384)
			(xy 155.521431 -385.238984) (xy 155.536265 -385.193343) (xy 155.558056 -385.150584) (xy 155.586268 -385.111761)
			(xy 155.620206 -385.077829) (xy 155.659035 -385.049624) (xy 155.701798 -385.027842) (xy 155.747443 -385.013017)
			(xy 155.794844 -385.005515) (xy 155.81884 -385.005072) (xy 155.842774 -385.005547) (xy 155.890059 -385.013003)
			(xy 155.935601 -385.027743) (xy 155.978288 -385.049405) (xy 156.017074 -385.07746) (xy 156.05101 -385.11122)
			(xy 156.079265 -385.14986) (xy 156.09062 -385.170934) (xy 156.091128 -385.17195) (xy 156.171434 -385.310888)
			(xy 156.713428 -385.310888) (xy 156.713428 -385.31038) (xy 156.713821 -385.286372) (xy 156.721339 -385.238948)
			(xy 156.736188 -385.193285) (xy 156.758002 -385.150509) (xy 156.786241 -385.111675) (xy 156.820211 -385.07774)
			(xy 156.859074 -385.049539) (xy 156.901872 -385.02777) (xy 156.94755 -385.012967) (xy 156.994981 -385.005497)
			(xy 157.01899 -385.005072) (xy 157.042926 -385.005506) (xy 157.090212 -385.01297) (xy 157.135756 -385.027717)
			(xy 157.178442 -385.049386) (xy 157.217227 -385.077447) (xy 157.251162 -385.111213) (xy 157.279416 -385.149857)
			(xy 157.29077 -385.170934) (xy 157.291278 -385.17195) (xy 157.371584 -385.310888) (xy 157.913324 -385.310888)
			(xy 157.913324 -385.31038) (xy 157.913721 -385.286372) (xy 157.921239 -385.238948) (xy 157.936088 -385.193286)
			(xy 157.957901 -385.15051) (xy 157.98614 -385.111676) (xy 158.020109 -385.077741) (xy 158.058972 -385.049541)
			(xy 158.101769 -385.027771) (xy 158.147446 -385.012968) (xy 158.194878 -385.005497) (xy 158.218886 -385.005072)
			(xy 158.242822 -385.00551) (xy 158.290108 -385.012973) (xy 158.335651 -385.027719) (xy 158.378338 -385.049388)
			(xy 158.417123 -385.077448) (xy 158.451058 -385.111213) (xy 158.479312 -385.149858) (xy 158.490666 -385.170934)
			(xy 158.491174 -385.17195) (xy 158.57148 -385.310888) (xy 159.113728 -385.310888) (xy 159.113728 -385.31038)
			(xy 159.11412 -385.286385) (xy 159.121631 -385.238985) (xy 159.136464 -385.193344) (xy 159.158255 -385.150585)
			(xy 159.186467 -385.111762) (xy 159.220405 -385.07783) (xy 159.259233 -385.049626) (xy 159.301996 -385.027843)
			(xy 159.347639 -385.013018) (xy 159.39504 -385.005515) (xy 159.419036 -385.005072) (xy 159.44297 -385.00555)
			(xy 159.490254 -385.013006) (xy 159.535797 -385.027745) (xy 159.578484 -385.049407) (xy 159.617269 -385.077461)
			(xy 159.651205 -385.11122) (xy 159.679461 -385.14986) (xy 159.690816 -385.170934) (xy 159.691324 -385.17195)
			(xy 159.77163 -385.310888) (xy 160.313624 -385.310888) (xy 160.313624 -385.31038) (xy 160.31402 -385.286385)
			(xy 160.321531 -385.238985) (xy 160.336364 -385.193345) (xy 160.358154 -385.150586) (xy 160.386366 -385.111764)
			(xy 160.420303 -385.077832) (xy 160.459131 -385.049627) (xy 160.501893 -385.027844) (xy 160.547536 -385.013018)
			(xy 160.594937 -385.005516) (xy 160.618932 -385.005072) (xy 160.642866 -385.005554) (xy 160.69015 -385.013009)
			(xy 160.735693 -385.027747) (xy 160.778379 -385.049408) (xy 160.817165 -385.077462) (xy 160.851101 -385.111221)
			(xy 160.879357 -385.14986) (xy 160.890712 -385.170934) (xy 160.89122 -385.17195) (xy 160.971526 -385.310888)
			(xy 161.51352 -385.310888) (xy 161.51352 -385.31038) (xy 161.51392 -385.286385) (xy 161.52143 -385.238986)
			(xy 161.536263 -385.193346) (xy 161.558054 -385.150588) (xy 161.586265 -385.111765) (xy 161.620201 -385.077833)
			(xy 161.659029 -385.049629) (xy 161.70179 -385.027845) (xy 161.747433 -385.013019) (xy 161.794833 -385.005516)
			(xy 161.818828 -385.005072) (xy 161.842762 -385.005557) (xy 161.890046 -385.013011) (xy 161.935588 -385.027749)
			(xy 161.978275 -385.04941) (xy 162.017061 -385.077463) (xy 162.050997 -385.111222) (xy 162.079253 -385.14986)
			(xy 162.090608 -385.170934) (xy 162.091116 -385.17195) (xy 162.171422 -385.310888) (xy 162.713416 -385.310888)
			(xy 162.713416 -385.31038) (xy 162.713821 -385.286372) (xy 162.721339 -385.238949) (xy 162.736187 -385.193288)
			(xy 162.757999 -385.150513) (xy 162.786238 -385.111679) (xy 162.820206 -385.077744) (xy 162.859067 -385.049543)
			(xy 162.901864 -385.027773) (xy 162.94754 -385.012969) (xy 162.99497 -385.005497) (xy 163.018978 -385.005072)
			(xy 163.042913 -385.005516) (xy 163.090199 -385.012978) (xy 163.135743 -385.027723) (xy 163.178429 -385.049391)
			(xy 163.217215 -385.07745) (xy 163.251149 -385.111214) (xy 163.279404 -385.149858) (xy 163.290758 -385.170934)
			(xy 163.291266 -385.17195) (xy 163.371572 -385.310888) (xy 163.913312 -385.310888) (xy 163.913312 -385.31038)
			(xy 163.913721 -385.286373) (xy 163.921239 -385.23895) (xy 163.936087 -385.193289) (xy 163.957899 -385.150514)
			(xy 163.986137 -385.111681) (xy 164.020104 -385.077745) (xy 164.058965 -385.049545) (xy 164.101761 -385.027774)
			(xy 164.147436 -385.01297) (xy 164.194866 -385.005498) (xy 164.218874 -385.005072) (xy 164.242809 -385.005519)
			(xy 164.290095 -385.012981) (xy 164.335638 -385.027726) (xy 164.378325 -385.049392) (xy 164.41711 -385.077451)
			(xy 164.451045 -385.111215) (xy 164.479299 -385.149858) (xy 164.490654 -385.170934) (xy 164.491162 -385.17195)
			(xy 164.571468 -385.310888) (xy 165.113716 -385.310888) (xy 165.113716 -385.31038) (xy 165.11412 -385.286385)
			(xy 165.12163 -385.238987) (xy 165.136463 -385.193347) (xy 165.158253 -385.150589) (xy 165.186463 -385.111766)
			(xy 165.2204 -385.077835) (xy 165.259226 -385.04963) (xy 165.301987 -385.027846) (xy 165.347629 -385.01302)
			(xy 165.395029 -385.005516) (xy 165.419024 -385.005072) (xy 165.442958 -385.00556) (xy 165.490242 -385.013014)
			(xy 165.535784 -385.027751) (xy 165.578471 -385.049411) (xy 165.617257 -385.077464) (xy 165.651193 -385.111222)
			(xy 165.679449 -385.14986) (xy 165.690804 -385.170934) (xy 165.691312 -385.17195) (xy 166.083742 -385.850892)
			(xy 166.096567 -385.874224) (xy 166.114787 -385.924247) (xy 166.124047 -385.976673) (xy 166.124636 -386.003292)
			(xy 166.124154 -386.027296) (xy 166.116641 -386.074713) (xy 166.1018 -386.12037) (xy 166.079996 -386.163141)
			(xy 166.051766 -386.201973) (xy 166.017807 -386.235908) (xy 165.978955 -386.26411) (xy 165.936168 -386.285883)
			(xy 165.890501 -386.300692) (xy 165.843079 -386.308171) (xy 165.819074 -386.3086) (xy 165.795499 -386.308227)
			(xy 165.74891 -386.300982) (xy 165.703991 -386.286652) (xy 165.661813 -386.26558) (xy 165.62338 -386.238267)
			(xy 165.589609 -386.205365) (xy 165.561304 -386.167657) (xy 165.549834 -386.147056) (xy 165.549326 -386.146294)
			(xy 165.151562 -385.457954) (xy 165.139704 -385.435268) (xy 165.122846 -385.38694) (xy 165.114266 -385.33648)
			(xy 165.113716 -385.310888) (xy 164.571468 -385.310888) (xy 164.883592 -385.850892) (xy 164.896342 -385.874249)
			(xy 164.914451 -385.924281) (xy 164.923654 -385.976688) (xy 164.924232 -386.003292) (xy 164.92373 -386.027282)
			(xy 164.916226 -386.074671) (xy 164.901401 -386.120303) (xy 164.879621 -386.163054) (xy 164.851421 -386.201871)
			(xy 164.817496 -386.2358) (xy 164.778681 -386.264004) (xy 164.735932 -386.285789) (xy 164.690302 -386.300618)
			(xy 164.642914 -386.308128) (xy 164.618924 -386.3086) (xy 164.595351 -386.308187) (xy 164.548763 -386.300949)
			(xy 164.503845 -386.286627) (xy 164.461667 -386.265561) (xy 164.423233 -386.238255) (xy 164.389461 -386.205358)
			(xy 164.361155 -386.167655) (xy 164.349684 -386.147056) (xy 164.349176 -386.146294) (xy 163.951412 -385.457954)
			(xy 163.939479 -385.435295) (xy 163.922547 -385.386965) (xy 163.913895 -385.336491) (xy 163.913312 -385.310888)
			(xy 163.371572 -385.310888) (xy 163.683696 -385.850892) (xy 163.696446 -385.874249) (xy 163.714555 -385.924281)
			(xy 163.723758 -385.976688) (xy 163.724336 -386.003292) (xy 163.72383 -386.027282) (xy 163.716326 -386.07467)
			(xy 163.701501 -386.120302) (xy 163.679721 -386.163053) (xy 163.651522 -386.20187) (xy 163.617597 -386.235798)
			(xy 163.578783 -386.264002) (xy 163.536035 -386.285788) (xy 163.490405 -386.300618) (xy 163.443018 -386.308127)
			(xy 163.419028 -386.3086) (xy 163.395455 -386.308184) (xy 163.348868 -386.300946) (xy 163.30395 -386.286625)
			(xy 163.261771 -386.26556) (xy 163.223338 -386.238254) (xy 163.189565 -386.205357) (xy 163.161259 -386.167654)
			(xy 163.149788 -386.147056) (xy 163.14928 -386.146294) (xy 162.751516 -385.457954) (xy 162.739583 -385.435294)
			(xy 162.722652 -385.386965) (xy 162.713999 -385.336491) (xy 162.713416 -385.310888) (xy 162.171422 -385.310888)
			(xy 162.483546 -385.850892) (xy 162.496371 -385.874224) (xy 162.514591 -385.924247) (xy 162.523851 -385.976673)
			(xy 162.52444 -386.003292) (xy 162.523954 -386.027296) (xy 162.516441 -386.074713) (xy 162.5016 -386.120369)
			(xy 162.479796 -386.16314) (xy 162.451567 -386.201972) (xy 162.417609 -386.235907) (xy 162.378757 -386.264108)
			(xy 162.335971 -386.285882) (xy 162.290304 -386.300691) (xy 162.242882 -386.30817) (xy 162.218878 -386.3086)
			(xy 162.195303 -386.308224) (xy 162.148714 -386.300979) (xy 162.103795 -386.28665) (xy 162.061617 -386.265579)
			(xy 162.023184 -386.238266) (xy 161.989413 -386.205364) (xy 161.961108 -386.167657) (xy 161.949638 -386.147056)
			(xy 161.94913 -386.146294) (xy 161.551366 -385.457954) (xy 161.539508 -385.435268) (xy 161.52265 -385.38694)
			(xy 161.51407 -385.33648) (xy 161.51352 -385.310888) (xy 160.971526 -385.310888) (xy 161.28365 -385.850892)
			(xy 161.296476 -385.874224) (xy 161.314695 -385.924247) (xy 161.323955 -385.976673) (xy 161.324544 -386.003292)
			(xy 161.324054 -386.027296) (xy 161.316541 -386.074712) (xy 161.301701 -386.120368) (xy 161.279897 -386.163139)
			(xy 161.251669 -386.20197) (xy 161.21771 -386.235905) (xy 161.17886 -386.264107) (xy 161.136074 -386.285881)
			(xy 161.090407 -386.30069) (xy 161.042986 -386.30817) (xy 161.018982 -386.3086) (xy 160.995407 -386.308221)
			(xy 160.948819 -386.300977) (xy 160.9039 -386.286648) (xy 160.861721 -386.265577) (xy 160.823288 -386.238265)
			(xy 160.789517 -386.205364) (xy 160.761212 -386.167657) (xy 160.749742 -386.147056) (xy 160.749234 -386.146294)
			(xy 160.35147 -385.457954) (xy 160.339612 -385.435268) (xy 160.322755 -385.386939) (xy 160.314174 -385.33648)
			(xy 160.313624 -385.310888) (xy 159.77163 -385.310888) (xy 160.083754 -385.850892) (xy 160.09658 -385.874224)
			(xy 160.114799 -385.924247) (xy 160.124059 -385.976673) (xy 160.124648 -386.003292) (xy 160.124154 -386.027296)
			(xy 160.116641 -386.074711) (xy 160.101801 -386.120367) (xy 160.079998 -386.163138) (xy 160.05177 -386.201969)
			(xy 160.017812 -386.235904) (xy 159.978962 -386.264106) (xy 159.936177 -386.28588) (xy 159.890511 -386.30069)
			(xy 159.84309 -386.30817) (xy 159.819086 -386.3086) (xy 159.795512 -386.308217) (xy 159.748923 -386.300974)
			(xy 159.704004 -386.286646) (xy 159.661826 -386.265576) (xy 159.623393 -386.238264) (xy 159.589621 -386.205363)
			(xy 159.561316 -386.167656) (xy 159.549846 -386.147056) (xy 159.549338 -386.146294) (xy 159.151574 -385.457954)
			(xy 159.139717 -385.435268) (xy 159.122859 -385.386939) (xy 159.114278 -385.336479) (xy 159.113728 -385.310888)
			(xy 158.57148 -385.310888) (xy 158.883604 -385.850892) (xy 158.896355 -385.874249) (xy 158.914464 -385.924281)
			(xy 158.923666 -385.976688) (xy 158.924244 -386.003292) (xy 158.92373 -386.027281) (xy 158.916226 -386.074669)
			(xy 158.901402 -386.1203) (xy 158.879623 -386.16305) (xy 158.851424 -386.201867) (xy 158.817501 -386.235796)
			(xy 158.778688 -386.264) (xy 158.735941 -386.285785) (xy 158.690312 -386.300616) (xy 158.642925 -386.308127)
			(xy 158.618936 -386.3086) (xy 158.595363 -386.308177) (xy 158.548776 -386.300941) (xy 158.503858 -386.286621)
			(xy 158.46168 -386.265557) (xy 158.423246 -386.238252) (xy 158.389474 -386.205356) (xy 158.361167 -386.167654)
			(xy 158.349696 -386.147056) (xy 158.349188 -386.146294) (xy 157.951424 -385.457954) (xy 157.939492 -385.435294)
			(xy 157.92256 -385.386965) (xy 157.913907 -385.336491) (xy 157.913324 -385.310888) (xy 157.371584 -385.310888)
			(xy 157.683708 -385.850892) (xy 157.696459 -385.874248) (xy 157.714568 -385.924281) (xy 157.72377 -385.976688)
			(xy 157.724348 -386.003292) (xy 157.72383 -386.027281) (xy 157.716326 -386.074669) (xy 157.701503 -386.120299)
			(xy 157.679724 -386.163049) (xy 157.651525 -386.201866) (xy 157.617603 -386.235794) (xy 157.57879 -386.263998)
			(xy 157.536043 -386.285784) (xy 157.490415 -386.300615) (xy 157.443029 -386.308126) (xy 157.41904 -386.3086)
			(xy 157.395467 -386.308174) (xy 157.34888 -386.300939) (xy 157.303963 -386.286618) (xy 157.261784 -386.265555)
			(xy 157.223351 -386.238251) (xy 157.189578 -386.205355) (xy 157.161271 -386.167654) (xy 157.1498 -386.147056)
			(xy 157.149292 -386.146294) (xy 156.751528 -385.457954) (xy 156.739596 -385.435294) (xy 156.722664 -385.386965)
			(xy 156.714011 -385.336491) (xy 156.713428 -385.310888) (xy 156.171434 -385.310888) (xy 156.483558 -385.850892)
			(xy 156.496384 -385.874224) (xy 156.514604 -385.924247) (xy 156.523863 -385.976673) (xy 156.524452 -386.003292)
			(xy 156.523954 -386.027295) (xy 156.516442 -386.074711) (xy 156.501601 -386.120366) (xy 156.479799 -386.163137)
			(xy 156.451571 -386.201968) (xy 156.417614 -386.235902) (xy 156.378764 -386.264104) (xy 156.335979 -386.285879)
			(xy 156.290314 -386.300689) (xy 156.242894 -386.308169) (xy 156.21889 -386.3086) (xy 156.195316 -386.308214)
			(xy 156.148727 -386.300971) (xy 156.103808 -386.286644) (xy 156.06163 -386.265574) (xy 156.023197 -386.238263)
			(xy 155.989426 -386.205363) (xy 155.96112 -386.167656) (xy 155.94965 -386.147056) (xy 155.949142 -386.146294)
			(xy 155.551378 -385.457954) (xy 155.539521 -385.435268) (xy 155.522663 -385.386939) (xy 155.514082 -385.336479)
			(xy 155.513532 -385.310888) (xy 154.971538 -385.310888) (xy 155.283662 -385.850892) (xy 155.296489 -385.874224)
			(xy 155.314708 -385.924247) (xy 155.323967 -385.976673) (xy 155.324556 -386.003292) (xy 155.324054 -386.027295)
			(xy 155.316542 -386.07471) (xy 155.301702 -386.120365) (xy 155.279899 -386.163135) (xy 155.251672 -386.201966)
			(xy 155.217715 -386.235901) (xy 155.178866 -386.264103) (xy 155.136082 -386.285878) (xy 155.090417 -386.300688)
			(xy 155.042998 -386.308169) (xy 155.018994 -386.3086) (xy 154.99542 -386.308211) (xy 154.948831 -386.300969)
			(xy 154.903913 -386.286642) (xy 154.861734 -386.265573) (xy 154.823301 -386.238262) (xy 154.78953 -386.205362)
			(xy 154.761224 -386.167656) (xy 154.749754 -386.147056) (xy 154.749246 -386.146294) (xy 154.351482 -385.457954)
			(xy 154.339625 -385.435268) (xy 154.322767 -385.386939) (xy 154.314186 -385.336479) (xy 154.313636 -385.310888)
			(xy 153.771642 -385.310888) (xy 154.083766 -385.850892) (xy 154.096593 -385.874223) (xy 154.114812 -385.924247)
			(xy 154.124071 -385.976673) (xy 154.12466 -386.003292) (xy 154.124253 -386.0273) (xy 154.116738 -386.074724)
			(xy 154.101893 -386.120388) (xy 154.080082 -386.163164) (xy 154.051844 -386.201999) (xy 154.017875 -386.235935)
			(xy 153.979013 -386.264136) (xy 153.936216 -386.285905) (xy 153.890538 -386.300707) (xy 153.843106 -386.308176)
			(xy 153.819098 -386.3086) (xy 153.795524 -386.308208) (xy 153.748936 -386.300966) (xy 153.704017 -386.28664)
			(xy 153.661839 -386.265571) (xy 153.623406 -386.238261) (xy 153.589634 -386.205361) (xy 153.561328 -386.167656)
			(xy 153.549858 -386.147056) (xy 153.54935 -386.146294) (xy 153.151586 -385.457954) (xy 153.13973 -385.435267)
			(xy 153.122871 -385.386939) (xy 153.11429 -385.336479) (xy 153.11374 -385.310888) (xy 152.571492 -385.310888)
			(xy 152.883616 -385.850892) (xy 152.896368 -385.874248) (xy 152.914476 -385.924281) (xy 152.923678 -385.976688)
			(xy 152.924256 -386.003292) (xy 152.92373 -386.027281) (xy 152.916227 -386.074667) (xy 152.901403 -386.120297)
			(xy 152.879625 -386.163047) (xy 152.851428 -386.201863) (xy 152.817506 -386.235791) (xy 152.778694 -386.263996)
			(xy 152.735949 -386.285782) (xy 152.690322 -386.300614) (xy 152.642937 -386.308126) (xy 152.618948 -386.3086)
			(xy 152.595375 -386.308168) (xy 152.548789 -386.300933) (xy 152.503871 -386.286614) (xy 152.461693 -386.265552)
			(xy 152.423259 -386.238248) (xy 152.389486 -386.205354) (xy 152.361179 -386.167654) (xy 152.349708 -386.147056)
			(xy 152.3492 -386.146294) (xy 151.951436 -385.457954) (xy 151.939505 -385.435294) (xy 151.922572 -385.386964)
			(xy 151.913919 -385.336491) (xy 151.913336 -385.310888) (xy 151.371596 -385.310888) (xy 151.68372 -385.850892)
			(xy 151.696472 -385.874248) (xy 151.71458 -385.924281) (xy 151.723782 -385.976688) (xy 151.72436 -386.003292)
			(xy 151.723954 -386.027287) (xy 151.716447 -386.074687) (xy 151.701617 -386.120329) (xy 151.679828 -386.163088)
			(xy 151.651618 -386.201912) (xy 151.617682 -386.235844) (xy 151.578854 -386.264049) (xy 151.536092 -386.285832)
			(xy 151.490448 -386.300657) (xy 151.443047 -386.308157) (xy 151.419052 -386.3086) (xy 151.395479 -386.308164)
			(xy 151.348893 -386.300931) (xy 151.303976 -386.286612) (xy 151.261797 -386.265551) (xy 151.223364 -386.238247)
			(xy 151.189591 -386.205354) (xy 151.161283 -386.167653) (xy 151.149812 -386.147056) (xy 151.149304 -386.146294)
			(xy 150.75154 -385.457954) (xy 150.739609 -385.435293) (xy 150.722676 -385.386964) (xy 150.714023 -385.336491)
			(xy 150.71344 -385.310888) (xy 150.171446 -385.310888) (xy 150.48357 -385.850892) (xy 150.496397 -385.874223)
			(xy 150.514616 -385.924247) (xy 150.523875 -385.976673) (xy 150.524464 -386.003292) (xy 150.524053 -386.0273)
			(xy 150.516539 -386.074724) (xy 150.501693 -386.120387) (xy 150.479883 -386.163163) (xy 150.451645 -386.201998)
			(xy 150.417677 -386.235934) (xy 150.378815 -386.264134) (xy 150.336018 -386.285904) (xy 150.290341 -386.300706)
			(xy 150.24291 -386.308176) (xy 150.218902 -386.3086) (xy 150.195328 -386.308205) (xy 150.14874 -386.300963)
			(xy 150.103821 -386.286638) (xy 150.061643 -386.26557) (xy 150.02321 -386.23826) (xy 149.989438 -386.205361)
			(xy 149.961133 -386.167656) (xy 149.949662 -386.147056) (xy 149.949154 -386.146294) (xy 149.55139 -385.457954)
			(xy 149.539534 -385.435267) (xy 149.522675 -385.386939) (xy 149.514094 -385.336479) (xy 149.513544 -385.310888)
			(xy 148.97155 -385.310888) (xy 149.283674 -385.850892) (xy 149.296501 -385.874223) (xy 149.31472 -385.924247)
			(xy 149.323979 -385.976673) (xy 149.324568 -386.003292) (xy 149.324153 -386.0273) (xy 149.316639 -386.074723)
			(xy 149.301793 -386.120386) (xy 149.279983 -386.163162) (xy 149.251746 -386.201996) (xy 149.217779 -386.235932)
			(xy 149.178917 -386.264133) (xy 149.136121 -386.285903) (xy 149.090445 -386.300706) (xy 149.043014 -386.308176)
			(xy 149.019006 -386.3086) (xy 148.995432 -386.308201) (xy 148.948844 -386.300961) (xy 148.903926 -386.286636)
			(xy 148.861747 -386.265568) (xy 148.823314 -386.238259) (xy 148.789542 -386.20536) (xy 148.761237 -386.167655)
			(xy 148.749766 -386.147056) (xy 148.749258 -386.146294) (xy 148.351494 -385.457954) (xy 148.339638 -385.435267)
			(xy 148.322779 -385.386939) (xy 148.314198 -385.336479) (xy 148.313648 -385.310888) (xy 147.771654 -385.310888)
			(xy 148.083778 -385.850892) (xy 148.096606 -385.874223) (xy 148.114824 -385.924247) (xy 148.124083 -385.976673)
			(xy 148.124672 -386.003292) (xy 148.124253 -386.027299) (xy 148.116739 -386.074723) (xy 148.101894 -386.120385)
			(xy 148.080084 -386.163161) (xy 148.051848 -386.201995) (xy 148.01788 -386.235931) (xy 147.97902 -386.264132)
			(xy 147.936224 -386.285902) (xy 147.890548 -386.300705) (xy 147.843118 -386.308175) (xy 147.81911 -386.3086)
			(xy 147.795536 -386.308198) (xy 147.748948 -386.300958) (xy 147.70403 -386.286634) (xy 147.661852 -386.265566)
			(xy 147.623418 -386.238258) (xy 147.589647 -386.20536) (xy 147.561341 -386.167655) (xy 147.54987 -386.147056)
			(xy 147.549362 -386.146294) (xy 147.151598 -385.457954) (xy 147.139742 -385.435267) (xy 147.122883 -385.386939)
			(xy 147.114302 -385.336479) (xy 147.113752 -385.310888) (xy 133.24387 -385.310888) (xy 133.555994 -385.850892)
			(xy 133.568823 -385.874222) (xy 133.587041 -385.924246) (xy 133.596299 -385.976673) (xy 133.596888 -386.003292)
			(xy 133.596453 -386.027299) (xy 133.588939 -386.07472) (xy 133.574095 -386.120381) (xy 133.552287 -386.163156)
			(xy 133.524052 -386.20199) (xy 133.490087 -386.235925) (xy 133.451229 -386.264126) (xy 133.408435 -386.285897)
			(xy 133.362761 -386.300702) (xy 133.315333 -386.308174) (xy 133.291326 -386.3086) (xy 133.267753 -386.308185)
			(xy 133.221165 -386.300948) (xy 133.176247 -386.286626) (xy 133.134069 -386.26556) (xy 133.095636 -386.238254)
			(xy 133.061863 -386.205357) (xy 133.033557 -386.167655) (xy 133.022086 -386.147056) (xy 133.021578 -386.146294)
			(xy 132.623814 -385.457954) (xy 132.611952 -385.43527) (xy 132.595097 -385.38694) (xy 132.586517 -385.33648)
			(xy 132.585968 -385.310888) (xy 132.04372 -385.310888) (xy 132.355844 -385.850892) (xy 132.368598 -385.874247)
			(xy 132.386705 -385.92428) (xy 132.395906 -385.976688) (xy 132.396484 -386.003292) (xy 132.396054 -386.027286)
			(xy 132.388548 -386.074684) (xy 132.373719 -386.120323) (xy 132.351933 -386.163081) (xy 132.323725 -386.201904)
			(xy 132.289792 -386.235836) (xy 132.250967 -386.264041) (xy 132.208208 -386.285825) (xy 132.162568 -386.300652)
			(xy 132.11517 -386.308156) (xy 132.091176 -386.3086) (xy 132.067601 -386.308226) (xy 132.021012 -386.30098)
			(xy 131.976093 -386.286651) (xy 131.933915 -386.265579) (xy 131.895482 -386.238267) (xy 131.861711 -386.205365)
			(xy 131.833406 -386.167657) (xy 131.821936 -386.147056) (xy 131.821428 -386.146294) (xy 131.423664 -385.457954)
			(xy 131.411735 -385.435292) (xy 131.394801 -385.386964) (xy 131.386148 -385.336491) (xy 131.385564 -385.310888)
			(xy 130.843824 -385.310888) (xy 131.155948 -385.850892) (xy 131.168702 -385.874247) (xy 131.186809 -385.92428)
			(xy 131.19601 -385.976688) (xy 131.196588 -386.003292) (xy 131.196154 -386.027286) (xy 131.188648 -386.074683)
			(xy 131.17382 -386.120322) (xy 131.152033 -386.16308) (xy 131.123826 -386.201902) (xy 131.089893 -386.235834)
			(xy 131.05107 -386.26404) (xy 131.008311 -386.285824) (xy 130.962671 -386.300651) (xy 130.915274 -386.308155)
			(xy 130.89128 -386.3086) (xy 130.867705 -386.308222) (xy 130.821116 -386.300978) (xy 130.776197 -386.286649)
			(xy 130.734019 -386.265578) (xy 130.695586 -386.238266) (xy 130.661815 -386.205364) (xy 130.63351 -386.167657)
			(xy 130.62204 -386.147056) (xy 130.621532 -386.146294) (xy 130.223768 -385.457954) (xy 130.211839 -385.435292)
			(xy 130.194906 -385.386964) (xy 130.186252 -385.336491) (xy 130.185668 -385.310888) (xy 129.643674 -385.310888)
			(xy 129.955798 -385.850892) (xy 129.968619 -385.874226) (xy 129.986842 -385.924248) (xy 129.996103 -385.976674)
			(xy 129.996692 -386.003292) (xy 129.996253 -386.027298) (xy 129.98874 -386.07472) (xy 129.973896 -386.12038)
			(xy 129.952088 -386.163155) (xy 129.923853 -386.201988) (xy 129.889889 -386.235924) (xy 129.851031 -386.264125)
			(xy 129.808238 -386.285896) (xy 129.762564 -386.300701) (xy 129.715137 -386.308174) (xy 129.69113 -386.3086)
			(xy 129.667557 -386.308182) (xy 129.62097 -386.300945) (xy 129.576052 -386.286624) (xy 129.533873 -386.265559)
			(xy 129.49544 -386.238253) (xy 129.461668 -386.205357) (xy 129.433361 -386.167654) (xy 129.42189 -386.147056)
			(xy 129.421382 -386.146294) (xy 129.023618 -385.457954) (xy 129.011756 -385.43527) (xy 128.994901 -385.38694)
			(xy 128.986321 -385.33648) (xy 128.985772 -385.310888) (xy 128.443778 -385.310888) (xy 128.755902 -385.850892)
			(xy 128.768724 -385.874226) (xy 128.786946 -385.924248) (xy 128.796207 -385.976674) (xy 128.796796 -386.003292)
			(xy 128.796353 -386.027298) (xy 128.78884 -386.074719) (xy 128.773996 -386.120379) (xy 128.752188 -386.163153)
			(xy 128.723955 -386.201987) (xy 128.68999 -386.235922) (xy 128.651133 -386.264123) (xy 128.608341 -386.285895)
			(xy 128.562668 -386.3007) (xy 128.515241 -386.308174) (xy 128.491234 -386.3086) (xy 128.467661 -386.308179)
			(xy 128.421074 -386.300942) (xy 128.376156 -386.286622) (xy 128.333978 -386.265557) (xy 128.295544 -386.238252)
			(xy 128.261772 -386.205356) (xy 128.233465 -386.167654) (xy 128.221994 -386.147056) (xy 128.221486 -386.146294)
			(xy 127.823722 -385.457954) (xy 127.811861 -385.43527) (xy 127.795005 -385.38694) (xy 127.786426 -385.33648)
			(xy 127.785876 -385.310888) (xy 127.243882 -385.310888) (xy 127.556006 -385.850892) (xy 127.568828 -385.874226)
			(xy 127.58705 -385.924248) (xy 127.596311 -385.976674) (xy 127.5969 -386.003292) (xy 127.596454 -386.027298)
			(xy 127.58894 -386.074718) (xy 127.574096 -386.120378) (xy 127.552289 -386.163152) (xy 127.524056 -386.201985)
			(xy 127.490092 -386.235921) (xy 127.451235 -386.264122) (xy 127.408443 -386.285894) (xy 127.362771 -386.300699)
			(xy 127.315344 -386.308173) (xy 127.291338 -386.3086) (xy 127.267765 -386.308176) (xy 127.221178 -386.30094)
			(xy 127.17626 -386.28662) (xy 127.134082 -386.265556) (xy 127.095648 -386.238251) (xy 127.061876 -386.205356)
			(xy 127.033569 -386.167654) (xy 127.022098 -386.147056) (xy 127.02159 -386.146294) (xy 126.623826 -385.457954)
			(xy 126.611965 -385.43527) (xy 126.595109 -385.38694) (xy 126.58653 -385.33648) (xy 126.58598 -385.310888)
			(xy 126.043732 -385.310888) (xy 126.355856 -385.850892) (xy 126.368611 -385.874246) (xy 126.386717 -385.92428)
			(xy 126.395918 -385.976688) (xy 126.396496 -386.003292) (xy 126.396054 -386.027286) (xy 126.388548 -386.074682)
			(xy 126.37372 -386.12032) (xy 126.351935 -386.163077) (xy 126.323729 -386.2019) (xy 126.289797 -386.235831)
			(xy 126.250974 -386.264037) (xy 126.208217 -386.285822) (xy 126.162578 -386.300649) (xy 126.115182 -386.308155)
			(xy 126.091188 -386.3086) (xy 126.067614 -386.308216) (xy 126.021025 -386.300973) (xy 125.976106 -386.286645)
			(xy 125.933928 -386.265575) (xy 125.895495 -386.238264) (xy 125.861723 -386.205363) (xy 125.833418 -386.167656)
			(xy 125.821948 -386.147056) (xy 125.82144 -386.146294) (xy 125.423676 -385.457954) (xy 125.41174 -385.435296)
			(xy 125.39481 -385.386965) (xy 125.386159 -385.336492) (xy 125.385576 -385.310888) (xy 124.843836 -385.310888)
			(xy 125.15596 -385.850892) (xy 125.168715 -385.874246) (xy 125.186821 -385.92428) (xy 125.196022 -385.976688)
			(xy 125.1966 -386.003292) (xy 125.196154 -386.027285) (xy 125.188649 -386.074681) (xy 125.173821 -386.12032)
			(xy 125.152036 -386.163076) (xy 125.12383 -386.201898) (xy 125.089898 -386.23583) (xy 125.051076 -386.264036)
			(xy 125.00832 -386.285821) (xy 124.962681 -386.300649) (xy 124.915285 -386.308154) (xy 124.891292 -386.3086)
			(xy 124.867718 -386.308213) (xy 124.821129 -386.30097) (xy 124.77621 -386.286643) (xy 124.734032 -386.265573)
			(xy 124.695599 -386.238263) (xy 124.661828 -386.205362) (xy 124.633522 -386.167656) (xy 124.622052 -386.147056)
			(xy 124.621544 -386.146294) (xy 124.22378 -385.457954) (xy 124.211844 -385.435296) (xy 124.194915 -385.386965)
			(xy 124.186263 -385.336492) (xy 124.18568 -385.310888) (xy 123.643686 -385.310888) (xy 123.95581 -385.850892)
			(xy 123.968632 -385.874226) (xy 123.986854 -385.924248) (xy 123.996115 -385.976673) (xy 123.996704 -386.003292)
			(xy 123.996254 -386.027298) (xy 123.98874 -386.074718) (xy 123.973897 -386.120377) (xy 123.95209 -386.163151)
			(xy 123.923857 -386.201984) (xy 123.889894 -386.23592) (xy 123.851037 -386.264121) (xy 123.808246 -386.285893)
			(xy 123.762574 -386.300698) (xy 123.715148 -386.308173) (xy 123.691142 -386.3086) (xy 123.667569 -386.308172)
			(xy 123.620983 -386.300937) (xy 123.576065 -386.286617) (xy 123.533886 -386.265554) (xy 123.495453 -386.23825)
			(xy 123.46168 -386.205355) (xy 123.433373 -386.167654) (xy 123.421902 -386.147056) (xy 123.421394 -386.146294)
			(xy 123.02363 -385.457954) (xy 123.011769 -385.43527) (xy 122.994913 -385.38694) (xy 122.986334 -385.33648)
			(xy 122.985784 -385.310888) (xy 122.44379 -385.310888) (xy 122.755914 -385.850892) (xy 122.768737 -385.874226)
			(xy 122.786958 -385.924248) (xy 122.796219 -385.976673) (xy 122.796808 -386.003292) (xy 122.796354 -386.027298)
			(xy 122.78884 -386.074717) (xy 122.773997 -386.120377) (xy 122.752191 -386.16315) (xy 122.723958 -386.201983)
			(xy 122.689995 -386.235918) (xy 122.65114 -386.264119) (xy 122.608349 -386.285891) (xy 122.562678 -386.300698)
			(xy 122.515252 -386.308173) (xy 122.491246 -386.3086) (xy 122.467673 -386.308169) (xy 122.421087 -386.300935)
			(xy 122.376169 -386.286615) (xy 122.333991 -386.265553) (xy 122.295557 -386.238249) (xy 122.261784 -386.205355)
			(xy 122.233477 -386.167654) (xy 122.222006 -386.147056) (xy 122.221498 -386.146294) (xy 121.823734 -385.457954)
			(xy 121.811874 -385.43527) (xy 121.795018 -385.38694) (xy 121.786438 -385.33648) (xy 121.785888 -385.310888)
			(xy 121.243894 -385.310888) (xy 121.556018 -385.850892) (xy 121.568841 -385.874226) (xy 121.587062 -385.924248)
			(xy 121.596323 -385.976673) (xy 121.596912 -386.003292) (xy 121.596454 -386.027297) (xy 121.58894 -386.074717)
			(xy 121.574098 -386.120376) (xy 121.552291 -386.163149) (xy 121.524059 -386.201981) (xy 121.490097 -386.235917)
			(xy 121.451242 -386.264118) (xy 121.408452 -386.28589) (xy 121.362781 -386.300697) (xy 121.315356 -386.308172)
			(xy 121.29135 -386.3086) (xy 121.267777 -386.308166) (xy 121.221191 -386.300932) (xy 121.176273 -386.286613)
			(xy 121.134095 -386.265551) (xy 121.095661 -386.238248) (xy 121.061888 -386.205354) (xy 121.033581 -386.167653)
			(xy 121.02211 -386.147056) (xy 121.021602 -386.146294) (xy 120.623838 -385.457954) (xy 120.611978 -385.435269)
			(xy 120.595122 -385.38694) (xy 120.586542 -385.33648) (xy 120.585992 -385.310888) (xy 120.043744 -385.310888)
			(xy 120.355868 -385.850892) (xy 120.368624 -385.874246) (xy 120.38673 -385.92428) (xy 120.39593 -385.976688)
			(xy 120.396508 -386.003292) (xy 120.396054 -386.027285) (xy 120.388549 -386.07468) (xy 120.373721 -386.120318)
			(xy 120.351937 -386.163074) (xy 120.323732 -386.201896) (xy 120.289802 -386.235827) (xy 120.250981 -386.264033)
			(xy 120.208225 -386.285818) (xy 120.162588 -386.300647) (xy 120.115193 -386.308154) (xy 120.0912 -386.3086)
			(xy 120.067626 -386.308206) (xy 120.021038 -386.300965) (xy 119.976119 -386.286639) (xy 119.933941 -386.26557)
			(xy 119.895508 -386.238261) (xy 119.861736 -386.205361) (xy 119.83343 -386.167656) (xy 119.82196 -386.147056)
			(xy 119.821452 -386.146294) (xy 119.423688 -385.457954) (xy 119.411753 -385.435296) (xy 119.394823 -385.386965)
			(xy 119.386171 -385.336491) (xy 119.385588 -385.310888) (xy 118.843848 -385.310888) (xy 119.155972 -385.850892)
			(xy 119.168728 -385.874246) (xy 119.186834 -385.92428) (xy 119.196034 -385.976688) (xy 119.196612 -386.003292)
			(xy 119.196154 -386.027285) (xy 119.188649 -386.07468) (xy 119.173822 -386.120317) (xy 119.152038 -386.163073)
			(xy 119.123834 -386.201894) (xy 119.089903 -386.235826) (xy 119.051083 -386.264032) (xy 119.008328 -386.285817)
			(xy 118.962691 -386.300646) (xy 118.915297 -386.308154) (xy 118.891304 -386.3086) (xy 118.86773 -386.308203)
			(xy 118.821142 -386.300962) (xy 118.776223 -386.286637) (xy 118.734045 -386.265569) (xy 118.695612 -386.23826)
			(xy 118.66184 -386.205361) (xy 118.633535 -386.167656) (xy 118.622064 -386.147056) (xy 118.621556 -386.146294)
			(xy 118.223792 -385.457954) (xy 118.211857 -385.435295) (xy 118.194927 -385.386965) (xy 118.186275 -385.336491)
			(xy 118.185692 -385.310888) (xy 117.643698 -385.310888) (xy 117.955822 -385.850892) (xy 117.968645 -385.874225)
			(xy 117.986866 -385.924248) (xy 117.996127 -385.976673) (xy 117.996716 -386.003292) (xy 117.996254 -386.027297)
			(xy 117.98874 -386.074716) (xy 117.973898 -386.120375) (xy 117.952092 -386.163147) (xy 117.92386 -386.20198)
			(xy 117.889899 -386.235915) (xy 117.851044 -386.264117) (xy 117.808254 -386.285889) (xy 117.762584 -386.300696)
			(xy 117.71516 -386.308172) (xy 117.691154 -386.3086) (xy 117.667582 -386.308163) (xy 117.620995 -386.300929)
			(xy 117.576078 -386.286611) (xy 117.533899 -386.26555) (xy 117.495466 -386.238247) (xy 117.461693 -386.205353)
			(xy 117.433385 -386.167653) (xy 117.421914 -386.147056) (xy 117.421406 -386.146294) (xy 117.023642 -385.457954)
			(xy 117.011782 -385.435269) (xy 116.994926 -385.38694) (xy 116.986346 -385.33648) (xy 116.985796 -385.310888)
			(xy 116.443802 -385.310888) (xy 116.755926 -385.850892) (xy 116.76875 -385.874225) (xy 116.786971 -385.924247)
			(xy 116.796231 -385.976673) (xy 116.79682 -386.003292) (xy 116.796354 -386.027297) (xy 116.788841 -386.074716)
			(xy 116.773998 -386.120374) (xy 116.752193 -386.163146) (xy 116.723962 -386.201979) (xy 116.69 -386.235914)
			(xy 116.651146 -386.264115) (xy 116.608357 -386.285888) (xy 116.562688 -386.300695) (xy 116.515263 -386.308172)
			(xy 116.491258 -386.3086) (xy 116.467686 -386.308159) (xy 116.4211 -386.300927) (xy 116.376182 -386.286609)
			(xy 116.334004 -386.265548) (xy 116.29557 -386.238246) (xy 116.261797 -386.205353) (xy 116.23349 -386.167653)
			(xy 116.222018 -386.147056) (xy 116.22151 -386.146294) (xy 115.823746 -385.457954) (xy 115.811886 -385.435269)
			(xy 115.79503 -385.38694) (xy 115.78645 -385.33648) (xy 115.7859 -385.310888) (xy 115.243906 -385.310888)
			(xy 115.55603 -385.850892) (xy 115.568854 -385.874225) (xy 115.587075 -385.924247) (xy 115.596335 -385.976673)
			(xy 115.596924 -386.003292) (xy 115.596454 -386.027297) (xy 115.588941 -386.074715) (xy 115.574099 -386.120373)
			(xy 115.552294 -386.163145) (xy 115.524063 -386.201977) (xy 115.490102 -386.235912) (xy 115.451249 -386.264114)
			(xy 115.40846 -386.285887) (xy 115.362791 -386.300694) (xy 115.315367 -386.308172) (xy 115.291362 -386.3086)
			(xy 115.26779 -386.308156) (xy 115.221204 -386.300924) (xy 115.176286 -386.286607) (xy 115.134108 -386.265547)
			(xy 115.095674 -386.238245) (xy 115.061901 -386.205352) (xy 115.033594 -386.167653) (xy 115.022122 -386.147056)
			(xy 115.021614 -386.146294) (xy 114.62385 -385.457954) (xy 114.611991 -385.435269) (xy 114.595134 -385.38694)
			(xy 114.586554 -385.33648) (xy 114.586004 -385.310888) (xy 98.671676 -385.310888) (xy 98.9838 -385.850892)
			(xy 98.99655 -385.874249) (xy 99.01466 -385.924281) (xy 99.023862 -385.976688) (xy 99.02444 -386.003292)
			(xy 99.02393 -386.027281) (xy 99.016426 -386.07467) (xy 99.001602 -386.120301) (xy 98.979822 -386.163051)
			(xy 98.951623 -386.201869) (xy 98.917699 -386.235797) (xy 98.878886 -386.264001) (xy 98.836138 -386.285787)
			(xy 98.790509 -386.300617) (xy 98.743121 -386.308127) (xy 98.719132 -386.3086) (xy 98.695559 -386.30818)
			(xy 98.648972 -386.300944) (xy 98.604054 -386.286623) (xy 98.561875 -386.265558) (xy 98.523442 -386.238253)
			(xy 98.48967 -386.205357) (xy 98.461363 -386.167654) (xy 98.449892 -386.147056) (xy 98.449384 -386.146294)
			(xy 98.05162 -385.457954) (xy 98.039687 -385.435294) (xy 98.022756 -385.386965) (xy 98.014103 -385.336491)
			(xy 98.01352 -385.310888) (xy 97.471526 -385.310888) (xy 97.78365 -385.850892) (xy 97.796476 -385.874224)
			(xy 97.814695 -385.924247) (xy 97.823955 -385.976673) (xy 97.824544 -386.003292) (xy 97.824054 -386.027296)
			(xy 97.816541 -386.074712) (xy 97.801701 -386.120368) (xy 97.779897 -386.163139) (xy 97.751669 -386.20197)
			(xy 97.71771 -386.235905) (xy 97.67886 -386.264107) (xy 97.636074 -386.285881) (xy 97.590407 -386.30069)
			(xy 97.542986 -386.30817) (xy 97.518982 -386.3086) (xy 97.495407 -386.308221) (xy 97.448819 -386.300977)
			(xy 97.4039 -386.286648) (xy 97.361721 -386.265577) (xy 97.323288 -386.238265) (xy 97.289517 -386.205364)
			(xy 97.261212 -386.167657) (xy 97.249742 -386.147056) (xy 97.249234 -386.146294) (xy 96.85147 -385.457954)
			(xy 96.839612 -385.435268) (xy 96.822755 -385.386939) (xy 96.814174 -385.33648) (xy 96.813624 -385.310888)
			(xy 96.27163 -385.310888) (xy 96.583754 -385.850892) (xy 96.59658 -385.874224) (xy 96.614799 -385.924247)
			(xy 96.624059 -385.976673) (xy 96.624648 -386.003292) (xy 96.624154 -386.027296) (xy 96.616641 -386.074711)
			(xy 96.601801 -386.120367) (xy 96.579998 -386.163138) (xy 96.55177 -386.201969) (xy 96.517812 -386.235904)
			(xy 96.478962 -386.264106) (xy 96.436177 -386.28588) (xy 96.390511 -386.30069) (xy 96.34309 -386.30817)
			(xy 96.319086 -386.3086) (xy 96.295512 -386.308217) (xy 96.248923 -386.300974) (xy 96.204004 -386.286646)
			(xy 96.161826 -386.265576) (xy 96.123393 -386.238264) (xy 96.089621 -386.205363) (xy 96.061316 -386.167656)
			(xy 96.049846 -386.147056) (xy 96.049338 -386.146294) (xy 95.651574 -385.457954) (xy 95.639717 -385.435268)
			(xy 95.622859 -385.386939) (xy 95.614278 -385.336479) (xy 95.613728 -385.310888) (xy 95.07148 -385.310888)
			(xy 95.383604 -385.850892) (xy 95.396355 -385.874249) (xy 95.414464 -385.924281) (xy 95.423666 -385.976688)
			(xy 95.424244 -386.003292) (xy 95.42373 -386.027281) (xy 95.416226 -386.074669) (xy 95.401402 -386.1203)
			(xy 95.379623 -386.16305) (xy 95.351424 -386.201867) (xy 95.317501 -386.235796) (xy 95.278688 -386.264)
			(xy 95.235941 -386.285785) (xy 95.190312 -386.300616) (xy 95.142925 -386.308127) (xy 95.118936 -386.3086)
			(xy 95.095363 -386.308177) (xy 95.048776 -386.300941) (xy 95.003858 -386.286621) (xy 94.96168 -386.265557)
			(xy 94.923246 -386.238252) (xy 94.889474 -386.205356) (xy 94.861167 -386.167654) (xy 94.849696 -386.147056)
			(xy 94.849188 -386.146294) (xy 94.451424 -385.457954) (xy 94.439492 -385.435294) (xy 94.42256 -385.386965)
			(xy 94.413907 -385.336491) (xy 94.413324 -385.310888) (xy 93.871584 -385.310888) (xy 94.183708 -385.850892)
			(xy 94.196459 -385.874248) (xy 94.214568 -385.924281) (xy 94.22377 -385.976688) (xy 94.224348 -386.003292)
			(xy 94.22383 -386.027281) (xy 94.216326 -386.074669) (xy 94.201503 -386.120299) (xy 94.179724 -386.163049)
			(xy 94.151525 -386.201866) (xy 94.117603 -386.235794) (xy 94.07879 -386.263998) (xy 94.036043 -386.285784)
			(xy 93.990415 -386.300615) (xy 93.943029 -386.308126) (xy 93.91904 -386.3086) (xy 93.895467 -386.308174)
			(xy 93.84888 -386.300939) (xy 93.803963 -386.286618) (xy 93.761784 -386.265555) (xy 93.723351 -386.238251)
			(xy 93.689578 -386.205355) (xy 93.661271 -386.167654) (xy 93.6498 -386.147056) (xy 93.649292 -386.146294)
			(xy 93.251528 -385.457954) (xy 93.239596 -385.435294) (xy 93.222664 -385.386965) (xy 93.214011 -385.336491)
			(xy 93.213428 -385.310888) (xy 92.671688 -385.310888) (xy 92.983812 -385.850892) (xy 92.996563 -385.874248)
			(xy 93.014672 -385.924281) (xy 93.023874 -385.976688) (xy 93.024452 -386.003292) (xy 93.02393 -386.027281)
			(xy 93.016427 -386.074668) (xy 93.001603 -386.120298) (xy 92.979824 -386.163048) (xy 92.951627 -386.201865)
			(xy 92.917704 -386.235793) (xy 92.878892 -386.263997) (xy 92.836146 -386.285783) (xy 92.790519 -386.300614)
			(xy 92.743133 -386.308126) (xy 92.719144 -386.3086) (xy 92.695571 -386.308171) (xy 92.648985 -386.300936)
			(xy 92.604067 -386.286616) (xy 92.561889 -386.265554) (xy 92.523455 -386.238249) (xy 92.489682 -386.205355)
			(xy 92.461375 -386.167654) (xy 92.449904 -386.147056) (xy 92.449396 -386.146294) (xy 92.051632 -385.457954)
			(xy 92.0397 -385.435294) (xy 92.022768 -385.386965) (xy 92.014115 -385.336491) (xy 92.013532 -385.310888)
			(xy 91.471538 -385.310888) (xy 91.783662 -385.850892) (xy 91.796489 -385.874224) (xy 91.814708 -385.924247)
			(xy 91.823967 -385.976673) (xy 91.824556 -386.003292) (xy 91.824054 -386.027295) (xy 91.816542 -386.07471)
			(xy 91.801702 -386.120365) (xy 91.779899 -386.163135) (xy 91.751672 -386.201966) (xy 91.717715 -386.235901)
			(xy 91.678866 -386.264103) (xy 91.636082 -386.285878) (xy 91.590417 -386.300688) (xy 91.542998 -386.308169)
			(xy 91.518994 -386.3086) (xy 91.49542 -386.308211) (xy 91.448831 -386.300969) (xy 91.403913 -386.286642)
			(xy 91.361734 -386.265573) (xy 91.323301 -386.238262) (xy 91.28953 -386.205362) (xy 91.261224 -386.167656)
			(xy 91.249754 -386.147056) (xy 91.249246 -386.146294) (xy 90.851482 -385.457954) (xy 90.839625 -385.435268)
			(xy 90.822767 -385.386939) (xy 90.814186 -385.336479) (xy 90.813636 -385.310888) (xy 90.271642 -385.310888)
			(xy 90.583766 -385.850892) (xy 90.596593 -385.874223) (xy 90.614812 -385.924247) (xy 90.624071 -385.976673)
			(xy 90.62466 -386.003292) (xy 90.624253 -386.0273) (xy 90.616738 -386.074724) (xy 90.601893 -386.120388)
			(xy 90.580082 -386.163164) (xy 90.551844 -386.201999) (xy 90.517875 -386.235935) (xy 90.479013 -386.264136)
			(xy 90.436216 -386.285905) (xy 90.390538 -386.300707) (xy 90.343106 -386.308176) (xy 90.319098 -386.3086)
			(xy 90.295524 -386.308208) (xy 90.248936 -386.300966) (xy 90.204017 -386.28664) (xy 90.161839 -386.265571)
			(xy 90.123406 -386.238261) (xy 90.089634 -386.205361) (xy 90.061328 -386.167656) (xy 90.049858 -386.147056)
			(xy 90.04935 -386.146294) (xy 89.651586 -385.457954) (xy 89.63973 -385.435267) (xy 89.622871 -385.386939)
			(xy 89.61429 -385.336479) (xy 89.61374 -385.310888) (xy 89.071492 -385.310888) (xy 89.383616 -385.850892)
			(xy 89.396368 -385.874248) (xy 89.414476 -385.924281) (xy 89.423678 -385.976688) (xy 89.424256 -386.003292)
			(xy 89.42373 -386.027281) (xy 89.416227 -386.074667) (xy 89.401403 -386.120297) (xy 89.379625 -386.163047)
			(xy 89.351428 -386.201863) (xy 89.317506 -386.235791) (xy 89.278694 -386.263996) (xy 89.235949 -386.285782)
			(xy 89.190322 -386.300614) (xy 89.142937 -386.308126) (xy 89.118948 -386.3086) (xy 89.095375 -386.308168)
			(xy 89.048789 -386.300933) (xy 89.003871 -386.286614) (xy 88.961693 -386.265552) (xy 88.923259 -386.238248)
			(xy 88.889486 -386.205354) (xy 88.861179 -386.167654) (xy 88.849708 -386.147056) (xy 88.8492 -386.146294)
			(xy 88.451436 -385.457954) (xy 88.439505 -385.435294) (xy 88.422572 -385.386964) (xy 88.413919 -385.336491)
			(xy 88.413336 -385.310888) (xy 87.871596 -385.310888) (xy 88.18372 -385.850892) (xy 88.196472 -385.874248)
			(xy 88.21458 -385.924281) (xy 88.223782 -385.976688) (xy 88.22436 -386.003292) (xy 88.223954 -386.027287)
			(xy 88.216447 -386.074687) (xy 88.201617 -386.120329) (xy 88.179828 -386.163088) (xy 88.151618 -386.201912)
			(xy 88.117682 -386.235844) (xy 88.078854 -386.264049) (xy 88.036092 -386.285832) (xy 87.990448 -386.300657)
			(xy 87.943047 -386.308157) (xy 87.919052 -386.3086) (xy 87.895479 -386.308164) (xy 87.848893 -386.300931)
			(xy 87.803976 -386.286612) (xy 87.761797 -386.265551) (xy 87.723364 -386.238247) (xy 87.689591 -386.205354)
			(xy 87.661283 -386.167653) (xy 87.649812 -386.147056) (xy 87.649304 -386.146294) (xy 87.25154 -385.457954)
			(xy 87.239609 -385.435293) (xy 87.222676 -385.386964) (xy 87.214023 -385.336491) (xy 87.21344 -385.310888)
			(xy 86.6717 -385.310888) (xy 86.983824 -385.850892) (xy 86.996576 -385.874248) (xy 87.014684 -385.92428)
			(xy 87.023886 -385.976688) (xy 87.024464 -386.003292) (xy 87.024054 -386.027287) (xy 87.016547 -386.074687)
			(xy 87.001717 -386.120328) (xy 86.979929 -386.163087) (xy 86.951719 -386.201911) (xy 86.917783 -386.235843)
			(xy 86.878956 -386.264048) (xy 86.836195 -386.285831) (xy 86.790552 -386.300656) (xy 86.743151 -386.308157)
			(xy 86.719156 -386.3086) (xy 86.695584 -386.308161) (xy 86.648997 -386.300928) (xy 86.60408 -386.28661)
			(xy 86.561902 -386.265549) (xy 86.523468 -386.238246) (xy 86.489695 -386.205353) (xy 86.461387 -386.167653)
			(xy 86.449916 -386.147056) (xy 86.449408 -386.146294) (xy 86.051644 -385.457954) (xy 86.039713 -385.435293)
			(xy 86.02278 -385.386964) (xy 86.014127 -385.336491) (xy 86.013544 -385.310888) (xy 85.47155 -385.310888)
			(xy 85.783674 -385.850892) (xy 85.796501 -385.874223) (xy 85.81472 -385.924247) (xy 85.823979 -385.976673)
			(xy 85.824568 -386.003292) (xy 85.824153 -386.0273) (xy 85.816639 -386.074723) (xy 85.801793 -386.120386)
			(xy 85.779983 -386.163162) (xy 85.751746 -386.201996) (xy 85.717779 -386.235932) (xy 85.678917 -386.264133)
			(xy 85.636121 -386.285903) (xy 85.590445 -386.300706) (xy 85.543014 -386.308176) (xy 85.519006 -386.3086)
			(xy 85.495432 -386.308201) (xy 85.448844 -386.300961) (xy 85.403926 -386.286636) (xy 85.361747 -386.265568)
			(xy 85.323314 -386.238259) (xy 85.289542 -386.20536) (xy 85.261237 -386.167655) (xy 85.249766 -386.147056)
			(xy 85.249258 -386.146294) (xy 84.851494 -385.457954) (xy 84.839638 -385.435267) (xy 84.822779 -385.386939)
			(xy 84.814198 -385.336479) (xy 84.813648 -385.310888) (xy 84.271654 -385.310888) (xy 84.583778 -385.850892)
			(xy 84.596606 -385.874223) (xy 84.614824 -385.924247) (xy 84.624083 -385.976673) (xy 84.624672 -386.003292)
			(xy 84.624253 -386.027299) (xy 84.616739 -386.074723) (xy 84.601894 -386.120385) (xy 84.580084 -386.163161)
			(xy 84.551848 -386.201995) (xy 84.51788 -386.235931) (xy 84.47902 -386.264132) (xy 84.436224 -386.285902)
			(xy 84.390548 -386.300705) (xy 84.343118 -386.308175) (xy 84.31911 -386.3086) (xy 84.295536 -386.308198)
			(xy 84.248948 -386.300958) (xy 84.20403 -386.286634) (xy 84.161852 -386.265566) (xy 84.123418 -386.238258)
			(xy 84.089647 -386.20536) (xy 84.061341 -386.167655) (xy 84.04987 -386.147056) (xy 84.049362 -386.146294)
			(xy 83.651598 -385.457954) (xy 83.639742 -385.435267) (xy 83.622883 -385.386939) (xy 83.614302 -385.336479)
			(xy 83.613752 -385.310888) (xy 83.071504 -385.310888) (xy 83.383628 -385.850892) (xy 83.396381 -385.874247)
			(xy 83.414488 -385.92428) (xy 83.42369 -385.976688) (xy 83.424268 -386.003292) (xy 83.423854 -386.027287)
			(xy 83.416348 -386.074686) (xy 83.401518 -386.120327) (xy 83.37973 -386.163086) (xy 83.351521 -386.201909)
			(xy 83.317585 -386.235841) (xy 83.278758 -386.264047) (xy 83.235997 -386.28583) (xy 83.190355 -386.300655)
			(xy 83.142955 -386.308157) (xy 83.11896 -386.3086) (xy 83.095388 -386.308158) (xy 83.048802 -386.300925)
			(xy 83.003884 -386.286608) (xy 82.961706 -386.265548) (xy 82.923272 -386.238245) (xy 82.889499 -386.205353)
			(xy 82.861192 -386.167653) (xy 82.84972 -386.147056) (xy 82.849212 -386.146294) (xy 82.451448 -385.457954)
			(xy 82.439517 -385.435293) (xy 82.422585 -385.386964) (xy 82.413931 -385.336491) (xy 82.413348 -385.310888)
			(xy 81.871608 -385.310888) (xy 82.183732 -385.850892) (xy 82.196485 -385.874247) (xy 82.214593 -385.92428)
			(xy 82.223794 -385.976688) (xy 82.224372 -386.003292) (xy 82.223954 -386.027287) (xy 82.216448 -386.074685)
			(xy 82.201618 -386.120326) (xy 82.179831 -386.163085) (xy 82.151622 -386.201908) (xy 82.117687 -386.23584)
			(xy 82.078861 -386.264045) (xy 82.0361 -386.285829) (xy 81.990458 -386.300654) (xy 81.943059 -386.308156)
			(xy 81.919064 -386.3086) (xy 81.895492 -386.308155) (xy 81.848906 -386.300923) (xy 81.803989 -386.286606)
			(xy 81.76181 -386.265546) (xy 81.723376 -386.238244) (xy 81.689603 -386.205352) (xy 81.661296 -386.167653)
			(xy 81.649824 -386.147056) (xy 81.649316 -386.146294) (xy 81.251552 -385.457954) (xy 81.239622 -385.435293)
			(xy 81.222689 -385.386964) (xy 81.214035 -385.336491) (xy 81.213452 -385.310888) (xy 80.671712 -385.310888)
			(xy 80.983836 -385.850892) (xy 80.996589 -385.874247) (xy 81.014697 -385.92428) (xy 81.023898 -385.976688)
			(xy 81.024476 -386.003292) (xy 81.024054 -386.027287) (xy 81.016548 -386.074685) (xy 81.001718 -386.120325)
			(xy 80.979931 -386.163083) (xy 80.951723 -386.201907) (xy 80.917788 -386.235839) (xy 80.878963 -386.264044)
			(xy 80.836203 -386.285828) (xy 80.790561 -386.300653) (xy 80.743163 -386.308156) (xy 80.719168 -386.3086)
			(xy 80.695596 -386.308151) (xy 80.64901 -386.30092) (xy 80.604093 -386.286604) (xy 80.561915 -386.265545)
			(xy 80.523481 -386.238243) (xy 80.489707 -386.205351) (xy 80.4614 -386.167653) (xy 80.449928 -386.147056)
			(xy 80.44942 -386.146294) (xy 80.051656 -385.457954) (xy 80.039726 -385.435293) (xy 80.022793 -385.386964)
			(xy 80.014139 -385.336491) (xy 80.013556 -385.310888) (xy 66.144182 -385.310888) (xy 66.456306 -385.850892)
			(xy 66.469128 -385.874226) (xy 66.48735 -385.924248) (xy 66.496611 -385.976674) (xy 66.4972 -386.003292)
			(xy 66.496754 -386.027298) (xy 66.48924 -386.074718) (xy 66.474396 -386.120378) (xy 66.452589 -386.163152)
			(xy 66.424356 -386.201985) (xy 66.390392 -386.235921) (xy 66.351535 -386.264122) (xy 66.308743 -386.285894)
			(xy 66.263071 -386.300699) (xy 66.215644 -386.308173) (xy 66.191638 -386.3086) (xy 66.191384 -386.3086)
			(xy 66.16781 -386.308219) (xy 66.121221 -386.300975) (xy 66.076302 -386.286647) (xy 66.034123 -386.265576)
			(xy 65.995691 -386.238265) (xy 65.961919 -386.205363) (xy 65.933614 -386.167656) (xy 65.922144 -386.147056)
			(xy 65.921636 -386.146294) (xy 65.523872 -385.457954) (xy 65.511936 -385.435296) (xy 65.495006 -385.386965)
			(xy 65.486355 -385.336492) (xy 65.485772 -385.310888) (xy 64.944032 -385.310888) (xy 65.256156 -385.850892)
			(xy 65.268911 -385.874246) (xy 65.287017 -385.92428) (xy 65.296218 -385.976688) (xy 65.296796 -386.003292)
			(xy 65.296354 -386.027286) (xy 65.288848 -386.074682) (xy 65.27402 -386.12032) (xy 65.252235 -386.163077)
			(xy 65.224029 -386.2019) (xy 65.190097 -386.235831) (xy 65.151274 -386.264037) (xy 65.108517 -386.285822)
			(xy 65.062878 -386.300649) (xy 65.015482 -386.308155) (xy 64.991488 -386.3086) (xy 64.991234 -386.3086)
			(xy 64.967661 -386.308179) (xy 64.921074 -386.300942) (xy 64.876156 -386.286622) (xy 64.833978 -386.265557)
			(xy 64.795544 -386.238252) (xy 64.761772 -386.205356) (xy 64.733465 -386.167654) (xy 64.721994 -386.147056)
			(xy 64.721486 -386.146294) (xy 64.323722 -385.457954) (xy 64.311861 -385.43527) (xy 64.295005 -385.38694)
			(xy 64.286426 -385.33648) (xy 64.285876 -385.310888) (xy 63.744136 -385.310888) (xy 64.05626 -385.850892)
			(xy 64.069015 -385.874246) (xy 64.087121 -385.92428) (xy 64.096322 -385.976688) (xy 64.0969 -386.003292)
			(xy 64.096454 -386.027285) (xy 64.088949 -386.074681) (xy 64.074121 -386.12032) (xy 64.052336 -386.163076)
			(xy 64.02413 -386.201898) (xy 63.990198 -386.23583) (xy 63.951376 -386.264036) (xy 63.90862 -386.285821)
			(xy 63.862981 -386.300649) (xy 63.815585 -386.308154) (xy 63.791592 -386.3086) (xy 63.791338 -386.3086)
			(xy 63.767765 -386.308176) (xy 63.721178 -386.30094) (xy 63.67626 -386.28662) (xy 63.634082 -386.265556)
			(xy 63.595648 -386.238251) (xy 63.561876 -386.205356) (xy 63.533569 -386.167654) (xy 63.522098 -386.147056)
			(xy 63.52159 -386.146294) (xy 63.123826 -385.457954) (xy 63.111965 -385.43527) (xy 63.095109 -385.38694)
			(xy 63.08653 -385.33648) (xy 63.08598 -385.310888) (xy 62.543986 -385.310888) (xy 62.85611 -385.850892)
			(xy 62.868932 -385.874226) (xy 62.887154 -385.924248) (xy 62.896415 -385.976673) (xy 62.897004 -386.003292)
			(xy 62.896554 -386.027298) (xy 62.88904 -386.074718) (xy 62.874197 -386.120377) (xy 62.85239 -386.163151)
			(xy 62.824157 -386.201984) (xy 62.790194 -386.23592) (xy 62.751337 -386.264121) (xy 62.708546 -386.285893)
			(xy 62.662874 -386.300698) (xy 62.615448 -386.308173) (xy 62.591442 -386.3086) (xy 62.591188 -386.3086)
			(xy 62.567614 -386.308216) (xy 62.521025 -386.300973) (xy 62.476106 -386.286645) (xy 62.433928 -386.265575)
			(xy 62.395495 -386.238264) (xy 62.361723 -386.205363) (xy 62.333418 -386.167656) (xy 62.321948 -386.147056)
			(xy 62.32144 -386.146294) (xy 61.923676 -385.457954) (xy 61.91174 -385.435296) (xy 61.89481 -385.386965)
			(xy 61.886159 -385.336492) (xy 61.885576 -385.310888) (xy 61.34409 -385.310888) (xy 61.656214 -385.850892)
			(xy 61.669037 -385.874226) (xy 61.687258 -385.924248) (xy 61.696519 -385.976673) (xy 61.697108 -386.003292)
			(xy 61.696654 -386.027298) (xy 61.68914 -386.074717) (xy 61.674297 -386.120377) (xy 61.652491 -386.16315)
			(xy 61.624258 -386.201983) (xy 61.590295 -386.235918) (xy 61.55144 -386.264119) (xy 61.508649 -386.285891)
			(xy 61.462978 -386.300698) (xy 61.415552 -386.308173) (xy 61.391546 -386.3086) (xy 61.391292 -386.3086)
			(xy 61.367718 -386.308213) (xy 61.321129 -386.30097) (xy 61.27621 -386.286643) (xy 61.234032 -386.265573)
			(xy 61.195599 -386.238263) (xy 61.161828 -386.205362) (xy 61.133522 -386.167656) (xy 61.122052 -386.147056)
			(xy 61.121544 -386.146294) (xy 60.72378 -385.457954) (xy 60.711844 -385.435296) (xy 60.694915 -385.386965)
			(xy 60.686263 -385.336492) (xy 60.68568 -385.310888) (xy 60.144194 -385.310888) (xy 60.456318 -385.850892)
			(xy 60.469141 -385.874226) (xy 60.487362 -385.924248) (xy 60.496623 -385.976673) (xy 60.497212 -386.003292)
			(xy 60.496754 -386.027297) (xy 60.48924 -386.074717) (xy 60.474398 -386.120376) (xy 60.452591 -386.163149)
			(xy 60.424359 -386.201981) (xy 60.390397 -386.235917) (xy 60.351542 -386.264118) (xy 60.308752 -386.28589)
			(xy 60.263081 -386.300697) (xy 60.215656 -386.308172) (xy 60.19165 -386.3086) (xy 60.191396 -386.3086)
			(xy 60.167822 -386.308209) (xy 60.121233 -386.300967) (xy 60.076315 -386.286641) (xy 60.034136 -386.265572)
			(xy 59.995703 -386.238262) (xy 59.961932 -386.205362) (xy 59.933626 -386.167656) (xy 59.922156 -386.147056)
			(xy 59.921648 -386.146294) (xy 59.523884 -385.457954) (xy 59.511948 -385.435296) (xy 59.495019 -385.386965)
			(xy 59.486367 -385.336492) (xy 59.485784 -385.310888) (xy 58.944044 -385.310888) (xy 59.256168 -385.850892)
			(xy 59.268924 -385.874246) (xy 59.28703 -385.92428) (xy 59.29623 -385.976688) (xy 59.296808 -386.003292)
			(xy 59.296354 -386.027285) (xy 59.288849 -386.07468) (xy 59.274021 -386.120318) (xy 59.252237 -386.163074)
			(xy 59.224032 -386.201896) (xy 59.190102 -386.235827) (xy 59.151281 -386.264033) (xy 59.108525 -386.285818)
			(xy 59.062888 -386.300647) (xy 59.015493 -386.308154) (xy 58.9915 -386.3086) (xy 58.991246 -386.3086)
			(xy 58.967673 -386.308169) (xy 58.921087 -386.300935) (xy 58.876169 -386.286615) (xy 58.833991 -386.265553)
			(xy 58.795557 -386.238249) (xy 58.761784 -386.205355) (xy 58.733477 -386.167654) (xy 58.722006 -386.147056)
			(xy 58.721498 -386.146294) (xy 58.323734 -385.457954) (xy 58.311874 -385.43527) (xy 58.295018 -385.38694)
			(xy 58.286438 -385.33648) (xy 58.285888 -385.310888) (xy 57.744148 -385.310888) (xy 58.056272 -385.850892)
			(xy 58.069028 -385.874246) (xy 58.087134 -385.92428) (xy 58.096334 -385.976688) (xy 58.096912 -386.003292)
			(xy 58.096454 -386.027285) (xy 58.088949 -386.07468) (xy 58.074122 -386.120317) (xy 58.052338 -386.163073)
			(xy 58.024134 -386.201894) (xy 57.990203 -386.235826) (xy 57.951383 -386.264032) (xy 57.908628 -386.285817)
			(xy 57.862991 -386.300646) (xy 57.815597 -386.308154) (xy 57.791604 -386.3086) (xy 57.79135 -386.3086)
			(xy 57.767777 -386.308166) (xy 57.721191 -386.300932) (xy 57.676273 -386.286613) (xy 57.634095 -386.265551)
			(xy 57.595661 -386.238248) (xy 57.561888 -386.205354) (xy 57.533581 -386.167653) (xy 57.52211 -386.147056)
			(xy 57.521602 -386.146294) (xy 57.123838 -385.457954) (xy 57.111978 -385.435269) (xy 57.095122 -385.38694)
			(xy 57.086542 -385.33648) (xy 57.085992 -385.310888) (xy 56.543744 -385.310888) (xy 56.855868 -385.850892)
			(xy 56.868624 -385.874246) (xy 56.88673 -385.92428) (xy 56.89593 -385.976688) (xy 56.896508 -386.003292)
			(xy 56.896054 -386.027285) (xy 56.888549 -386.07468) (xy 56.873721 -386.120318) (xy 56.851937 -386.163074)
			(xy 56.823732 -386.201896) (xy 56.789802 -386.235827) (xy 56.750981 -386.264033) (xy 56.708225 -386.285818)
			(xy 56.662588 -386.300647) (xy 56.615193 -386.308154) (xy 56.5912 -386.3086) (xy 56.567626 -386.308206)
			(xy 56.521038 -386.300965) (xy 56.476119 -386.286639) (xy 56.433941 -386.26557) (xy 56.395508 -386.238261)
			(xy 56.361736 -386.205361) (xy 56.33343 -386.167656) (xy 56.32196 -386.147056) (xy 56.321452 -386.146294)
			(xy 55.923688 -385.457954) (xy 55.911753 -385.435296) (xy 55.894823 -385.386965) (xy 55.886171 -385.336491)
			(xy 55.885588 -385.310888) (xy 55.343848 -385.310888) (xy 55.655972 -385.850892) (xy 55.668728 -385.874246)
			(xy 55.686834 -385.92428) (xy 55.696034 -385.976688) (xy 55.696612 -386.003292) (xy 55.696154 -386.027285)
			(xy 55.688649 -386.07468) (xy 55.673822 -386.120317) (xy 55.652038 -386.163073) (xy 55.623834 -386.201894)
			(xy 55.589903 -386.235826) (xy 55.551083 -386.264032) (xy 55.508328 -386.285817) (xy 55.462691 -386.300646)
			(xy 55.415297 -386.308154) (xy 55.391304 -386.3086) (xy 55.36773 -386.308203) (xy 55.321142 -386.300962)
			(xy 55.276223 -386.286637) (xy 55.234045 -386.265569) (xy 55.195612 -386.23826) (xy 55.16184 -386.205361)
			(xy 55.133535 -386.167656) (xy 55.122064 -386.147056) (xy 55.121556 -386.146294) (xy 54.723792 -385.457954)
			(xy 54.711857 -385.435295) (xy 54.694927 -385.386965) (xy 54.686275 -385.336491) (xy 54.685692 -385.310888)
			(xy 54.143952 -385.310888) (xy 54.456076 -385.850892) (xy 54.468824 -385.87425) (xy 54.486935 -385.924281)
			(xy 54.496138 -385.976688) (xy 54.496716 -386.003292) (xy 54.49623 -386.027283) (xy 54.488725 -386.074673)
			(xy 54.4739 -386.120306) (xy 54.452118 -386.163059) (xy 54.423916 -386.201877) (xy 54.389989 -386.235806)
			(xy 54.351172 -386.264009) (xy 54.308421 -386.285793) (xy 54.262789 -386.300622) (xy 54.215399 -386.308129)
			(xy 54.191408 -386.3086) (xy 54.167834 -386.3082) (xy 54.121246 -386.30096) (xy 54.076328 -386.286635)
			(xy 54.034149 -386.265567) (xy 53.995716 -386.238259) (xy 53.961944 -386.20536) (xy 53.933639 -386.167655)
			(xy 53.922168 -386.147056) (xy 53.92166 -386.146294) (xy 53.523896 -385.457954) (xy 53.511961 -385.435295)
			(xy 53.495031 -385.386965) (xy 53.486379 -385.336491) (xy 53.485796 -385.310888) (xy 52.943802 -385.310888)
			(xy 53.255926 -385.850892) (xy 53.26875 -385.874225) (xy 53.286971 -385.924247) (xy 53.296231 -385.976673)
			(xy 53.29682 -386.003292) (xy 53.296354 -386.027297) (xy 53.288841 -386.074716) (xy 53.273998 -386.120374)
			(xy 53.252193 -386.163146) (xy 53.223962 -386.201979) (xy 53.19 -386.235914) (xy 53.151146 -386.264115)
			(xy 53.108357 -386.285888) (xy 53.062688 -386.300695) (xy 53.015263 -386.308172) (xy 52.991258 -386.3086)
			(xy 52.967686 -386.308159) (xy 52.9211 -386.300927) (xy 52.876182 -386.286609) (xy 52.834004 -386.265548)
			(xy 52.79557 -386.238246) (xy 52.761797 -386.205353) (xy 52.73349 -386.167653) (xy 52.722018 -386.147056)
			(xy 52.72151 -386.146294) (xy 52.323746 -385.457954) (xy 52.311886 -385.435269) (xy 52.29503 -385.38694)
			(xy 52.28645 -385.33648) (xy 52.2859 -385.310888) (xy 51.743906 -385.310888) (xy 52.05603 -385.850892)
			(xy 52.068854 -385.874225) (xy 52.087075 -385.924247) (xy 52.096335 -385.976673) (xy 52.096924 -386.003292)
			(xy 52.096454 -386.027297) (xy 52.088941 -386.074715) (xy 52.074099 -386.120373) (xy 52.052294 -386.163145)
			(xy 52.024063 -386.201977) (xy 51.990102 -386.235912) (xy 51.951249 -386.264114) (xy 51.90846 -386.285887)
			(xy 51.862791 -386.300694) (xy 51.815367 -386.308172) (xy 51.791362 -386.3086) (xy 51.76779 -386.308156)
			(xy 51.721204 -386.300924) (xy 51.676286 -386.286607) (xy 51.634108 -386.265547) (xy 51.595674 -386.238245)
			(xy 51.561901 -386.205352) (xy 51.533594 -386.167653) (xy 51.522122 -386.147056) (xy 51.521614 -386.146294)
			(xy 51.12385 -385.457954) (xy 51.111991 -385.435269) (xy 51.095134 -385.38694) (xy 51.086554 -385.33648)
			(xy 51.086004 -385.310888) (xy 50.543756 -385.310888) (xy 50.85588 -385.850892) (xy 50.868629 -385.87425)
			(xy 50.886739 -385.924281) (xy 50.895942 -385.976688) (xy 50.89652 -386.003292) (xy 50.89603 -386.027282)
			(xy 50.888526 -386.074673) (xy 50.8737 -386.120306) (xy 50.851918 -386.163057) (xy 50.823717 -386.201876)
			(xy 50.789791 -386.235804) (xy 50.750974 -386.264008) (xy 50.708224 -386.285792) (xy 50.662592 -386.300621)
			(xy 50.615202 -386.308128) (xy 50.591212 -386.3086) (xy 50.567638 -386.308197) (xy 50.521051 -386.300957)
			(xy 50.476132 -386.286633) (xy 50.433954 -386.265566) (xy 50.395521 -386.238258) (xy 50.361749 -386.205359)
			(xy 50.333443 -386.167655) (xy 50.321972 -386.147056) (xy 50.321464 -386.146294) (xy 49.9237 -385.457954)
			(xy 49.911766 -385.435295) (xy 49.894835 -385.386965) (xy 49.886183 -385.336491) (xy 49.8856 -385.310888)
			(xy 49.34386 -385.310888) (xy 49.655984 -385.850892) (xy 49.668733 -385.874249) (xy 49.686843 -385.924281)
			(xy 49.696046 -385.976688) (xy 49.696624 -386.003292) (xy 49.69613 -386.027282) (xy 49.688626 -386.074672)
			(xy 49.6738 -386.120305) (xy 49.652019 -386.163056) (xy 49.623818 -386.201874) (xy 49.589892 -386.235803)
			(xy 49.551077 -386.264007) (xy 49.508327 -386.285791) (xy 49.462695 -386.30062) (xy 49.415306 -386.308128)
			(xy 49.391316 -386.3086) (xy 49.367742 -386.308193) (xy 49.321155 -386.300954) (xy 49.276236 -386.286631)
			(xy 49.234058 -386.265564) (xy 49.195625 -386.238257) (xy 49.161853 -386.205359) (xy 49.133547 -386.167655)
			(xy 49.122076 -386.147056) (xy 49.121568 -386.146294) (xy 48.723804 -385.457954) (xy 48.71187 -385.435295)
			(xy 48.694939 -385.386965) (xy 48.686287 -385.336491) (xy 48.685704 -385.310888) (xy 48.143964 -385.310888)
			(xy 48.456088 -385.850892) (xy 48.468837 -385.874249) (xy 48.486947 -385.924281) (xy 48.49615 -385.976688)
			(xy 48.496728 -386.003292) (xy 48.49623 -386.027282) (xy 48.488726 -386.074672) (xy 48.473901 -386.120304)
			(xy 48.45212 -386.163055) (xy 48.42392 -386.201873) (xy 48.389994 -386.235801) (xy 48.351179 -386.264005)
			(xy 48.30843 -386.28579) (xy 48.262799 -386.300619) (xy 48.21541 -386.308128) (xy 48.19142 -386.3086)
			(xy 48.167847 -386.30819) (xy 48.121259 -386.300952) (xy 48.076341 -386.286629) (xy 48.034162 -386.265563)
			(xy 47.995729 -386.238256) (xy 47.961957 -386.205358) (xy 47.933651 -386.167655) (xy 47.92218 -386.147056)
			(xy 47.921672 -386.146294) (xy 47.523908 -385.457954) (xy 47.511974 -385.435295) (xy 47.495043 -385.386965)
			(xy 47.486391 -385.336491) (xy 47.485808 -385.310888) (xy 2.509012 -385.310888) (xy 2.509012 -387.789674)
			(xy 40.901112 -387.789674) (xy 40.901112 -386.926074) (xy 40.901598 -386.898805) (xy 40.90936 -386.844821)
			(xy 40.924725 -386.792491) (xy 40.947382 -386.742881) (xy 40.976868 -386.697) (xy 41.012583 -386.655783)
			(xy 41.0538 -386.620068) (xy 41.099681 -386.590582) (xy 41.149291 -386.567925) (xy 41.201621 -386.55256)
			(xy 41.255605 -386.544798) (xy 41.310143 -386.544798) (xy 41.364127 -386.55256) (xy 41.416457 -386.567925)
			(xy 41.466067 -386.590582) (xy 41.511948 -386.620068) (xy 41.553165 -386.655783) (xy 41.58888 -386.697)
			(xy 41.618366 -386.742881) (xy 41.641023 -386.792491) (xy 41.656388 -386.844821) (xy 41.66415 -386.898805)
			(xy 41.664636 -386.926074) (xy 41.664636 -387.789674) (xy 73.42886 -387.789674) (xy 73.42886 -386.926074)
			(xy 73.429346 -386.898805) (xy 73.437108 -386.844821) (xy 73.452473 -386.792491) (xy 73.47513 -386.742881)
			(xy 73.504616 -386.697) (xy 73.540331 -386.655783) (xy 73.581548 -386.620068) (xy 73.627429 -386.590582)
			(xy 73.677039 -386.567925) (xy 73.729369 -386.55256) (xy 73.783353 -386.544798) (xy 73.837891 -386.544798)
			(xy 73.891875 -386.55256) (xy 73.944205 -386.567925) (xy 73.993815 -386.590582) (xy 74.039696 -386.620068)
			(xy 74.080913 -386.655783) (xy 74.116628 -386.697) (xy 74.146114 -386.742881) (xy 74.168771 -386.792491)
			(xy 74.184136 -386.844821) (xy 74.191898 -386.898805) (xy 74.192384 -386.926074) (xy 74.192384 -387.789674)
			(xy 108.001308 -387.789674) (xy 108.001308 -386.926074) (xy 108.001794 -386.898823) (xy 108.00955 -386.844875)
			(xy 108.024905 -386.79258) (xy 108.047547 -386.743003) (xy 108.077013 -386.697153) (xy 108.112704 -386.655962)
			(xy 108.153895 -386.620271) (xy 108.199745 -386.590805) (xy 108.249322 -386.568163) (xy 108.301617 -386.552808)
			(xy 108.355565 -386.545052) (xy 108.410067 -386.545052) (xy 108.464015 -386.552808) (xy 108.51631 -386.568163)
			(xy 108.565887 -386.590805) (xy 108.611737 -386.620271) (xy 108.652928 -386.655962) (xy 108.688619 -386.697153)
			(xy 108.718085 -386.743003) (xy 108.740727 -386.79258) (xy 108.756082 -386.844875) (xy 108.763838 -386.898823)
			(xy 108.764324 -386.926074) (xy 108.764324 -387.789674) (xy 140.529056 -387.789674) (xy 140.529056 -386.926074)
			(xy 140.529542 -386.898823) (xy 140.537298 -386.844875) (xy 140.552653 -386.79258) (xy 140.575295 -386.743003)
			(xy 140.604761 -386.697153) (xy 140.640452 -386.655962) (xy 140.681643 -386.620271) (xy 140.727493 -386.590805)
			(xy 140.77707 -386.568163) (xy 140.829365 -386.552808) (xy 140.883313 -386.545052) (xy 140.937815 -386.545052)
			(xy 140.991763 -386.552808) (xy 141.044058 -386.568163) (xy 141.093635 -386.590805) (xy 141.139485 -386.620271)
			(xy 141.180676 -386.655962) (xy 141.216367 -386.697153) (xy 141.245833 -386.743003) (xy 141.268475 -386.79258)
			(xy 141.28383 -386.844875) (xy 141.291586 -386.898823) (xy 141.292072 -386.926074) (xy 141.292072 -387.789674)
			(xy 141.291586 -387.816925) (xy 141.28383 -387.870873) (xy 141.268475 -387.923168) (xy 141.245833 -387.972745)
			(xy 141.216367 -388.018595) (xy 141.180676 -388.059786) (xy 141.139485 -388.095477) (xy 141.093635 -388.124943)
			(xy 141.044058 -388.147585) (xy 140.991763 -388.16294) (xy 140.937815 -388.170696) (xy 140.883313 -388.170696)
			(xy 140.829365 -388.16294) (xy 140.77707 -388.147585) (xy 140.727493 -388.124943) (xy 140.681643 -388.095477)
			(xy 140.640452 -388.059786) (xy 140.604761 -388.018595) (xy 140.575295 -387.972745) (xy 140.552653 -387.923168)
			(xy 140.537298 -387.870873) (xy 140.529542 -387.816925) (xy 140.529056 -387.789674) (xy 108.764324 -387.789674)
			(xy 108.763838 -387.816925) (xy 108.756082 -387.870873) (xy 108.740727 -387.923168) (xy 108.718085 -387.972745)
			(xy 108.688619 -388.018595) (xy 108.652928 -388.059786) (xy 108.611737 -388.095477) (xy 108.565887 -388.124943)
			(xy 108.51631 -388.147585) (xy 108.464015 -388.16294) (xy 108.410067 -388.170696) (xy 108.355565 -388.170696)
			(xy 108.301617 -388.16294) (xy 108.249322 -388.147585) (xy 108.199745 -388.124943) (xy 108.153895 -388.095477)
			(xy 108.112704 -388.059786) (xy 108.077013 -388.018595) (xy 108.047547 -387.972745) (xy 108.024905 -387.923168)
			(xy 108.00955 -387.870873) (xy 108.001794 -387.816925) (xy 108.001308 -387.789674) (xy 74.192384 -387.789674)
			(xy 74.191898 -387.816943) (xy 74.184136 -387.870927) (xy 74.168771 -387.923257) (xy 74.146114 -387.972867)
			(xy 74.116628 -388.018748) (xy 74.080913 -388.059965) (xy 74.039696 -388.09568) (xy 73.993815 -388.125166)
			(xy 73.944205 -388.147823) (xy 73.891875 -388.163188) (xy 73.837891 -388.17095) (xy 73.783353 -388.17095)
			(xy 73.729369 -388.163188) (xy 73.677039 -388.147823) (xy 73.627429 -388.125166) (xy 73.581548 -388.09568)
			(xy 73.540331 -388.059965) (xy 73.504616 -388.018748) (xy 73.47513 -387.972867) (xy 73.452473 -387.923257)
			(xy 73.437108 -387.870927) (xy 73.429346 -387.816943) (xy 73.42886 -387.789674) (xy 41.664636 -387.789674)
			(xy 41.66415 -387.816943) (xy 41.656388 -387.870927) (xy 41.641023 -387.923257) (xy 41.618366 -387.972867)
			(xy 41.58888 -388.018748) (xy 41.553165 -388.059965) (xy 41.511948 -388.09568) (xy 41.466067 -388.125166)
			(xy 41.416457 -388.147823) (xy 41.364127 -388.163188) (xy 41.310143 -388.17095) (xy 41.255605 -388.17095)
			(xy 41.201621 -388.163188) (xy 41.149291 -388.147823) (xy 41.099681 -388.125166) (xy 41.0538 -388.09568)
			(xy 41.012583 -388.059965) (xy 40.976868 -388.018748) (xy 40.947382 -387.972867) (xy 40.924725 -387.923257)
			(xy 40.90936 -387.870927) (xy 40.901598 -387.816943) (xy 40.901112 -387.789674) (xy 2.509012 -387.789674)
			(xy 2.509012 -388.77494) (xy 47.485808 -388.77494) (xy 47.485808 -388.774432) (xy 47.486269 -388.750426)
			(xy 47.493779 -388.703006) (xy 47.50862 -388.657346) (xy 47.530425 -388.614571) (xy 47.558656 -388.575737)
			(xy 47.592619 -388.541801) (xy 47.631475 -388.5136) (xy 47.674266 -388.491828) (xy 47.719938 -388.477023)
			(xy 47.767364 -388.46955) (xy 47.79137 -388.469124) (xy 47.815307 -388.469547) (xy 47.862595 -388.477009)
			(xy 47.90814 -388.491756) (xy 47.950828 -388.513426) (xy 47.989613 -388.541489) (xy 48.023547 -388.575259)
			(xy 48.051798 -388.613907) (xy 48.06315 -388.634986) (xy 48.063658 -388.636002) (xy 48.143964 -388.77494)
			(xy 48.685704 -388.77494) (xy 48.685704 -388.774432) (xy 48.686169 -388.750426) (xy 48.693679 -388.703006)
			(xy 48.708519 -388.657347) (xy 48.730324 -388.614573) (xy 48.758555 -388.575739) (xy 48.792517 -388.541803)
			(xy 48.831372 -388.513601) (xy 48.874163 -388.49183) (xy 48.919834 -388.477024) (xy 48.96726 -388.46955)
			(xy 48.991266 -388.469124) (xy 49.015203 -388.46955) (xy 49.06249 -388.477012) (xy 49.108036 -388.491758)
			(xy 49.150724 -388.513428) (xy 49.189509 -388.54149) (xy 49.223443 -388.575259) (xy 49.251694 -388.613908)
			(xy 49.263046 -388.634986) (xy 49.263554 -388.636002) (xy 49.34386 -388.77494) (xy 49.8856 -388.77494)
			(xy 49.8856 -388.774432) (xy 49.886069 -388.750427) (xy 49.893579 -388.703007) (xy 49.908419 -388.657347)
			(xy 49.930223 -388.614574) (xy 49.958454 -388.57574) (xy 49.992415 -388.541804) (xy 50.03127 -388.513603)
			(xy 50.07406 -388.491831) (xy 50.119731 -388.477025) (xy 50.167156 -388.469551) (xy 50.191162 -388.469124)
			(xy 50.215098 -388.469553) (xy 50.262386 -388.477014) (xy 50.307931 -388.49176) (xy 50.350619 -388.513429)
			(xy 50.389405 -388.541491) (xy 50.423338 -388.57526) (xy 50.45159 -388.613908) (xy 50.462942 -388.634986)
			(xy 50.46345 -388.636002) (xy 50.543756 -388.77494) (xy 51.086004 -388.77494) (xy 51.086004 -388.774432)
			(xy 51.086468 -388.750439) (xy 51.09397 -388.703044) (xy 51.108795 -388.657405) (xy 51.130577 -388.614648)
			(xy 51.158781 -388.575826) (xy 51.192711 -388.541894) (xy 51.231531 -388.513688) (xy 51.274287 -388.491903)
			(xy 51.319924 -388.477075) (xy 51.367319 -388.469569) (xy 51.391312 -388.469124) (xy 51.415247 -388.469594)
			(xy 51.462533 -388.477047) (xy 51.508077 -388.491786) (xy 51.550765 -388.513448) (xy 51.589551 -388.541504)
			(xy 51.623486 -388.575267) (xy 51.651739 -388.61391) (xy 51.663092 -388.634986) (xy 51.6636 -388.636002)
			(xy 51.743906 -388.77494) (xy 52.2859 -388.77494) (xy 52.2859 -388.774432) (xy 52.286368 -388.750439)
			(xy 52.29387 -388.703044) (xy 52.308695 -388.657406) (xy 52.330477 -388.61465) (xy 52.35868 -388.575827)
			(xy 52.392609 -388.541895) (xy 52.431429 -388.513689) (xy 52.474184 -388.491904) (xy 52.519821 -388.477076)
			(xy 52.567215 -388.46957) (xy 52.591208 -388.469124) (xy 52.615143 -388.469597) (xy 52.662429 -388.47705)
			(xy 52.707973 -388.491788) (xy 52.750661 -388.51345) (xy 52.789447 -388.541505) (xy 52.823382 -388.575268)
			(xy 52.851635 -388.61391) (xy 52.862988 -388.634986) (xy 52.863496 -388.636002) (xy 52.943802 -388.77494)
			(xy 53.485796 -388.77494) (xy 53.485796 -388.774432) (xy 53.486269 -388.750427) (xy 53.493779 -388.703008)
			(xy 53.508618 -388.657348) (xy 53.530422 -388.614575) (xy 53.558653 -388.575742) (xy 53.592614 -388.541806)
			(xy 53.631468 -388.513604) (xy 53.674258 -388.491832) (xy 53.719928 -388.477026) (xy 53.767353 -388.469551)
			(xy 53.791358 -388.469124) (xy 53.815294 -388.469556) (xy 53.862582 -388.477017) (xy 53.908127 -388.491762)
			(xy 53.950815 -388.513431) (xy 53.9896 -388.541492) (xy 54.023534 -388.57526) (xy 54.051786 -388.613908)
			(xy 54.063138 -388.634986) (xy 54.063646 -388.636002) (xy 54.143952 -388.77494) (xy 54.685692 -388.77494)
			(xy 54.685692 -388.774432) (xy 54.686169 -388.750427) (xy 54.693678 -388.703008) (xy 54.708518 -388.657349)
			(xy 54.730322 -388.614576) (xy 54.758552 -388.575743) (xy 54.792512 -388.541807) (xy 54.831366 -388.513605)
			(xy 54.874155 -388.491833) (xy 54.919824 -388.477027) (xy 54.967249 -388.469551) (xy 54.991254 -388.469124)
			(xy 55.01519 -388.46956) (xy 55.062478 -388.47702) (xy 55.108023 -388.491764) (xy 55.150711 -388.513432)
			(xy 55.189496 -388.541493) (xy 55.22343 -388.575261) (xy 55.251681 -388.613908) (xy 55.263034 -388.634986)
			(xy 55.263542 -388.636002) (xy 55.343848 -388.77494) (xy 55.885588 -388.77494) (xy 55.885588 -388.774432)
			(xy 55.886069 -388.750427) (xy 55.893578 -388.703009) (xy 55.908418 -388.65735) (xy 55.930221 -388.614577)
			(xy 55.95845 -388.575744) (xy 55.99241 -388.541809) (xy 56.031263 -388.513607) (xy 56.074052 -388.491834)
			(xy 56.119721 -388.477027) (xy 56.167145 -388.469552) (xy 56.19115 -388.469124) (xy 56.215086 -388.469563)
			(xy 56.262373 -388.477022) (xy 56.307918 -388.491766) (xy 56.350606 -388.513434) (xy 56.389392 -388.541494)
			(xy 56.423326 -388.575262) (xy 56.451577 -388.613908) (xy 56.46293 -388.634986) (xy 56.463438 -388.636002)
			(xy 56.543744 -388.77494) (xy 57.085992 -388.77494) (xy 57.085992 -388.774432) (xy 57.086468 -388.75044)
			(xy 57.09397 -388.703045) (xy 57.108794 -388.657408) (xy 57.130575 -388.614652) (xy 57.158777 -388.57583)
			(xy 57.192706 -388.541898) (xy 57.231525 -388.513692) (xy 57.274279 -388.491906) (xy 57.319914 -388.477077)
			(xy 57.367308 -388.46957) (xy 57.3913 -388.469124) (xy 57.415235 -388.469603) (xy 57.46252 -388.477055)
			(xy 57.508064 -388.491792) (xy 57.550752 -388.513453) (xy 57.589538 -388.541507) (xy 57.623473 -388.575269)
			(xy 57.651726 -388.613911) (xy 57.66308 -388.634986) (xy 57.663588 -388.636002) (xy 57.743894 -388.77494)
			(xy 58.285888 -388.77494) (xy 58.285888 -388.774432) (xy 58.286368 -388.75044) (xy 58.29387 -388.703046)
			(xy 58.308693 -388.657409) (xy 58.330474 -388.614653) (xy 58.358676 -388.575831) (xy 58.392604 -388.5419)
			(xy 58.431423 -388.513693) (xy 58.474176 -388.491907) (xy 58.519811 -388.477078) (xy 58.567204 -388.469571)
			(xy 58.591196 -388.469124) (xy 58.615133 -388.469526) (xy 58.662423 -388.476992) (xy 58.707968 -388.491742)
			(xy 58.750656 -388.513416) (xy 58.789441 -388.541483) (xy 58.823374 -388.575255) (xy 58.851624 -388.613906)
			(xy 58.862976 -388.634986) (xy 58.863484 -388.636002) (xy 58.94379 -388.77494) (xy 59.485784 -388.77494)
			(xy 59.485784 -388.774432) (xy 59.486269 -388.750427) (xy 59.493778 -388.703009) (xy 59.508617 -388.657351)
			(xy 59.53042 -388.614578) (xy 59.558649 -388.575746) (xy 59.592609 -388.54181) (xy 59.631461 -388.513608)
			(xy 59.674249 -388.491835) (xy 59.719918 -388.477028) (xy 59.767341 -388.469552) (xy 59.791346 -388.469124)
			(xy 59.815282 -388.469566) (xy 59.862569 -388.477025) (xy 59.908114 -388.491768) (xy 59.950802 -388.513435)
			(xy 59.989587 -388.541495) (xy 60.023522 -388.575262) (xy 60.051773 -388.613909) (xy 60.063126 -388.634986)
			(xy 60.063634 -388.636002) (xy 60.14394 -388.77494) (xy 60.68568 -388.77494) (xy 60.68568 -388.774432)
			(xy 60.686169 -388.750428) (xy 60.693678 -388.70301) (xy 60.708517 -388.657352) (xy 60.730319 -388.61458)
			(xy 60.758548 -388.575747) (xy 60.792507 -388.541811) (xy 60.831359 -388.51361) (xy 60.874146 -388.491836)
			(xy 60.919814 -388.477029) (xy 60.967237 -388.469552) (xy 60.991242 -388.469124) (xy 61.015178 -388.469569)
			(xy 61.062465 -388.477028) (xy 61.10801 -388.49177) (xy 61.150697 -388.513437) (xy 61.189483 -388.541496)
			(xy 61.223417 -388.575263) (xy 61.251669 -388.613909) (xy 61.263022 -388.634986) (xy 61.26353 -388.636002)
			(xy 61.343836 -388.77494) (xy 61.885576 -388.77494) (xy 61.885576 -388.774432) (xy 61.886069 -388.750428)
			(xy 61.893578 -388.703011) (xy 61.908417 -388.657353) (xy 61.930219 -388.614581) (xy 61.958447 -388.575748)
			(xy 61.992405 -388.541813) (xy 62.031257 -388.513611) (xy 62.074044 -388.491838) (xy 62.119711 -388.47703)
			(xy 62.167134 -388.469552) (xy 62.191138 -388.469124) (xy 62.215074 -388.469573) (xy 62.262361 -388.47703)
			(xy 62.307905 -388.491772) (xy 62.350593 -388.513438) (xy 62.389379 -388.541498) (xy 62.423313 -388.575263)
			(xy 62.451565 -388.613909) (xy 62.462918 -388.634986) (xy 62.463426 -388.636002) (xy 62.543732 -388.77494)
			(xy 63.08598 -388.77494) (xy 63.08598 -388.774432) (xy 63.086468 -388.75044) (xy 63.093969 -388.703047)
			(xy 63.108793 -388.657411) (xy 63.130573 -388.614656) (xy 63.158774 -388.575834) (xy 63.192701 -388.541902)
			(xy 63.231518 -388.513696) (xy 63.27427 -388.49191) (xy 63.319904 -388.47708) (xy 63.367296 -388.469571)
			(xy 63.391288 -388.469124) (xy 63.415225 -388.469532) (xy 63.462514 -388.476997) (xy 63.50806 -388.491747)
			(xy 63.550747 -388.513419) (xy 63.589533 -388.541485) (xy 63.623466 -388.575256) (xy 63.651716 -388.613907)
			(xy 63.663068 -388.634986) (xy 63.663576 -388.636002) (xy 63.743882 -388.77494) (xy 64.285876 -388.77494)
			(xy 64.285876 -388.774432) (xy 64.286368 -388.750441) (xy 64.293869 -388.703048) (xy 64.308692 -388.657412)
			(xy 64.330472 -388.614657) (xy 64.358673 -388.575836) (xy 64.392599 -388.541904) (xy 64.431416 -388.513697)
			(xy 64.474167 -388.491911) (xy 64.519801 -388.47708) (xy 64.567193 -388.469571) (xy 64.591184 -388.469124)
			(xy 64.615121 -388.469535) (xy 64.66241 -388.477) (xy 64.707955 -388.491749) (xy 64.750643 -388.513421)
			(xy 64.789428 -388.541486) (xy 64.823361 -388.575257) (xy 64.851612 -388.613907) (xy 64.862964 -388.634986)
			(xy 64.863472 -388.636002) (xy 64.943778 -388.77494) (xy 65.485772 -388.77494) (xy 65.485772 -388.774432)
			(xy 65.486269 -388.750428) (xy 65.493778 -388.703011) (xy 65.508616 -388.657354) (xy 65.530418 -388.614582)
			(xy 65.558646 -388.57575) (xy 65.592604 -388.541814) (xy 65.631455 -388.513612) (xy 65.674241 -388.491839)
			(xy 65.719908 -388.477031) (xy 65.76733 -388.469553) (xy 65.791334 -388.469124) (xy 65.81527 -388.469576)
			(xy 65.862556 -388.477033) (xy 65.908101 -388.491774) (xy 65.950789 -388.51344) (xy 65.989575 -388.541499)
			(xy 66.023509 -388.575264) (xy 66.051761 -388.613909) (xy 66.063114 -388.634986) (xy 66.063622 -388.636002)
			(xy 66.143928 -388.77494) (xy 80.013556 -388.77494) (xy 80.013556 -388.774432) (xy 80.014068 -388.750429)
			(xy 80.021577 -388.703013) (xy 80.036415 -388.657358) (xy 80.058215 -388.614587) (xy 80.086441 -388.575755)
			(xy 80.120397 -388.54182) (xy 80.159246 -388.513618) (xy 80.20203 -388.491843) (xy 80.247695 -388.477034)
			(xy 80.295115 -388.469554) (xy 80.319118 -388.469124) (xy 80.343053 -388.469589) (xy 80.390339 -388.477043)
			(xy 80.435884 -388.491783) (xy 80.478571 -388.513446) (xy 80.517357 -388.541503) (xy 80.551292 -388.575266)
			(xy 80.579545 -388.61391) (xy 80.590898 -388.634986) (xy 80.591406 -388.636002) (xy 80.671712 -388.77494)
			(xy 81.213452 -388.77494) (xy 81.213452 -388.774432) (xy 81.213968 -388.750429) (xy 81.221477 -388.703014)
			(xy 81.236314 -388.657359) (xy 81.258114 -388.614588) (xy 81.28634 -388.575757) (xy 81.320295 -388.541822)
			(xy 81.359144 -388.513619) (xy 81.401927 -388.491845) (xy 81.447591 -388.477035) (xy 81.495011 -388.469554)
			(xy 81.519014 -388.469124) (xy 81.542949 -388.469592) (xy 81.590235 -388.477046) (xy 81.635779 -388.491785)
			(xy 81.678467 -388.513447) (xy 81.717253 -388.541504) (xy 81.751188 -388.575267) (xy 81.779441 -388.61391)
			(xy 81.790794 -388.634986) (xy 81.791302 -388.636002) (xy 81.871608 -388.77494) (xy 82.413348 -388.77494)
			(xy 82.413348 -388.774432) (xy 82.413868 -388.750429) (xy 82.421377 -388.703015) (xy 82.436214 -388.65736)
			(xy 82.458014 -388.614589) (xy 82.486239 -388.575758) (xy 82.520194 -388.541823) (xy 82.559041 -388.51362)
			(xy 82.601824 -388.491846) (xy 82.647488 -388.477035) (xy 82.694907 -388.469555) (xy 82.71891 -388.469124)
			(xy 82.742845 -388.469595) (xy 82.790131 -388.477049) (xy 82.835675 -388.491787) (xy 82.878363 -388.513449)
			(xy 82.917149 -388.541505) (xy 82.951084 -388.575267) (xy 82.979337 -388.61391) (xy 82.99069 -388.634986)
			(xy 82.991198 -388.636002) (xy 83.071504 -388.77494) (xy 83.613752 -388.77494) (xy 83.613752 -388.774432)
			(xy 83.614292 -388.750444) (xy 83.621792 -388.703057) (xy 83.636613 -388.657427) (xy 83.658389 -388.614677)
			(xy 83.686584 -388.57586) (xy 83.720505 -388.541931) (xy 83.759315 -388.513726) (xy 83.80206 -388.49194)
			(xy 83.847687 -388.477109) (xy 83.895072 -388.469598) (xy 83.91906 -388.469124) (xy 83.942996 -388.469555)
			(xy 83.990284 -388.477016) (xy 84.035829 -388.491761) (xy 84.078517 -388.51343) (xy 84.117303 -388.541492)
			(xy 84.151236 -388.57526) (xy 84.179488 -388.613908) (xy 84.19084 -388.634986) (xy 84.191348 -388.636002)
			(xy 84.271654 -388.77494) (xy 84.813648 -388.77494) (xy 84.813648 -388.774432) (xy 84.814192 -388.750444)
			(xy 84.821692 -388.703057) (xy 84.836512 -388.657428) (xy 84.858288 -388.614678) (xy 84.886483 -388.575861)
			(xy 84.920403 -388.541933) (xy 84.959213 -388.513728) (xy 85.001957 -388.491941) (xy 85.047583 -388.47711)
			(xy 85.094968 -388.469598) (xy 85.118956 -388.469124) (xy 85.142892 -388.469558) (xy 85.19018 -388.477018)
			(xy 85.235725 -388.491763) (xy 85.278413 -388.513431) (xy 85.317198 -388.541493) (xy 85.351132 -388.575261)
			(xy 85.379383 -388.613908) (xy 85.390736 -388.634986) (xy 85.391244 -388.636002) (xy 85.47155 -388.77494)
			(xy 86.013544 -388.77494) (xy 86.013544 -388.774432) (xy 86.014068 -388.750429) (xy 86.021577 -388.703015)
			(xy 86.036414 -388.65736) (xy 86.058213 -388.61459) (xy 86.086438 -388.575759) (xy 86.120392 -388.541824)
			(xy 86.159239 -388.513622) (xy 86.202021 -388.491847) (xy 86.247685 -388.477036) (xy 86.295103 -388.469555)
			(xy 86.319106 -388.469124) (xy 86.343041 -388.469599) (xy 86.390326 -388.477051) (xy 86.435871 -388.491789)
			(xy 86.478558 -388.51345) (xy 86.517345 -388.541506) (xy 86.55128 -388.575268) (xy 86.579533 -388.61391)
			(xy 86.590886 -388.634986) (xy 86.591394 -388.636002) (xy 86.6717 -388.77494) (xy 87.21344 -388.77494)
			(xy 87.21344 -388.774432) (xy 87.213869 -388.750425) (xy 87.22138 -388.703001) (xy 87.236223 -388.657338)
			(xy 87.25803 -388.614562) (xy 87.286266 -388.575726) (xy 87.320232 -388.54179) (xy 87.359092 -388.513589)
			(xy 87.401888 -388.491819) (xy 87.447564 -388.477017) (xy 87.494994 -388.469548) (xy 87.519002 -388.469124)
			(xy 87.542937 -388.469602) (xy 87.590222 -388.477054) (xy 87.635766 -388.491791) (xy 87.678454 -388.513452)
			(xy 87.71724 -388.541507) (xy 87.751175 -388.575268) (xy 87.779429 -388.61391) (xy 87.790782 -388.634986)
			(xy 87.79129 -388.636002) (xy 87.871596 -388.77494) (xy 88.413336 -388.77494) (xy 88.413336 -388.774432)
			(xy 88.413769 -388.750425) (xy 88.42128 -388.703002) (xy 88.436122 -388.657339) (xy 88.45793 -388.614563)
			(xy 88.486164 -388.575728) (xy 88.52013 -388.541791) (xy 88.55899 -388.51359) (xy 88.601785 -388.49182)
			(xy 88.647461 -388.477018) (xy 88.69489 -388.469548) (xy 88.718898 -388.469124) (xy 88.742835 -388.469524)
			(xy 88.790125 -388.476991) (xy 88.835671 -388.491741) (xy 88.878358 -388.513415) (xy 88.917143 -388.541482)
			(xy 88.951076 -388.575255) (xy 88.979326 -388.613906) (xy 88.990678 -388.634986) (xy 88.991186 -388.636002)
			(xy 89.071492 -388.77494) (xy 89.61374 -388.77494) (xy 89.61374 -388.774432) (xy 89.614168 -388.750437)
			(xy 89.621671 -388.703038) (xy 89.636498 -388.657397) (xy 89.658284 -388.614638) (xy 89.686491 -388.575814)
			(xy 89.720426 -388.541881) (xy 89.759251 -388.513676) (xy 89.802012 -388.491892) (xy 89.847654 -388.477068)
			(xy 89.895053 -388.469567) (xy 89.919048 -388.469124) (xy 89.942984 -388.469565) (xy 89.990271 -388.477024)
			(xy 90.035816 -388.491767) (xy 90.078504 -388.513434) (xy 90.11729 -388.541495) (xy 90.151224 -388.575262)
			(xy 90.179475 -388.613908) (xy 90.190828 -388.634986) (xy 90.191336 -388.636002) (xy 90.271642 -388.77494)
			(xy 90.813636 -388.77494) (xy 90.813636 -388.774432) (xy 90.814068 -388.750438) (xy 90.821571 -388.703039)
			(xy 90.836398 -388.657398) (xy 90.858183 -388.614639) (xy 90.88639 -388.575815) (xy 90.920324 -388.541882)
			(xy 90.959149 -388.513677) (xy 91.001909 -388.491893) (xy 91.047551 -388.477068) (xy 91.09495 -388.469567)
			(xy 91.118944 -388.469124) (xy 91.14288 -388.469568) (xy 91.190167 -388.477026) (xy 91.235712 -388.491769)
			(xy 91.2784 -388.513436) (xy 91.317185 -388.541496) (xy 91.351119 -388.575262) (xy 91.379371 -388.613909)
			(xy 91.390724 -388.634986) (xy 91.391232 -388.636002) (xy 91.471538 -388.77494) (xy 92.013532 -388.77494)
			(xy 92.013532 -388.774432) (xy 92.013969 -388.750425) (xy 92.02148 -388.703002) (xy 92.036322 -388.65734)
			(xy 92.058129 -388.614564) (xy 92.086363 -388.575729) (xy 92.120329 -388.541793) (xy 92.159188 -388.513592)
			(xy 92.201983 -388.491822) (xy 92.247658 -388.477019) (xy 92.295087 -388.469548) (xy 92.319094 -388.469124)
			(xy 92.343031 -388.469527) (xy 92.39032 -388.476993) (xy 92.435866 -388.491744) (xy 92.478554 -388.513417)
			(xy 92.517339 -388.541483) (xy 92.551272 -388.575255) (xy 92.579522 -388.613906) (xy 92.590874 -388.634986)
			(xy 92.591382 -388.636002) (xy 92.671688 -388.77494) (xy 93.213428 -388.77494) (xy 93.213428 -388.774432)
			(xy 93.213869 -388.750425) (xy 93.22138 -388.703003) (xy 93.236222 -388.657341) (xy 93.258028 -388.614565)
			(xy 93.286262 -388.575731) (xy 93.320227 -388.541794) (xy 93.359086 -388.513593) (xy 93.40188 -388.491823)
			(xy 93.447554 -388.477019) (xy 93.494983 -388.469549) (xy 93.51899 -388.469124) (xy 93.542927 -388.46953)
			(xy 93.590216 -388.476996) (xy 93.635762 -388.491746) (xy 93.67845 -388.513419) (xy 93.717235 -388.541484)
			(xy 93.751168 -388.575256) (xy 93.779418 -388.613907) (xy 93.79077 -388.634986) (xy 93.791278 -388.636002)
			(xy 93.871584 -388.77494) (xy 94.413324 -388.77494) (xy 94.413324 -388.774432) (xy 94.413769 -388.750425)
			(xy 94.42128 -388.703004) (xy 94.436121 -388.657342) (xy 94.457927 -388.614567) (xy 94.486161 -388.575732)
			(xy 94.520125 -388.541796) (xy 94.558983 -388.513595) (xy 94.601777 -388.491824) (xy 94.647451 -388.47702)
			(xy 94.694879 -388.469549) (xy 94.718886 -388.469124) (xy 94.742823 -388.469534) (xy 94.790112 -388.476998)
			(xy 94.835657 -388.491748) (xy 94.878345 -388.51342) (xy 94.91713 -388.541485) (xy 94.951064 -388.575256)
			(xy 94.979314 -388.613907) (xy 94.990666 -388.634986) (xy 94.991174 -388.636002) (xy 95.07148 -388.77494)
			(xy 95.613728 -388.77494) (xy 95.613728 -388.774432) (xy 95.614168 -388.750438) (xy 95.621671 -388.70304)
			(xy 95.636497 -388.6574) (xy 95.658282 -388.614641) (xy 95.686488 -388.575818) (xy 95.720421 -388.541885)
			(xy 95.759245 -388.51368) (xy 95.802004 -388.491896) (xy 95.847644 -388.47707) (xy 95.895042 -388.469568)
			(xy 95.919036 -388.469124) (xy 95.942972 -388.469574) (xy 95.990258 -388.477031) (xy 96.035803 -388.491773)
			(xy 96.078491 -388.513439) (xy 96.117277 -388.541498) (xy 96.151211 -388.575264) (xy 96.179463 -388.613909)
			(xy 96.190816 -388.634986) (xy 96.191324 -388.636002) (xy 96.27163 -388.77494) (xy 96.813624 -388.77494)
			(xy 96.813624 -388.774432) (xy 96.814068 -388.750438) (xy 96.821571 -388.703041) (xy 96.836397 -388.657401)
			(xy 96.858181 -388.614643) (xy 96.886387 -388.575819) (xy 96.920319 -388.541887) (xy 96.959143 -388.513681)
			(xy 97.001901 -388.491897) (xy 97.047541 -388.477071) (xy 97.094938 -388.469568) (xy 97.118932 -388.469124)
			(xy 97.142868 -388.469578) (xy 97.190154 -388.477034) (xy 97.235699 -388.491775) (xy 97.278387 -388.51344)
			(xy 97.317172 -388.541499) (xy 97.351107 -388.575264) (xy 97.379359 -388.613909) (xy 97.390712 -388.634986)
			(xy 97.39122 -388.636002) (xy 97.471526 -388.77494) (xy 98.01352 -388.77494) (xy 98.01352 -388.774432)
			(xy 98.013969 -388.750426) (xy 98.021479 -388.703004) (xy 98.036321 -388.657343) (xy 98.058127 -388.614568)
			(xy 98.08636 -388.575733) (xy 98.120324 -388.541797) (xy 98.159181 -388.513596) (xy 98.201974 -388.491825)
			(xy 98.247648 -388.477021) (xy 98.295075 -388.469549) (xy 98.319082 -388.469124) (xy 98.343019 -388.469537)
			(xy 98.390308 -388.477001) (xy 98.435853 -388.49175) (xy 98.478541 -388.513422) (xy 98.517326 -388.541486)
			(xy 98.551259 -388.575257) (xy 98.57951 -388.613907) (xy 98.590862 -388.634986) (xy 98.59137 -388.636002)
			(xy 98.671676 -388.77494) (xy 114.586004 -388.77494) (xy 114.586004 -388.774432) (xy 114.586468 -388.750439)
			(xy 114.59397 -388.703044) (xy 114.608795 -388.657405) (xy 114.630577 -388.614648) (xy 114.658781 -388.575826)
			(xy 114.692711 -388.541894) (xy 114.731531 -388.513688) (xy 114.774287 -388.491903) (xy 114.819924 -388.477075)
			(xy 114.867319 -388.469569) (xy 114.891312 -388.469124) (xy 114.915247 -388.469594) (xy 114.962533 -388.477047)
			(xy 115.008077 -388.491786) (xy 115.050765 -388.513448) (xy 115.089551 -388.541504) (xy 115.123486 -388.575267)
			(xy 115.151739 -388.61391) (xy 115.163092 -388.634986) (xy 115.1636 -388.636002) (xy 115.243906 -388.77494)
			(xy 115.7859 -388.77494) (xy 115.7859 -388.774432) (xy 115.786368 -388.750439) (xy 115.79387 -388.703044)
			(xy 115.808695 -388.657406) (xy 115.830477 -388.61465) (xy 115.85868 -388.575827) (xy 115.892609 -388.541895)
			(xy 115.931429 -388.513689) (xy 115.974184 -388.491904) (xy 116.019821 -388.477076) (xy 116.067215 -388.46957)
			(xy 116.091208 -388.469124) (xy 116.115143 -388.469597) (xy 116.162429 -388.47705) (xy 116.207973 -388.491788)
			(xy 116.250661 -388.51345) (xy 116.289447 -388.541505) (xy 116.323382 -388.575268) (xy 116.351635 -388.61391)
			(xy 116.362988 -388.634986) (xy 116.363496 -388.636002) (xy 116.443802 -388.77494) (xy 116.985796 -388.77494)
			(xy 116.985796 -388.774432) (xy 116.986268 -388.75044) (xy 116.99377 -388.703045) (xy 117.008594 -388.657407)
			(xy 117.030376 -388.614651) (xy 117.058578 -388.575829) (xy 117.092507 -388.541897) (xy 117.131327 -388.513691)
			(xy 117.174081 -388.491905) (xy 117.219717 -388.477076) (xy 117.267112 -388.46957) (xy 117.291104 -388.469124)
			(xy 117.315039 -388.4696) (xy 117.362324 -388.477053) (xy 117.407868 -388.49179) (xy 117.450556 -388.513451)
			(xy 117.489342 -388.541506) (xy 117.523277 -388.575268) (xy 117.551531 -388.61391) (xy 117.562884 -388.634986)
			(xy 117.563392 -388.636002) (xy 117.643698 -388.77494) (xy 118.185692 -388.77494) (xy 118.185692 -388.774432)
			(xy 118.186169 -388.750427) (xy 118.193678 -388.703008) (xy 118.208518 -388.657349) (xy 118.230322 -388.614576)
			(xy 118.258552 -388.575743) (xy 118.292512 -388.541807) (xy 118.331366 -388.513605) (xy 118.374155 -388.491833)
			(xy 118.419824 -388.477027) (xy 118.467249 -388.469551) (xy 118.491254 -388.469124) (xy 118.51519 -388.46956)
			(xy 118.562478 -388.47702) (xy 118.608023 -388.491764) (xy 118.650711 -388.513432) (xy 118.689496 -388.541493)
			(xy 118.72343 -388.575261) (xy 118.751681 -388.613908) (xy 118.763034 -388.634986) (xy 118.763542 -388.636002)
			(xy 118.843848 -388.77494) (xy 119.385588 -388.77494) (xy 119.385588 -388.774432) (xy 119.386069 -388.750427)
			(xy 119.393578 -388.703009) (xy 119.408418 -388.65735) (xy 119.430221 -388.614577) (xy 119.45845 -388.575744)
			(xy 119.49241 -388.541809) (xy 119.531263 -388.513607) (xy 119.574052 -388.491834) (xy 119.619721 -388.477027)
			(xy 119.667145 -388.469552) (xy 119.69115 -388.469124) (xy 119.715086 -388.469563) (xy 119.762373 -388.477022)
			(xy 119.807918 -388.491766) (xy 119.850606 -388.513434) (xy 119.889392 -388.541494) (xy 119.923326 -388.575262)
			(xy 119.951577 -388.613908) (xy 119.96293 -388.634986) (xy 119.963438 -388.636002) (xy 120.043744 -388.77494)
			(xy 120.585992 -388.77494) (xy 120.585992 -388.774432) (xy 120.586468 -388.75044) (xy 120.59397 -388.703045)
			(xy 120.608794 -388.657408) (xy 120.630575 -388.614652) (xy 120.658777 -388.57583) (xy 120.692706 -388.541898)
			(xy 120.731525 -388.513692) (xy 120.774279 -388.491906) (xy 120.819914 -388.477077) (xy 120.867308 -388.46957)
			(xy 120.8913 -388.469124) (xy 120.915235 -388.469603) (xy 120.96252 -388.477055) (xy 121.008064 -388.491792)
			(xy 121.050752 -388.513453) (xy 121.089538 -388.541507) (xy 121.123473 -388.575269) (xy 121.151726 -388.613911)
			(xy 121.16308 -388.634986) (xy 121.163588 -388.636002) (xy 121.243894 -388.77494) (xy 121.785888 -388.77494)
			(xy 121.785888 -388.774432) (xy 121.786368 -388.75044) (xy 121.79387 -388.703046) (xy 121.808693 -388.657409)
			(xy 121.830474 -388.614653) (xy 121.858676 -388.575831) (xy 121.892604 -388.5419) (xy 121.931423 -388.513693)
			(xy 121.974176 -388.491907) (xy 122.019811 -388.477078) (xy 122.067204 -388.469571) (xy 122.091196 -388.469124)
			(xy 122.115133 -388.469526) (xy 122.162423 -388.476992) (xy 122.207968 -388.491742) (xy 122.250656 -388.513416)
			(xy 122.289441 -388.541483) (xy 122.323374 -388.575255) (xy 122.351624 -388.613906) (xy 122.362976 -388.634986)
			(xy 122.363484 -388.636002) (xy 122.44379 -388.77494) (xy 122.985784 -388.77494) (xy 122.985784 -388.774432)
			(xy 122.986268 -388.75044) (xy 122.993769 -388.703046) (xy 123.008593 -388.65741) (xy 123.030374 -388.614654)
			(xy 123.058575 -388.575833) (xy 123.092502 -388.541901) (xy 123.13132 -388.513695) (xy 123.174073 -388.491908)
			(xy 123.219708 -388.477079) (xy 123.2671 -388.469571) (xy 123.291092 -388.469124) (xy 123.315029 -388.469529)
			(xy 123.362318 -388.476995) (xy 123.407864 -388.491745) (xy 123.450552 -388.513418) (xy 123.489337 -388.541484)
			(xy 123.52327 -388.575256) (xy 123.55152 -388.613906) (xy 123.562872 -388.634986) (xy 123.56338 -388.636002)
			(xy 123.643686 -388.77494) (xy 124.18568 -388.77494) (xy 124.18568 -388.774432) (xy 124.186169 -388.750428)
			(xy 124.193678 -388.70301) (xy 124.208517 -388.657352) (xy 124.230319 -388.61458) (xy 124.258548 -388.575747)
			(xy 124.292507 -388.541811) (xy 124.331359 -388.51361) (xy 124.374146 -388.491836) (xy 124.419814 -388.477029)
			(xy 124.467237 -388.469552) (xy 124.491242 -388.469124) (xy 124.515178 -388.469569) (xy 124.562465 -388.477028)
			(xy 124.60801 -388.49177) (xy 124.650697 -388.513437) (xy 124.689483 -388.541496) (xy 124.723417 -388.575263)
			(xy 124.751669 -388.613909) (xy 124.763022 -388.634986) (xy 124.76353 -388.636002) (xy 124.843836 -388.77494)
			(xy 125.385576 -388.77494) (xy 125.385576 -388.774432) (xy 125.386069 -388.750428) (xy 125.393578 -388.703011)
			(xy 125.408417 -388.657353) (xy 125.430219 -388.614581) (xy 125.458447 -388.575748) (xy 125.492405 -388.541813)
			(xy 125.531257 -388.513611) (xy 125.574044 -388.491838) (xy 125.619711 -388.47703) (xy 125.667134 -388.469552)
			(xy 125.691138 -388.469124) (xy 125.715074 -388.469573) (xy 125.762361 -388.47703) (xy 125.807905 -388.491772)
			(xy 125.850593 -388.513438) (xy 125.889379 -388.541498) (xy 125.923313 -388.575263) (xy 125.951565 -388.613909)
			(xy 125.962918 -388.634986) (xy 125.963426 -388.636002) (xy 126.043732 -388.77494) (xy 126.58598 -388.77494)
			(xy 126.58598 -388.774432) (xy 126.586468 -388.75044) (xy 126.593969 -388.703047) (xy 126.608793 -388.657411)
			(xy 126.630573 -388.614656) (xy 126.658774 -388.575834) (xy 126.692701 -388.541902) (xy 126.731518 -388.513696)
			(xy 126.77427 -388.49191) (xy 126.819904 -388.47708) (xy 126.867296 -388.469571) (xy 126.891288 -388.469124)
			(xy 126.915225 -388.469532) (xy 126.962514 -388.476997) (xy 127.00806 -388.491747) (xy 127.050747 -388.513419)
			(xy 127.089533 -388.541485) (xy 127.123466 -388.575256) (xy 127.151716 -388.613907) (xy 127.163068 -388.634986)
			(xy 127.163576 -388.636002) (xy 127.243882 -388.77494) (xy 127.785876 -388.77494) (xy 127.785876 -388.774432)
			(xy 127.786368 -388.750441) (xy 127.793869 -388.703048) (xy 127.808692 -388.657412) (xy 127.830472 -388.614657)
			(xy 127.858673 -388.575836) (xy 127.892599 -388.541904) (xy 127.931416 -388.513697) (xy 127.974167 -388.491911)
			(xy 128.019801 -388.47708) (xy 128.067193 -388.469571) (xy 128.091184 -388.469124) (xy 128.115121 -388.469535)
			(xy 128.16241 -388.477) (xy 128.207955 -388.491749) (xy 128.250643 -388.513421) (xy 128.289428 -388.541486)
			(xy 128.323361 -388.575257) (xy 128.351612 -388.613907) (xy 128.362964 -388.634986) (xy 128.363472 -388.636002)
			(xy 128.443778 -388.77494) (xy 128.985772 -388.77494) (xy 128.985772 -388.774432) (xy 128.986268 -388.750441)
			(xy 128.993769 -388.703048) (xy 129.008592 -388.657413) (xy 129.030372 -388.614658) (xy 129.058571 -388.575837)
			(xy 129.092497 -388.541905) (xy 129.131314 -388.513699) (xy 129.174065 -388.491912) (xy 129.219698 -388.477081)
			(xy 129.267089 -388.469572) (xy 129.29108 -388.469124) (xy 129.315017 -388.469539) (xy 129.362305 -388.477002)
			(xy 129.407851 -388.491751) (xy 129.450539 -388.513422) (xy 129.489324 -388.541487) (xy 129.523257 -388.575257)
			(xy 129.551508 -388.613907) (xy 129.56286 -388.634986) (xy 129.563368 -388.636002) (xy 129.643674 -388.77494)
			(xy 130.185668 -388.77494) (xy 130.185668 -388.774432) (xy 130.186169 -388.750428) (xy 130.193678 -388.703012)
			(xy 130.208516 -388.657355) (xy 130.230317 -388.614583) (xy 130.258545 -388.575751) (xy 130.292502 -388.541816)
			(xy 130.331352 -388.513614) (xy 130.374138 -388.49184) (xy 130.419805 -388.477031) (xy 130.467226 -388.469553)
			(xy 130.49123 -388.469124) (xy 130.515165 -388.469579) (xy 130.562452 -388.477035) (xy 130.607997 -388.491776)
			(xy 130.650684 -388.513441) (xy 130.68947 -388.5415) (xy 130.723405 -388.575264) (xy 130.751657 -388.613909)
			(xy 130.76301 -388.634986) (xy 130.763518 -388.636002) (xy 130.843824 -388.77494) (xy 131.385564 -388.77494)
			(xy 131.385564 -388.774432) (xy 131.386069 -388.750428) (xy 131.393578 -388.703012) (xy 131.408415 -388.657356)
			(xy 131.430217 -388.614584) (xy 131.458443 -388.575753) (xy 131.4924 -388.541817) (xy 131.53125 -388.513615)
			(xy 131.574035 -388.491841) (xy 131.619701 -388.477032) (xy 131.667122 -388.469553) (xy 131.691126 -388.469124)
			(xy 131.715061 -388.469582) (xy 131.762348 -388.477038) (xy 131.807892 -388.491778) (xy 131.85058 -388.513443)
			(xy 131.889366 -388.541501) (xy 131.923301 -388.575265) (xy 131.951553 -388.613909) (xy 131.962906 -388.634986)
			(xy 131.963414 -388.636002) (xy 132.04372 -388.77494) (xy 132.585968 -388.77494) (xy 132.585968 -388.774432)
			(xy 132.586468 -388.750441) (xy 132.593969 -388.703049) (xy 132.608792 -388.657414) (xy 132.630571 -388.614659)
			(xy 132.65877 -388.575838) (xy 132.692696 -388.541907) (xy 132.731511 -388.5137) (xy 132.774262 -388.491913)
			(xy 132.819894 -388.477082) (xy 132.867285 -388.469572) (xy 132.891276 -388.469124) (xy 132.915213 -388.469542)
			(xy 132.962501 -388.477005) (xy 133.008047 -388.491753) (xy 133.050734 -388.513424) (xy 133.08952 -388.541488)
			(xy 133.123453 -388.575258) (xy 133.151704 -388.613907) (xy 133.163056 -388.634986) (xy 133.163564 -388.636002)
			(xy 133.24387 -388.77494) (xy 147.113752 -388.77494) (xy 147.113752 -388.774432) (xy 147.114292 -388.750444)
			(xy 147.121792 -388.703057) (xy 147.136613 -388.657427) (xy 147.158389 -388.614677) (xy 147.186584 -388.57586)
			(xy 147.220505 -388.541931) (xy 147.259315 -388.513726) (xy 147.30206 -388.49194) (xy 147.347687 -388.477109)
			(xy 147.395072 -388.469598) (xy 147.41906 -388.469124) (xy 147.442996 -388.469555) (xy 147.490284 -388.477016)
			(xy 147.535829 -388.491761) (xy 147.578517 -388.51343) (xy 147.617303 -388.541492) (xy 147.651236 -388.57526)
			(xy 147.679488 -388.613908) (xy 147.69084 -388.634986) (xy 147.691348 -388.636002) (xy 147.771654 -388.77494)
			(xy 148.313648 -388.77494) (xy 148.313648 -388.774432) (xy 148.314192 -388.750444) (xy 148.321692 -388.703057)
			(xy 148.336512 -388.657428) (xy 148.358288 -388.614678) (xy 148.386483 -388.575861) (xy 148.420403 -388.541933)
			(xy 148.459213 -388.513728) (xy 148.501957 -388.491941) (xy 148.547583 -388.47711) (xy 148.594968 -388.469598)
			(xy 148.618956 -388.469124) (xy 148.642892 -388.469558) (xy 148.69018 -388.477018) (xy 148.735725 -388.491763)
			(xy 148.778413 -388.513431) (xy 148.817198 -388.541493) (xy 148.851132 -388.575261) (xy 148.879383 -388.613908)
			(xy 148.890736 -388.634986) (xy 148.891244 -388.636002) (xy 148.97155 -388.77494) (xy 149.513544 -388.77494)
			(xy 149.513544 -388.774432) (xy 149.514092 -388.750444) (xy 149.521592 -388.703058) (xy 149.536412 -388.657429)
			(xy 149.558187 -388.614679) (xy 149.586382 -388.575862) (xy 149.620301 -388.541934) (xy 149.659111 -388.513729)
			(xy 149.701855 -388.491943) (xy 149.74748 -388.477111) (xy 149.794864 -388.469598) (xy 149.818852 -388.469124)
			(xy 149.842788 -388.469561) (xy 149.890076 -388.477021) (xy 149.935621 -388.491765) (xy 149.978308 -388.513433)
			(xy 150.017094 -388.541494) (xy 150.051028 -388.575261) (xy 150.079279 -388.613908) (xy 150.090632 -388.634986)
			(xy 150.09114 -388.636002) (xy 150.171446 -388.77494) (xy 150.71344 -388.77494) (xy 150.71344 -388.774432)
			(xy 150.713869 -388.750425) (xy 150.72138 -388.703001) (xy 150.736223 -388.657338) (xy 150.75803 -388.614562)
			(xy 150.786266 -388.575726) (xy 150.820232 -388.54179) (xy 150.859092 -388.513589) (xy 150.901888 -388.491819)
			(xy 150.947564 -388.477017) (xy 150.994994 -388.469548) (xy 151.019002 -388.469124) (xy 151.042937 -388.469602)
			(xy 151.090222 -388.477054) (xy 151.135766 -388.491791) (xy 151.178454 -388.513452) (xy 151.21724 -388.541507)
			(xy 151.251175 -388.575268) (xy 151.279429 -388.61391) (xy 151.290782 -388.634986) (xy 151.29129 -388.636002)
			(xy 151.371596 -388.77494) (xy 151.913336 -388.77494) (xy 151.913336 -388.774432) (xy 151.913769 -388.750425)
			(xy 151.92128 -388.703002) (xy 151.936122 -388.657339) (xy 151.95793 -388.614563) (xy 151.986164 -388.575728)
			(xy 152.02013 -388.541791) (xy 152.05899 -388.51359) (xy 152.101785 -388.49182) (xy 152.147461 -388.477018)
			(xy 152.19489 -388.469548) (xy 152.218898 -388.469124) (xy 152.242835 -388.469524) (xy 152.290125 -388.476991)
			(xy 152.335671 -388.491741) (xy 152.378358 -388.513415) (xy 152.417143 -388.541482) (xy 152.451076 -388.575255)
			(xy 152.479326 -388.613906) (xy 152.490678 -388.634986) (xy 152.491186 -388.636002) (xy 152.571492 -388.77494)
			(xy 153.11374 -388.77494) (xy 153.11374 -388.774432) (xy 153.114168 -388.750437) (xy 153.121671 -388.703038)
			(xy 153.136498 -388.657397) (xy 153.158284 -388.614638) (xy 153.186491 -388.575814) (xy 153.220426 -388.541881)
			(xy 153.259251 -388.513676) (xy 153.302012 -388.491892) (xy 153.347654 -388.477068) (xy 153.395053 -388.469567)
			(xy 153.419048 -388.469124) (xy 153.442984 -388.469565) (xy 153.490271 -388.477024) (xy 153.535816 -388.491767)
			(xy 153.578504 -388.513434) (xy 153.61729 -388.541495) (xy 153.651224 -388.575262) (xy 153.679475 -388.613908)
			(xy 153.690828 -388.634986) (xy 153.691336 -388.636002) (xy 153.771642 -388.77494) (xy 154.313636 -388.77494)
			(xy 154.313636 -388.774432) (xy 154.314068 -388.750438) (xy 154.321571 -388.703039) (xy 154.336398 -388.657398)
			(xy 154.358183 -388.614639) (xy 154.38639 -388.575815) (xy 154.420324 -388.541882) (xy 154.459149 -388.513677)
			(xy 154.501909 -388.491893) (xy 154.547551 -388.477068) (xy 154.59495 -388.469567) (xy 154.618944 -388.469124)
			(xy 154.64288 -388.469568) (xy 154.690167 -388.477026) (xy 154.735712 -388.491769) (xy 154.7784 -388.513436)
			(xy 154.817185 -388.541496) (xy 154.851119 -388.575262) (xy 154.879371 -388.613909) (xy 154.890724 -388.634986)
			(xy 154.891232 -388.636002) (xy 154.971538 -388.77494) (xy 155.513532 -388.77494) (xy 155.513532 -388.774432)
			(xy 155.513968 -388.750438) (xy 155.521471 -388.703039) (xy 155.536298 -388.657399) (xy 155.558083 -388.61464)
			(xy 155.586289 -388.575816) (xy 155.620222 -388.541884) (xy 155.659047 -388.513678) (xy 155.701806 -388.491895)
			(xy 155.747447 -388.477069) (xy 155.794846 -388.469567) (xy 155.81884 -388.469124) (xy 155.842776 -388.469571)
			(xy 155.890063 -388.477029) (xy 155.935608 -388.491771) (xy 155.978295 -388.513437) (xy 156.017081 -388.541497)
			(xy 156.051015 -388.575263) (xy 156.079267 -388.613909) (xy 156.09062 -388.634986) (xy 156.091128 -388.636002)
			(xy 156.171434 -388.77494) (xy 156.713428 -388.77494) (xy 156.713428 -388.774432) (xy 156.713869 -388.750425)
			(xy 156.72138 -388.703003) (xy 156.736222 -388.657341) (xy 156.758028 -388.614565) (xy 156.786262 -388.575731)
			(xy 156.820227 -388.541794) (xy 156.859086 -388.513593) (xy 156.90188 -388.491823) (xy 156.947554 -388.477019)
			(xy 156.994983 -388.469549) (xy 157.01899 -388.469124) (xy 157.042927 -388.46953) (xy 157.090216 -388.476996)
			(xy 157.135762 -388.491746) (xy 157.17845 -388.513419) (xy 157.217235 -388.541484) (xy 157.251168 -388.575256)
			(xy 157.279418 -388.613907) (xy 157.29077 -388.634986) (xy 157.291278 -388.636002) (xy 157.371584 -388.77494)
			(xy 157.913324 -388.77494) (xy 157.913324 -388.774432) (xy 157.913769 -388.750425) (xy 157.92128 -388.703004)
			(xy 157.936121 -388.657342) (xy 157.957927 -388.614567) (xy 157.986161 -388.575732) (xy 158.020125 -388.541796)
			(xy 158.058983 -388.513595) (xy 158.101777 -388.491824) (xy 158.147451 -388.47702) (xy 158.194879 -388.469549)
			(xy 158.218886 -388.469124) (xy 158.242823 -388.469534) (xy 158.290112 -388.476998) (xy 158.335657 -388.491748)
			(xy 158.378345 -388.51342) (xy 158.41713 -388.541485) (xy 158.451064 -388.575256) (xy 158.479314 -388.613907)
			(xy 158.490666 -388.634986) (xy 158.491174 -388.636002) (xy 158.57148 -388.77494) (xy 159.113728 -388.77494)
			(xy 159.113728 -388.774432) (xy 159.114168 -388.750438) (xy 159.121671 -388.70304) (xy 159.136497 -388.6574)
			(xy 159.158282 -388.614641) (xy 159.186488 -388.575818) (xy 159.220421 -388.541885) (xy 159.259245 -388.51368)
			(xy 159.302004 -388.491896) (xy 159.347644 -388.47707) (xy 159.395042 -388.469568) (xy 159.419036 -388.469124)
			(xy 159.442972 -388.469574) (xy 159.490258 -388.477031) (xy 159.535803 -388.491773) (xy 159.578491 -388.513439)
			(xy 159.617277 -388.541498) (xy 159.651211 -388.575264) (xy 159.679463 -388.613909) (xy 159.690816 -388.634986)
			(xy 159.691324 -388.636002) (xy 159.77163 -388.77494) (xy 160.313624 -388.77494) (xy 160.313624 -388.774432)
			(xy 160.314068 -388.750438) (xy 160.321571 -388.703041) (xy 160.336397 -388.657401) (xy 160.358181 -388.614643)
			(xy 160.386387 -388.575819) (xy 160.420319 -388.541887) (xy 160.459143 -388.513681) (xy 160.501901 -388.491897)
			(xy 160.547541 -388.477071) (xy 160.594938 -388.469568) (xy 160.618932 -388.469124) (xy 160.642868 -388.469578)
			(xy 160.690154 -388.477034) (xy 160.735699 -388.491775) (xy 160.778387 -388.51344) (xy 160.817172 -388.541499)
			(xy 160.851107 -388.575264) (xy 160.879359 -388.613909) (xy 160.890712 -388.634986) (xy 160.89122 -388.636002)
			(xy 160.971526 -388.77494) (xy 161.51352 -388.77494) (xy 161.51352 -388.774432) (xy 161.513968 -388.750438)
			(xy 161.521471 -388.703041) (xy 161.536297 -388.657402) (xy 161.55808 -388.614644) (xy 161.586286 -388.57582)
			(xy 161.620217 -388.541888) (xy 161.65904 -388.513682) (xy 161.701798 -388.491898) (xy 161.747437 -388.477072)
			(xy 161.794834 -388.469568) (xy 161.818828 -388.469124) (xy 161.842763 -388.469581) (xy 161.89005 -388.477037)
			(xy 161.935595 -388.491777) (xy 161.978282 -388.513442) (xy 162.017068 -388.5415) (xy 162.051003 -388.575265)
			(xy 162.079255 -388.613909) (xy 162.090608 -388.634986) (xy 162.091116 -388.636002) (xy 162.171422 -388.77494)
			(xy 162.713416 -388.77494) (xy 162.713416 -388.774432) (xy 162.713869 -388.750426) (xy 162.721379 -388.703005)
			(xy 162.73622 -388.657344) (xy 162.758026 -388.614569) (xy 162.786259 -388.575735) (xy 162.820222 -388.541799)
			(xy 162.859079 -388.513597) (xy 162.901871 -388.491826) (xy 162.947544 -388.477022) (xy 162.994971 -388.469549)
			(xy 163.018978 -388.469124) (xy 163.042915 -388.46954) (xy 163.090203 -388.477004) (xy 163.135749 -388.491752)
			(xy 163.178437 -388.513423) (xy 163.217222 -388.541487) (xy 163.251155 -388.575258) (xy 163.279406 -388.613907)
			(xy 163.290758 -388.634986) (xy 163.291266 -388.636002) (xy 163.371572 -388.77494) (xy 163.913312 -388.77494)
			(xy 163.913312 -388.774432) (xy 163.913769 -388.750426) (xy 163.921279 -388.703005) (xy 163.93612 -388.657345)
			(xy 163.957925 -388.61457) (xy 163.986157 -388.575736) (xy 164.02012 -388.5418) (xy 164.058977 -388.513599)
			(xy 164.101769 -388.491827) (xy 164.147441 -388.477023) (xy 164.194868 -388.46955) (xy 164.218874 -388.469124)
			(xy 164.242811 -388.469543) (xy 164.290099 -388.477006) (xy 164.335644 -388.491754) (xy 164.378332 -388.513425)
			(xy 164.417118 -388.541488) (xy 164.451051 -388.575258) (xy 164.479302 -388.613907) (xy 164.490654 -388.634986)
			(xy 164.491162 -388.636002) (xy 164.571468 -388.77494) (xy 165.113716 -388.77494) (xy 165.113716 -388.774432)
			(xy 165.114168 -388.750439) (xy 165.121671 -388.703042) (xy 165.136496 -388.657403) (xy 165.15828 -388.614645)
			(xy 165.186484 -388.575822) (xy 165.220416 -388.54189) (xy 165.259238 -388.513684) (xy 165.301995 -388.491899)
			(xy 165.347634 -388.477072) (xy 165.395031 -388.469568) (xy 165.419024 -388.469124) (xy 165.442959 -388.469584)
			(xy 165.490246 -388.477039) (xy 165.53579 -388.491779) (xy 165.578478 -388.513444) (xy 165.617264 -388.541501)
			(xy 165.651198 -388.575265) (xy 165.679451 -388.61391) (xy 165.690804 -388.634986) (xy 165.691312 -388.636002)
			(xy 165.744132 -388.727385) (xy 193.900548 -388.727385) (xy 193.900548 -388.642663) (xy 193.908601 -388.558326)
			(xy 193.924635 -388.475136) (xy 193.948503 -388.393846) (xy 193.979991 -388.315194) (xy 194.018813 -388.239891)
			(xy 194.064616 -388.168619) (xy 194.116987 -388.102023) (xy 194.175452 -388.040708) (xy 194.23948 -387.985227)
			(xy 194.308492 -387.936084) (xy 194.381862 -387.893724) (xy 194.458927 -387.858529) (xy 194.538989 -387.83082)
			(xy 194.621322 -387.810846) (xy 194.705181 -387.798789) (xy 194.789806 -387.794758) (xy 194.874431 -387.798789)
			(xy 194.95829 -387.810846) (xy 195.040623 -387.83082) (xy 195.120685 -387.858529) (xy 195.19775 -387.893724)
			(xy 195.27112 -387.936084) (xy 195.340132 -387.985227) (xy 195.40416 -388.040708) (xy 195.462625 -388.102023)
			(xy 195.514996 -388.168619) (xy 195.560799 -388.239891) (xy 195.599621 -388.315194) (xy 195.631109 -388.393846)
			(xy 195.654977 -388.475136) (xy 195.671011 -388.558326) (xy 195.679064 -388.642663) (xy 195.679568 -388.685024)
			(xy 195.679064 -388.727385) (xy 195.671011 -388.811722) (xy 195.654977 -388.894912) (xy 195.631109 -388.976202)
			(xy 195.599621 -389.054854) (xy 195.560799 -389.130157) (xy 195.514996 -389.201429) (xy 195.462625 -389.268025)
			(xy 195.40416 -389.32934) (xy 195.340132 -389.384821) (xy 195.27112 -389.433964) (xy 195.19775 -389.476324)
			(xy 195.120685 -389.511519) (xy 195.040623 -389.539228) (xy 194.95829 -389.559202) (xy 194.874431 -389.571259)
			(xy 194.789806 -389.575291) (xy 194.705181 -389.571259) (xy 194.621322 -389.559202) (xy 194.538989 -389.539228)
			(xy 194.458927 -389.511519) (xy 194.381862 -389.476324) (xy 194.308492 -389.433964) (xy 194.23948 -389.384821)
			(xy 194.175452 -389.32934) (xy 194.116987 -389.268025) (xy 194.064616 -389.201429) (xy 194.018813 -389.130157)
			(xy 193.979991 -389.054854) (xy 193.948503 -388.976202) (xy 193.924635 -388.894912) (xy 193.908601 -388.811722)
			(xy 193.900548 -388.727385) (xy 165.744132 -388.727385) (xy 166.083742 -389.314944) (xy 166.096549 -389.338286)
			(xy 166.114776 -389.388304) (xy 166.124043 -389.440727) (xy 166.124636 -389.467344) (xy 166.124202 -389.49135)
			(xy 166.116681 -389.538768) (xy 166.101833 -389.584426) (xy 166.080022 -389.627197) (xy 166.051787 -389.666029)
			(xy 166.017823 -389.699963) (xy 165.978967 -389.728164) (xy 165.936176 -389.749936) (xy 165.890505 -389.764744)
			(xy 165.84308 -389.772223) (xy 165.819074 -389.772652) (xy 165.795501 -389.772252) (xy 165.748914 -389.765008)
			(xy 165.703997 -389.750681) (xy 165.66182 -389.729613) (xy 165.623387 -389.702305) (xy 165.589614 -389.669408)
			(xy 165.561306 -389.631706) (xy 165.549834 -389.611108) (xy 165.549326 -389.610346) (xy 165.151562 -388.922006)
			(xy 165.139686 -388.899329) (xy 165.122835 -388.850996) (xy 165.114262 -388.800533) (xy 165.113716 -388.77494)
			(xy 164.571468 -388.77494) (xy 164.883592 -389.314944) (xy 164.896324 -389.33831) (xy 164.91444 -389.388338)
			(xy 164.92365 -389.440741) (xy 164.924232 -389.467344) (xy 164.923778 -389.491335) (xy 164.916266 -389.538726)
			(xy 164.901434 -389.584359) (xy 164.879647 -389.62711) (xy 164.851442 -389.665927) (xy 164.817512 -389.699855)
			(xy 164.778693 -389.728058) (xy 164.73594 -389.749842) (xy 164.690307 -389.764671) (xy 164.642915 -389.77218)
			(xy 164.618924 -389.772652) (xy 164.595352 -389.772211) (xy 164.548767 -389.764975) (xy 164.503851 -389.750656)
			(xy 164.461674 -389.729594) (xy 164.423241 -389.702292) (xy 164.389467 -389.669401) (xy 164.361157 -389.631704)
			(xy 164.349684 -389.611108) (xy 164.349176 -389.610346) (xy 163.951412 -388.922006) (xy 163.939498 -388.899337)
			(xy 163.92256 -388.851012) (xy 163.9139 -388.800542) (xy 163.913312 -388.77494) (xy 163.371572 -388.77494)
			(xy 163.683696 -389.314944) (xy 163.696428 -389.33831) (xy 163.714544 -389.388338) (xy 163.723754 -389.440741)
			(xy 163.724336 -389.467344) (xy 163.723878 -389.491335) (xy 163.716366 -389.538726) (xy 163.701535 -389.584358)
			(xy 163.679748 -389.627109) (xy 163.651543 -389.665926) (xy 163.617613 -389.699853) (xy 163.578795 -389.728056)
			(xy 163.536043 -389.749841) (xy 163.49041 -389.76467) (xy 163.443019 -389.772179) (xy 163.419028 -389.772652)
			(xy 163.395456 -389.772208) (xy 163.348872 -389.764972) (xy 163.303956 -389.750653) (xy 163.261778 -389.729592)
			(xy 163.223345 -389.702291) (xy 163.189571 -389.6694) (xy 163.161261 -389.631704) (xy 163.149788 -389.611108)
			(xy 163.14928 -389.610346) (xy 162.751516 -388.922006) (xy 162.739602 -388.899337) (xy 162.722664 -388.851012)
			(xy 162.714004 -388.800542) (xy 162.713416 -388.77494) (xy 162.171422 -388.77494) (xy 162.483546 -389.314944)
			(xy 162.496353 -389.338286) (xy 162.51458 -389.388304) (xy 162.523847 -389.440727) (xy 162.52444 -389.467344)
			(xy 162.524002 -389.491349) (xy 162.516481 -389.538768) (xy 162.501633 -389.584425) (xy 162.479823 -389.627196)
			(xy 162.451588 -389.666027) (xy 162.417625 -389.699961) (xy 162.378769 -389.728162) (xy 162.335979 -389.749935)
			(xy 162.290309 -389.764744) (xy 162.242884 -389.772222) (xy 162.218878 -389.772652) (xy 162.195305 -389.772249)
			(xy 162.148718 -389.765005) (xy 162.103801 -389.750679) (xy 162.061624 -389.729611) (xy 162.023191 -389.702304)
			(xy 161.989418 -389.669408) (xy 161.96111 -389.631706) (xy 161.949638 -389.611108) (xy 161.94913 -389.610346)
			(xy 161.551366 -388.922006) (xy 161.539491 -388.899329) (xy 161.522639 -388.850996) (xy 161.514066 -388.800533)
			(xy 161.51352 -388.77494) (xy 160.971526 -388.77494) (xy 161.28365 -389.314944) (xy 161.296457 -389.338285)
			(xy 161.314684 -389.388304) (xy 161.323951 -389.440726) (xy 161.324544 -389.467344) (xy 161.324102 -389.491349)
			(xy 161.316582 -389.538767) (xy 161.301734 -389.584424) (xy 161.279924 -389.627195) (xy 161.25169 -389.666026)
			(xy 161.217726 -389.69996) (xy 161.178871 -389.728161) (xy 161.136082 -389.749934) (xy 161.090412 -389.764743)
			(xy 161.042988 -389.772222) (xy 161.018982 -389.772652) (xy 160.995409 -389.772245) (xy 160.948822 -389.765003)
			(xy 160.903906 -389.750677) (xy 160.861728 -389.72961) (xy 160.823295 -389.702303) (xy 160.789523 -389.669407)
			(xy 160.761214 -389.631706) (xy 160.749742 -389.611108) (xy 160.749234 -389.610346) (xy 160.35147 -388.922006)
			(xy 160.339595 -388.899329) (xy 160.322743 -388.850996) (xy 160.31417 -388.800533) (xy 160.313624 -388.77494)
			(xy 159.77163 -388.77494) (xy 160.083754 -389.314944) (xy 160.096562 -389.338285) (xy 160.114788 -389.388304)
			(xy 160.124055 -389.440726) (xy 160.124648 -389.467344) (xy 160.124202 -389.491349) (xy 160.116682 -389.538767)
			(xy 160.101834 -389.584423) (xy 160.080025 -389.627194) (xy 160.051791 -389.666025) (xy 160.017828 -389.699959)
			(xy 159.978973 -389.72816) (xy 159.936184 -389.749933) (xy 159.890515 -389.764742) (xy 159.843091 -389.772222)
			(xy 159.819086 -389.772652) (xy 159.795513 -389.772242) (xy 159.748927 -389.765) (xy 159.70401 -389.750675)
			(xy 159.661833 -389.729608) (xy 159.6234 -389.702302) (xy 159.589627 -389.669406) (xy 159.561319 -389.631705)
			(xy 159.549846 -389.611108) (xy 159.549338 -389.610346) (xy 159.151574 -388.922006) (xy 159.139699 -388.899329)
			(xy 159.122848 -388.850996) (xy 159.114274 -388.800533) (xy 159.113728 -388.77494) (xy 158.57148 -388.77494)
			(xy 158.883604 -389.314944) (xy 158.896337 -389.33831) (xy 158.914452 -389.388337) (xy 158.923662 -389.440741)
			(xy 158.924244 -389.467344) (xy 158.923778 -389.491335) (xy 158.916267 -389.538724) (xy 158.901435 -389.584356)
			(xy 158.879649 -389.627106) (xy 158.851445 -389.665923) (xy 158.817517 -389.69985) (xy 158.778699 -389.728054)
			(xy 158.735949 -389.749838) (xy 158.690317 -389.764668) (xy 158.642927 -389.772179) (xy 158.618936 -389.772652)
			(xy 158.595364 -389.772202) (xy 158.54878 -389.764967) (xy 158.503864 -389.750649) (xy 158.461687 -389.729589)
			(xy 158.423253 -389.702289) (xy 158.389479 -389.669399) (xy 158.361169 -389.631703) (xy 158.349696 -389.611108)
			(xy 158.349188 -389.610346) (xy 157.951424 -388.922006) (xy 157.939511 -388.899337) (xy 157.922572 -388.851012)
			(xy 157.913912 -388.800542) (xy 157.913324 -388.77494) (xy 157.371584 -388.77494) (xy 157.683708 -389.314944)
			(xy 157.696441 -389.33831) (xy 157.714556 -389.388337) (xy 157.723766 -389.440741) (xy 157.724348 -389.467344)
			(xy 157.723878 -389.491334) (xy 157.716367 -389.538724) (xy 157.701536 -389.584355) (xy 157.67975 -389.627105)
			(xy 157.651546 -389.665922) (xy 157.617618 -389.699849) (xy 157.578802 -389.728052) (xy 157.536051 -389.749837)
			(xy 157.49042 -389.764668) (xy 157.44303 -389.772178) (xy 157.41904 -389.772652) (xy 157.395469 -389.772199)
			(xy 157.348884 -389.764965) (xy 157.303969 -389.750647) (xy 157.261791 -389.729588) (xy 157.223358 -389.702288)
			(xy 157.189583 -389.669399) (xy 157.161273 -389.631703) (xy 157.1498 -389.611108) (xy 157.149292 -389.610346)
			(xy 156.751528 -388.922006) (xy 156.739615 -388.899337) (xy 156.722676 -388.851012) (xy 156.714016 -388.800542)
			(xy 156.713428 -388.77494) (xy 156.171434 -388.77494) (xy 156.483558 -389.314944) (xy 156.496366 -389.338285)
			(xy 156.514592 -389.388304) (xy 156.523859 -389.440726) (xy 156.524452 -389.467344) (xy 156.524002 -389.491349)
			(xy 156.516482 -389.538766) (xy 156.501634 -389.584422) (xy 156.479825 -389.627193) (xy 156.451592 -389.666023)
			(xy 156.41763 -389.699957) (xy 156.378776 -389.728158) (xy 156.335987 -389.749932) (xy 156.290319 -389.764741)
			(xy 156.242895 -389.772222) (xy 156.21889 -389.772652) (xy 156.195317 -389.772239) (xy 156.148731 -389.764997)
			(xy 156.103814 -389.750673) (xy 156.061637 -389.729607) (xy 156.023204 -389.702301) (xy 155.989431 -389.669406)
			(xy 155.961123 -389.631705) (xy 155.94965 -389.611108) (xy 155.949142 -389.610346) (xy 155.551378 -388.922006)
			(xy 155.539503 -388.899328) (xy 155.522652 -388.850996) (xy 155.514078 -388.800533) (xy 155.513532 -388.77494)
			(xy 154.971538 -388.77494) (xy 155.283662 -389.314944) (xy 155.29647 -389.338285) (xy 155.314696 -389.388304)
			(xy 155.323963 -389.440726) (xy 155.324556 -389.467344) (xy 155.324102 -389.491349) (xy 155.316582 -389.538765)
			(xy 155.301735 -389.584421) (xy 155.279926 -389.627191) (xy 155.251693 -389.666022) (xy 155.217731 -389.699956)
			(xy 155.178878 -389.728157) (xy 155.13609 -389.749931) (xy 155.090422 -389.76474) (xy 155.042999 -389.772221)
			(xy 155.018994 -389.772652) (xy 154.995421 -389.772236) (xy 154.948835 -389.764995) (xy 154.903919 -389.750671)
			(xy 154.861741 -389.729605) (xy 154.823308 -389.7023) (xy 154.789535 -389.669405) (xy 154.761227 -389.631705)
			(xy 154.749754 -389.611108) (xy 154.749246 -389.610346) (xy 154.351482 -388.922006) (xy 154.339608 -388.899328)
			(xy 154.322756 -388.850996) (xy 154.314182 -388.800533) (xy 154.313636 -388.77494) (xy 153.771642 -388.77494)
			(xy 154.083766 -389.314944) (xy 154.096575 -389.338285) (xy 154.1148 -389.388303) (xy 154.124067 -389.440726)
			(xy 154.12466 -389.467344) (xy 154.124301 -389.491353) (xy 154.116779 -389.53878) (xy 154.101926 -389.584444)
			(xy 154.080109 -389.62722) (xy 154.051865 -389.666055) (xy 154.017891 -389.69999) (xy 153.979025 -389.72819)
			(xy 153.936223 -389.749958) (xy 153.890542 -389.764759) (xy 153.843108 -389.772228) (xy 153.819098 -389.772652)
			(xy 153.795525 -389.772232) (xy 153.74894 -389.764992) (xy 153.704023 -389.750669) (xy 153.661846 -389.729604)
			(xy 153.623413 -389.702299) (xy 153.589639 -389.669405) (xy 153.561331 -389.631705) (xy 153.549858 -389.611108)
			(xy 153.54935 -389.610346) (xy 153.151586 -388.922006) (xy 153.139712 -388.899328) (xy 153.12286 -388.850996)
			(xy 153.114286 -388.800533) (xy 153.11374 -388.77494) (xy 152.571492 -388.77494) (xy 152.883616 -389.314944)
			(xy 152.89635 -389.338309) (xy 152.914465 -389.388337) (xy 152.923674 -389.440741) (xy 152.924256 -389.467344)
			(xy 152.923778 -389.491334) (xy 152.916267 -389.538723) (xy 152.901436 -389.584353) (xy 152.879652 -389.627103)
			(xy 152.851449 -389.665919) (xy 152.817522 -389.699846) (xy 152.778706 -389.72805) (xy 152.735957 -389.749835)
			(xy 152.690327 -389.764666) (xy 152.642938 -389.772178) (xy 152.618948 -389.772652) (xy 152.595377 -389.772192)
			(xy 152.548793 -389.764959) (xy 152.503877 -389.750643) (xy 152.4617 -389.729585) (xy 152.423266 -389.702286)
			(xy 152.389492 -389.669398) (xy 152.361182 -389.631703) (xy 152.349708 -389.611108) (xy 152.3492 -389.610346)
			(xy 151.951436 -388.922006) (xy 151.939523 -388.899336) (xy 151.922584 -388.851012) (xy 151.913924 -388.800542)
			(xy 151.913336 -388.77494) (xy 151.371596 -388.77494) (xy 151.68372 -389.314944) (xy 151.696454 -389.338309)
			(xy 151.714569 -389.388337) (xy 151.723778 -389.440741) (xy 151.72436 -389.467344) (xy 151.724002 -389.491341)
			(xy 151.716487 -389.538742) (xy 151.70165 -389.584385) (xy 151.679855 -389.627144) (xy 151.651639 -389.665968)
			(xy 151.617698 -389.699899) (xy 151.578866 -389.728103) (xy 151.5361 -389.749885) (xy 151.490453 -389.764709)
			(xy 151.443049 -389.772209) (xy 151.419052 -389.772652) (xy 151.395481 -389.772189) (xy 151.348897 -389.764957)
			(xy 151.303982 -389.750641) (xy 151.261804 -389.729583) (xy 151.223371 -389.702285) (xy 151.189596 -389.669397)
			(xy 151.161286 -389.631703) (xy 151.149812 -389.611108) (xy 151.149304 -389.610346) (xy 150.75154 -388.922006)
			(xy 150.739628 -388.899336) (xy 150.722688 -388.851012) (xy 150.714028 -388.800542) (xy 150.71344 -388.77494)
			(xy 150.171446 -388.77494) (xy 150.48357 -389.314944) (xy 150.496379 -389.338285) (xy 150.514604 -389.388303)
			(xy 150.523871 -389.440726) (xy 150.524464 -389.467344) (xy 150.524101 -389.491353) (xy 150.516579 -389.538779)
			(xy 150.501726 -389.584443) (xy 150.479909 -389.627219) (xy 150.451666 -389.666053) (xy 150.417693 -389.699989)
			(xy 150.378827 -389.728188) (xy 150.336026 -389.749957) (xy 150.290346 -389.764759) (xy 150.242912 -389.772228)
			(xy 150.218902 -389.772652) (xy 150.195329 -389.772229) (xy 150.148744 -389.76499) (xy 150.103827 -389.750667)
			(xy 150.06165 -389.729602) (xy 150.023217 -389.702298) (xy 149.989444 -389.669404) (xy 149.961135 -389.631705)
			(xy 149.949662 -389.611108) (xy 149.949154 -389.610346) (xy 149.55139 -388.922006) (xy 149.539516 -388.899328)
			(xy 149.522664 -388.850995) (xy 149.51409 -388.800533) (xy 149.513544 -388.77494) (xy 148.97155 -388.77494)
			(xy 149.283674 -389.314944) (xy 149.296483 -389.338284) (xy 149.314708 -389.388303) (xy 149.323975 -389.440726)
			(xy 149.324568 -389.467344) (xy 149.324201 -389.491353) (xy 149.316679 -389.538778) (xy 149.301826 -389.584442)
			(xy 149.28001 -389.627218) (xy 149.251767 -389.666052) (xy 149.217795 -389.699987) (xy 149.178929 -389.728187)
			(xy 149.136129 -389.749956) (xy 149.090449 -389.764758) (xy 149.043016 -389.772228) (xy 149.019006 -389.772652)
			(xy 148.995434 -389.772226) (xy 148.948848 -389.764987) (xy 148.903932 -389.750665) (xy 148.861754 -389.729601)
			(xy 148.823321 -389.702297) (xy 148.789548 -389.669404) (xy 148.761239 -389.631705) (xy 148.749766 -389.611108)
			(xy 148.749258 -389.610346) (xy 148.351494 -388.922006) (xy 148.339621 -388.899328) (xy 148.322768 -388.850995)
			(xy 148.314194 -388.800532) (xy 148.313648 -388.77494) (xy 147.771654 -388.77494) (xy 148.083778 -389.314944)
			(xy 148.096588 -389.338284) (xy 148.114813 -389.388303) (xy 148.124079 -389.440726) (xy 148.124672 -389.467344)
			(xy 148.124301 -389.491353) (xy 148.116779 -389.538778) (xy 148.101927 -389.584441) (xy 148.080111 -389.627217)
			(xy 148.051868 -389.666051) (xy 148.017896 -389.699986) (xy 147.979031 -389.728185) (xy 147.936232 -389.749955)
			(xy 147.890552 -389.764757) (xy 147.843119 -389.772228) (xy 147.81911 -389.772652) (xy 147.795538 -389.772223)
			(xy 147.748952 -389.764984) (xy 147.704036 -389.750663) (xy 147.661859 -389.729599) (xy 147.623425 -389.702296)
			(xy 147.589652 -389.669403) (xy 147.561343 -389.631704) (xy 147.54987 -389.611108) (xy 147.549362 -389.610346)
			(xy 147.151598 -388.922006) (xy 147.139725 -388.899328) (xy 147.122872 -388.850995) (xy 147.114298 -388.800532)
			(xy 147.113752 -388.77494) (xy 133.24387 -388.77494) (xy 133.555994 -389.314944) (xy 133.568805 -389.338283)
			(xy 133.587029 -389.388303) (xy 133.596295 -389.440726) (xy 133.596888 -389.467344) (xy 133.596501 -389.491352)
			(xy 133.58898 -389.538775) (xy 133.574128 -389.584437) (xy 133.552314 -389.627212) (xy 133.524073 -389.666045)
			(xy 133.490103 -389.69998) (xy 133.45124 -389.72818) (xy 133.408443 -389.74995) (xy 133.362766 -389.764754)
			(xy 133.315334 -389.772226) (xy 133.291326 -389.772652) (xy 133.267754 -389.77221) (xy 133.221169 -389.764974)
			(xy 133.176253 -389.750654) (xy 133.134076 -389.729593) (xy 133.095643 -389.702292) (xy 133.061869 -389.669401)
			(xy 133.033559 -389.631704) (xy 133.022086 -389.611108) (xy 133.021578 -389.610346) (xy 132.623814 -388.922006)
			(xy 132.611935 -388.899331) (xy 132.595086 -388.850997) (xy 132.586514 -388.800533) (xy 132.585968 -388.77494)
			(xy 132.04372 -388.77494) (xy 132.355844 -389.314944) (xy 132.36858 -389.338308) (xy 132.386693 -389.388337)
			(xy 132.395902 -389.440741) (xy 132.396484 -389.467344) (xy 132.396078 -389.491338) (xy 132.388564 -389.538733)
			(xy 132.37373 -389.58437) (xy 132.351938 -389.627124) (xy 132.323728 -389.665943) (xy 132.289792 -389.699872)
			(xy 132.250966 -389.728074) (xy 132.208207 -389.749856) (xy 132.162567 -389.76468) (xy 132.11517 -389.772183)
			(xy 132.091176 -389.772652) (xy 132.067603 -389.77225) (xy 132.021016 -389.765007) (xy 131.976099 -389.75068)
			(xy 131.933922 -389.729612) (xy 131.895489 -389.702305) (xy 131.861716 -389.669408) (xy 131.833408 -389.631706)
			(xy 131.821936 -389.611108) (xy 131.821428 -389.610346) (xy 131.423664 -388.922006) (xy 131.411754 -388.899335)
			(xy 131.394814 -388.851011) (xy 131.386152 -388.800542) (xy 131.385564 -388.77494) (xy 130.843824 -388.77494)
			(xy 131.155948 -389.314944) (xy 131.168684 -389.338308) (xy 131.186797 -389.388337) (xy 131.196006 -389.440741)
			(xy 131.196588 -389.467344) (xy 131.196178 -389.491337) (xy 131.188665 -389.538733) (xy 131.17383 -389.584369)
			(xy 131.152039 -389.627123) (xy 131.123829 -389.665942) (xy 131.089893 -389.69987) (xy 131.051068 -389.728073)
			(xy 131.00831 -389.749854) (xy 130.96267 -389.76468) (xy 130.915274 -389.772183) (xy 130.89128 -389.772652)
			(xy 130.867707 -389.772247) (xy 130.82112 -389.765004) (xy 130.776203 -389.750678) (xy 130.734026 -389.729611)
			(xy 130.695593 -389.702304) (xy 130.661821 -389.669407) (xy 130.633512 -389.631706) (xy 130.62204 -389.611108)
			(xy 130.621532 -389.610346) (xy 130.223768 -388.922006) (xy 130.211858 -388.899335) (xy 130.194918 -388.851011)
			(xy 130.186256 -388.800542) (xy 130.185668 -388.77494) (xy 129.643674 -388.77494) (xy 129.955798 -389.314944)
			(xy 129.968601 -389.338288) (xy 129.98683 -389.388305) (xy 129.996099 -389.440727) (xy 129.996692 -389.467344)
			(xy 129.996301 -389.491352) (xy 129.98878 -389.538775) (xy 129.973929 -389.584436) (xy 129.952114 -389.627211)
			(xy 129.923874 -389.666044) (xy 129.889905 -389.699979) (xy 129.851042 -389.728179) (xy 129.808246 -389.749949)
			(xy 129.762569 -389.764753) (xy 129.715138 -389.772226) (xy 129.69113 -389.772652) (xy 129.667558 -389.772207)
			(xy 129.620974 -389.764971) (xy 129.576058 -389.750652) (xy 129.53388 -389.729592) (xy 129.495447 -389.702291)
			(xy 129.461673 -389.6694) (xy 129.433363 -389.631704) (xy 129.42189 -389.611108) (xy 129.421382 -389.610346)
			(xy 129.023618 -388.922006) (xy 129.011739 -388.899331) (xy 128.99489 -388.850997) (xy 128.986318 -388.800533)
			(xy 128.985772 -388.77494) (xy 128.443778 -388.77494) (xy 128.755902 -389.314944) (xy 128.768705 -389.338288)
			(xy 128.786934 -389.388305) (xy 128.796203 -389.440727) (xy 128.796796 -389.467344) (xy 128.796401 -389.491352)
			(xy 128.78888 -389.538774) (xy 128.774029 -389.584435) (xy 128.752215 -389.627209) (xy 128.723975 -389.666042)
			(xy 128.690006 -389.699977) (xy 128.651145 -389.728177) (xy 128.608348 -389.749948) (xy 128.562672 -389.764752)
			(xy 128.515242 -389.772226) (xy 128.491234 -389.772652) (xy 128.467662 -389.772203) (xy 128.421078 -389.764969)
			(xy 128.376162 -389.75065) (xy 128.333985 -389.72959) (xy 128.295551 -389.70229) (xy 128.261777 -389.6694)
			(xy 128.233467 -389.631703) (xy 128.221994 -389.611108) (xy 128.221486 -389.610346) (xy 127.823722 -388.922006)
			(xy 127.811843 -388.899331) (xy 127.794994 -388.850996) (xy 127.786422 -388.800533) (xy 127.785876 -388.77494)
			(xy 127.243882 -388.77494) (xy 127.556006 -389.314944) (xy 127.56881 -389.338287) (xy 127.587038 -389.388304)
			(xy 127.596307 -389.440727) (xy 127.5969 -389.467344) (xy 127.596501 -389.491351) (xy 127.58898 -389.538774)
			(xy 127.57413 -389.584434) (xy 127.552316 -389.627208) (xy 127.524077 -389.666041) (xy 127.490108 -389.699976)
			(xy 127.451247 -389.728176) (xy 127.408451 -389.749947) (xy 127.362776 -389.764752) (xy 127.315346 -389.772225)
			(xy 127.291338 -389.772652) (xy 127.267766 -389.7722) (xy 127.221182 -389.764966) (xy 127.176266 -389.750648)
			(xy 127.134089 -389.729589) (xy 127.095656 -389.702289) (xy 127.061881 -389.669399) (xy 127.033571 -389.631703)
			(xy 127.022098 -389.611108) (xy 127.02159 -389.610346) (xy 126.623826 -388.922006) (xy 126.611947 -388.89933)
			(xy 126.595098 -388.850996) (xy 126.586526 -388.800533) (xy 126.58598 -388.77494) (xy 126.043732 -388.77494)
			(xy 126.355856 -389.314944) (xy 126.368593 -389.338307) (xy 126.386706 -389.388337) (xy 126.395914 -389.440741)
			(xy 126.396496 -389.467344) (xy 126.396078 -389.491337) (xy 126.388565 -389.538731) (xy 126.373731 -389.584367)
			(xy 126.351941 -389.627121) (xy 126.323731 -389.665939) (xy 126.289797 -389.699868) (xy 126.250973 -389.72807)
			(xy 126.208215 -389.749852) (xy 126.162577 -389.764678) (xy 126.115181 -389.772182) (xy 126.091188 -389.772652)
			(xy 126.067615 -389.772241) (xy 126.021029 -389.764999) (xy 125.976112 -389.750674) (xy 125.933935 -389.729608)
			(xy 125.895502 -389.702301) (xy 125.861729 -389.669406) (xy 125.833421 -389.631705) (xy 125.821948 -389.611108)
			(xy 125.82144 -389.610346) (xy 125.423676 -388.922006) (xy 125.411759 -388.899339) (xy 125.394823 -388.851013)
			(xy 125.386163 -388.800542) (xy 125.385576 -388.77494) (xy 124.843836 -388.77494) (xy 125.15596 -389.314944)
			(xy 125.168697 -389.338307) (xy 125.18681 -389.388337) (xy 125.196018 -389.440741) (xy 125.1966 -389.467344)
			(xy 125.196178 -389.491337) (xy 125.188665 -389.538731) (xy 125.173831 -389.584366) (xy 125.152041 -389.627119)
			(xy 125.123832 -389.665938) (xy 125.089898 -389.699866) (xy 125.051075 -389.728069) (xy 125.008318 -389.749851)
			(xy 124.96268 -389.764677) (xy 124.915285 -389.772182) (xy 124.891292 -389.772652) (xy 124.867719 -389.772237)
			(xy 124.821133 -389.764996) (xy 124.776216 -389.750672) (xy 124.734039 -389.729606) (xy 124.695606 -389.7023)
			(xy 124.661833 -389.669406) (xy 124.633525 -389.631705) (xy 124.622052 -389.611108) (xy 124.621544 -389.610346)
			(xy 124.22378 -388.922006) (xy 124.211863 -388.899339) (xy 124.194927 -388.851013) (xy 124.186267 -388.800542)
			(xy 124.18568 -388.77494) (xy 123.643686 -388.77494) (xy 123.95581 -389.314944) (xy 123.968614 -389.338287)
			(xy 123.986843 -389.388304) (xy 123.996111 -389.440727) (xy 123.996704 -389.467344) (xy 123.996301 -389.491351)
			(xy 123.98878 -389.538773) (xy 123.97393 -389.584433) (xy 123.952117 -389.627207) (xy 123.923878 -389.66604)
			(xy 123.88991 -389.699974) (xy 123.851049 -389.728175) (xy 123.808254 -389.749946) (xy 123.762579 -389.764751)
			(xy 123.71515 -389.772225) (xy 123.691142 -389.772652) (xy 123.667571 -389.772197) (xy 123.620986 -389.764963)
			(xy 123.576071 -389.750646) (xy 123.533893 -389.729587) (xy 123.49546 -389.702288) (xy 123.461686 -389.669398)
			(xy 123.433376 -389.631703) (xy 123.421902 -389.611108) (xy 123.421394 -389.610346) (xy 123.02363 -388.922006)
			(xy 123.011752 -388.89933) (xy 122.994902 -388.850996) (xy 122.98633 -388.800533) (xy 122.985784 -388.77494)
			(xy 122.44379 -388.77494) (xy 122.755914 -389.314944) (xy 122.768718 -389.338287) (xy 122.786947 -389.388304)
			(xy 122.796215 -389.440727) (xy 122.796808 -389.467344) (xy 122.796401 -389.491351) (xy 122.78888 -389.538772)
			(xy 122.77403 -389.584432) (xy 122.752217 -389.627206) (xy 122.723979 -389.666038) (xy 122.690011 -389.699973)
			(xy 122.651151 -389.728173) (xy 122.608357 -389.749944) (xy 122.562682 -389.76475) (xy 122.515253 -389.772225)
			(xy 122.491246 -389.772652) (xy 122.467675 -389.772194) (xy 122.421091 -389.764961) (xy 122.376175 -389.750644)
			(xy 122.333998 -389.729586) (xy 122.295564 -389.702287) (xy 122.26179 -389.669398) (xy 122.23348 -389.631703)
			(xy 122.222006 -389.611108) (xy 122.221498 -389.610346) (xy 121.823734 -388.922006) (xy 121.811856 -388.89933)
			(xy 121.795006 -388.850996) (xy 121.786434 -388.800533) (xy 121.785888 -388.77494) (xy 121.243894 -388.77494)
			(xy 121.556018 -389.314944) (xy 121.568823 -389.338287) (xy 121.587051 -389.388304) (xy 121.596319 -389.440727)
			(xy 121.596912 -389.467344) (xy 121.596502 -389.491351) (xy 121.58898 -389.538772) (xy 121.574131 -389.584432)
			(xy 121.552318 -389.627205) (xy 121.52408 -389.666037) (xy 121.490113 -389.699971) (xy 121.451253 -389.728172)
			(xy 121.408459 -389.749943) (xy 121.362786 -389.764749) (xy 121.315357 -389.772225) (xy 121.29135 -389.772652)
			(xy 121.267779 -389.772191) (xy 121.221195 -389.764958) (xy 121.176279 -389.750642) (xy 121.134102 -389.729584)
			(xy 121.095668 -389.702286) (xy 121.061894 -389.669397) (xy 121.033584 -389.631703) (xy 121.02211 -389.611108)
			(xy 121.021602 -389.610346) (xy 120.623838 -388.922006) (xy 120.61196 -388.89933) (xy 120.595111 -388.850996)
			(xy 120.586538 -388.800533) (xy 120.585992 -388.77494) (xy 120.043744 -388.77494) (xy 120.355868 -389.314944)
			(xy 120.368606 -389.338307) (xy 120.386718 -389.388336) (xy 120.395926 -389.440741) (xy 120.396508 -389.467344)
			(xy 120.396078 -389.491336) (xy 120.388565 -389.53873) (xy 120.373732 -389.584364) (xy 120.351943 -389.627117)
			(xy 120.323735 -389.665935) (xy 120.289802 -389.699863) (xy 120.250979 -389.728066) (xy 120.208224 -389.749849)
			(xy 120.162587 -389.764676) (xy 120.115192 -389.772181) (xy 120.0912 -389.772652) (xy 120.067627 -389.772231)
			(xy 120.021042 -389.764991) (xy 119.976125 -389.750668) (xy 119.933948 -389.729603) (xy 119.895515 -389.702298)
			(xy 119.861742 -389.669404) (xy 119.833433 -389.631705) (xy 119.82196 -389.611108) (xy 119.821452 -389.610346)
			(xy 119.423688 -388.922006) (xy 119.411772 -388.899338) (xy 119.394835 -388.851013) (xy 119.386175 -388.800542)
			(xy 119.385588 -388.77494) (xy 118.843848 -388.77494) (xy 119.155972 -389.314944) (xy 119.16871 -389.338307)
			(xy 119.186822 -389.388336) (xy 119.19603 -389.440741) (xy 119.196612 -389.467344) (xy 119.196178 -389.491336)
			(xy 119.188665 -389.538729) (xy 119.173832 -389.584363) (xy 119.152044 -389.627116) (xy 119.123836 -389.665934)
			(xy 119.089903 -389.699862) (xy 119.051082 -389.728065) (xy 119.008326 -389.749848) (xy 118.96269 -389.764675)
			(xy 118.915296 -389.772181) (xy 118.891304 -389.772652) (xy 118.867732 -389.772228) (xy 118.821146 -389.764988)
			(xy 118.776229 -389.750666) (xy 118.734052 -389.729602) (xy 118.695619 -389.702297) (xy 118.661846 -389.669404)
			(xy 118.633537 -389.631705) (xy 118.622064 -389.611108) (xy 118.621556 -389.610346) (xy 118.223792 -388.922006)
			(xy 118.211876 -388.899338) (xy 118.194939 -388.851012) (xy 118.186279 -388.800542) (xy 118.185692 -388.77494)
			(xy 117.643698 -388.77494) (xy 117.955822 -389.314944) (xy 117.968627 -389.338287) (xy 117.986855 -389.388304)
			(xy 117.996123 -389.440727) (xy 117.996716 -389.467344) (xy 117.996302 -389.491351) (xy 117.988781 -389.538771)
			(xy 117.973931 -389.584431) (xy 117.952119 -389.627203) (xy 117.923881 -389.666036) (xy 117.889915 -389.69997)
			(xy 117.851056 -389.728171) (xy 117.808262 -389.749942) (xy 117.762589 -389.764748) (xy 117.715161 -389.772224)
			(xy 117.691154 -389.772652) (xy 117.667583 -389.772187) (xy 117.620999 -389.764955) (xy 117.576084 -389.75064)
			(xy 117.533906 -389.729583) (xy 117.495473 -389.702285) (xy 117.461698 -389.669397) (xy 117.433388 -389.631702)
			(xy 117.421914 -389.611108) (xy 117.421406 -389.610346) (xy 117.023642 -388.922006) (xy 117.011765 -388.89933)
			(xy 116.994915 -388.850996) (xy 116.986342 -388.800533) (xy 116.985796 -388.77494) (xy 116.443802 -388.77494)
			(xy 116.755926 -389.314944) (xy 116.768731 -389.338286) (xy 116.786959 -389.388304) (xy 116.796227 -389.440727)
			(xy 116.79682 -389.467344) (xy 116.796402 -389.49135) (xy 116.788881 -389.538771) (xy 116.774031 -389.58443)
			(xy 116.752219 -389.627202) (xy 116.723982 -389.666034) (xy 116.690016 -389.699969) (xy 116.651158 -389.728169)
			(xy 116.608365 -389.749941) (xy 116.562692 -389.764748) (xy 116.515265 -389.772224) (xy 116.491258 -389.772652)
			(xy 116.467687 -389.772184) (xy 116.421104 -389.764953) (xy 116.376188 -389.750638) (xy 116.334011 -389.729581)
			(xy 116.295577 -389.702284) (xy 116.261802 -389.669396) (xy 116.233492 -389.631702) (xy 116.222018 -389.611108)
			(xy 116.22151 -389.610346) (xy 115.823746 -388.922006) (xy 115.811869 -388.89933) (xy 115.795019 -388.850996)
			(xy 115.786446 -388.800533) (xy 115.7859 -388.77494) (xy 115.243906 -388.77494) (xy 115.55603 -389.314944)
			(xy 115.568836 -389.338286) (xy 115.587063 -389.388304) (xy 115.596331 -389.440727) (xy 115.596924 -389.467344)
			(xy 115.596502 -389.49135) (xy 115.588981 -389.53877) (xy 115.574132 -389.584429) (xy 115.55232 -389.627201)
			(xy 115.524084 -389.666033) (xy 115.490118 -389.699967) (xy 115.45126 -389.728168) (xy 115.408468 -389.74994)
			(xy 115.362795 -389.764747) (xy 115.315369 -389.772224) (xy 115.291362 -389.772652) (xy 115.267791 -389.772181)
			(xy 115.221208 -389.76495) (xy 115.176292 -389.750636) (xy 115.134115 -389.72958) (xy 115.095681 -389.702283)
			(xy 115.061907 -389.669396) (xy 115.033596 -389.631702) (xy 115.022122 -389.611108) (xy 115.021614 -389.610346)
			(xy 114.62385 -388.922006) (xy 114.611973 -388.899329) (xy 114.595123 -388.850996) (xy 114.58655 -388.800533)
			(xy 114.586004 -388.77494) (xy 98.671676 -388.77494) (xy 98.9838 -389.314944) (xy 98.996532 -389.33831)
			(xy 99.014648 -389.388338) (xy 99.023858 -389.440741) (xy 99.02444 -389.467344) (xy 99.023978 -389.491335)
			(xy 99.016466 -389.538725) (xy 99.001635 -389.584357) (xy 98.979849 -389.627107) (xy 98.951644 -389.665924)
			(xy 98.917715 -389.699852) (xy 98.878897 -389.728055) (xy 98.836146 -389.74984) (xy 98.790513 -389.764669)
			(xy 98.743123 -389.772179) (xy 98.719132 -389.772652) (xy 98.69556 -389.772205) (xy 98.648976 -389.76497)
			(xy 98.60406 -389.750651) (xy 98.561883 -389.729591) (xy 98.523449 -389.70229) (xy 98.489675 -389.6694)
			(xy 98.461365 -389.631703) (xy 98.449892 -389.611108) (xy 98.449384 -389.610346) (xy 98.05162 -388.922006)
			(xy 98.039706 -388.899337) (xy 98.022768 -388.851012) (xy 98.014108 -388.800542) (xy 98.01352 -388.77494)
			(xy 97.471526 -388.77494) (xy 97.78365 -389.314944) (xy 97.796457 -389.338285) (xy 97.814684 -389.388304)
			(xy 97.823951 -389.440726) (xy 97.824544 -389.467344) (xy 97.824102 -389.491349) (xy 97.816582 -389.538767)
			(xy 97.801734 -389.584424) (xy 97.779924 -389.627195) (xy 97.75169 -389.666026) (xy 97.717726 -389.69996)
			(xy 97.678871 -389.728161) (xy 97.636082 -389.749934) (xy 97.590412 -389.764743) (xy 97.542988 -389.772222)
			(xy 97.518982 -389.772652) (xy 97.495409 -389.772245) (xy 97.448822 -389.765003) (xy 97.403906 -389.750677)
			(xy 97.361728 -389.72961) (xy 97.323295 -389.702303) (xy 97.289523 -389.669407) (xy 97.261214 -389.631706)
			(xy 97.249742 -389.611108) (xy 97.249234 -389.610346) (xy 96.85147 -388.922006) (xy 96.839595 -388.899329)
			(xy 96.822743 -388.850996) (xy 96.81417 -388.800533) (xy 96.813624 -388.77494) (xy 96.27163 -388.77494)
			(xy 96.583754 -389.314944) (xy 96.596562 -389.338285) (xy 96.614788 -389.388304) (xy 96.624055 -389.440726)
			(xy 96.624648 -389.467344) (xy 96.624202 -389.491349) (xy 96.616682 -389.538767) (xy 96.601834 -389.584423)
			(xy 96.580025 -389.627194) (xy 96.551791 -389.666025) (xy 96.517828 -389.699959) (xy 96.478973 -389.72816)
			(xy 96.436184 -389.749933) (xy 96.390515 -389.764742) (xy 96.343091 -389.772222) (xy 96.319086 -389.772652)
			(xy 96.295513 -389.772242) (xy 96.248927 -389.765) (xy 96.20401 -389.750675) (xy 96.161833 -389.729608)
			(xy 96.1234 -389.702302) (xy 96.089627 -389.669406) (xy 96.061319 -389.631705) (xy 96.049846 -389.611108)
			(xy 96.049338 -389.610346) (xy 95.651574 -388.922006) (xy 95.639699 -388.899329) (xy 95.622848 -388.850996)
			(xy 95.614274 -388.800533) (xy 95.613728 -388.77494) (xy 95.07148 -388.77494) (xy 95.383604 -389.314944)
			(xy 95.396337 -389.33831) (xy 95.414452 -389.388337) (xy 95.423662 -389.440741) (xy 95.424244 -389.467344)
			(xy 95.423778 -389.491335) (xy 95.416267 -389.538724) (xy 95.401435 -389.584356) (xy 95.379649 -389.627106)
			(xy 95.351445 -389.665923) (xy 95.317517 -389.69985) (xy 95.278699 -389.728054) (xy 95.235949 -389.749838)
			(xy 95.190317 -389.764668) (xy 95.142927 -389.772179) (xy 95.118936 -389.772652) (xy 95.095364 -389.772202)
			(xy 95.04878 -389.764967) (xy 95.003864 -389.750649) (xy 94.961687 -389.729589) (xy 94.923253 -389.702289)
			(xy 94.889479 -389.669399) (xy 94.861169 -389.631703) (xy 94.849696 -389.611108) (xy 94.849188 -389.610346)
			(xy 94.451424 -388.922006) (xy 94.439511 -388.899337) (xy 94.422572 -388.851012) (xy 94.413912 -388.800542)
			(xy 94.413324 -388.77494) (xy 93.871584 -388.77494) (xy 94.183708 -389.314944) (xy 94.196441 -389.33831)
			(xy 94.214556 -389.388337) (xy 94.223766 -389.440741) (xy 94.224348 -389.467344) (xy 94.223878 -389.491334)
			(xy 94.216367 -389.538724) (xy 94.201536 -389.584355) (xy 94.17975 -389.627105) (xy 94.151546 -389.665922)
			(xy 94.117618 -389.699849) (xy 94.078802 -389.728052) (xy 94.036051 -389.749837) (xy 93.99042 -389.764668)
			(xy 93.94303 -389.772178) (xy 93.91904 -389.772652) (xy 93.895469 -389.772199) (xy 93.848884 -389.764965)
			(xy 93.803969 -389.750647) (xy 93.761791 -389.729588) (xy 93.723358 -389.702288) (xy 93.689583 -389.669399)
			(xy 93.661273 -389.631703) (xy 93.6498 -389.611108) (xy 93.649292 -389.610346) (xy 93.251528 -388.922006)
			(xy 93.239615 -388.899337) (xy 93.222676 -388.851012) (xy 93.214016 -388.800542) (xy 93.213428 -388.77494)
			(xy 92.671688 -388.77494) (xy 92.983812 -389.314944) (xy 92.996545 -389.338309) (xy 93.01466 -389.388337)
			(xy 93.02387 -389.440741) (xy 93.024452 -389.467344) (xy 93.023978 -389.491334) (xy 93.016467 -389.538723)
			(xy 93.001636 -389.584354) (xy 92.979851 -389.627104) (xy 92.951648 -389.66592) (xy 92.91772 -389.699848)
			(xy 92.878904 -389.728051) (xy 92.836154 -389.749836) (xy 92.790523 -389.764667) (xy 92.743134 -389.772178)
			(xy 92.719144 -389.772652) (xy 92.695573 -389.772195) (xy 92.648989 -389.764962) (xy 92.604073 -389.750645)
			(xy 92.561896 -389.729586) (xy 92.523462 -389.702287) (xy 92.489688 -389.669398) (xy 92.461378 -389.631703)
			(xy 92.449904 -389.611108) (xy 92.449396 -389.610346) (xy 92.051632 -388.922006) (xy 92.039719 -388.899336)
			(xy 92.02278 -388.851012) (xy 92.01412 -388.800542) (xy 92.013532 -388.77494) (xy 91.471538 -388.77494)
			(xy 91.783662 -389.314944) (xy 91.79647 -389.338285) (xy 91.814696 -389.388304) (xy 91.823963 -389.440726)
			(xy 91.824556 -389.467344) (xy 91.824102 -389.491349) (xy 91.816582 -389.538765) (xy 91.801735 -389.584421)
			(xy 91.779926 -389.627191) (xy 91.751693 -389.666022) (xy 91.717731 -389.699956) (xy 91.678878 -389.728157)
			(xy 91.63609 -389.749931) (xy 91.590422 -389.76474) (xy 91.542999 -389.772221) (xy 91.518994 -389.772652)
			(xy 91.495421 -389.772236) (xy 91.448835 -389.764995) (xy 91.403919 -389.750671) (xy 91.361741 -389.729605)
			(xy 91.323308 -389.7023) (xy 91.289535 -389.669405) (xy 91.261227 -389.631705) (xy 91.249754 -389.611108)
			(xy 91.249246 -389.610346) (xy 90.851482 -388.922006) (xy 90.839608 -388.899328) (xy 90.822756 -388.850996)
			(xy 90.814182 -388.800533) (xy 90.813636 -388.77494) (xy 90.271642 -388.77494) (xy 90.583766 -389.314944)
			(xy 90.596575 -389.338285) (xy 90.6148 -389.388303) (xy 90.624067 -389.440726) (xy 90.62466 -389.467344)
			(xy 90.624301 -389.491353) (xy 90.616779 -389.53878) (xy 90.601926 -389.584444) (xy 90.580109 -389.62722)
			(xy 90.551865 -389.666055) (xy 90.517891 -389.69999) (xy 90.479025 -389.72819) (xy 90.436223 -389.749958)
			(xy 90.390542 -389.764759) (xy 90.343108 -389.772228) (xy 90.319098 -389.772652) (xy 90.295525 -389.772232)
			(xy 90.24894 -389.764992) (xy 90.204023 -389.750669) (xy 90.161846 -389.729604) (xy 90.123413 -389.702299)
			(xy 90.089639 -389.669405) (xy 90.061331 -389.631705) (xy 90.049858 -389.611108) (xy 90.04935 -389.610346)
			(xy 89.651586 -388.922006) (xy 89.639712 -388.899328) (xy 89.62286 -388.850996) (xy 89.614286 -388.800533)
			(xy 89.61374 -388.77494) (xy 89.071492 -388.77494) (xy 89.383616 -389.314944) (xy 89.39635 -389.338309)
			(xy 89.414465 -389.388337) (xy 89.423674 -389.440741) (xy 89.424256 -389.467344) (xy 89.423778 -389.491334)
			(xy 89.416267 -389.538723) (xy 89.401436 -389.584353) (xy 89.379652 -389.627103) (xy 89.351449 -389.665919)
			(xy 89.317522 -389.699846) (xy 89.278706 -389.72805) (xy 89.235957 -389.749835) (xy 89.190327 -389.764666)
			(xy 89.142938 -389.772178) (xy 89.118948 -389.772652) (xy 89.095377 -389.772192) (xy 89.048793 -389.764959)
			(xy 89.003877 -389.750643) (xy 88.9617 -389.729585) (xy 88.923266 -389.702286) (xy 88.889492 -389.669398)
			(xy 88.861182 -389.631703) (xy 88.849708 -389.611108) (xy 88.8492 -389.610346) (xy 88.451436 -388.922006)
			(xy 88.439523 -388.899336) (xy 88.422584 -388.851012) (xy 88.413924 -388.800542) (xy 88.413336 -388.77494)
			(xy 87.871596 -388.77494) (xy 88.18372 -389.314944) (xy 88.196454 -389.338309) (xy 88.214569 -389.388337)
			(xy 88.223778 -389.440741) (xy 88.22436 -389.467344) (xy 88.224002 -389.491341) (xy 88.216487 -389.538742)
			(xy 88.20165 -389.584385) (xy 88.179855 -389.627144) (xy 88.151639 -389.665968) (xy 88.117698 -389.699899)
			(xy 88.078866 -389.728103) (xy 88.0361 -389.749885) (xy 87.990453 -389.764709) (xy 87.943049 -389.772209)
			(xy 87.919052 -389.772652) (xy 87.895481 -389.772189) (xy 87.848897 -389.764957) (xy 87.803982 -389.750641)
			(xy 87.761804 -389.729583) (xy 87.723371 -389.702285) (xy 87.689596 -389.669397) (xy 87.661286 -389.631703)
			(xy 87.649812 -389.611108) (xy 87.649304 -389.610346) (xy 87.25154 -388.922006) (xy 87.239628 -388.899336)
			(xy 87.222688 -388.851012) (xy 87.214028 -388.800542) (xy 87.21344 -388.77494) (xy 86.6717 -388.77494)
			(xy 86.983824 -389.314944) (xy 86.996558 -389.338309) (xy 87.014673 -389.388337) (xy 87.023882 -389.440741)
			(xy 87.024464 -389.467344) (xy 87.024078 -389.491339) (xy 87.016564 -389.538736) (xy 87.001728 -389.584375)
			(xy 86.979935 -389.62713) (xy 86.951722 -389.66595) (xy 86.917783 -389.699879) (xy 86.878955 -389.728081)
			(xy 86.836193 -389.749861) (xy 86.79055 -389.764684) (xy 86.743151 -389.772185) (xy 86.719156 -389.772652)
			(xy 86.695585 -389.772186) (xy 86.649001 -389.764954) (xy 86.604086 -389.750639) (xy 86.561909 -389.729582)
			(xy 86.523475 -389.702284) (xy 86.4897 -389.669396) (xy 86.46139 -389.631702) (xy 86.449916 -389.611108)
			(xy 86.449408 -389.610346) (xy 86.051644 -388.922006) (xy 86.039732 -388.899336) (xy 86.022793 -388.851012)
			(xy 86.014132 -388.800542) (xy 86.013544 -388.77494) (xy 85.47155 -388.77494) (xy 85.783674 -389.314944)
			(xy 85.796483 -389.338284) (xy 85.814708 -389.388303) (xy 85.823975 -389.440726) (xy 85.824568 -389.467344)
			(xy 85.824201 -389.491353) (xy 85.816679 -389.538778) (xy 85.801826 -389.584442) (xy 85.78001 -389.627218)
			(xy 85.751767 -389.666052) (xy 85.717795 -389.699987) (xy 85.678929 -389.728187) (xy 85.636129 -389.749956)
			(xy 85.590449 -389.764758) (xy 85.543016 -389.772228) (xy 85.519006 -389.772652) (xy 85.495434 -389.772226)
			(xy 85.448848 -389.764987) (xy 85.403932 -389.750665) (xy 85.361754 -389.729601) (xy 85.323321 -389.702297)
			(xy 85.289548 -389.669404) (xy 85.261239 -389.631705) (xy 85.249766 -389.611108) (xy 85.249258 -389.610346)
			(xy 84.851494 -388.922006) (xy 84.839621 -388.899328) (xy 84.822768 -388.850995) (xy 84.814194 -388.800532)
			(xy 84.813648 -388.77494) (xy 84.271654 -388.77494) (xy 84.583778 -389.314944) (xy 84.596588 -389.338284)
			(xy 84.614813 -389.388303) (xy 84.624079 -389.440726) (xy 84.624672 -389.467344) (xy 84.624301 -389.491353)
			(xy 84.616779 -389.538778) (xy 84.601927 -389.584441) (xy 84.580111 -389.627217) (xy 84.551868 -389.666051)
			(xy 84.517896 -389.699986) (xy 84.479031 -389.728185) (xy 84.436232 -389.749955) (xy 84.390552 -389.764757)
			(xy 84.343119 -389.772228) (xy 84.31911 -389.772652) (xy 84.295538 -389.772223) (xy 84.248952 -389.764984)
			(xy 84.204036 -389.750663) (xy 84.161859 -389.729599) (xy 84.123425 -389.702296) (xy 84.089652 -389.669403)
			(xy 84.061343 -389.631704) (xy 84.04987 -389.611108) (xy 84.049362 -389.610346) (xy 83.651598 -388.922006)
			(xy 83.639725 -388.899328) (xy 83.622872 -388.850995) (xy 83.614298 -388.800532) (xy 83.613752 -388.77494)
			(xy 83.071504 -388.77494) (xy 83.383628 -389.314944) (xy 83.396363 -389.338309) (xy 83.414477 -389.388337)
			(xy 83.423686 -389.440741) (xy 83.424268 -389.467344) (xy 83.423878 -389.491338) (xy 83.416364 -389.538735)
			(xy 83.401528 -389.584374) (xy 83.379736 -389.627129) (xy 83.351523 -389.665949) (xy 83.317585 -389.699878)
			(xy 83.278757 -389.728079) (xy 83.235996 -389.74986) (xy 83.190354 -389.764684) (xy 83.142955 -389.772184)
			(xy 83.11896 -389.772652) (xy 83.095389 -389.772182) (xy 83.048806 -389.764951) (xy 83.00389 -389.750637)
			(xy 82.961713 -389.72958) (xy 82.923279 -389.702283) (xy 82.889504 -389.669396) (xy 82.861194 -389.631702)
			(xy 82.84972 -389.611108) (xy 82.849212 -389.610346) (xy 82.451448 -388.922006) (xy 82.439536 -388.899336)
			(xy 82.422597 -388.851012) (xy 82.413936 -388.800542) (xy 82.413348 -388.77494) (xy 81.871608 -388.77494)
			(xy 82.183732 -389.314944) (xy 82.196467 -389.338308) (xy 82.214581 -389.388337) (xy 82.22379 -389.440741)
			(xy 82.224372 -389.467344) (xy 82.223978 -389.491338) (xy 82.216464 -389.538735) (xy 82.201628 -389.584373)
			(xy 82.179836 -389.627128) (xy 82.151624 -389.665948) (xy 82.117687 -389.699876) (xy 82.078859 -389.728078)
			(xy 82.036099 -389.749859) (xy 81.990457 -389.764683) (xy 81.943058 -389.772184) (xy 81.919064 -389.772652)
			(xy 81.895493 -389.772179) (xy 81.84891 -389.764949) (xy 81.803995 -389.750635) (xy 81.761817 -389.729579)
			(xy 81.723383 -389.702282) (xy 81.689609 -389.669395) (xy 81.661298 -389.631702) (xy 81.649824 -389.611108)
			(xy 81.649316 -389.610346) (xy 81.251552 -388.922006) (xy 81.239641 -388.899336) (xy 81.222701 -388.851012)
			(xy 81.21404 -388.800542) (xy 81.213452 -388.77494) (xy 80.671712 -388.77494) (xy 80.983836 -389.314944)
			(xy 80.996571 -389.338308) (xy 81.014685 -389.388337) (xy 81.023894 -389.440741) (xy 81.024476 -389.467344)
			(xy 81.024078 -389.491338) (xy 81.016564 -389.538734) (xy 81.001729 -389.584372) (xy 80.979937 -389.627127)
			(xy 80.951725 -389.665946) (xy 80.917788 -389.699875) (xy 80.878962 -389.728077) (xy 80.836201 -389.749858)
			(xy 80.79056 -389.764682) (xy 80.743162 -389.772184) (xy 80.719168 -389.772652) (xy 80.695597 -389.772176)
			(xy 80.649014 -389.764946) (xy 80.604099 -389.750633) (xy 80.561922 -389.729577) (xy 80.523488 -389.702281)
			(xy 80.489713 -389.669395) (xy 80.461402 -389.631702) (xy 80.449928 -389.611108) (xy 80.44942 -389.610346)
			(xy 80.051656 -388.922006) (xy 80.039745 -388.899335) (xy 80.022805 -388.851011) (xy 80.014144 -388.800542)
			(xy 80.013556 -388.77494) (xy 66.143928 -388.77494) (xy 66.456052 -389.314944) (xy 66.468789 -389.338308)
			(xy 66.486902 -389.388337) (xy 66.49611 -389.440741) (xy 66.496692 -389.467344) (xy 66.496278 -389.491337)
			(xy 66.488765 -389.538732) (xy 66.47393 -389.584368) (xy 66.45214 -389.627122) (xy 66.42393 -389.665941)
			(xy 66.389995 -389.699869) (xy 66.351171 -389.728071) (xy 66.308412 -389.749853) (xy 66.262774 -389.764679)
			(xy 66.215377 -389.772183) (xy 66.191384 -389.772652) (xy 66.167811 -389.772244) (xy 66.121225 -389.765001)
			(xy 66.076308 -389.750676) (xy 66.034131 -389.729609) (xy 65.995698 -389.702302) (xy 65.961925 -389.669407)
			(xy 65.933616 -389.631706) (xy 65.922144 -389.611108) (xy 65.921636 -389.610346) (xy 65.523872 -388.922006)
			(xy 65.511954 -388.899339) (xy 65.495018 -388.851013) (xy 65.486359 -388.800542) (xy 65.485772 -388.77494)
			(xy 64.943778 -388.77494) (xy 65.255902 -389.314944) (xy 65.268705 -389.338288) (xy 65.286934 -389.388305)
			(xy 65.296203 -389.440727) (xy 65.296796 -389.467344) (xy 65.296401 -389.491352) (xy 65.28888 -389.538774)
			(xy 65.274029 -389.584435) (xy 65.252215 -389.627209) (xy 65.223975 -389.666042) (xy 65.190006 -389.699977)
			(xy 65.151145 -389.728177) (xy 65.108348 -389.749948) (xy 65.062672 -389.764752) (xy 65.015242 -389.772226)
			(xy 64.991234 -389.772652) (xy 64.967662 -389.772203) (xy 64.921078 -389.764969) (xy 64.876162 -389.75065)
			(xy 64.833985 -389.72959) (xy 64.795551 -389.70229) (xy 64.761777 -389.6694) (xy 64.733467 -389.631703)
			(xy 64.721994 -389.611108) (xy 64.721486 -389.610346) (xy 64.323722 -388.922006) (xy 64.311843 -388.899331)
			(xy 64.294994 -388.850996) (xy 64.286422 -388.800533) (xy 64.285876 -388.77494) (xy 63.743882 -388.77494)
			(xy 64.056006 -389.314944) (xy 64.06881 -389.338287) (xy 64.087038 -389.388304) (xy 64.096307 -389.440727)
			(xy 64.0969 -389.467344) (xy 64.096501 -389.491351) (xy 64.08898 -389.538774) (xy 64.07413 -389.584434)
			(xy 64.052316 -389.627208) (xy 64.024077 -389.666041) (xy 63.990108 -389.699976) (xy 63.951247 -389.728176)
			(xy 63.908451 -389.749947) (xy 63.862776 -389.764752) (xy 63.815346 -389.772225) (xy 63.791338 -389.772652)
			(xy 63.767766 -389.7722) (xy 63.721182 -389.764966) (xy 63.676266 -389.750648) (xy 63.634089 -389.729589)
			(xy 63.595656 -389.702289) (xy 63.561881 -389.669399) (xy 63.533571 -389.631703) (xy 63.522098 -389.611108)
			(xy 63.52159 -389.610346) (xy 63.123826 -388.922006) (xy 63.111947 -388.89933) (xy 63.095098 -388.850996)
			(xy 63.086526 -388.800533) (xy 63.08598 -388.77494) (xy 62.543732 -388.77494) (xy 62.855856 -389.314944)
			(xy 62.868593 -389.338307) (xy 62.886706 -389.388337) (xy 62.895914 -389.440741) (xy 62.896496 -389.467344)
			(xy 62.896078 -389.491337) (xy 62.888565 -389.538731) (xy 62.873731 -389.584367) (xy 62.851941 -389.627121)
			(xy 62.823731 -389.665939) (xy 62.789797 -389.699868) (xy 62.750973 -389.72807) (xy 62.708215 -389.749852)
			(xy 62.662577 -389.764678) (xy 62.615181 -389.772182) (xy 62.591188 -389.772652) (xy 62.567615 -389.772241)
			(xy 62.521029 -389.764999) (xy 62.476112 -389.750674) (xy 62.433935 -389.729608) (xy 62.395502 -389.702301)
			(xy 62.361729 -389.669406) (xy 62.333421 -389.631705) (xy 62.321948 -389.611108) (xy 62.32144 -389.610346)
			(xy 61.923676 -388.922006) (xy 61.911759 -388.899339) (xy 61.894823 -388.851013) (xy 61.886163 -388.800542)
			(xy 61.885576 -388.77494) (xy 61.343836 -388.77494) (xy 61.65596 -389.314944) (xy 61.668697 -389.338307)
			(xy 61.68681 -389.388337) (xy 61.696018 -389.440741) (xy 61.6966 -389.467344) (xy 61.696178 -389.491337)
			(xy 61.688665 -389.538731) (xy 61.673831 -389.584366) (xy 61.652041 -389.627119) (xy 61.623832 -389.665938)
			(xy 61.589898 -389.699866) (xy 61.551075 -389.728069) (xy 61.508318 -389.749851) (xy 61.46268 -389.764677)
			(xy 61.415285 -389.772182) (xy 61.391292 -389.772652) (xy 61.367719 -389.772237) (xy 61.321133 -389.764996)
			(xy 61.276216 -389.750672) (xy 61.234039 -389.729606) (xy 61.195606 -389.7023) (xy 61.161833 -389.669406)
			(xy 61.133525 -389.631705) (xy 61.122052 -389.611108) (xy 61.121544 -389.610346) (xy 60.72378 -388.922006)
			(xy 60.711863 -388.899339) (xy 60.694927 -388.851013) (xy 60.686267 -388.800542) (xy 60.68568 -388.77494)
			(xy 60.14394 -388.77494) (xy 60.456064 -389.314944) (xy 60.468802 -389.338307) (xy 60.486914 -389.388336)
			(xy 60.496122 -389.440741) (xy 60.496704 -389.467344) (xy 60.496278 -389.491337) (xy 60.488765 -389.53873)
			(xy 60.473931 -389.584365) (xy 60.452142 -389.627118) (xy 60.423933 -389.665937) (xy 60.39 -389.699865)
			(xy 60.351177 -389.728067) (xy 60.308421 -389.74985) (xy 60.262783 -389.764676) (xy 60.215389 -389.772182)
			(xy 60.191396 -389.772652) (xy 60.167823 -389.772234) (xy 60.121237 -389.764993) (xy 60.076321 -389.75067)
			(xy 60.034144 -389.729605) (xy 59.99571 -389.702299) (xy 59.961937 -389.669405) (xy 59.933629 -389.631705)
			(xy 59.922156 -389.611108) (xy 59.921648 -389.610346) (xy 59.523884 -388.922006) (xy 59.511967 -388.899338)
			(xy 59.495031 -388.851013) (xy 59.486371 -388.800542) (xy 59.485784 -388.77494) (xy 58.94379 -388.77494)
			(xy 59.255914 -389.314944) (xy 59.268718 -389.338287) (xy 59.286947 -389.388304) (xy 59.296215 -389.440727)
			(xy 59.296808 -389.467344) (xy 59.296401 -389.491351) (xy 59.28888 -389.538772) (xy 59.27403 -389.584432)
			(xy 59.252217 -389.627206) (xy 59.223979 -389.666038) (xy 59.190011 -389.699973) (xy 59.151151 -389.728173)
			(xy 59.108357 -389.749944) (xy 59.062682 -389.76475) (xy 59.015253 -389.772225) (xy 58.991246 -389.772652)
			(xy 58.967675 -389.772194) (xy 58.921091 -389.764961) (xy 58.876175 -389.750644) (xy 58.833998 -389.729586)
			(xy 58.795564 -389.702287) (xy 58.76179 -389.669398) (xy 58.73348 -389.631703) (xy 58.722006 -389.611108)
			(xy 58.721498 -389.610346) (xy 58.323734 -388.922006) (xy 58.311856 -388.89933) (xy 58.295006 -388.850996)
			(xy 58.286434 -388.800533) (xy 58.285888 -388.77494) (xy 57.743894 -388.77494) (xy 58.056018 -389.314944)
			(xy 58.068823 -389.338287) (xy 58.087051 -389.388304) (xy 58.096319 -389.440727) (xy 58.096912 -389.467344)
			(xy 58.096502 -389.491351) (xy 58.08898 -389.538772) (xy 58.074131 -389.584432) (xy 58.052318 -389.627205)
			(xy 58.02408 -389.666037) (xy 57.990113 -389.699971) (xy 57.951253 -389.728172) (xy 57.908459 -389.749943)
			(xy 57.862786 -389.764749) (xy 57.815357 -389.772225) (xy 57.79135 -389.772652) (xy 57.767779 -389.772191)
			(xy 57.721195 -389.764958) (xy 57.676279 -389.750642) (xy 57.634102 -389.729584) (xy 57.595668 -389.702286)
			(xy 57.561894 -389.669397) (xy 57.533584 -389.631703) (xy 57.52211 -389.611108) (xy 57.521602 -389.610346)
			(xy 57.123838 -388.922006) (xy 57.11196 -388.89933) (xy 57.095111 -388.850996) (xy 57.086538 -388.800533)
			(xy 57.085992 -388.77494) (xy 56.543744 -388.77494) (xy 56.855868 -389.314944) (xy 56.868606 -389.338307)
			(xy 56.886718 -389.388336) (xy 56.895926 -389.440741) (xy 56.896508 -389.467344) (xy 56.896078 -389.491336)
			(xy 56.888565 -389.53873) (xy 56.873732 -389.584364) (xy 56.851943 -389.627117) (xy 56.823735 -389.665935)
			(xy 56.789802 -389.699863) (xy 56.750979 -389.728066) (xy 56.708224 -389.749849) (xy 56.662587 -389.764676)
			(xy 56.615192 -389.772181) (xy 56.5912 -389.772652) (xy 56.567627 -389.772231) (xy 56.521042 -389.764991)
			(xy 56.476125 -389.750668) (xy 56.433948 -389.729603) (xy 56.395515 -389.702298) (xy 56.361742 -389.669404)
			(xy 56.333433 -389.631705) (xy 56.32196 -389.611108) (xy 56.321452 -389.610346) (xy 55.923688 -388.922006)
			(xy 55.911772 -388.899338) (xy 55.894835 -388.851013) (xy 55.886175 -388.800542) (xy 55.885588 -388.77494)
			(xy 55.343848 -388.77494) (xy 55.655972 -389.314944) (xy 55.66871 -389.338307) (xy 55.686822 -389.388336)
			(xy 55.69603 -389.440741) (xy 55.696612 -389.467344) (xy 55.696178 -389.491336) (xy 55.688665 -389.538729)
			(xy 55.673832 -389.584363) (xy 55.652044 -389.627116) (xy 55.623836 -389.665934) (xy 55.589903 -389.699862)
			(xy 55.551082 -389.728065) (xy 55.508326 -389.749848) (xy 55.46269 -389.764675) (xy 55.415296 -389.772181)
			(xy 55.391304 -389.772652) (xy 55.367732 -389.772228) (xy 55.321146 -389.764988) (xy 55.276229 -389.750666)
			(xy 55.234052 -389.729602) (xy 55.195619 -389.702297) (xy 55.161846 -389.669404) (xy 55.133537 -389.631705)
			(xy 55.122064 -389.611108) (xy 55.121556 -389.610346) (xy 54.723792 -388.922006) (xy 54.711876 -388.899338)
			(xy 54.694939 -388.851012) (xy 54.686279 -388.800542) (xy 54.685692 -388.77494) (xy 54.143952 -388.77494)
			(xy 54.456076 -389.314944) (xy 54.468806 -389.338311) (xy 54.486923 -389.388338) (xy 54.496134 -389.440741)
			(xy 54.496716 -389.467344) (xy 54.496278 -389.491336) (xy 54.488766 -389.538728) (xy 54.473933 -389.584362)
			(xy 54.452144 -389.627115) (xy 54.423937 -389.665932) (xy 54.390005 -389.69986) (xy 54.351184 -389.728063)
			(xy 54.308429 -389.749846) (xy 54.262793 -389.764674) (xy 54.2154 -389.772181) (xy 54.191408 -389.772652)
			(xy 54.167836 -389.772224) (xy 54.12125 -389.764986) (xy 54.076334 -389.750664) (xy 54.034157 -389.7296)
			(xy 53.995723 -389.702296) (xy 53.96195 -389.669403) (xy 53.933641 -389.631704) (xy 53.922168 -389.611108)
			(xy 53.92166 -389.610346) (xy 53.523896 -388.922006) (xy 53.51198 -388.899338) (xy 53.495043 -388.851012)
			(xy 53.486383 -388.800542) (xy 53.485796 -388.77494) (xy 52.943802 -388.77494) (xy 53.255926 -389.314944)
			(xy 53.268731 -389.338286) (xy 53.286959 -389.388304) (xy 53.296227 -389.440727) (xy 53.29682 -389.467344)
			(xy 53.296402 -389.49135) (xy 53.288881 -389.538771) (xy 53.274031 -389.58443) (xy 53.252219 -389.627202)
			(xy 53.223982 -389.666034) (xy 53.190016 -389.699969) (xy 53.151158 -389.728169) (xy 53.108365 -389.749941)
			(xy 53.062692 -389.764748) (xy 53.015265 -389.772224) (xy 52.991258 -389.772652) (xy 52.967687 -389.772184)
			(xy 52.921104 -389.764953) (xy 52.876188 -389.750638) (xy 52.834011 -389.729581) (xy 52.795577 -389.702284)
			(xy 52.761802 -389.669396) (xy 52.733492 -389.631702) (xy 52.722018 -389.611108) (xy 52.72151 -389.610346)
			(xy 52.323746 -388.922006) (xy 52.311869 -388.89933) (xy 52.295019 -388.850996) (xy 52.286446 -388.800533)
			(xy 52.2859 -388.77494) (xy 51.743906 -388.77494) (xy 52.05603 -389.314944) (xy 52.068836 -389.338286)
			(xy 52.087063 -389.388304) (xy 52.096331 -389.440727) (xy 52.096924 -389.467344) (xy 52.096502 -389.49135)
			(xy 52.088981 -389.53877) (xy 52.074132 -389.584429) (xy 52.05232 -389.627201) (xy 52.024084 -389.666033)
			(xy 51.990118 -389.699967) (xy 51.95126 -389.728168) (xy 51.908468 -389.74994) (xy 51.862795 -389.764747)
			(xy 51.815369 -389.772224) (xy 51.791362 -389.772652) (xy 51.767791 -389.772181) (xy 51.721208 -389.76495)
			(xy 51.676292 -389.750636) (xy 51.634115 -389.72958) (xy 51.595681 -389.702283) (xy 51.561907 -389.669396)
			(xy 51.533596 -389.631702) (xy 51.522122 -389.611108) (xy 51.521614 -389.610346) (xy 51.12385 -388.922006)
			(xy 51.111973 -388.899329) (xy 51.095123 -388.850996) (xy 51.08655 -388.800533) (xy 51.086004 -388.77494)
			(xy 50.543756 -388.77494) (xy 50.85588 -389.314944) (xy 50.868611 -389.338311) (xy 50.886727 -389.388338)
			(xy 50.895938 -389.440741) (xy 50.89652 -389.467344) (xy 50.896078 -389.491336) (xy 50.888566 -389.538728)
			(xy 50.873733 -389.584362) (xy 50.851945 -389.627113) (xy 50.823738 -389.665931) (xy 50.789807 -389.699859)
			(xy 50.750986 -389.728062) (xy 50.708232 -389.749845) (xy 50.662597 -389.764673) (xy 50.615204 -389.772181)
			(xy 50.591212 -389.772652) (xy 50.56764 -389.772221) (xy 50.521054 -389.764983) (xy 50.476138 -389.750662)
			(xy 50.433961 -389.729599) (xy 50.395528 -389.702295) (xy 50.361754 -389.669403) (xy 50.333445 -389.631704)
			(xy 50.321972 -389.611108) (xy 50.321464 -389.610346) (xy 49.9237 -388.922006) (xy 49.911785 -388.899338)
			(xy 49.894847 -388.851012) (xy 49.886188 -388.800542) (xy 49.8856 -388.77494) (xy 49.34386 -388.77494)
			(xy 49.655984 -389.314944) (xy 49.668715 -389.338311) (xy 49.686832 -389.388338) (xy 49.696042 -389.440741)
			(xy 49.696624 -389.467344) (xy 49.696178 -389.491336) (xy 49.688666 -389.538727) (xy 49.673833 -389.584361)
			(xy 49.652046 -389.627112) (xy 49.623839 -389.66593) (xy 49.589908 -389.699858) (xy 49.551088 -389.72806)
			(xy 49.508335 -389.749844) (xy 49.4627 -389.764672) (xy 49.415308 -389.77218) (xy 49.391316 -389.772652)
			(xy 49.367744 -389.772218) (xy 49.321159 -389.76498) (xy 49.276242 -389.75066) (xy 49.234065 -389.729597)
			(xy 49.195632 -389.702294) (xy 49.161858 -389.669402) (xy 49.133549 -389.631704) (xy 49.122076 -389.611108)
			(xy 49.121568 -389.610346) (xy 48.723804 -388.922006) (xy 48.711889 -388.899338) (xy 48.694951 -388.851012)
			(xy 48.686292 -388.800542) (xy 48.685704 -388.77494) (xy 48.143964 -388.77494) (xy 48.456088 -389.314944)
			(xy 48.468819 -389.33831) (xy 48.486936 -389.388338) (xy 48.496146 -389.440741) (xy 48.496728 -389.467344)
			(xy 48.496278 -389.491335) (xy 48.488766 -389.538727) (xy 48.473934 -389.58436) (xy 48.452147 -389.627111)
			(xy 48.423941 -389.665928) (xy 48.39001 -389.699856) (xy 48.351191 -389.728059) (xy 48.308437 -389.749843)
			(xy 48.262803 -389.764672) (xy 48.215411 -389.77218) (xy 48.19142 -389.772652) (xy 48.167848 -389.772215)
			(xy 48.121263 -389.764978) (xy 48.076347 -389.750658) (xy 48.03417 -389.729595) (xy 47.995736 -389.702293)
			(xy 47.961962 -389.669402) (xy 47.933653 -389.631704) (xy 47.92218 -389.611108) (xy 47.921672 -389.610346)
			(xy 47.523908 -388.922006) (xy 47.511993 -388.899337) (xy 47.495055 -388.851012) (xy 47.486396 -388.800542)
			(xy 47.485808 -388.77494) (xy 2.509012 -388.77494) (xy 2.509012 -393.292838) (xy 47.435008 -393.292838)
			(xy 47.435008 -392.429238) (xy 47.435494 -392.401987) (xy 47.44325 -392.348039) (xy 47.458605 -392.295744)
			(xy 47.481247 -392.246167) (xy 47.510713 -392.200317) (xy 47.546404 -392.159126) (xy 47.587595 -392.123435)
			(xy 47.633445 -392.093969) (xy 47.683022 -392.071327) (xy 47.735317 -392.055972) (xy 47.789265 -392.048216)
			(xy 47.843767 -392.048216) (xy 47.897715 -392.055972) (xy 47.95001 -392.071327) (xy 47.999587 -392.093969)
			(xy 48.045437 -392.123435) (xy 48.086628 -392.159126) (xy 48.122319 -392.200317) (xy 48.151785 -392.246167)
			(xy 48.174427 -392.295744) (xy 48.189782 -392.348039) (xy 48.197538 -392.401987) (xy 48.198024 -392.429238)
			(xy 48.198024 -393.292838) (xy 48.634904 -393.292838) (xy 48.634904 -392.429238) (xy 48.63539 -392.401987)
			(xy 48.643146 -392.348039) (xy 48.658501 -392.295744) (xy 48.681143 -392.246167) (xy 48.710609 -392.200317)
			(xy 48.7463 -392.159126) (xy 48.787491 -392.123435) (xy 48.833341 -392.093969) (xy 48.882918 -392.071327)
			(xy 48.935213 -392.055972) (xy 48.989161 -392.048216) (xy 49.043663 -392.048216) (xy 49.097611 -392.055972)
			(xy 49.149906 -392.071327) (xy 49.199483 -392.093969) (xy 49.245333 -392.123435) (xy 49.286524 -392.159126)
			(xy 49.322215 -392.200317) (xy 49.351681 -392.246167) (xy 49.374323 -392.295744) (xy 49.389678 -392.348039)
			(xy 49.397434 -392.401987) (xy 49.39792 -392.429238) (xy 49.39792 -393.292838) (xy 49.8348 -393.292838)
			(xy 49.8348 -392.429238) (xy 49.835286 -392.401969) (xy 49.843048 -392.347985) (xy 49.858413 -392.295655)
			(xy 49.88107 -392.246045) (xy 49.910556 -392.200164) (xy 49.946271 -392.158947) (xy 49.987488 -392.123232)
			(xy 50.033369 -392.093746) (xy 50.082979 -392.071089) (xy 50.135309 -392.055724) (xy 50.189293 -392.047962)
			(xy 50.243831 -392.047962) (xy 50.297815 -392.055724) (xy 50.350145 -392.071089) (xy 50.399755 -392.093746)
			(xy 50.445636 -392.123232) (xy 50.486853 -392.158947) (xy 50.522568 -392.200164) (xy 50.552054 -392.246045)
			(xy 50.574711 -392.295655) (xy 50.590076 -392.347985) (xy 50.597838 -392.401969) (xy 50.598324 -392.429238)
			(xy 50.598324 -393.292838) (xy 51.034696 -393.292838) (xy 51.034696 -392.429238) (xy 51.035182 -392.401969)
			(xy 51.042944 -392.347985) (xy 51.058309 -392.295655) (xy 51.080966 -392.246045) (xy 51.110452 -392.200164)
			(xy 51.146167 -392.158947) (xy 51.187384 -392.123232) (xy 51.233265 -392.093746) (xy 51.282875 -392.071089)
			(xy 51.335205 -392.055724) (xy 51.389189 -392.047962) (xy 51.443727 -392.047962) (xy 51.497711 -392.055724)
			(xy 51.550041 -392.071089) (xy 51.599651 -392.093746) (xy 51.645532 -392.123232) (xy 51.686749 -392.158947)
			(xy 51.722464 -392.200164) (xy 51.75195 -392.246045) (xy 51.774607 -392.295655) (xy 51.789972 -392.347985)
			(xy 51.797734 -392.401969) (xy 51.79822 -392.429238) (xy 51.79822 -393.292838) (xy 52.2351 -393.292838)
			(xy 52.2351 -392.429238) (xy 52.235586 -392.401987) (xy 52.243342 -392.348039) (xy 52.258697 -392.295744)
			(xy 52.281339 -392.246167) (xy 52.310805 -392.200317) (xy 52.346496 -392.159126) (xy 52.387687 -392.123435)
			(xy 52.433537 -392.093969) (xy 52.483114 -392.071327) (xy 52.535409 -392.055972) (xy 52.589357 -392.048216)
			(xy 52.643859 -392.048216) (xy 52.697807 -392.055972) (xy 52.750102 -392.071327) (xy 52.799679 -392.093969)
			(xy 52.845529 -392.123435) (xy 52.88672 -392.159126) (xy 52.922411 -392.200317) (xy 52.951877 -392.246167)
			(xy 52.974519 -392.295744) (xy 52.989874 -392.348039) (xy 52.99763 -392.401987) (xy 52.998116 -392.429238)
			(xy 52.998116 -393.292838) (xy 53.434996 -393.292838) (xy 53.434996 -392.429238) (xy 53.435482 -392.401987)
			(xy 53.443238 -392.348039) (xy 53.458593 -392.295744) (xy 53.481235 -392.246167) (xy 53.510701 -392.200317)
			(xy 53.546392 -392.159126) (xy 53.587583 -392.123435) (xy 53.633433 -392.093969) (xy 53.68301 -392.071327)
			(xy 53.735305 -392.055972) (xy 53.789253 -392.048216) (xy 53.843755 -392.048216) (xy 53.897703 -392.055972)
			(xy 53.949998 -392.071327) (xy 53.999575 -392.093969) (xy 54.045425 -392.123435) (xy 54.086616 -392.159126)
			(xy 54.122307 -392.200317) (xy 54.151773 -392.246167) (xy 54.174415 -392.295744) (xy 54.18977 -392.348039)
			(xy 54.197526 -392.401987) (xy 54.198012 -392.429238) (xy 54.198012 -393.292838) (xy 54.634892 -393.292838)
			(xy 54.634892 -392.429238) (xy 54.635378 -392.401969) (xy 54.64314 -392.347985) (xy 54.658505 -392.295655)
			(xy 54.681162 -392.246045) (xy 54.710648 -392.200164) (xy 54.746363 -392.158947) (xy 54.78758 -392.123232)
			(xy 54.833461 -392.093746) (xy 54.883071 -392.071089) (xy 54.935401 -392.055724) (xy 54.989385 -392.047962)
			(xy 55.043923 -392.047962) (xy 55.097907 -392.055724) (xy 55.150237 -392.071089) (xy 55.199847 -392.093746)
			(xy 55.245728 -392.123232) (xy 55.286945 -392.158947) (xy 55.32266 -392.200164) (xy 55.352146 -392.246045)
			(xy 55.374803 -392.295655) (xy 55.390168 -392.347985) (xy 55.39793 -392.401969) (xy 55.398416 -392.429238)
			(xy 55.398416 -393.292838) (xy 55.834788 -393.292838) (xy 55.834788 -392.429238) (xy 55.835274 -392.401969)
			(xy 55.843036 -392.347985) (xy 55.858401 -392.295655) (xy 55.881058 -392.246045) (xy 55.910544 -392.200164)
			(xy 55.946259 -392.158947) (xy 55.987476 -392.123232) (xy 56.033357 -392.093746) (xy 56.082967 -392.071089)
			(xy 56.135297 -392.055724) (xy 56.189281 -392.047962) (xy 56.243819 -392.047962) (xy 56.297803 -392.055724)
			(xy 56.350133 -392.071089) (xy 56.399743 -392.093746) (xy 56.445624 -392.123232) (xy 56.486841 -392.158947)
			(xy 56.522556 -392.200164) (xy 56.552042 -392.246045) (xy 56.574699 -392.295655) (xy 56.590064 -392.347985)
			(xy 56.597826 -392.401969) (xy 56.598312 -392.429238) (xy 56.598312 -393.292838) (xy 57.035192 -393.292838)
			(xy 57.035192 -392.429238) (xy 57.035678 -392.401987) (xy 57.043434 -392.348039) (xy 57.058789 -392.295744)
			(xy 57.081431 -392.246167) (xy 57.110897 -392.200317) (xy 57.146588 -392.159126) (xy 57.187779 -392.123435)
			(xy 57.233629 -392.093969) (xy 57.283206 -392.071327) (xy 57.335501 -392.055972) (xy 57.389449 -392.048216)
			(xy 57.443951 -392.048216) (xy 57.497899 -392.055972) (xy 57.550194 -392.071327) (xy 57.599771 -392.093969)
			(xy 57.645621 -392.123435) (xy 57.686812 -392.159126) (xy 57.722503 -392.200317) (xy 57.751969 -392.246167)
			(xy 57.774611 -392.295744) (xy 57.789966 -392.348039) (xy 57.797722 -392.401987) (xy 57.798208 -392.429238)
			(xy 57.798208 -393.292838) (xy 58.235088 -393.292838) (xy 58.235088 -392.429238) (xy 58.235574 -392.401987)
			(xy 58.24333 -392.348039) (xy 58.258685 -392.295744) (xy 58.281327 -392.246167) (xy 58.310793 -392.200317)
			(xy 58.346484 -392.159126) (xy 58.387675 -392.123435) (xy 58.433525 -392.093969) (xy 58.483102 -392.071327)
			(xy 58.535397 -392.055972) (xy 58.589345 -392.048216) (xy 58.643847 -392.048216) (xy 58.697795 -392.055972)
			(xy 58.75009 -392.071327) (xy 58.799667 -392.093969) (xy 58.845517 -392.123435) (xy 58.886708 -392.159126)
			(xy 58.922399 -392.200317) (xy 58.951865 -392.246167) (xy 58.974507 -392.295744) (xy 58.989862 -392.348039)
			(xy 58.997618 -392.401987) (xy 58.998104 -392.429238) (xy 58.998104 -393.292838) (xy 59.434984 -393.292838)
			(xy 59.434984 -392.429238) (xy 59.43547 -392.401969) (xy 59.443232 -392.347985) (xy 59.458597 -392.295655)
			(xy 59.481254 -392.246045) (xy 59.51074 -392.200164) (xy 59.546455 -392.158947) (xy 59.587672 -392.123232)
			(xy 59.633553 -392.093746) (xy 59.683163 -392.071089) (xy 59.735493 -392.055724) (xy 59.789477 -392.047962)
			(xy 59.844015 -392.047962) (xy 59.897999 -392.055724) (xy 59.950329 -392.071089) (xy 59.999939 -392.093746)
			(xy 60.04582 -392.123232) (xy 60.087037 -392.158947) (xy 60.122752 -392.200164) (xy 60.152238 -392.246045)
			(xy 60.174895 -392.295655) (xy 60.19026 -392.347985) (xy 60.198022 -392.401969) (xy 60.198508 -392.429238)
			(xy 60.198508 -393.292838) (xy 60.63488 -393.292838) (xy 60.63488 -392.429238) (xy 60.635366 -392.401969)
			(xy 60.643128 -392.347985) (xy 60.658493 -392.295655) (xy 60.68115 -392.246045) (xy 60.710636 -392.200164)
			(xy 60.746351 -392.158947) (xy 60.787568 -392.123232) (xy 60.833449 -392.093746) (xy 60.883059 -392.071089)
			(xy 60.935389 -392.055724) (xy 60.989373 -392.047962) (xy 61.043911 -392.047962) (xy 61.097895 -392.055724)
			(xy 61.150225 -392.071089) (xy 61.199835 -392.093746) (xy 61.245716 -392.123232) (xy 61.286933 -392.158947)
			(xy 61.322648 -392.200164) (xy 61.352134 -392.246045) (xy 61.374791 -392.295655) (xy 61.390156 -392.347985)
			(xy 61.397918 -392.401969) (xy 61.398404 -392.429238) (xy 61.398404 -393.292838) (xy 61.834776 -393.292838)
			(xy 61.834776 -392.429238) (xy 61.835262 -392.401969) (xy 61.843024 -392.347985) (xy 61.858389 -392.295655)
			(xy 61.881046 -392.246045) (xy 61.910532 -392.200164) (xy 61.946247 -392.158947) (xy 61.987464 -392.123232)
			(xy 62.033345 -392.093746) (xy 62.082955 -392.071089) (xy 62.135285 -392.055724) (xy 62.189269 -392.047962)
			(xy 62.243807 -392.047962) (xy 62.297791 -392.055724) (xy 62.350121 -392.071089) (xy 62.399731 -392.093746)
			(xy 62.445612 -392.123232) (xy 62.486829 -392.158947) (xy 62.522544 -392.200164) (xy 62.55203 -392.246045)
			(xy 62.574687 -392.295655) (xy 62.590052 -392.347985) (xy 62.597814 -392.401969) (xy 62.5983 -392.429238)
			(xy 62.5983 -393.292838) (xy 63.034672 -393.292838) (xy 63.034672 -392.429238) (xy 63.035158 -392.401969)
			(xy 63.04292 -392.347985) (xy 63.058285 -392.295655) (xy 63.080942 -392.246045) (xy 63.110428 -392.200164)
			(xy 63.146143 -392.158947) (xy 63.18736 -392.123232) (xy 63.233241 -392.093746) (xy 63.282851 -392.071089)
			(xy 63.335181 -392.055724) (xy 63.389165 -392.047962) (xy 63.443703 -392.047962) (xy 63.497687 -392.055724)
			(xy 63.550017 -392.071089) (xy 63.599627 -392.093746) (xy 63.645508 -392.123232) (xy 63.686725 -392.158947)
			(xy 63.72244 -392.200164) (xy 63.751926 -392.246045) (xy 63.774583 -392.295655) (xy 63.789948 -392.347985)
			(xy 63.79771 -392.401969) (xy 63.798196 -392.429238) (xy 63.798196 -393.292838) (xy 64.235076 -393.292838)
			(xy 64.235076 -392.429238) (xy 64.235562 -392.401987) (xy 64.243318 -392.348039) (xy 64.258673 -392.295744)
			(xy 64.281315 -392.246167) (xy 64.310781 -392.200317) (xy 64.346472 -392.159126) (xy 64.387663 -392.123435)
			(xy 64.433513 -392.093969) (xy 64.48309 -392.071327) (xy 64.535385 -392.055972) (xy 64.589333 -392.048216)
			(xy 64.643835 -392.048216) (xy 64.697783 -392.055972) (xy 64.750078 -392.071327) (xy 64.799655 -392.093969)
			(xy 64.845505 -392.123435) (xy 64.886696 -392.159126) (xy 64.922387 -392.200317) (xy 64.951853 -392.246167)
			(xy 64.974495 -392.295744) (xy 64.98985 -392.348039) (xy 64.997606 -392.401987) (xy 64.998092 -392.429238)
			(xy 64.998092 -393.292838) (xy 65.434972 -393.292838) (xy 65.434972 -392.429238) (xy 65.435458 -392.401987)
			(xy 65.443214 -392.348039) (xy 65.458569 -392.295744) (xy 65.481211 -392.246167) (xy 65.510677 -392.200317)
			(xy 65.546368 -392.159126) (xy 65.587559 -392.123435) (xy 65.633409 -392.093969) (xy 65.682986 -392.071327)
			(xy 65.735281 -392.055972) (xy 65.789229 -392.048216) (xy 65.843731 -392.048216) (xy 65.897679 -392.055972)
			(xy 65.949974 -392.071327) (xy 65.999551 -392.093969) (xy 66.045401 -392.123435) (xy 66.086592 -392.159126)
			(xy 66.122283 -392.200317) (xy 66.151749 -392.246167) (xy 66.174391 -392.295744) (xy 66.189746 -392.348039)
			(xy 66.197502 -392.401987) (xy 66.197988 -392.429238) (xy 66.197988 -393.292838) (xy 79.962756 -393.292838)
			(xy 79.962756 -392.429238) (xy 79.963242 -392.401987) (xy 79.970998 -392.348039) (xy 79.986353 -392.295744)
			(xy 80.008995 -392.246167) (xy 80.038461 -392.200317) (xy 80.074152 -392.159126) (xy 80.115343 -392.123435)
			(xy 80.161193 -392.093969) (xy 80.21077 -392.071327) (xy 80.263065 -392.055972) (xy 80.317013 -392.048216)
			(xy 80.371515 -392.048216) (xy 80.425463 -392.055972) (xy 80.477758 -392.071327) (xy 80.527335 -392.093969)
			(xy 80.573185 -392.123435) (xy 80.614376 -392.159126) (xy 80.650067 -392.200317) (xy 80.679533 -392.246167)
			(xy 80.702175 -392.295744) (xy 80.71753 -392.348039) (xy 80.725286 -392.401987) (xy 80.725772 -392.429238)
			(xy 80.725772 -393.292838) (xy 81.162652 -393.292838) (xy 81.162652 -392.429238) (xy 81.163138 -392.401987)
			(xy 81.170894 -392.348039) (xy 81.186249 -392.295744) (xy 81.208891 -392.246167) (xy 81.238357 -392.200317)
			(xy 81.274048 -392.159126) (xy 81.315239 -392.123435) (xy 81.361089 -392.093969) (xy 81.410666 -392.071327)
			(xy 81.462961 -392.055972) (xy 81.516909 -392.048216) (xy 81.571411 -392.048216) (xy 81.625359 -392.055972)
			(xy 81.677654 -392.071327) (xy 81.727231 -392.093969) (xy 81.773081 -392.123435) (xy 81.814272 -392.159126)
			(xy 81.849963 -392.200317) (xy 81.879429 -392.246167) (xy 81.902071 -392.295744) (xy 81.917426 -392.348039)
			(xy 81.925182 -392.401987) (xy 81.925668 -392.429238) (xy 81.925668 -393.292838) (xy 82.362548 -393.292838)
			(xy 82.362548 -392.429238) (xy 82.363034 -392.401969) (xy 82.370796 -392.347985) (xy 82.386161 -392.295655)
			(xy 82.408818 -392.246045) (xy 82.438304 -392.200164) (xy 82.474019 -392.158947) (xy 82.515236 -392.123232)
			(xy 82.561117 -392.093746) (xy 82.610727 -392.071089) (xy 82.663057 -392.055724) (xy 82.717041 -392.047962)
			(xy 82.771579 -392.047962) (xy 82.825563 -392.055724) (xy 82.877893 -392.071089) (xy 82.927503 -392.093746)
			(xy 82.973384 -392.123232) (xy 83.014601 -392.158947) (xy 83.050316 -392.200164) (xy 83.079802 -392.246045)
			(xy 83.102459 -392.295655) (xy 83.117824 -392.347985) (xy 83.125586 -392.401969) (xy 83.126072 -392.429238)
			(xy 83.126072 -393.292838) (xy 83.562444 -393.292838) (xy 83.562444 -392.429238) (xy 83.56293 -392.401969)
			(xy 83.570692 -392.347985) (xy 83.586057 -392.295655) (xy 83.608714 -392.246045) (xy 83.6382 -392.200164)
			(xy 83.673915 -392.158947) (xy 83.715132 -392.123232) (xy 83.761013 -392.093746) (xy 83.810623 -392.071089)
			(xy 83.862953 -392.055724) (xy 83.916937 -392.047962) (xy 83.971475 -392.047962) (xy 84.025459 -392.055724)
			(xy 84.077789 -392.071089) (xy 84.127399 -392.093746) (xy 84.17328 -392.123232) (xy 84.214497 -392.158947)
			(xy 84.250212 -392.200164) (xy 84.279698 -392.246045) (xy 84.302355 -392.295655) (xy 84.31772 -392.347985)
			(xy 84.325482 -392.401969) (xy 84.325968 -392.429238) (xy 84.325968 -393.292838) (xy 84.762848 -393.292838)
			(xy 84.762848 -392.429238) (xy 84.763334 -392.401987) (xy 84.77109 -392.348039) (xy 84.786445 -392.295744)
			(xy 84.809087 -392.246167) (xy 84.838553 -392.200317) (xy 84.874244 -392.159126) (xy 84.915435 -392.123435)
			(xy 84.961285 -392.093969) (xy 85.010862 -392.071327) (xy 85.063157 -392.055972) (xy 85.117105 -392.048216)
			(xy 85.171607 -392.048216) (xy 85.225555 -392.055972) (xy 85.27785 -392.071327) (xy 85.327427 -392.093969)
			(xy 85.373277 -392.123435) (xy 85.414468 -392.159126) (xy 85.450159 -392.200317) (xy 85.479625 -392.246167)
			(xy 85.502267 -392.295744) (xy 85.517622 -392.348039) (xy 85.525378 -392.401987) (xy 85.525864 -392.429238)
			(xy 85.525864 -393.292838) (xy 85.962744 -393.292838) (xy 85.962744 -392.429238) (xy 85.96323 -392.401987)
			(xy 85.970986 -392.348039) (xy 85.986341 -392.295744) (xy 86.008983 -392.246167) (xy 86.038449 -392.200317)
			(xy 86.07414 -392.159126) (xy 86.115331 -392.123435) (xy 86.161181 -392.093969) (xy 86.210758 -392.071327)
			(xy 86.263053 -392.055972) (xy 86.317001 -392.048216) (xy 86.371503 -392.048216) (xy 86.425451 -392.055972)
			(xy 86.477746 -392.071327) (xy 86.527323 -392.093969) (xy 86.573173 -392.123435) (xy 86.614364 -392.159126)
			(xy 86.650055 -392.200317) (xy 86.679521 -392.246167) (xy 86.702163 -392.295744) (xy 86.717518 -392.348039)
			(xy 86.725274 -392.401987) (xy 86.72576 -392.429238) (xy 86.72576 -393.292838) (xy 87.16264 -393.292838)
			(xy 87.16264 -392.429238) (xy 87.163126 -392.401969) (xy 87.170888 -392.347985) (xy 87.186253 -392.295655)
			(xy 87.20891 -392.246045) (xy 87.238396 -392.200164) (xy 87.274111 -392.158947) (xy 87.315328 -392.123232)
			(xy 87.361209 -392.093746) (xy 87.410819 -392.071089) (xy 87.463149 -392.055724) (xy 87.517133 -392.047962)
			(xy 87.571671 -392.047962) (xy 87.625655 -392.055724) (xy 87.677985 -392.071089) (xy 87.727595 -392.093746)
			(xy 87.773476 -392.123232) (xy 87.814693 -392.158947) (xy 87.850408 -392.200164) (xy 87.879894 -392.246045)
			(xy 87.902551 -392.295655) (xy 87.917916 -392.347985) (xy 87.925678 -392.401969) (xy 87.926164 -392.429238)
			(xy 87.926164 -393.292838) (xy 88.362536 -393.292838) (xy 88.362536 -392.429238) (xy 88.363022 -392.401969)
			(xy 88.370784 -392.347985) (xy 88.386149 -392.295655) (xy 88.408806 -392.246045) (xy 88.438292 -392.200164)
			(xy 88.474007 -392.158947) (xy 88.515224 -392.123232) (xy 88.561105 -392.093746) (xy 88.610715 -392.071089)
			(xy 88.663045 -392.055724) (xy 88.717029 -392.047962) (xy 88.771567 -392.047962) (xy 88.825551 -392.055724)
			(xy 88.877881 -392.071089) (xy 88.927491 -392.093746) (xy 88.973372 -392.123232) (xy 89.014589 -392.158947)
			(xy 89.050304 -392.200164) (xy 89.07979 -392.246045) (xy 89.102447 -392.295655) (xy 89.117812 -392.347985)
			(xy 89.125574 -392.401969) (xy 89.12606 -392.429238) (xy 89.12606 -393.292838) (xy 89.56294 -393.292838)
			(xy 89.56294 -392.429238) (xy 89.563426 -392.401987) (xy 89.571182 -392.348039) (xy 89.586537 -392.295744)
			(xy 89.609179 -392.246167) (xy 89.638645 -392.200317) (xy 89.674336 -392.159126) (xy 89.715527 -392.123435)
			(xy 89.761377 -392.093969) (xy 89.810954 -392.071327) (xy 89.863249 -392.055972) (xy 89.917197 -392.048216)
			(xy 89.971699 -392.048216) (xy 90.025647 -392.055972) (xy 90.077942 -392.071327) (xy 90.127519 -392.093969)
			(xy 90.173369 -392.123435) (xy 90.21456 -392.159126) (xy 90.250251 -392.200317) (xy 90.279717 -392.246167)
			(xy 90.302359 -392.295744) (xy 90.317714 -392.348039) (xy 90.32547 -392.401987) (xy 90.325956 -392.429238)
			(xy 90.325956 -393.292838) (xy 90.762836 -393.292838) (xy 90.762836 -392.429238) (xy 90.763322 -392.401987)
			(xy 90.771078 -392.348039) (xy 90.786433 -392.295744) (xy 90.809075 -392.246167) (xy 90.838541 -392.200317)
			(xy 90.874232 -392.159126) (xy 90.915423 -392.123435) (xy 90.961273 -392.093969) (xy 91.01085 -392.071327)
			(xy 91.063145 -392.055972) (xy 91.117093 -392.048216) (xy 91.171595 -392.048216) (xy 91.225543 -392.055972)
			(xy 91.277838 -392.071327) (xy 91.327415 -392.093969) (xy 91.373265 -392.123435) (xy 91.414456 -392.159126)
			(xy 91.450147 -392.200317) (xy 91.479613 -392.246167) (xy 91.502255 -392.295744) (xy 91.51761 -392.348039)
			(xy 91.525366 -392.401987) (xy 91.525852 -392.429238) (xy 91.525852 -393.292838) (xy 91.962732 -393.292838)
			(xy 91.962732 -392.429238) (xy 91.963218 -392.401969) (xy 91.97098 -392.347985) (xy 91.986345 -392.295655)
			(xy 92.009002 -392.246045) (xy 92.038488 -392.200164) (xy 92.074203 -392.158947) (xy 92.11542 -392.123232)
			(xy 92.161301 -392.093746) (xy 92.210911 -392.071089) (xy 92.263241 -392.055724) (xy 92.317225 -392.047962)
			(xy 92.371763 -392.047962) (xy 92.425747 -392.055724) (xy 92.478077 -392.071089) (xy 92.527687 -392.093746)
			(xy 92.573568 -392.123232) (xy 92.614785 -392.158947) (xy 92.6505 -392.200164) (xy 92.679986 -392.246045)
			(xy 92.702643 -392.295655) (xy 92.718008 -392.347985) (xy 92.72577 -392.401969) (xy 92.726256 -392.429238)
			(xy 92.726256 -393.292838) (xy 93.162628 -393.292838) (xy 93.162628 -392.429238) (xy 93.163114 -392.401969)
			(xy 93.170876 -392.347985) (xy 93.186241 -392.295655) (xy 93.208898 -392.246045) (xy 93.238384 -392.200164)
			(xy 93.274099 -392.158947) (xy 93.315316 -392.123232) (xy 93.361197 -392.093746) (xy 93.410807 -392.071089)
			(xy 93.463137 -392.055724) (xy 93.517121 -392.047962) (xy 93.571659 -392.047962) (xy 93.625643 -392.055724)
			(xy 93.677973 -392.071089) (xy 93.727583 -392.093746) (xy 93.773464 -392.123232) (xy 93.814681 -392.158947)
			(xy 93.850396 -392.200164) (xy 93.879882 -392.246045) (xy 93.902539 -392.295655) (xy 93.917904 -392.347985)
			(xy 93.925666 -392.401969) (xy 93.926152 -392.429238) (xy 93.926152 -393.292838) (xy 94.362524 -393.292838)
			(xy 94.362524 -392.429238) (xy 94.36301 -392.401969) (xy 94.370772 -392.347985) (xy 94.386137 -392.295655)
			(xy 94.408794 -392.246045) (xy 94.43828 -392.200164) (xy 94.473995 -392.158947) (xy 94.515212 -392.123232)
			(xy 94.561093 -392.093746) (xy 94.610703 -392.071089) (xy 94.663033 -392.055724) (xy 94.717017 -392.047962)
			(xy 94.771555 -392.047962) (xy 94.825539 -392.055724) (xy 94.877869 -392.071089) (xy 94.927479 -392.093746)
			(xy 94.97336 -392.123232) (xy 95.014577 -392.158947) (xy 95.050292 -392.200164) (xy 95.079778 -392.246045)
			(xy 95.102435 -392.295655) (xy 95.1178 -392.347985) (xy 95.125562 -392.401969) (xy 95.126048 -392.429238)
			(xy 95.126048 -393.292838) (xy 95.56242 -393.292838) (xy 95.56242 -392.429238) (xy 95.562906 -392.401969)
			(xy 95.570668 -392.347985) (xy 95.586033 -392.295655) (xy 95.60869 -392.246045) (xy 95.638176 -392.200164)
			(xy 95.673891 -392.158947) (xy 95.715108 -392.123232) (xy 95.760989 -392.093746) (xy 95.810599 -392.071089)
			(xy 95.862929 -392.055724) (xy 95.916913 -392.047962) (xy 95.971451 -392.047962) (xy 96.025435 -392.055724)
			(xy 96.077765 -392.071089) (xy 96.127375 -392.093746) (xy 96.173256 -392.123232) (xy 96.214473 -392.158947)
			(xy 96.250188 -392.200164) (xy 96.279674 -392.246045) (xy 96.302331 -392.295655) (xy 96.317696 -392.347985)
			(xy 96.325458 -392.401969) (xy 96.325944 -392.429238) (xy 96.325944 -393.292838) (xy 96.762824 -393.292838)
			(xy 96.762824 -392.429238) (xy 96.76331 -392.401987) (xy 96.771066 -392.348039) (xy 96.786421 -392.295744)
			(xy 96.809063 -392.246167) (xy 96.838529 -392.200317) (xy 96.87422 -392.159126) (xy 96.915411 -392.123435)
			(xy 96.961261 -392.093969) (xy 97.010838 -392.071327) (xy 97.063133 -392.055972) (xy 97.117081 -392.048216)
			(xy 97.171583 -392.048216) (xy 97.225531 -392.055972) (xy 97.277826 -392.071327) (xy 97.327403 -392.093969)
			(xy 97.373253 -392.123435) (xy 97.414444 -392.159126) (xy 97.450135 -392.200317) (xy 97.479601 -392.246167)
			(xy 97.502243 -392.295744) (xy 97.517598 -392.348039) (xy 97.525354 -392.401987) (xy 97.52584 -392.429238)
			(xy 97.52584 -393.292838) (xy 97.96272 -393.292838) (xy 97.96272 -392.429238) (xy 97.963206 -392.401987)
			(xy 97.970962 -392.348039) (xy 97.986317 -392.295744) (xy 98.008959 -392.246167) (xy 98.038425 -392.200317)
			(xy 98.074116 -392.159126) (xy 98.115307 -392.123435) (xy 98.161157 -392.093969) (xy 98.210734 -392.071327)
			(xy 98.263029 -392.055972) (xy 98.316977 -392.048216) (xy 98.371479 -392.048216) (xy 98.425427 -392.055972)
			(xy 98.477722 -392.071327) (xy 98.527299 -392.093969) (xy 98.573149 -392.123435) (xy 98.61434 -392.159126)
			(xy 98.650031 -392.200317) (xy 98.679497 -392.246167) (xy 98.702139 -392.295744) (xy 98.717494 -392.348039)
			(xy 98.72525 -392.401987) (xy 98.725736 -392.429238) (xy 98.725736 -393.292838) (xy 114.534696 -393.292838)
			(xy 114.534696 -392.429238) (xy 114.535182 -392.401969) (xy 114.542944 -392.347985) (xy 114.558309 -392.295655)
			(xy 114.580966 -392.246045) (xy 114.610452 -392.200164) (xy 114.646167 -392.158947) (xy 114.687384 -392.123232)
			(xy 114.733265 -392.093746) (xy 114.782875 -392.071089) (xy 114.835205 -392.055724) (xy 114.889189 -392.047962)
			(xy 114.943727 -392.047962) (xy 114.997711 -392.055724) (xy 115.050041 -392.071089) (xy 115.099651 -392.093746)
			(xy 115.145532 -392.123232) (xy 115.186749 -392.158947) (xy 115.222464 -392.200164) (xy 115.25195 -392.246045)
			(xy 115.274607 -392.295655) (xy 115.289972 -392.347985) (xy 115.297734 -392.401969) (xy 115.29822 -392.429238)
			(xy 115.29822 -393.292838) (xy 115.734592 -393.292838) (xy 115.734592 -392.429238) (xy 115.735078 -392.401969)
			(xy 115.74284 -392.347985) (xy 115.758205 -392.295655) (xy 115.780862 -392.246045) (xy 115.810348 -392.200164)
			(xy 115.846063 -392.158947) (xy 115.88728 -392.123232) (xy 115.933161 -392.093746) (xy 115.982771 -392.071089)
			(xy 116.035101 -392.055724) (xy 116.089085 -392.047962) (xy 116.143623 -392.047962) (xy 116.197607 -392.055724)
			(xy 116.249937 -392.071089) (xy 116.299547 -392.093746) (xy 116.345428 -392.123232) (xy 116.386645 -392.158947)
			(xy 116.42236 -392.200164) (xy 116.451846 -392.246045) (xy 116.474503 -392.295655) (xy 116.489868 -392.347985)
			(xy 116.49763 -392.401969) (xy 116.498116 -392.429238) (xy 116.498116 -393.292838) (xy 116.934996 -393.292838)
			(xy 116.934996 -392.429238) (xy 116.935482 -392.401987) (xy 116.943238 -392.348039) (xy 116.958593 -392.295744)
			(xy 116.981235 -392.246167) (xy 117.010701 -392.200317) (xy 117.046392 -392.159126) (xy 117.087583 -392.123435)
			(xy 117.133433 -392.093969) (xy 117.18301 -392.071327) (xy 117.235305 -392.055972) (xy 117.289253 -392.048216)
			(xy 117.343755 -392.048216) (xy 117.397703 -392.055972) (xy 117.449998 -392.071327) (xy 117.499575 -392.093969)
			(xy 117.545425 -392.123435) (xy 117.586616 -392.159126) (xy 117.622307 -392.200317) (xy 117.651773 -392.246167)
			(xy 117.674415 -392.295744) (xy 117.68977 -392.348039) (xy 117.697526 -392.401987) (xy 117.698012 -392.429238)
			(xy 117.698012 -393.292838) (xy 118.134892 -393.292838) (xy 118.134892 -392.429238) (xy 118.135378 -392.401987)
			(xy 118.143134 -392.348039) (xy 118.158489 -392.295744) (xy 118.181131 -392.246167) (xy 118.210597 -392.200317)
			(xy 118.246288 -392.159126) (xy 118.287479 -392.123435) (xy 118.333329 -392.093969) (xy 118.382906 -392.071327)
			(xy 118.435201 -392.055972) (xy 118.489149 -392.048216) (xy 118.543651 -392.048216) (xy 118.597599 -392.055972)
			(xy 118.649894 -392.071327) (xy 118.699471 -392.093969) (xy 118.745321 -392.123435) (xy 118.786512 -392.159126)
			(xy 118.822203 -392.200317) (xy 118.851669 -392.246167) (xy 118.874311 -392.295744) (xy 118.889666 -392.348039)
			(xy 118.897422 -392.401987) (xy 118.897908 -392.429238) (xy 118.897908 -393.292838) (xy 119.334788 -393.292838)
			(xy 119.334788 -392.429238) (xy 119.335274 -392.401969) (xy 119.343036 -392.347985) (xy 119.358401 -392.295655)
			(xy 119.381058 -392.246045) (xy 119.410544 -392.200164) (xy 119.446259 -392.158947) (xy 119.487476 -392.123232)
			(xy 119.533357 -392.093746) (xy 119.582967 -392.071089) (xy 119.635297 -392.055724) (xy 119.689281 -392.047962)
			(xy 119.743819 -392.047962) (xy 119.797803 -392.055724) (xy 119.850133 -392.071089) (xy 119.899743 -392.093746)
			(xy 119.945624 -392.123232) (xy 119.986841 -392.158947) (xy 120.022556 -392.200164) (xy 120.052042 -392.246045)
			(xy 120.074699 -392.295655) (xy 120.090064 -392.347985) (xy 120.097826 -392.401969) (xy 120.098312 -392.429238)
			(xy 120.098312 -393.292838) (xy 120.534684 -393.292838) (xy 120.534684 -392.429238) (xy 120.53517 -392.401969)
			(xy 120.542932 -392.347985) (xy 120.558297 -392.295655) (xy 120.580954 -392.246045) (xy 120.61044 -392.200164)
			(xy 120.646155 -392.158947) (xy 120.687372 -392.123232) (xy 120.733253 -392.093746) (xy 120.782863 -392.071089)
			(xy 120.835193 -392.055724) (xy 120.889177 -392.047962) (xy 120.943715 -392.047962) (xy 120.997699 -392.055724)
			(xy 121.050029 -392.071089) (xy 121.099639 -392.093746) (xy 121.14552 -392.123232) (xy 121.186737 -392.158947)
			(xy 121.222452 -392.200164) (xy 121.251938 -392.246045) (xy 121.274595 -392.295655) (xy 121.28996 -392.347985)
			(xy 121.297722 -392.401969) (xy 121.298208 -392.429238) (xy 121.298208 -393.292838) (xy 121.735088 -393.292838)
			(xy 121.735088 -392.429238) (xy 121.735574 -392.401987) (xy 121.74333 -392.348039) (xy 121.758685 -392.295744)
			(xy 121.781327 -392.246167) (xy 121.810793 -392.200317) (xy 121.846484 -392.159126) (xy 121.887675 -392.123435)
			(xy 121.933525 -392.093969) (xy 121.983102 -392.071327) (xy 122.035397 -392.055972) (xy 122.089345 -392.048216)
			(xy 122.143847 -392.048216) (xy 122.197795 -392.055972) (xy 122.25009 -392.071327) (xy 122.299667 -392.093969)
			(xy 122.345517 -392.123435) (xy 122.386708 -392.159126) (xy 122.422399 -392.200317) (xy 122.451865 -392.246167)
			(xy 122.474507 -392.295744) (xy 122.489862 -392.348039) (xy 122.497618 -392.401987) (xy 122.498104 -392.429238)
			(xy 122.498104 -393.292838) (xy 122.934984 -393.292838) (xy 122.934984 -392.429238) (xy 122.93547 -392.401987)
			(xy 122.943226 -392.348039) (xy 122.958581 -392.295744) (xy 122.981223 -392.246167) (xy 123.010689 -392.200317)
			(xy 123.04638 -392.159126) (xy 123.087571 -392.123435) (xy 123.133421 -392.093969) (xy 123.182998 -392.071327)
			(xy 123.235293 -392.055972) (xy 123.289241 -392.048216) (xy 123.343743 -392.048216) (xy 123.397691 -392.055972)
			(xy 123.449986 -392.071327) (xy 123.499563 -392.093969) (xy 123.545413 -392.123435) (xy 123.586604 -392.159126)
			(xy 123.622295 -392.200317) (xy 123.651761 -392.246167) (xy 123.674403 -392.295744) (xy 123.689758 -392.348039)
			(xy 123.697514 -392.401987) (xy 123.698 -392.429238) (xy 123.698 -393.292838) (xy 124.13488 -393.292838)
			(xy 124.13488 -392.429238) (xy 124.135366 -392.401969) (xy 124.143128 -392.347985) (xy 124.158493 -392.295655)
			(xy 124.18115 -392.246045) (xy 124.210636 -392.200164) (xy 124.246351 -392.158947) (xy 124.287568 -392.123232)
			(xy 124.333449 -392.093746) (xy 124.383059 -392.071089) (xy 124.435389 -392.055724) (xy 124.489373 -392.047962)
			(xy 124.543911 -392.047962) (xy 124.597895 -392.055724) (xy 124.650225 -392.071089) (xy 124.699835 -392.093746)
			(xy 124.745716 -392.123232) (xy 124.786933 -392.158947) (xy 124.822648 -392.200164) (xy 124.852134 -392.246045)
			(xy 124.874791 -392.295655) (xy 124.890156 -392.347985) (xy 124.897918 -392.401969) (xy 124.898404 -392.429238)
			(xy 124.898404 -393.292838) (xy 125.334776 -393.292838) (xy 125.334776 -392.429238) (xy 125.335262 -392.401969)
			(xy 125.343024 -392.347985) (xy 125.358389 -392.295655) (xy 125.381046 -392.246045) (xy 125.410532 -392.200164)
			(xy 125.446247 -392.158947) (xy 125.487464 -392.123232) (xy 125.533345 -392.093746) (xy 125.582955 -392.071089)
			(xy 125.635285 -392.055724) (xy 125.689269 -392.047962) (xy 125.743807 -392.047962) (xy 125.797791 -392.055724)
			(xy 125.850121 -392.071089) (xy 125.899731 -392.093746) (xy 125.945612 -392.123232) (xy 125.986829 -392.158947)
			(xy 126.022544 -392.200164) (xy 126.05203 -392.246045) (xy 126.074687 -392.295655) (xy 126.090052 -392.347985)
			(xy 126.097814 -392.401969) (xy 126.0983 -392.429238) (xy 126.0983 -393.292838) (xy 126.53518 -393.292838)
			(xy 126.53518 -392.429238) (xy 126.535666 -392.401987) (xy 126.543422 -392.348039) (xy 126.558777 -392.295744)
			(xy 126.581419 -392.246167) (xy 126.610885 -392.200317) (xy 126.646576 -392.159126) (xy 126.687767 -392.123435)
			(xy 126.733617 -392.093969) (xy 126.783194 -392.071327) (xy 126.835489 -392.055972) (xy 126.889437 -392.048216)
			(xy 126.943939 -392.048216) (xy 126.997887 -392.055972) (xy 127.050182 -392.071327) (xy 127.099759 -392.093969)
			(xy 127.145609 -392.123435) (xy 127.1868 -392.159126) (xy 127.222491 -392.200317) (xy 127.251957 -392.246167)
			(xy 127.274599 -392.295744) (xy 127.289954 -392.348039) (xy 127.29771 -392.401987) (xy 127.298196 -392.429238)
			(xy 127.298196 -393.292838) (xy 127.735076 -393.292838) (xy 127.735076 -392.429238) (xy 127.735562 -392.401987)
			(xy 127.743318 -392.348039) (xy 127.758673 -392.295744) (xy 127.781315 -392.246167) (xy 127.810781 -392.200317)
			(xy 127.846472 -392.159126) (xy 127.887663 -392.123435) (xy 127.933513 -392.093969) (xy 127.98309 -392.071327)
			(xy 128.035385 -392.055972) (xy 128.089333 -392.048216) (xy 128.143835 -392.048216) (xy 128.197783 -392.055972)
			(xy 128.250078 -392.071327) (xy 128.299655 -392.093969) (xy 128.345505 -392.123435) (xy 128.386696 -392.159126)
			(xy 128.422387 -392.200317) (xy 128.451853 -392.246167) (xy 128.474495 -392.295744) (xy 128.48985 -392.348039)
			(xy 128.497606 -392.401987) (xy 128.498092 -392.429238) (xy 128.498092 -393.292838) (xy 128.934972 -393.292838)
			(xy 128.934972 -392.429238) (xy 128.935458 -392.401987) (xy 128.943214 -392.348039) (xy 128.958569 -392.295744)
			(xy 128.981211 -392.246167) (xy 129.010677 -392.200317) (xy 129.046368 -392.159126) (xy 129.087559 -392.123435)
			(xy 129.133409 -392.093969) (xy 129.182986 -392.071327) (xy 129.235281 -392.055972) (xy 129.289229 -392.048216)
			(xy 129.343731 -392.048216) (xy 129.397679 -392.055972) (xy 129.449974 -392.071327) (xy 129.499551 -392.093969)
			(xy 129.545401 -392.123435) (xy 129.586592 -392.159126) (xy 129.622283 -392.200317) (xy 129.651749 -392.246167)
			(xy 129.674391 -392.295744) (xy 129.689746 -392.348039) (xy 129.697502 -392.401987) (xy 129.697988 -392.429238)
			(xy 129.697988 -393.292838) (xy 130.134868 -393.292838) (xy 130.134868 -392.429238) (xy 130.135354 -392.401987)
			(xy 130.14311 -392.348039) (xy 130.158465 -392.295744) (xy 130.181107 -392.246167) (xy 130.210573 -392.200317)
			(xy 130.246264 -392.159126) (xy 130.287455 -392.123435) (xy 130.333305 -392.093969) (xy 130.382882 -392.071327)
			(xy 130.435177 -392.055972) (xy 130.489125 -392.048216) (xy 130.543627 -392.048216) (xy 130.597575 -392.055972)
			(xy 130.64987 -392.071327) (xy 130.699447 -392.093969) (xy 130.745297 -392.123435) (xy 130.786488 -392.159126)
			(xy 130.822179 -392.200317) (xy 130.851645 -392.246167) (xy 130.874287 -392.295744) (xy 130.889642 -392.348039)
			(xy 130.897398 -392.401987) (xy 130.897884 -392.429238) (xy 130.897884 -393.292838) (xy 131.334764 -393.292838)
			(xy 131.334764 -392.429238) (xy 131.33525 -392.401969) (xy 131.343012 -392.347985) (xy 131.358377 -392.295655)
			(xy 131.381034 -392.246045) (xy 131.41052 -392.200164) (xy 131.446235 -392.158947) (xy 131.487452 -392.123232)
			(xy 131.533333 -392.093746) (xy 131.582943 -392.071089) (xy 131.635273 -392.055724) (xy 131.689257 -392.047962)
			(xy 131.743795 -392.047962) (xy 131.797779 -392.055724) (xy 131.850109 -392.071089) (xy 131.899719 -392.093746)
			(xy 131.9456 -392.123232) (xy 131.986817 -392.158947) (xy 132.022532 -392.200164) (xy 132.052018 -392.246045)
			(xy 132.074675 -392.295655) (xy 132.09004 -392.347985) (xy 132.097802 -392.401969) (xy 132.098288 -392.429238)
			(xy 132.098288 -393.292838) (xy 132.53466 -393.292838) (xy 132.53466 -392.429238) (xy 132.535146 -392.401969)
			(xy 132.542908 -392.347985) (xy 132.558273 -392.295655) (xy 132.58093 -392.246045) (xy 132.610416 -392.200164)
			(xy 132.646131 -392.158947) (xy 132.687348 -392.123232) (xy 132.733229 -392.093746) (xy 132.782839 -392.071089)
			(xy 132.835169 -392.055724) (xy 132.889153 -392.047962) (xy 132.943691 -392.047962) (xy 132.997675 -392.055724)
			(xy 133.050005 -392.071089) (xy 133.099615 -392.093746) (xy 133.145496 -392.123232) (xy 133.186713 -392.158947)
			(xy 133.222428 -392.200164) (xy 133.251914 -392.246045) (xy 133.274571 -392.295655) (xy 133.289936 -392.347985)
			(xy 133.297698 -392.401969) (xy 133.298184 -392.429238) (xy 133.298184 -393.292838) (xy 147.062444 -393.292838)
			(xy 147.062444 -392.429238) (xy 147.06293 -392.401969) (xy 147.070692 -392.347985) (xy 147.086057 -392.295655)
			(xy 147.108714 -392.246045) (xy 147.1382 -392.200164) (xy 147.173915 -392.158947) (xy 147.215132 -392.123232)
			(xy 147.261013 -392.093746) (xy 147.310623 -392.071089) (xy 147.362953 -392.055724) (xy 147.416937 -392.047962)
			(xy 147.471475 -392.047962) (xy 147.525459 -392.055724) (xy 147.577789 -392.071089) (xy 147.627399 -392.093746)
			(xy 147.67328 -392.123232) (xy 147.714497 -392.158947) (xy 147.750212 -392.200164) (xy 147.779698 -392.246045)
			(xy 147.802355 -392.295655) (xy 147.81772 -392.347985) (xy 147.825482 -392.401969) (xy 147.825968 -392.429238)
			(xy 147.825968 -393.292838) (xy 148.26234 -393.292838) (xy 148.26234 -392.429238) (xy 148.262826 -392.401969)
			(xy 148.270588 -392.347985) (xy 148.285953 -392.295655) (xy 148.30861 -392.246045) (xy 148.338096 -392.200164)
			(xy 148.373811 -392.158947) (xy 148.415028 -392.123232) (xy 148.460909 -392.093746) (xy 148.510519 -392.071089)
			(xy 148.562849 -392.055724) (xy 148.616833 -392.047962) (xy 148.671371 -392.047962) (xy 148.725355 -392.055724)
			(xy 148.777685 -392.071089) (xy 148.827295 -392.093746) (xy 148.873176 -392.123232) (xy 148.914393 -392.158947)
			(xy 148.950108 -392.200164) (xy 148.979594 -392.246045) (xy 149.002251 -392.295655) (xy 149.017616 -392.347985)
			(xy 149.025378 -392.401969) (xy 149.025864 -392.429238) (xy 149.025864 -393.292838) (xy 149.462744 -393.292838)
			(xy 149.462744 -392.429238) (xy 149.46323 -392.401987) (xy 149.470986 -392.348039) (xy 149.486341 -392.295744)
			(xy 149.508983 -392.246167) (xy 149.538449 -392.200317) (xy 149.57414 -392.159126) (xy 149.615331 -392.123435)
			(xy 149.661181 -392.093969) (xy 149.710758 -392.071327) (xy 149.763053 -392.055972) (xy 149.817001 -392.048216)
			(xy 149.871503 -392.048216) (xy 149.925451 -392.055972) (xy 149.977746 -392.071327) (xy 150.027323 -392.093969)
			(xy 150.073173 -392.123435) (xy 150.114364 -392.159126) (xy 150.150055 -392.200317) (xy 150.179521 -392.246167)
			(xy 150.202163 -392.295744) (xy 150.217518 -392.348039) (xy 150.225274 -392.401987) (xy 150.22576 -392.429238)
			(xy 150.22576 -393.292838) (xy 150.66264 -393.292838) (xy 150.66264 -392.429238) (xy 150.663126 -392.401987)
			(xy 150.670882 -392.348039) (xy 150.686237 -392.295744) (xy 150.708879 -392.246167) (xy 150.738345 -392.200317)
			(xy 150.774036 -392.159126) (xy 150.815227 -392.123435) (xy 150.861077 -392.093969) (xy 150.910654 -392.071327)
			(xy 150.962949 -392.055972) (xy 151.016897 -392.048216) (xy 151.071399 -392.048216) (xy 151.125347 -392.055972)
			(xy 151.177642 -392.071327) (xy 151.227219 -392.093969) (xy 151.273069 -392.123435) (xy 151.31426 -392.159126)
			(xy 151.349951 -392.200317) (xy 151.379417 -392.246167) (xy 151.402059 -392.295744) (xy 151.417414 -392.348039)
			(xy 151.42517 -392.401987) (xy 151.425656 -392.429238) (xy 151.425656 -393.292838) (xy 151.862536 -393.292838)
			(xy 151.862536 -392.429238) (xy 151.863022 -392.401969) (xy 151.870784 -392.347985) (xy 151.886149 -392.295655)
			(xy 151.908806 -392.246045) (xy 151.938292 -392.200164) (xy 151.974007 -392.158947) (xy 152.015224 -392.123232)
			(xy 152.061105 -392.093746) (xy 152.110715 -392.071089) (xy 152.163045 -392.055724) (xy 152.217029 -392.047962)
			(xy 152.271567 -392.047962) (xy 152.325551 -392.055724) (xy 152.377881 -392.071089) (xy 152.427491 -392.093746)
			(xy 152.473372 -392.123232) (xy 152.514589 -392.158947) (xy 152.550304 -392.200164) (xy 152.57979 -392.246045)
			(xy 152.602447 -392.295655) (xy 152.617812 -392.347985) (xy 152.625574 -392.401969) (xy 152.62606 -392.429238)
			(xy 152.62606 -393.292838) (xy 153.062432 -393.292838) (xy 153.062432 -392.429238) (xy 153.062918 -392.401969)
			(xy 153.07068 -392.347985) (xy 153.086045 -392.295655) (xy 153.108702 -392.246045) (xy 153.138188 -392.200164)
			(xy 153.173903 -392.158947) (xy 153.21512 -392.123232) (xy 153.261001 -392.093746) (xy 153.310611 -392.071089)
			(xy 153.362941 -392.055724) (xy 153.416925 -392.047962) (xy 153.471463 -392.047962) (xy 153.525447 -392.055724)
			(xy 153.577777 -392.071089) (xy 153.627387 -392.093746) (xy 153.673268 -392.123232) (xy 153.714485 -392.158947)
			(xy 153.7502 -392.200164) (xy 153.779686 -392.246045) (xy 153.802343 -392.295655) (xy 153.817708 -392.347985)
			(xy 153.82547 -392.401969) (xy 153.825956 -392.429238) (xy 153.825956 -393.292838) (xy 154.262836 -393.292838)
			(xy 154.262836 -392.429238) (xy 154.263322 -392.401987) (xy 154.271078 -392.348039) (xy 154.286433 -392.295744)
			(xy 154.309075 -392.246167) (xy 154.338541 -392.200317) (xy 154.374232 -392.159126) (xy 154.415423 -392.123435)
			(xy 154.461273 -392.093969) (xy 154.51085 -392.071327) (xy 154.563145 -392.055972) (xy 154.617093 -392.048216)
			(xy 154.671595 -392.048216) (xy 154.725543 -392.055972) (xy 154.777838 -392.071327) (xy 154.827415 -392.093969)
			(xy 154.873265 -392.123435) (xy 154.914456 -392.159126) (xy 154.950147 -392.200317) (xy 154.979613 -392.246167)
			(xy 155.002255 -392.295744) (xy 155.01761 -392.348039) (xy 155.025366 -392.401987) (xy 155.025852 -392.429238)
			(xy 155.025852 -393.292838) (xy 155.462732 -393.292838) (xy 155.462732 -392.429238) (xy 155.463218 -392.401987)
			(xy 155.470974 -392.348039) (xy 155.486329 -392.295744) (xy 155.508971 -392.246167) (xy 155.538437 -392.200317)
			(xy 155.574128 -392.159126) (xy 155.615319 -392.123435) (xy 155.661169 -392.093969) (xy 155.710746 -392.071327)
			(xy 155.763041 -392.055972) (xy 155.816989 -392.048216) (xy 155.871491 -392.048216) (xy 155.925439 -392.055972)
			(xy 155.977734 -392.071327) (xy 156.027311 -392.093969) (xy 156.073161 -392.123435) (xy 156.114352 -392.159126)
			(xy 156.150043 -392.200317) (xy 156.179509 -392.246167) (xy 156.202151 -392.295744) (xy 156.217506 -392.348039)
			(xy 156.225262 -392.401987) (xy 156.225748 -392.429238) (xy 156.225748 -393.292838) (xy 156.662628 -393.292838)
			(xy 156.662628 -392.429238) (xy 156.663114 -392.401969) (xy 156.670876 -392.347985) (xy 156.686241 -392.295655)
			(xy 156.708898 -392.246045) (xy 156.738384 -392.200164) (xy 156.774099 -392.158947) (xy 156.815316 -392.123232)
			(xy 156.861197 -392.093746) (xy 156.910807 -392.071089) (xy 156.963137 -392.055724) (xy 157.017121 -392.047962)
			(xy 157.071659 -392.047962) (xy 157.125643 -392.055724) (xy 157.177973 -392.071089) (xy 157.227583 -392.093746)
			(xy 157.273464 -392.123232) (xy 157.314681 -392.158947) (xy 157.350396 -392.200164) (xy 157.379882 -392.246045)
			(xy 157.402539 -392.295655) (xy 157.417904 -392.347985) (xy 157.425666 -392.401969) (xy 157.426152 -392.429238)
			(xy 157.426152 -393.292838) (xy 157.862524 -393.292838) (xy 157.862524 -392.429238) (xy 157.86301 -392.401969)
			(xy 157.870772 -392.347985) (xy 157.886137 -392.295655) (xy 157.908794 -392.246045) (xy 157.93828 -392.200164)
			(xy 157.973995 -392.158947) (xy 158.015212 -392.123232) (xy 158.061093 -392.093746) (xy 158.110703 -392.071089)
			(xy 158.163033 -392.055724) (xy 158.217017 -392.047962) (xy 158.271555 -392.047962) (xy 158.325539 -392.055724)
			(xy 158.377869 -392.071089) (xy 158.427479 -392.093746) (xy 158.47336 -392.123232) (xy 158.514577 -392.158947)
			(xy 158.550292 -392.200164) (xy 158.579778 -392.246045) (xy 158.602435 -392.295655) (xy 158.6178 -392.347985)
			(xy 158.625562 -392.401969) (xy 158.626048 -392.429238) (xy 158.626048 -393.292838) (xy 159.062928 -393.292838)
			(xy 159.062928 -392.429238) (xy 159.063414 -392.401987) (xy 159.07117 -392.348039) (xy 159.086525 -392.295744)
			(xy 159.109167 -392.246167) (xy 159.138633 -392.200317) (xy 159.174324 -392.159126) (xy 159.215515 -392.123435)
			(xy 159.261365 -392.093969) (xy 159.310942 -392.071327) (xy 159.363237 -392.055972) (xy 159.417185 -392.048216)
			(xy 159.471687 -392.048216) (xy 159.525635 -392.055972) (xy 159.57793 -392.071327) (xy 159.627507 -392.093969)
			(xy 159.673357 -392.123435) (xy 159.714548 -392.159126) (xy 159.750239 -392.200317) (xy 159.779705 -392.246167)
			(xy 159.802347 -392.295744) (xy 159.817702 -392.348039) (xy 159.825458 -392.401987) (xy 159.825944 -392.429238)
			(xy 159.825944 -393.292838) (xy 160.262824 -393.292838) (xy 160.262824 -392.429238) (xy 160.26331 -392.401987)
			(xy 160.271066 -392.348039) (xy 160.286421 -392.295744) (xy 160.309063 -392.246167) (xy 160.338529 -392.200317)
			(xy 160.37422 -392.159126) (xy 160.415411 -392.123435) (xy 160.461261 -392.093969) (xy 160.510838 -392.071327)
			(xy 160.563133 -392.055972) (xy 160.617081 -392.048216) (xy 160.671583 -392.048216) (xy 160.725531 -392.055972)
			(xy 160.777826 -392.071327) (xy 160.827403 -392.093969) (xy 160.873253 -392.123435) (xy 160.914444 -392.159126)
			(xy 160.950135 -392.200317) (xy 160.979601 -392.246167) (xy 161.002243 -392.295744) (xy 161.017598 -392.348039)
			(xy 161.025354 -392.401987) (xy 161.02584 -392.429238) (xy 161.02584 -393.292838) (xy 161.46272 -393.292838)
			(xy 161.46272 -392.429238) (xy 161.463206 -392.401987) (xy 161.470962 -392.348039) (xy 161.486317 -392.295744)
			(xy 161.508959 -392.246167) (xy 161.538425 -392.200317) (xy 161.574116 -392.159126) (xy 161.615307 -392.123435)
			(xy 161.661157 -392.093969) (xy 161.710734 -392.071327) (xy 161.763029 -392.055972) (xy 161.816977 -392.048216)
			(xy 161.871479 -392.048216) (xy 161.925427 -392.055972) (xy 161.977722 -392.071327) (xy 162.027299 -392.093969)
			(xy 162.073149 -392.123435) (xy 162.11434 -392.159126) (xy 162.150031 -392.200317) (xy 162.179497 -392.246167)
			(xy 162.202139 -392.295744) (xy 162.217494 -392.348039) (xy 162.22525 -392.401987) (xy 162.225736 -392.429238)
			(xy 162.225736 -393.292838) (xy 162.662616 -393.292838) (xy 162.662616 -392.429238) (xy 162.663102 -392.401987)
			(xy 162.670858 -392.348039) (xy 162.686213 -392.295744) (xy 162.708855 -392.246167) (xy 162.738321 -392.200317)
			(xy 162.774012 -392.159126) (xy 162.815203 -392.123435) (xy 162.861053 -392.093969) (xy 162.91063 -392.071327)
			(xy 162.962925 -392.055972) (xy 163.016873 -392.048216) (xy 163.071375 -392.048216) (xy 163.125323 -392.055972)
			(xy 163.177618 -392.071327) (xy 163.227195 -392.093969) (xy 163.273045 -392.123435) (xy 163.314236 -392.159126)
			(xy 163.349927 -392.200317) (xy 163.379393 -392.246167) (xy 163.402035 -392.295744) (xy 163.41739 -392.348039)
			(xy 163.425146 -392.401987) (xy 163.425632 -392.429238) (xy 163.425632 -393.292838) (xy 163.862512 -393.292838)
			(xy 163.862512 -392.429238) (xy 163.862998 -392.401969) (xy 163.87076 -392.347985) (xy 163.886125 -392.295655)
			(xy 163.908782 -392.246045) (xy 163.938268 -392.200164) (xy 163.973983 -392.158947) (xy 164.0152 -392.123232)
			(xy 164.061081 -392.093746) (xy 164.110691 -392.071089) (xy 164.163021 -392.055724) (xy 164.217005 -392.047962)
			(xy 164.271543 -392.047962) (xy 164.325527 -392.055724) (xy 164.377857 -392.071089) (xy 164.427467 -392.093746)
			(xy 164.473348 -392.123232) (xy 164.514565 -392.158947) (xy 164.55028 -392.200164) (xy 164.579766 -392.246045)
			(xy 164.602423 -392.295655) (xy 164.617788 -392.347985) (xy 164.62555 -392.401969) (xy 164.626036 -392.429238)
			(xy 164.626036 -393.292838) (xy 165.062408 -393.292838) (xy 165.062408 -392.429238) (xy 165.062894 -392.401969)
			(xy 165.070656 -392.347985) (xy 165.086021 -392.295655) (xy 165.108678 -392.246045) (xy 165.138164 -392.200164)
			(xy 165.173879 -392.158947) (xy 165.215096 -392.123232) (xy 165.260977 -392.093746) (xy 165.310587 -392.071089)
			(xy 165.362917 -392.055724) (xy 165.416901 -392.047962) (xy 165.471439 -392.047962) (xy 165.525423 -392.055724)
			(xy 165.577753 -392.071089) (xy 165.627363 -392.093746) (xy 165.673244 -392.123232) (xy 165.714461 -392.158947)
			(xy 165.750176 -392.200164) (xy 165.779662 -392.246045) (xy 165.802319 -392.295655) (xy 165.817684 -392.347985)
			(xy 165.825446 -392.401969) (xy 165.825932 -392.429238) (xy 165.825932 -393.292838) (xy 165.825446 -393.320107)
			(xy 165.817684 -393.374091) (xy 165.802319 -393.426421) (xy 165.779662 -393.476031) (xy 165.750176 -393.521912)
			(xy 165.714461 -393.563129) (xy 165.673244 -393.598844) (xy 165.627363 -393.62833) (xy 165.577753 -393.650987)
			(xy 165.525423 -393.666352) (xy 165.471439 -393.674114) (xy 165.416901 -393.674114) (xy 165.362917 -393.666352)
			(xy 165.310587 -393.650987) (xy 165.260977 -393.62833) (xy 165.215096 -393.598844) (xy 165.173879 -393.563129)
			(xy 165.138164 -393.521912) (xy 165.108678 -393.476031) (xy 165.086021 -393.426421) (xy 165.070656 -393.374091)
			(xy 165.062894 -393.320107) (xy 165.062408 -393.292838) (xy 164.626036 -393.292838) (xy 164.62555 -393.320107)
			(xy 164.617788 -393.374091) (xy 164.602423 -393.426421) (xy 164.579766 -393.476031) (xy 164.55028 -393.521912)
			(xy 164.514565 -393.563129) (xy 164.473348 -393.598844) (xy 164.427467 -393.62833) (xy 164.377857 -393.650987)
			(xy 164.325527 -393.666352) (xy 164.271543 -393.674114) (xy 164.217005 -393.674114) (xy 164.163021 -393.666352)
			(xy 164.110691 -393.650987) (xy 164.061081 -393.62833) (xy 164.0152 -393.598844) (xy 163.973983 -393.563129)
			(xy 163.938268 -393.521912) (xy 163.908782 -393.476031) (xy 163.886125 -393.426421) (xy 163.87076 -393.374091)
			(xy 163.862998 -393.320107) (xy 163.862512 -393.292838) (xy 163.425632 -393.292838) (xy 163.425146 -393.320089)
			(xy 163.41739 -393.374037) (xy 163.402035 -393.426332) (xy 163.379393 -393.475909) (xy 163.349927 -393.521759)
			(xy 163.314236 -393.56295) (xy 163.273045 -393.598641) (xy 163.227195 -393.628107) (xy 163.177618 -393.650749)
			(xy 163.125323 -393.666104) (xy 163.071375 -393.67386) (xy 163.016873 -393.67386) (xy 162.962925 -393.666104)
			(xy 162.91063 -393.650749) (xy 162.861053 -393.628107) (xy 162.815203 -393.598641) (xy 162.774012 -393.56295)
			(xy 162.738321 -393.521759) (xy 162.708855 -393.475909) (xy 162.686213 -393.426332) (xy 162.670858 -393.374037)
			(xy 162.663102 -393.320089) (xy 162.662616 -393.292838) (xy 162.225736 -393.292838) (xy 162.22525 -393.320089)
			(xy 162.217494 -393.374037) (xy 162.202139 -393.426332) (xy 162.179497 -393.475909) (xy 162.150031 -393.521759)
			(xy 162.11434 -393.56295) (xy 162.073149 -393.598641) (xy 162.027299 -393.628107) (xy 161.977722 -393.650749)
			(xy 161.925427 -393.666104) (xy 161.871479 -393.67386) (xy 161.816977 -393.67386) (xy 161.763029 -393.666104)
			(xy 161.710734 -393.650749) (xy 161.661157 -393.628107) (xy 161.615307 -393.598641) (xy 161.574116 -393.56295)
			(xy 161.538425 -393.521759) (xy 161.508959 -393.475909) (xy 161.486317 -393.426332) (xy 161.470962 -393.374037)
			(xy 161.463206 -393.320089) (xy 161.46272 -393.292838) (xy 161.02584 -393.292838) (xy 161.025354 -393.320089)
			(xy 161.017598 -393.374037) (xy 161.002243 -393.426332) (xy 160.979601 -393.475909) (xy 160.950135 -393.521759)
			(xy 160.914444 -393.56295) (xy 160.873253 -393.598641) (xy 160.827403 -393.628107) (xy 160.777826 -393.650749)
			(xy 160.725531 -393.666104) (xy 160.671583 -393.67386) (xy 160.617081 -393.67386) (xy 160.563133 -393.666104)
			(xy 160.510838 -393.650749) (xy 160.461261 -393.628107) (xy 160.415411 -393.598641) (xy 160.37422 -393.56295)
			(xy 160.338529 -393.521759) (xy 160.309063 -393.475909) (xy 160.286421 -393.426332) (xy 160.271066 -393.374037)
			(xy 160.26331 -393.320089) (xy 160.262824 -393.292838) (xy 159.825944 -393.292838) (xy 159.825458 -393.320089)
			(xy 159.817702 -393.374037) (xy 159.802347 -393.426332) (xy 159.779705 -393.475909) (xy 159.750239 -393.521759)
			(xy 159.714548 -393.56295) (xy 159.673357 -393.598641) (xy 159.627507 -393.628107) (xy 159.57793 -393.650749)
			(xy 159.525635 -393.666104) (xy 159.471687 -393.67386) (xy 159.417185 -393.67386) (xy 159.363237 -393.666104)
			(xy 159.310942 -393.650749) (xy 159.261365 -393.628107) (xy 159.215515 -393.598641) (xy 159.174324 -393.56295)
			(xy 159.138633 -393.521759) (xy 159.109167 -393.475909) (xy 159.086525 -393.426332) (xy 159.07117 -393.374037)
			(xy 159.063414 -393.320089) (xy 159.062928 -393.292838) (xy 158.626048 -393.292838) (xy 158.625562 -393.320107)
			(xy 158.6178 -393.374091) (xy 158.602435 -393.426421) (xy 158.579778 -393.476031) (xy 158.550292 -393.521912)
			(xy 158.514577 -393.563129) (xy 158.47336 -393.598844) (xy 158.427479 -393.62833) (xy 158.377869 -393.650987)
			(xy 158.325539 -393.666352) (xy 158.271555 -393.674114) (xy 158.217017 -393.674114) (xy 158.163033 -393.666352)
			(xy 158.110703 -393.650987) (xy 158.061093 -393.62833) (xy 158.015212 -393.598844) (xy 157.973995 -393.563129)
			(xy 157.93828 -393.521912) (xy 157.908794 -393.476031) (xy 157.886137 -393.426421) (xy 157.870772 -393.374091)
			(xy 157.86301 -393.320107) (xy 157.862524 -393.292838) (xy 157.426152 -393.292838) (xy 157.425666 -393.320107)
			(xy 157.417904 -393.374091) (xy 157.402539 -393.426421) (xy 157.379882 -393.476031) (xy 157.350396 -393.521912)
			(xy 157.314681 -393.563129) (xy 157.273464 -393.598844) (xy 157.227583 -393.62833) (xy 157.177973 -393.650987)
			(xy 157.125643 -393.666352) (xy 157.071659 -393.674114) (xy 157.017121 -393.674114) (xy 156.963137 -393.666352)
			(xy 156.910807 -393.650987) (xy 156.861197 -393.62833) (xy 156.815316 -393.598844) (xy 156.774099 -393.563129)
			(xy 156.738384 -393.521912) (xy 156.708898 -393.476031) (xy 156.686241 -393.426421) (xy 156.670876 -393.374091)
			(xy 156.663114 -393.320107) (xy 156.662628 -393.292838) (xy 156.225748 -393.292838) (xy 156.225262 -393.320089)
			(xy 156.217506 -393.374037) (xy 156.202151 -393.426332) (xy 156.179509 -393.475909) (xy 156.150043 -393.521759)
			(xy 156.114352 -393.56295) (xy 156.073161 -393.598641) (xy 156.027311 -393.628107) (xy 155.977734 -393.650749)
			(xy 155.925439 -393.666104) (xy 155.871491 -393.67386) (xy 155.816989 -393.67386) (xy 155.763041 -393.666104)
			(xy 155.710746 -393.650749) (xy 155.661169 -393.628107) (xy 155.615319 -393.598641) (xy 155.574128 -393.56295)
			(xy 155.538437 -393.521759) (xy 155.508971 -393.475909) (xy 155.486329 -393.426332) (xy 155.470974 -393.374037)
			(xy 155.463218 -393.320089) (xy 155.462732 -393.292838) (xy 155.025852 -393.292838) (xy 155.025366 -393.320089)
			(xy 155.01761 -393.374037) (xy 155.002255 -393.426332) (xy 154.979613 -393.475909) (xy 154.950147 -393.521759)
			(xy 154.914456 -393.56295) (xy 154.873265 -393.598641) (xy 154.827415 -393.628107) (xy 154.777838 -393.650749)
			(xy 154.725543 -393.666104) (xy 154.671595 -393.67386) (xy 154.617093 -393.67386) (xy 154.563145 -393.666104)
			(xy 154.51085 -393.650749) (xy 154.461273 -393.628107) (xy 154.415423 -393.598641) (xy 154.374232 -393.56295)
			(xy 154.338541 -393.521759) (xy 154.309075 -393.475909) (xy 154.286433 -393.426332) (xy 154.271078 -393.374037)
			(xy 154.263322 -393.320089) (xy 154.262836 -393.292838) (xy 153.825956 -393.292838) (xy 153.82547 -393.320107)
			(xy 153.817708 -393.374091) (xy 153.802343 -393.426421) (xy 153.779686 -393.476031) (xy 153.7502 -393.521912)
			(xy 153.714485 -393.563129) (xy 153.673268 -393.598844) (xy 153.627387 -393.62833) (xy 153.577777 -393.650987)
			(xy 153.525447 -393.666352) (xy 153.471463 -393.674114) (xy 153.416925 -393.674114) (xy 153.362941 -393.666352)
			(xy 153.310611 -393.650987) (xy 153.261001 -393.62833) (xy 153.21512 -393.598844) (xy 153.173903 -393.563129)
			(xy 153.138188 -393.521912) (xy 153.108702 -393.476031) (xy 153.086045 -393.426421) (xy 153.07068 -393.374091)
			(xy 153.062918 -393.320107) (xy 153.062432 -393.292838) (xy 152.62606 -393.292838) (xy 152.625574 -393.320107)
			(xy 152.617812 -393.374091) (xy 152.602447 -393.426421) (xy 152.57979 -393.476031) (xy 152.550304 -393.521912)
			(xy 152.514589 -393.563129) (xy 152.473372 -393.598844) (xy 152.427491 -393.62833) (xy 152.377881 -393.650987)
			(xy 152.325551 -393.666352) (xy 152.271567 -393.674114) (xy 152.217029 -393.674114) (xy 152.163045 -393.666352)
			(xy 152.110715 -393.650987) (xy 152.061105 -393.62833) (xy 152.015224 -393.598844) (xy 151.974007 -393.563129)
			(xy 151.938292 -393.521912) (xy 151.908806 -393.476031) (xy 151.886149 -393.426421) (xy 151.870784 -393.374091)
			(xy 151.863022 -393.320107) (xy 151.862536 -393.292838) (xy 151.425656 -393.292838) (xy 151.42517 -393.320089)
			(xy 151.417414 -393.374037) (xy 151.402059 -393.426332) (xy 151.379417 -393.475909) (xy 151.349951 -393.521759)
			(xy 151.31426 -393.56295) (xy 151.273069 -393.598641) (xy 151.227219 -393.628107) (xy 151.177642 -393.650749)
			(xy 151.125347 -393.666104) (xy 151.071399 -393.67386) (xy 151.016897 -393.67386) (xy 150.962949 -393.666104)
			(xy 150.910654 -393.650749) (xy 150.861077 -393.628107) (xy 150.815227 -393.598641) (xy 150.774036 -393.56295)
			(xy 150.738345 -393.521759) (xy 150.708879 -393.475909) (xy 150.686237 -393.426332) (xy 150.670882 -393.374037)
			(xy 150.663126 -393.320089) (xy 150.66264 -393.292838) (xy 150.22576 -393.292838) (xy 150.225274 -393.320089)
			(xy 150.217518 -393.374037) (xy 150.202163 -393.426332) (xy 150.179521 -393.475909) (xy 150.150055 -393.521759)
			(xy 150.114364 -393.56295) (xy 150.073173 -393.598641) (xy 150.027323 -393.628107) (xy 149.977746 -393.650749)
			(xy 149.925451 -393.666104) (xy 149.871503 -393.67386) (xy 149.817001 -393.67386) (xy 149.763053 -393.666104)
			(xy 149.710758 -393.650749) (xy 149.661181 -393.628107) (xy 149.615331 -393.598641) (xy 149.57414 -393.56295)
			(xy 149.538449 -393.521759) (xy 149.508983 -393.475909) (xy 149.486341 -393.426332) (xy 149.470986 -393.374037)
			(xy 149.46323 -393.320089) (xy 149.462744 -393.292838) (xy 149.025864 -393.292838) (xy 149.025378 -393.320107)
			(xy 149.017616 -393.374091) (xy 149.002251 -393.426421) (xy 148.979594 -393.476031) (xy 148.950108 -393.521912)
			(xy 148.914393 -393.563129) (xy 148.873176 -393.598844) (xy 148.827295 -393.62833) (xy 148.777685 -393.650987)
			(xy 148.725355 -393.666352) (xy 148.671371 -393.674114) (xy 148.616833 -393.674114) (xy 148.562849 -393.666352)
			(xy 148.510519 -393.650987) (xy 148.460909 -393.62833) (xy 148.415028 -393.598844) (xy 148.373811 -393.563129)
			(xy 148.338096 -393.521912) (xy 148.30861 -393.476031) (xy 148.285953 -393.426421) (xy 148.270588 -393.374091)
			(xy 148.262826 -393.320107) (xy 148.26234 -393.292838) (xy 147.825968 -393.292838) (xy 147.825482 -393.320107)
			(xy 147.81772 -393.374091) (xy 147.802355 -393.426421) (xy 147.779698 -393.476031) (xy 147.750212 -393.521912)
			(xy 147.714497 -393.563129) (xy 147.67328 -393.598844) (xy 147.627399 -393.62833) (xy 147.577789 -393.650987)
			(xy 147.525459 -393.666352) (xy 147.471475 -393.674114) (xy 147.416937 -393.674114) (xy 147.362953 -393.666352)
			(xy 147.310623 -393.650987) (xy 147.261013 -393.62833) (xy 147.215132 -393.598844) (xy 147.173915 -393.563129)
			(xy 147.1382 -393.521912) (xy 147.108714 -393.476031) (xy 147.086057 -393.426421) (xy 147.070692 -393.374091)
			(xy 147.06293 -393.320107) (xy 147.062444 -393.292838) (xy 133.298184 -393.292838) (xy 133.297698 -393.320107)
			(xy 133.289936 -393.374091) (xy 133.274571 -393.426421) (xy 133.251914 -393.476031) (xy 133.222428 -393.521912)
			(xy 133.186713 -393.563129) (xy 133.145496 -393.598844) (xy 133.099615 -393.62833) (xy 133.050005 -393.650987)
			(xy 132.997675 -393.666352) (xy 132.943691 -393.674114) (xy 132.889153 -393.674114) (xy 132.835169 -393.666352)
			(xy 132.782839 -393.650987) (xy 132.733229 -393.62833) (xy 132.687348 -393.598844) (xy 132.646131 -393.563129)
			(xy 132.610416 -393.521912) (xy 132.58093 -393.476031) (xy 132.558273 -393.426421) (xy 132.542908 -393.374091)
			(xy 132.535146 -393.320107) (xy 132.53466 -393.292838) (xy 132.098288 -393.292838) (xy 132.097802 -393.320107)
			(xy 132.09004 -393.374091) (xy 132.074675 -393.426421) (xy 132.052018 -393.476031) (xy 132.022532 -393.521912)
			(xy 131.986817 -393.563129) (xy 131.9456 -393.598844) (xy 131.899719 -393.62833) (xy 131.850109 -393.650987)
			(xy 131.797779 -393.666352) (xy 131.743795 -393.674114) (xy 131.689257 -393.674114) (xy 131.635273 -393.666352)
			(xy 131.582943 -393.650987) (xy 131.533333 -393.62833) (xy 131.487452 -393.598844) (xy 131.446235 -393.563129)
			(xy 131.41052 -393.521912) (xy 131.381034 -393.476031) (xy 131.358377 -393.426421) (xy 131.343012 -393.374091)
			(xy 131.33525 -393.320107) (xy 131.334764 -393.292838) (xy 130.897884 -393.292838) (xy 130.897398 -393.320089)
			(xy 130.889642 -393.374037) (xy 130.874287 -393.426332) (xy 130.851645 -393.475909) (xy 130.822179 -393.521759)
			(xy 130.786488 -393.56295) (xy 130.745297 -393.598641) (xy 130.699447 -393.628107) (xy 130.64987 -393.650749)
			(xy 130.597575 -393.666104) (xy 130.543627 -393.67386) (xy 130.489125 -393.67386) (xy 130.435177 -393.666104)
			(xy 130.382882 -393.650749) (xy 130.333305 -393.628107) (xy 130.287455 -393.598641) (xy 130.246264 -393.56295)
			(xy 130.210573 -393.521759) (xy 130.181107 -393.475909) (xy 130.158465 -393.426332) (xy 130.14311 -393.374037)
			(xy 130.135354 -393.320089) (xy 130.134868 -393.292838) (xy 129.697988 -393.292838) (xy 129.697502 -393.320089)
			(xy 129.689746 -393.374037) (xy 129.674391 -393.426332) (xy 129.651749 -393.475909) (xy 129.622283 -393.521759)
			(xy 129.586592 -393.56295) (xy 129.545401 -393.598641) (xy 129.499551 -393.628107) (xy 129.449974 -393.650749)
			(xy 129.397679 -393.666104) (xy 129.343731 -393.67386) (xy 129.289229 -393.67386) (xy 129.235281 -393.666104)
			(xy 129.182986 -393.650749) (xy 129.133409 -393.628107) (xy 129.087559 -393.598641) (xy 129.046368 -393.56295)
			(xy 129.010677 -393.521759) (xy 128.981211 -393.475909) (xy 128.958569 -393.426332) (xy 128.943214 -393.374037)
			(xy 128.935458 -393.320089) (xy 128.934972 -393.292838) (xy 128.498092 -393.292838) (xy 128.497606 -393.320089)
			(xy 128.48985 -393.374037) (xy 128.474495 -393.426332) (xy 128.451853 -393.475909) (xy 128.422387 -393.521759)
			(xy 128.386696 -393.56295) (xy 128.345505 -393.598641) (xy 128.299655 -393.628107) (xy 128.250078 -393.650749)
			(xy 128.197783 -393.666104) (xy 128.143835 -393.67386) (xy 128.089333 -393.67386) (xy 128.035385 -393.666104)
			(xy 127.98309 -393.650749) (xy 127.933513 -393.628107) (xy 127.887663 -393.598641) (xy 127.846472 -393.56295)
			(xy 127.810781 -393.521759) (xy 127.781315 -393.475909) (xy 127.758673 -393.426332) (xy 127.743318 -393.374037)
			(xy 127.735562 -393.320089) (xy 127.735076 -393.292838) (xy 127.298196 -393.292838) (xy 127.29771 -393.320089)
			(xy 127.289954 -393.374037) (xy 127.274599 -393.426332) (xy 127.251957 -393.475909) (xy 127.222491 -393.521759)
			(xy 127.1868 -393.56295) (xy 127.145609 -393.598641) (xy 127.099759 -393.628107) (xy 127.050182 -393.650749)
			(xy 126.997887 -393.666104) (xy 126.943939 -393.67386) (xy 126.889437 -393.67386) (xy 126.835489 -393.666104)
			(xy 126.783194 -393.650749) (xy 126.733617 -393.628107) (xy 126.687767 -393.598641) (xy 126.646576 -393.56295)
			(xy 126.610885 -393.521759) (xy 126.581419 -393.475909) (xy 126.558777 -393.426332) (xy 126.543422 -393.374037)
			(xy 126.535666 -393.320089) (xy 126.53518 -393.292838) (xy 126.0983 -393.292838) (xy 126.097814 -393.320107)
			(xy 126.090052 -393.374091) (xy 126.074687 -393.426421) (xy 126.05203 -393.476031) (xy 126.022544 -393.521912)
			(xy 125.986829 -393.563129) (xy 125.945612 -393.598844) (xy 125.899731 -393.62833) (xy 125.850121 -393.650987)
			(xy 125.797791 -393.666352) (xy 125.743807 -393.674114) (xy 125.689269 -393.674114) (xy 125.635285 -393.666352)
			(xy 125.582955 -393.650987) (xy 125.533345 -393.62833) (xy 125.487464 -393.598844) (xy 125.446247 -393.563129)
			(xy 125.410532 -393.521912) (xy 125.381046 -393.476031) (xy 125.358389 -393.426421) (xy 125.343024 -393.374091)
			(xy 125.335262 -393.320107) (xy 125.334776 -393.292838) (xy 124.898404 -393.292838) (xy 124.897918 -393.320107)
			(xy 124.890156 -393.374091) (xy 124.874791 -393.426421) (xy 124.852134 -393.476031) (xy 124.822648 -393.521912)
			(xy 124.786933 -393.563129) (xy 124.745716 -393.598844) (xy 124.699835 -393.62833) (xy 124.650225 -393.650987)
			(xy 124.597895 -393.666352) (xy 124.543911 -393.674114) (xy 124.489373 -393.674114) (xy 124.435389 -393.666352)
			(xy 124.383059 -393.650987) (xy 124.333449 -393.62833) (xy 124.287568 -393.598844) (xy 124.246351 -393.563129)
			(xy 124.210636 -393.521912) (xy 124.18115 -393.476031) (xy 124.158493 -393.426421) (xy 124.143128 -393.374091)
			(xy 124.135366 -393.320107) (xy 124.13488 -393.292838) (xy 123.698 -393.292838) (xy 123.697514 -393.320089)
			(xy 123.689758 -393.374037) (xy 123.674403 -393.426332) (xy 123.651761 -393.475909) (xy 123.622295 -393.521759)
			(xy 123.586604 -393.56295) (xy 123.545413 -393.598641) (xy 123.499563 -393.628107) (xy 123.449986 -393.650749)
			(xy 123.397691 -393.666104) (xy 123.343743 -393.67386) (xy 123.289241 -393.67386) (xy 123.235293 -393.666104)
			(xy 123.182998 -393.650749) (xy 123.133421 -393.628107) (xy 123.087571 -393.598641) (xy 123.04638 -393.56295)
			(xy 123.010689 -393.521759) (xy 122.981223 -393.475909) (xy 122.958581 -393.426332) (xy 122.943226 -393.374037)
			(xy 122.93547 -393.320089) (xy 122.934984 -393.292838) (xy 122.498104 -393.292838) (xy 122.497618 -393.320089)
			(xy 122.489862 -393.374037) (xy 122.474507 -393.426332) (xy 122.451865 -393.475909) (xy 122.422399 -393.521759)
			(xy 122.386708 -393.56295) (xy 122.345517 -393.598641) (xy 122.299667 -393.628107) (xy 122.25009 -393.650749)
			(xy 122.197795 -393.666104) (xy 122.143847 -393.67386) (xy 122.089345 -393.67386) (xy 122.035397 -393.666104)
			(xy 121.983102 -393.650749) (xy 121.933525 -393.628107) (xy 121.887675 -393.598641) (xy 121.846484 -393.56295)
			(xy 121.810793 -393.521759) (xy 121.781327 -393.475909) (xy 121.758685 -393.426332) (xy 121.74333 -393.374037)
			(xy 121.735574 -393.320089) (xy 121.735088 -393.292838) (xy 121.298208 -393.292838) (xy 121.297722 -393.320107)
			(xy 121.28996 -393.374091) (xy 121.274595 -393.426421) (xy 121.251938 -393.476031) (xy 121.222452 -393.521912)
			(xy 121.186737 -393.563129) (xy 121.14552 -393.598844) (xy 121.099639 -393.62833) (xy 121.050029 -393.650987)
			(xy 120.997699 -393.666352) (xy 120.943715 -393.674114) (xy 120.889177 -393.674114) (xy 120.835193 -393.666352)
			(xy 120.782863 -393.650987) (xy 120.733253 -393.62833) (xy 120.687372 -393.598844) (xy 120.646155 -393.563129)
			(xy 120.61044 -393.521912) (xy 120.580954 -393.476031) (xy 120.558297 -393.426421) (xy 120.542932 -393.374091)
			(xy 120.53517 -393.320107) (xy 120.534684 -393.292838) (xy 120.098312 -393.292838) (xy 120.097826 -393.320107)
			(xy 120.090064 -393.374091) (xy 120.074699 -393.426421) (xy 120.052042 -393.476031) (xy 120.022556 -393.521912)
			(xy 119.986841 -393.563129) (xy 119.945624 -393.598844) (xy 119.899743 -393.62833) (xy 119.850133 -393.650987)
			(xy 119.797803 -393.666352) (xy 119.743819 -393.674114) (xy 119.689281 -393.674114) (xy 119.635297 -393.666352)
			(xy 119.582967 -393.650987) (xy 119.533357 -393.62833) (xy 119.487476 -393.598844) (xy 119.446259 -393.563129)
			(xy 119.410544 -393.521912) (xy 119.381058 -393.476031) (xy 119.358401 -393.426421) (xy 119.343036 -393.374091)
			(xy 119.335274 -393.320107) (xy 119.334788 -393.292838) (xy 118.897908 -393.292838) (xy 118.897422 -393.320089)
			(xy 118.889666 -393.374037) (xy 118.874311 -393.426332) (xy 118.851669 -393.475909) (xy 118.822203 -393.521759)
			(xy 118.786512 -393.56295) (xy 118.745321 -393.598641) (xy 118.699471 -393.628107) (xy 118.649894 -393.650749)
			(xy 118.597599 -393.666104) (xy 118.543651 -393.67386) (xy 118.489149 -393.67386) (xy 118.435201 -393.666104)
			(xy 118.382906 -393.650749) (xy 118.333329 -393.628107) (xy 118.287479 -393.598641) (xy 118.246288 -393.56295)
			(xy 118.210597 -393.521759) (xy 118.181131 -393.475909) (xy 118.158489 -393.426332) (xy 118.143134 -393.374037)
			(xy 118.135378 -393.320089) (xy 118.134892 -393.292838) (xy 117.698012 -393.292838) (xy 117.697526 -393.320089)
			(xy 117.68977 -393.374037) (xy 117.674415 -393.426332) (xy 117.651773 -393.475909) (xy 117.622307 -393.521759)
			(xy 117.586616 -393.56295) (xy 117.545425 -393.598641) (xy 117.499575 -393.628107) (xy 117.449998 -393.650749)
			(xy 117.397703 -393.666104) (xy 117.343755 -393.67386) (xy 117.289253 -393.67386) (xy 117.235305 -393.666104)
			(xy 117.18301 -393.650749) (xy 117.133433 -393.628107) (xy 117.087583 -393.598641) (xy 117.046392 -393.56295)
			(xy 117.010701 -393.521759) (xy 116.981235 -393.475909) (xy 116.958593 -393.426332) (xy 116.943238 -393.374037)
			(xy 116.935482 -393.320089) (xy 116.934996 -393.292838) (xy 116.498116 -393.292838) (xy 116.49763 -393.320107)
			(xy 116.489868 -393.374091) (xy 116.474503 -393.426421) (xy 116.451846 -393.476031) (xy 116.42236 -393.521912)
			(xy 116.386645 -393.563129) (xy 116.345428 -393.598844) (xy 116.299547 -393.62833) (xy 116.249937 -393.650987)
			(xy 116.197607 -393.666352) (xy 116.143623 -393.674114) (xy 116.089085 -393.674114) (xy 116.035101 -393.666352)
			(xy 115.982771 -393.650987) (xy 115.933161 -393.62833) (xy 115.88728 -393.598844) (xy 115.846063 -393.563129)
			(xy 115.810348 -393.521912) (xy 115.780862 -393.476031) (xy 115.758205 -393.426421) (xy 115.74284 -393.374091)
			(xy 115.735078 -393.320107) (xy 115.734592 -393.292838) (xy 115.29822 -393.292838) (xy 115.297734 -393.320107)
			(xy 115.289972 -393.374091) (xy 115.274607 -393.426421) (xy 115.25195 -393.476031) (xy 115.222464 -393.521912)
			(xy 115.186749 -393.563129) (xy 115.145532 -393.598844) (xy 115.099651 -393.62833) (xy 115.050041 -393.650987)
			(xy 114.997711 -393.666352) (xy 114.943727 -393.674114) (xy 114.889189 -393.674114) (xy 114.835205 -393.666352)
			(xy 114.782875 -393.650987) (xy 114.733265 -393.62833) (xy 114.687384 -393.598844) (xy 114.646167 -393.563129)
			(xy 114.610452 -393.521912) (xy 114.580966 -393.476031) (xy 114.558309 -393.426421) (xy 114.542944 -393.374091)
			(xy 114.535182 -393.320107) (xy 114.534696 -393.292838) (xy 98.725736 -393.292838) (xy 98.72525 -393.320089)
			(xy 98.717494 -393.374037) (xy 98.702139 -393.426332) (xy 98.679497 -393.475909) (xy 98.650031 -393.521759)
			(xy 98.61434 -393.56295) (xy 98.573149 -393.598641) (xy 98.527299 -393.628107) (xy 98.477722 -393.650749)
			(xy 98.425427 -393.666104) (xy 98.371479 -393.67386) (xy 98.316977 -393.67386) (xy 98.263029 -393.666104)
			(xy 98.210734 -393.650749) (xy 98.161157 -393.628107) (xy 98.115307 -393.598641) (xy 98.074116 -393.56295)
			(xy 98.038425 -393.521759) (xy 98.008959 -393.475909) (xy 97.986317 -393.426332) (xy 97.970962 -393.374037)
			(xy 97.963206 -393.320089) (xy 97.96272 -393.292838) (xy 97.52584 -393.292838) (xy 97.525354 -393.320089)
			(xy 97.517598 -393.374037) (xy 97.502243 -393.426332) (xy 97.479601 -393.475909) (xy 97.450135 -393.521759)
			(xy 97.414444 -393.56295) (xy 97.373253 -393.598641) (xy 97.327403 -393.628107) (xy 97.277826 -393.650749)
			(xy 97.225531 -393.666104) (xy 97.171583 -393.67386) (xy 97.117081 -393.67386) (xy 97.063133 -393.666104)
			(xy 97.010838 -393.650749) (xy 96.961261 -393.628107) (xy 96.915411 -393.598641) (xy 96.87422 -393.56295)
			(xy 96.838529 -393.521759) (xy 96.809063 -393.475909) (xy 96.786421 -393.426332) (xy 96.771066 -393.374037)
			(xy 96.76331 -393.320089) (xy 96.762824 -393.292838) (xy 96.325944 -393.292838) (xy 96.325458 -393.320107)
			(xy 96.317696 -393.374091) (xy 96.302331 -393.426421) (xy 96.279674 -393.476031) (xy 96.250188 -393.521912)
			(xy 96.214473 -393.563129) (xy 96.173256 -393.598844) (xy 96.127375 -393.62833) (xy 96.077765 -393.650987)
			(xy 96.025435 -393.666352) (xy 95.971451 -393.674114) (xy 95.916913 -393.674114) (xy 95.862929 -393.666352)
			(xy 95.810599 -393.650987) (xy 95.760989 -393.62833) (xy 95.715108 -393.598844) (xy 95.673891 -393.563129)
			(xy 95.638176 -393.521912) (xy 95.60869 -393.476031) (xy 95.586033 -393.426421) (xy 95.570668 -393.374091)
			(xy 95.562906 -393.320107) (xy 95.56242 -393.292838) (xy 95.126048 -393.292838) (xy 95.125562 -393.320107)
			(xy 95.1178 -393.374091) (xy 95.102435 -393.426421) (xy 95.079778 -393.476031) (xy 95.050292 -393.521912)
			(xy 95.014577 -393.563129) (xy 94.97336 -393.598844) (xy 94.927479 -393.62833) (xy 94.877869 -393.650987)
			(xy 94.825539 -393.666352) (xy 94.771555 -393.674114) (xy 94.717017 -393.674114) (xy 94.663033 -393.666352)
			(xy 94.610703 -393.650987) (xy 94.561093 -393.62833) (xy 94.515212 -393.598844) (xy 94.473995 -393.563129)
			(xy 94.43828 -393.521912) (xy 94.408794 -393.476031) (xy 94.386137 -393.426421) (xy 94.370772 -393.374091)
			(xy 94.36301 -393.320107) (xy 94.362524 -393.292838) (xy 93.926152 -393.292838) (xy 93.925666 -393.320107)
			(xy 93.917904 -393.374091) (xy 93.902539 -393.426421) (xy 93.879882 -393.476031) (xy 93.850396 -393.521912)
			(xy 93.814681 -393.563129) (xy 93.773464 -393.598844) (xy 93.727583 -393.62833) (xy 93.677973 -393.650987)
			(xy 93.625643 -393.666352) (xy 93.571659 -393.674114) (xy 93.517121 -393.674114) (xy 93.463137 -393.666352)
			(xy 93.410807 -393.650987) (xy 93.361197 -393.62833) (xy 93.315316 -393.598844) (xy 93.274099 -393.563129)
			(xy 93.238384 -393.521912) (xy 93.208898 -393.476031) (xy 93.186241 -393.426421) (xy 93.170876 -393.374091)
			(xy 93.163114 -393.320107) (xy 93.162628 -393.292838) (xy 92.726256 -393.292838) (xy 92.72577 -393.320107)
			(xy 92.718008 -393.374091) (xy 92.702643 -393.426421) (xy 92.679986 -393.476031) (xy 92.6505 -393.521912)
			(xy 92.614785 -393.563129) (xy 92.573568 -393.598844) (xy 92.527687 -393.62833) (xy 92.478077 -393.650987)
			(xy 92.425747 -393.666352) (xy 92.371763 -393.674114) (xy 92.317225 -393.674114) (xy 92.263241 -393.666352)
			(xy 92.210911 -393.650987) (xy 92.161301 -393.62833) (xy 92.11542 -393.598844) (xy 92.074203 -393.563129)
			(xy 92.038488 -393.521912) (xy 92.009002 -393.476031) (xy 91.986345 -393.426421) (xy 91.97098 -393.374091)
			(xy 91.963218 -393.320107) (xy 91.962732 -393.292838) (xy 91.525852 -393.292838) (xy 91.525366 -393.320089)
			(xy 91.51761 -393.374037) (xy 91.502255 -393.426332) (xy 91.479613 -393.475909) (xy 91.450147 -393.521759)
			(xy 91.414456 -393.56295) (xy 91.373265 -393.598641) (xy 91.327415 -393.628107) (xy 91.277838 -393.650749)
			(xy 91.225543 -393.666104) (xy 91.171595 -393.67386) (xy 91.117093 -393.67386) (xy 91.063145 -393.666104)
			(xy 91.01085 -393.650749) (xy 90.961273 -393.628107) (xy 90.915423 -393.598641) (xy 90.874232 -393.56295)
			(xy 90.838541 -393.521759) (xy 90.809075 -393.475909) (xy 90.786433 -393.426332) (xy 90.771078 -393.374037)
			(xy 90.763322 -393.320089) (xy 90.762836 -393.292838) (xy 90.325956 -393.292838) (xy 90.32547 -393.320089)
			(xy 90.317714 -393.374037) (xy 90.302359 -393.426332) (xy 90.279717 -393.475909) (xy 90.250251 -393.521759)
			(xy 90.21456 -393.56295) (xy 90.173369 -393.598641) (xy 90.127519 -393.628107) (xy 90.077942 -393.650749)
			(xy 90.025647 -393.666104) (xy 89.971699 -393.67386) (xy 89.917197 -393.67386) (xy 89.863249 -393.666104)
			(xy 89.810954 -393.650749) (xy 89.761377 -393.628107) (xy 89.715527 -393.598641) (xy 89.674336 -393.56295)
			(xy 89.638645 -393.521759) (xy 89.609179 -393.475909) (xy 89.586537 -393.426332) (xy 89.571182 -393.374037)
			(xy 89.563426 -393.320089) (xy 89.56294 -393.292838) (xy 89.12606 -393.292838) (xy 89.125574 -393.320107)
			(xy 89.117812 -393.374091) (xy 89.102447 -393.426421) (xy 89.07979 -393.476031) (xy 89.050304 -393.521912)
			(xy 89.014589 -393.563129) (xy 88.973372 -393.598844) (xy 88.927491 -393.62833) (xy 88.877881 -393.650987)
			(xy 88.825551 -393.666352) (xy 88.771567 -393.674114) (xy 88.717029 -393.674114) (xy 88.663045 -393.666352)
			(xy 88.610715 -393.650987) (xy 88.561105 -393.62833) (xy 88.515224 -393.598844) (xy 88.474007 -393.563129)
			(xy 88.438292 -393.521912) (xy 88.408806 -393.476031) (xy 88.386149 -393.426421) (xy 88.370784 -393.374091)
			(xy 88.363022 -393.320107) (xy 88.362536 -393.292838) (xy 87.926164 -393.292838) (xy 87.925678 -393.320107)
			(xy 87.917916 -393.374091) (xy 87.902551 -393.426421) (xy 87.879894 -393.476031) (xy 87.850408 -393.521912)
			(xy 87.814693 -393.563129) (xy 87.773476 -393.598844) (xy 87.727595 -393.62833) (xy 87.677985 -393.650987)
			(xy 87.625655 -393.666352) (xy 87.571671 -393.674114) (xy 87.517133 -393.674114) (xy 87.463149 -393.666352)
			(xy 87.410819 -393.650987) (xy 87.361209 -393.62833) (xy 87.315328 -393.598844) (xy 87.274111 -393.563129)
			(xy 87.238396 -393.521912) (xy 87.20891 -393.476031) (xy 87.186253 -393.426421) (xy 87.170888 -393.374091)
			(xy 87.163126 -393.320107) (xy 87.16264 -393.292838) (xy 86.72576 -393.292838) (xy 86.725274 -393.320089)
			(xy 86.717518 -393.374037) (xy 86.702163 -393.426332) (xy 86.679521 -393.475909) (xy 86.650055 -393.521759)
			(xy 86.614364 -393.56295) (xy 86.573173 -393.598641) (xy 86.527323 -393.628107) (xy 86.477746 -393.650749)
			(xy 86.425451 -393.666104) (xy 86.371503 -393.67386) (xy 86.317001 -393.67386) (xy 86.263053 -393.666104)
			(xy 86.210758 -393.650749) (xy 86.161181 -393.628107) (xy 86.115331 -393.598641) (xy 86.07414 -393.56295)
			(xy 86.038449 -393.521759) (xy 86.008983 -393.475909) (xy 85.986341 -393.426332) (xy 85.970986 -393.374037)
			(xy 85.96323 -393.320089) (xy 85.962744 -393.292838) (xy 85.525864 -393.292838) (xy 85.525378 -393.320089)
			(xy 85.517622 -393.374037) (xy 85.502267 -393.426332) (xy 85.479625 -393.475909) (xy 85.450159 -393.521759)
			(xy 85.414468 -393.56295) (xy 85.373277 -393.598641) (xy 85.327427 -393.628107) (xy 85.27785 -393.650749)
			(xy 85.225555 -393.666104) (xy 85.171607 -393.67386) (xy 85.117105 -393.67386) (xy 85.063157 -393.666104)
			(xy 85.010862 -393.650749) (xy 84.961285 -393.628107) (xy 84.915435 -393.598641) (xy 84.874244 -393.56295)
			(xy 84.838553 -393.521759) (xy 84.809087 -393.475909) (xy 84.786445 -393.426332) (xy 84.77109 -393.374037)
			(xy 84.763334 -393.320089) (xy 84.762848 -393.292838) (xy 84.325968 -393.292838) (xy 84.325482 -393.320107)
			(xy 84.31772 -393.374091) (xy 84.302355 -393.426421) (xy 84.279698 -393.476031) (xy 84.250212 -393.521912)
			(xy 84.214497 -393.563129) (xy 84.17328 -393.598844) (xy 84.127399 -393.62833) (xy 84.077789 -393.650987)
			(xy 84.025459 -393.666352) (xy 83.971475 -393.674114) (xy 83.916937 -393.674114) (xy 83.862953 -393.666352)
			(xy 83.810623 -393.650987) (xy 83.761013 -393.62833) (xy 83.715132 -393.598844) (xy 83.673915 -393.563129)
			(xy 83.6382 -393.521912) (xy 83.608714 -393.476031) (xy 83.586057 -393.426421) (xy 83.570692 -393.374091)
			(xy 83.56293 -393.320107) (xy 83.562444 -393.292838) (xy 83.126072 -393.292838) (xy 83.125586 -393.320107)
			(xy 83.117824 -393.374091) (xy 83.102459 -393.426421) (xy 83.079802 -393.476031) (xy 83.050316 -393.521912)
			(xy 83.014601 -393.563129) (xy 82.973384 -393.598844) (xy 82.927503 -393.62833) (xy 82.877893 -393.650987)
			(xy 82.825563 -393.666352) (xy 82.771579 -393.674114) (xy 82.717041 -393.674114) (xy 82.663057 -393.666352)
			(xy 82.610727 -393.650987) (xy 82.561117 -393.62833) (xy 82.515236 -393.598844) (xy 82.474019 -393.563129)
			(xy 82.438304 -393.521912) (xy 82.408818 -393.476031) (xy 82.386161 -393.426421) (xy 82.370796 -393.374091)
			(xy 82.363034 -393.320107) (xy 82.362548 -393.292838) (xy 81.925668 -393.292838) (xy 81.925182 -393.320089)
			(xy 81.917426 -393.374037) (xy 81.902071 -393.426332) (xy 81.879429 -393.475909) (xy 81.849963 -393.521759)
			(xy 81.814272 -393.56295) (xy 81.773081 -393.598641) (xy 81.727231 -393.628107) (xy 81.677654 -393.650749)
			(xy 81.625359 -393.666104) (xy 81.571411 -393.67386) (xy 81.516909 -393.67386) (xy 81.462961 -393.666104)
			(xy 81.410666 -393.650749) (xy 81.361089 -393.628107) (xy 81.315239 -393.598641) (xy 81.274048 -393.56295)
			(xy 81.238357 -393.521759) (xy 81.208891 -393.475909) (xy 81.186249 -393.426332) (xy 81.170894 -393.374037)
			(xy 81.163138 -393.320089) (xy 81.162652 -393.292838) (xy 80.725772 -393.292838) (xy 80.725286 -393.320089)
			(xy 80.71753 -393.374037) (xy 80.702175 -393.426332) (xy 80.679533 -393.475909) (xy 80.650067 -393.521759)
			(xy 80.614376 -393.56295) (xy 80.573185 -393.598641) (xy 80.527335 -393.628107) (xy 80.477758 -393.650749)
			(xy 80.425463 -393.666104) (xy 80.371515 -393.67386) (xy 80.317013 -393.67386) (xy 80.263065 -393.666104)
			(xy 80.21077 -393.650749) (xy 80.161193 -393.628107) (xy 80.115343 -393.598641) (xy 80.074152 -393.56295)
			(xy 80.038461 -393.521759) (xy 80.008995 -393.475909) (xy 79.986353 -393.426332) (xy 79.970998 -393.374037)
			(xy 79.963242 -393.320089) (xy 79.962756 -393.292838) (xy 66.197988 -393.292838) (xy 66.197502 -393.320089)
			(xy 66.189746 -393.374037) (xy 66.174391 -393.426332) (xy 66.151749 -393.475909) (xy 66.122283 -393.521759)
			(xy 66.086592 -393.56295) (xy 66.045401 -393.598641) (xy 65.999551 -393.628107) (xy 65.949974 -393.650749)
			(xy 65.897679 -393.666104) (xy 65.843731 -393.67386) (xy 65.789229 -393.67386) (xy 65.735281 -393.666104)
			(xy 65.682986 -393.650749) (xy 65.633409 -393.628107) (xy 65.587559 -393.598641) (xy 65.546368 -393.56295)
			(xy 65.510677 -393.521759) (xy 65.481211 -393.475909) (xy 65.458569 -393.426332) (xy 65.443214 -393.374037)
			(xy 65.435458 -393.320089) (xy 65.434972 -393.292838) (xy 64.998092 -393.292838) (xy 64.997606 -393.320089)
			(xy 64.98985 -393.374037) (xy 64.974495 -393.426332) (xy 64.951853 -393.475909) (xy 64.922387 -393.521759)
			(xy 64.886696 -393.56295) (xy 64.845505 -393.598641) (xy 64.799655 -393.628107) (xy 64.750078 -393.650749)
			(xy 64.697783 -393.666104) (xy 64.643835 -393.67386) (xy 64.589333 -393.67386) (xy 64.535385 -393.666104)
			(xy 64.48309 -393.650749) (xy 64.433513 -393.628107) (xy 64.387663 -393.598641) (xy 64.346472 -393.56295)
			(xy 64.310781 -393.521759) (xy 64.281315 -393.475909) (xy 64.258673 -393.426332) (xy 64.243318 -393.374037)
			(xy 64.235562 -393.320089) (xy 64.235076 -393.292838) (xy 63.798196 -393.292838) (xy 63.79771 -393.320107)
			(xy 63.789948 -393.374091) (xy 63.774583 -393.426421) (xy 63.751926 -393.476031) (xy 63.72244 -393.521912)
			(xy 63.686725 -393.563129) (xy 63.645508 -393.598844) (xy 63.599627 -393.62833) (xy 63.550017 -393.650987)
			(xy 63.497687 -393.666352) (xy 63.443703 -393.674114) (xy 63.389165 -393.674114) (xy 63.335181 -393.666352)
			(xy 63.282851 -393.650987) (xy 63.233241 -393.62833) (xy 63.18736 -393.598844) (xy 63.146143 -393.563129)
			(xy 63.110428 -393.521912) (xy 63.080942 -393.476031) (xy 63.058285 -393.426421) (xy 63.04292 -393.374091)
			(xy 63.035158 -393.320107) (xy 63.034672 -393.292838) (xy 62.5983 -393.292838) (xy 62.597814 -393.320107)
			(xy 62.590052 -393.374091) (xy 62.574687 -393.426421) (xy 62.55203 -393.476031) (xy 62.522544 -393.521912)
			(xy 62.486829 -393.563129) (xy 62.445612 -393.598844) (xy 62.399731 -393.62833) (xy 62.350121 -393.650987)
			(xy 62.297791 -393.666352) (xy 62.243807 -393.674114) (xy 62.189269 -393.674114) (xy 62.135285 -393.666352)
			(xy 62.082955 -393.650987) (xy 62.033345 -393.62833) (xy 61.987464 -393.598844) (xy 61.946247 -393.563129)
			(xy 61.910532 -393.521912) (xy 61.881046 -393.476031) (xy 61.858389 -393.426421) (xy 61.843024 -393.374091)
			(xy 61.835262 -393.320107) (xy 61.834776 -393.292838) (xy 61.398404 -393.292838) (xy 61.397918 -393.320107)
			(xy 61.390156 -393.374091) (xy 61.374791 -393.426421) (xy 61.352134 -393.476031) (xy 61.322648 -393.521912)
			(xy 61.286933 -393.563129) (xy 61.245716 -393.598844) (xy 61.199835 -393.62833) (xy 61.150225 -393.650987)
			(xy 61.097895 -393.666352) (xy 61.043911 -393.674114) (xy 60.989373 -393.674114) (xy 60.935389 -393.666352)
			(xy 60.883059 -393.650987) (xy 60.833449 -393.62833) (xy 60.787568 -393.598844) (xy 60.746351 -393.563129)
			(xy 60.710636 -393.521912) (xy 60.68115 -393.476031) (xy 60.658493 -393.426421) (xy 60.643128 -393.374091)
			(xy 60.635366 -393.320107) (xy 60.63488 -393.292838) (xy 60.198508 -393.292838) (xy 60.198022 -393.320107)
			(xy 60.19026 -393.374091) (xy 60.174895 -393.426421) (xy 60.152238 -393.476031) (xy 60.122752 -393.521912)
			(xy 60.087037 -393.563129) (xy 60.04582 -393.598844) (xy 59.999939 -393.62833) (xy 59.950329 -393.650987)
			(xy 59.897999 -393.666352) (xy 59.844015 -393.674114) (xy 59.789477 -393.674114) (xy 59.735493 -393.666352)
			(xy 59.683163 -393.650987) (xy 59.633553 -393.62833) (xy 59.587672 -393.598844) (xy 59.546455 -393.563129)
			(xy 59.51074 -393.521912) (xy 59.481254 -393.476031) (xy 59.458597 -393.426421) (xy 59.443232 -393.374091)
			(xy 59.43547 -393.320107) (xy 59.434984 -393.292838) (xy 58.998104 -393.292838) (xy 58.997618 -393.320089)
			(xy 58.989862 -393.374037) (xy 58.974507 -393.426332) (xy 58.951865 -393.475909) (xy 58.922399 -393.521759)
			(xy 58.886708 -393.56295) (xy 58.845517 -393.598641) (xy 58.799667 -393.628107) (xy 58.75009 -393.650749)
			(xy 58.697795 -393.666104) (xy 58.643847 -393.67386) (xy 58.589345 -393.67386) (xy 58.535397 -393.666104)
			(xy 58.483102 -393.650749) (xy 58.433525 -393.628107) (xy 58.387675 -393.598641) (xy 58.346484 -393.56295)
			(xy 58.310793 -393.521759) (xy 58.281327 -393.475909) (xy 58.258685 -393.426332) (xy 58.24333 -393.374037)
			(xy 58.235574 -393.320089) (xy 58.235088 -393.292838) (xy 57.798208 -393.292838) (xy 57.797722 -393.320089)
			(xy 57.789966 -393.374037) (xy 57.774611 -393.426332) (xy 57.751969 -393.475909) (xy 57.722503 -393.521759)
			(xy 57.686812 -393.56295) (xy 57.645621 -393.598641) (xy 57.599771 -393.628107) (xy 57.550194 -393.650749)
			(xy 57.497899 -393.666104) (xy 57.443951 -393.67386) (xy 57.389449 -393.67386) (xy 57.335501 -393.666104)
			(xy 57.283206 -393.650749) (xy 57.233629 -393.628107) (xy 57.187779 -393.598641) (xy 57.146588 -393.56295)
			(xy 57.110897 -393.521759) (xy 57.081431 -393.475909) (xy 57.058789 -393.426332) (xy 57.043434 -393.374037)
			(xy 57.035678 -393.320089) (xy 57.035192 -393.292838) (xy 56.598312 -393.292838) (xy 56.597826 -393.320107)
			(xy 56.590064 -393.374091) (xy 56.574699 -393.426421) (xy 56.552042 -393.476031) (xy 56.522556 -393.521912)
			(xy 56.486841 -393.563129) (xy 56.445624 -393.598844) (xy 56.399743 -393.62833) (xy 56.350133 -393.650987)
			(xy 56.297803 -393.666352) (xy 56.243819 -393.674114) (xy 56.189281 -393.674114) (xy 56.135297 -393.666352)
			(xy 56.082967 -393.650987) (xy 56.033357 -393.62833) (xy 55.987476 -393.598844) (xy 55.946259 -393.563129)
			(xy 55.910544 -393.521912) (xy 55.881058 -393.476031) (xy 55.858401 -393.426421) (xy 55.843036 -393.374091)
			(xy 55.835274 -393.320107) (xy 55.834788 -393.292838) (xy 55.398416 -393.292838) (xy 55.39793 -393.320107)
			(xy 55.390168 -393.374091) (xy 55.374803 -393.426421) (xy 55.352146 -393.476031) (xy 55.32266 -393.521912)
			(xy 55.286945 -393.563129) (xy 55.245728 -393.598844) (xy 55.199847 -393.62833) (xy 55.150237 -393.650987)
			(xy 55.097907 -393.666352) (xy 55.043923 -393.674114) (xy 54.989385 -393.674114) (xy 54.935401 -393.666352)
			(xy 54.883071 -393.650987) (xy 54.833461 -393.62833) (xy 54.78758 -393.598844) (xy 54.746363 -393.563129)
			(xy 54.710648 -393.521912) (xy 54.681162 -393.476031) (xy 54.658505 -393.426421) (xy 54.64314 -393.374091)
			(xy 54.635378 -393.320107) (xy 54.634892 -393.292838) (xy 54.198012 -393.292838) (xy 54.197526 -393.320089)
			(xy 54.18977 -393.374037) (xy 54.174415 -393.426332) (xy 54.151773 -393.475909) (xy 54.122307 -393.521759)
			(xy 54.086616 -393.56295) (xy 54.045425 -393.598641) (xy 53.999575 -393.628107) (xy 53.949998 -393.650749)
			(xy 53.897703 -393.666104) (xy 53.843755 -393.67386) (xy 53.789253 -393.67386) (xy 53.735305 -393.666104)
			(xy 53.68301 -393.650749) (xy 53.633433 -393.628107) (xy 53.587583 -393.598641) (xy 53.546392 -393.56295)
			(xy 53.510701 -393.521759) (xy 53.481235 -393.475909) (xy 53.458593 -393.426332) (xy 53.443238 -393.374037)
			(xy 53.435482 -393.320089) (xy 53.434996 -393.292838) (xy 52.998116 -393.292838) (xy 52.99763 -393.320089)
			(xy 52.989874 -393.374037) (xy 52.974519 -393.426332) (xy 52.951877 -393.475909) (xy 52.922411 -393.521759)
			(xy 52.88672 -393.56295) (xy 52.845529 -393.598641) (xy 52.799679 -393.628107) (xy 52.750102 -393.650749)
			(xy 52.697807 -393.666104) (xy 52.643859 -393.67386) (xy 52.589357 -393.67386) (xy 52.535409 -393.666104)
			(xy 52.483114 -393.650749) (xy 52.433537 -393.628107) (xy 52.387687 -393.598641) (xy 52.346496 -393.56295)
			(xy 52.310805 -393.521759) (xy 52.281339 -393.475909) (xy 52.258697 -393.426332) (xy 52.243342 -393.374037)
			(xy 52.235586 -393.320089) (xy 52.2351 -393.292838) (xy 51.79822 -393.292838) (xy 51.797734 -393.320107)
			(xy 51.789972 -393.374091) (xy 51.774607 -393.426421) (xy 51.75195 -393.476031) (xy 51.722464 -393.521912)
			(xy 51.686749 -393.563129) (xy 51.645532 -393.598844) (xy 51.599651 -393.62833) (xy 51.550041 -393.650987)
			(xy 51.497711 -393.666352) (xy 51.443727 -393.674114) (xy 51.389189 -393.674114) (xy 51.335205 -393.666352)
			(xy 51.282875 -393.650987) (xy 51.233265 -393.62833) (xy 51.187384 -393.598844) (xy 51.146167 -393.563129)
			(xy 51.110452 -393.521912) (xy 51.080966 -393.476031) (xy 51.058309 -393.426421) (xy 51.042944 -393.374091)
			(xy 51.035182 -393.320107) (xy 51.034696 -393.292838) (xy 50.598324 -393.292838) (xy 50.597838 -393.320107)
			(xy 50.590076 -393.374091) (xy 50.574711 -393.426421) (xy 50.552054 -393.476031) (xy 50.522568 -393.521912)
			(xy 50.486853 -393.563129) (xy 50.445636 -393.598844) (xy 50.399755 -393.62833) (xy 50.350145 -393.650987)
			(xy 50.297815 -393.666352) (xy 50.243831 -393.674114) (xy 50.189293 -393.674114) (xy 50.135309 -393.666352)
			(xy 50.082979 -393.650987) (xy 50.033369 -393.62833) (xy 49.987488 -393.598844) (xy 49.946271 -393.563129)
			(xy 49.910556 -393.521912) (xy 49.88107 -393.476031) (xy 49.858413 -393.426421) (xy 49.843048 -393.374091)
			(xy 49.835286 -393.320107) (xy 49.8348 -393.292838) (xy 49.39792 -393.292838) (xy 49.397434 -393.320089)
			(xy 49.389678 -393.374037) (xy 49.374323 -393.426332) (xy 49.351681 -393.475909) (xy 49.322215 -393.521759)
			(xy 49.286524 -393.56295) (xy 49.245333 -393.598641) (xy 49.199483 -393.628107) (xy 49.149906 -393.650749)
			(xy 49.097611 -393.666104) (xy 49.043663 -393.67386) (xy 48.989161 -393.67386) (xy 48.935213 -393.666104)
			(xy 48.882918 -393.650749) (xy 48.833341 -393.628107) (xy 48.787491 -393.598641) (xy 48.7463 -393.56295)
			(xy 48.710609 -393.521759) (xy 48.681143 -393.475909) (xy 48.658501 -393.426332) (xy 48.643146 -393.374037)
			(xy 48.63539 -393.320089) (xy 48.634904 -393.292838) (xy 48.198024 -393.292838) (xy 48.197538 -393.320089)
			(xy 48.189782 -393.374037) (xy 48.174427 -393.426332) (xy 48.151785 -393.475909) (xy 48.122319 -393.521759)
			(xy 48.086628 -393.56295) (xy 48.045437 -393.598641) (xy 47.999587 -393.628107) (xy 47.95001 -393.650749)
			(xy 47.897715 -393.666104) (xy 47.843767 -393.67386) (xy 47.789265 -393.67386) (xy 47.735317 -393.666104)
			(xy 47.683022 -393.650749) (xy 47.633445 -393.628107) (xy 47.587595 -393.598641) (xy 47.546404 -393.56295)
			(xy 47.510713 -393.521759) (xy 47.481247 -393.475909) (xy 47.458605 -393.426332) (xy 47.44325 -393.374037)
			(xy 47.435494 -393.320089) (xy 47.435008 -393.292838) (xy 2.509012 -393.292838) (xy 2.509012 -400.50847)
			(xy 103.485188 -400.50847) (xy 103.485723 -400.479553) (xy 103.494444 -400.422381) (xy 103.511697 -400.367182)
			(xy 103.537085 -400.315219) (xy 103.570027 -400.267685) (xy 103.609768 -400.225669) (xy 103.632254 -400.20748)
			(xy 103.641069 -400.199881) (xy 103.651246 -400.178974) (xy 103.651812 -400.167348) (xy 103.651812 -400.087592)
			(xy 103.651259 -400.075962) (xy 103.64108 -400.055053) (xy 103.632254 -400.04746) (xy 103.609742 -400.029303)
			(xy 103.57001 -399.987275) (xy 103.537076 -399.939733) (xy 103.511693 -399.887765) (xy 103.494443 -399.832562)
			(xy 103.48572 -399.775388) (xy 103.485188 -399.74647) (xy 103.485674 -399.719201) (xy 103.493436 -399.665217)
			(xy 103.508801 -399.612887) (xy 103.531458 -399.563277) (xy 103.560944 -399.517396) (xy 103.596659 -399.476179)
			(xy 103.637876 -399.440464) (xy 103.683757 -399.410978) (xy 103.733367 -399.388321) (xy 103.785697 -399.372956)
			(xy 103.839681 -399.365194) (xy 103.894219 -399.365194) (xy 103.948203 -399.372956) (xy 104.000533 -399.388321)
			(xy 104.050143 -399.410978) (xy 104.096024 -399.440464) (xy 104.137241 -399.476179) (xy 104.172956 -399.517396)
			(xy 104.202442 -399.563277) (xy 104.225099 -399.612887) (xy 104.240464 -399.665217) (xy 104.248226 -399.719201)
			(xy 104.248712 -399.74647) (xy 104.248206 -399.775388) (xy 104.239479 -399.832561) (xy 104.222221 -399.887762)
			(xy 104.196827 -399.939724) (xy 104.16388 -399.987257) (xy 104.124134 -400.029272) (xy 104.101646 -400.04746)
			(xy 104.092858 -400.055085) (xy 104.082666 -400.075972) (xy 104.082088 -400.087592) (xy 104.082088 -400.167348)
			(xy 104.082618 -400.178981) (xy 104.092814 -400.19989) (xy 104.101646 -400.20748) (xy 104.124129 -400.225671)
			(xy 104.163863 -400.267692) (xy 104.1968 -400.315227) (xy 104.222188 -400.367188) (xy 104.239445 -400.422385)
			(xy 104.248176 -400.479554) (xy 104.248712 -400.50847) (xy 104.248226 -400.535739) (xy 104.240464 -400.589723)
			(xy 104.225099 -400.642053) (xy 104.202442 -400.691663) (xy 104.172956 -400.737544) (xy 104.137241 -400.778761)
			(xy 104.096024 -400.814476) (xy 104.050143 -400.843962) (xy 104.000533 -400.866619) (xy 103.948203 -400.881984)
			(xy 103.894219 -400.889746) (xy 103.839681 -400.889746) (xy 103.785697 -400.881984) (xy 103.733367 -400.866619)
			(xy 103.683757 -400.843962) (xy 103.637876 -400.814476) (xy 103.596659 -400.778761) (xy 103.560944 -400.737544)
			(xy 103.531458 -400.691663) (xy 103.508801 -400.642053) (xy 103.493436 -400.589723) (xy 103.485674 -400.535739)
			(xy 103.485188 -400.50847) (xy 2.509012 -400.50847) (xy 2.509012 -403.371812) (xy 2.5095 -403.425034)
			(xy 2.517117 -403.531207) (xy 2.532283 -403.636566) (xy 2.554922 -403.740575) (xy 2.584919 -403.842706)
			(xy 2.622121 -403.942439) (xy 2.666338 -404.039266) (xy 2.717346 -404.132693) (xy 2.774884 -404.222247)
			(xy 2.838661 -404.307471) (xy 2.908351 -404.387931) (xy 2.945638 -404.425912) (xy 3.30962 -404.789894)
			(xy 37.568898 -404.789894) (xy 37.57287 -404.611651) (xy 37.584778 -404.433762) (xy 37.604599 -404.25658)
			(xy 37.632293 -404.080456) (xy 37.667805 -403.905741) (xy 37.711065 -403.732782) (xy 37.761987 -403.561921)
			(xy 37.82047 -403.393499) (xy 37.886397 -403.227849) (xy 37.959638 -403.0653) (xy 38.040048 -402.906175)
			(xy 38.127466 -402.75079) (xy 38.221719 -402.599454) (xy 38.32262 -402.452466) (xy 38.429969 -402.310119)
			(xy 38.543552 -402.172696) (xy 38.663145 -402.040469) (xy 38.788509 -401.9137) (xy 38.919396 -401.792642)
			(xy 39.055545 -401.677535) (xy 39.196687 -401.568607) (xy 39.342542 -401.466075) (xy 39.492819 -401.370141)
			(xy 39.64722 -401.280998) (xy 39.805439 -401.198821) (xy 39.967162 -401.123773) (xy 40.132067 -401.056005)
			(xy 40.299828 -400.995649) (xy 40.470111 -400.942827) (xy 40.642578 -400.897643) (xy 40.816886 -400.860186)
			(xy 40.99269 -400.830532) (xy 41.16964 -400.808739) (xy 41.347386 -400.794849) (xy 41.525573 -400.788892)
			(xy 41.70385 -400.790878) (xy 41.881861 -400.800804) (xy 42.059253 -400.81865) (xy 42.235673 -400.84438)
			(xy 42.410773 -400.877944) (xy 42.584204 -400.919274) (xy 42.755621 -400.96829) (xy 42.924684 -401.024892)
			(xy 43.091059 -401.08897) (xy 43.254413 -401.160396) (xy 43.414424 -401.239028) (xy 43.570773 -401.324709)
			(xy 43.72315 -401.417271) (xy 43.871253 -401.516528) (xy 44.014787 -401.622285) (xy 44.153467 -401.73433)
			(xy 44.287018 -401.852442) (xy 44.415175 -401.976386) (xy 44.537684 -402.105916) (xy 44.654301 -402.240775)
			(xy 44.764794 -402.380695) (xy 44.868945 -402.525398) (xy 44.966547 -402.674597) (xy 45.057405 -402.827996)
			(xy 45.141339 -402.98529) (xy 45.218184 -403.146166) (xy 45.287785 -403.310307) (xy 45.350006 -403.477384)
			(xy 45.404722 -403.647068) (xy 45.451824 -403.819021) (xy 45.49122 -403.992901) (xy 45.522831 -404.168364)
			(xy 45.546595 -404.34506) (xy 45.559703 -404.491748) (xy 47.413198 -404.491748) (xy 47.413198 -404.437252)
			(xy 47.420953 -404.38331) (xy 47.436306 -404.331021) (xy 47.458943 -404.281449) (xy 47.488404 -404.235603)
			(xy 47.52409 -404.194416) (xy 47.565274 -404.158726) (xy 47.611117 -404.12926) (xy 47.660687 -404.106618)
			(xy 47.712975 -404.091261) (xy 47.766916 -404.083501) (xy 47.794164 -404.083012) (xy 48.657764 -404.083012)
			(xy 48.68502 -404.083432) (xy 48.738978 -404.091186) (xy 48.791283 -404.106539) (xy 48.84087 -404.129181)
			(xy 48.88673 -404.15865) (xy 48.927929 -404.194345) (xy 48.963629 -404.235541) (xy 48.993102 -404.281398)
			(xy 49.015748 -404.330984) (xy 49.031107 -404.383287) (xy 49.038865 -404.437244) (xy 49.038865 -404.491752)
			(xy 50.476375 -404.491752) (xy 50.476375 -404.437248) (xy 50.484132 -404.3833) (xy 50.499487 -404.331005)
			(xy 50.522129 -404.281427) (xy 50.551596 -404.235576) (xy 50.587288 -404.194385) (xy 50.628479 -404.158693)
			(xy 50.67433 -404.129227) (xy 50.723908 -404.106586) (xy 50.776204 -404.091231) (xy 50.830152 -404.083475)
			(xy 50.857404 -404.083012) (xy 51.721004 -404.083012) (xy 51.748256 -404.083458) (xy 51.802207 -404.091215)
			(xy 51.854504 -404.106572) (xy 51.904083 -404.129214) (xy 51.949935 -404.158682) (xy 51.991127 -404.194376)
			(xy 52.02682 -404.235568) (xy 52.056288 -404.281421) (xy 52.07893 -404.331) (xy 52.094285 -404.383297)
			(xy 52.102042 -404.437248) (xy 52.102042 -404.491752) (xy 52.102042 -404.491753) (xy 53.539575 -404.491753)
			(xy 53.539575 -404.437247) (xy 53.547333 -404.383295) (xy 53.562691 -404.330996) (xy 53.585335 -404.281416)
			(xy 53.614806 -404.235563) (xy 53.650502 -404.194371) (xy 53.691698 -404.158679) (xy 53.737554 -404.129214)
			(xy 53.787137 -404.106575) (xy 53.839438 -404.091224) (xy 53.893391 -404.083472) (xy 53.920644 -404.083012)
			(xy 54.784244 -404.083012) (xy 54.811495 -404.083461) (xy 54.86544 -404.091223) (xy 54.917733 -404.106583)
			(xy 54.967307 -404.129227) (xy 55.013154 -404.158696) (xy 55.054341 -404.19439) (xy 55.09003 -404.235581)
			(xy 55.119494 -404.281432) (xy 55.142133 -404.331009) (xy 55.157487 -404.383303) (xy 55.165242 -404.437249)
			(xy 55.165242 -404.491749) (xy 56.602898 -404.491749) (xy 56.602898 -404.437251) (xy 56.610654 -404.383308)
			(xy 56.626007 -404.331017) (xy 56.648646 -404.281443) (xy 56.678109 -404.235596) (xy 56.713797 -404.194409)
			(xy 56.754983 -404.158719) (xy 56.800829 -404.129254) (xy 56.850402 -404.106613) (xy 56.902692 -404.091257)
			(xy 56.956635 -404.083499) (xy 56.983884 -404.083012) (xy 57.847484 -404.083012) (xy 57.874739 -404.083434)
			(xy 57.928695 -404.091189) (xy 57.980997 -404.106545) (xy 58.030582 -404.129188) (xy 58.07644 -404.158657)
			(xy 58.117636 -404.194352) (xy 58.153334 -404.235548) (xy 58.182805 -404.281404) (xy 58.20545 -404.330988)
			(xy 58.220807 -404.38329) (xy 58.228565 -404.437245) (xy 58.228565 -404.491753) (xy 59.666075 -404.491753)
			(xy 59.666075 -404.437247) (xy 59.673833 -404.383297) (xy 59.689189 -404.331) (xy 59.711832 -404.281421)
			(xy 59.741301 -404.235569) (xy 59.776995 -404.194378) (xy 59.818188 -404.158686) (xy 59.864042 -404.129221)
			(xy 59.913623 -404.106581) (xy 59.965921 -404.091227) (xy 60.019871 -404.083474) (xy 60.047124 -404.083012)
			(xy 60.910724 -404.083012) (xy 60.937976 -404.083459) (xy 60.991924 -404.091219) (xy 61.044218 -404.106577)
			(xy 61.093795 -404.129221) (xy 61.139645 -404.158689) (xy 61.180834 -404.194383) (xy 61.216525 -404.235575)
			(xy 61.245991 -404.281426) (xy 61.268631 -404.331004) (xy 61.283986 -404.3833) (xy 61.291742 -404.437248)
			(xy 61.291742 -404.491748) (xy 62.729398 -404.491748) (xy 62.729398 -404.437252) (xy 62.737153 -404.38331)
			(xy 62.752506 -404.331021) (xy 62.775143 -404.281449) (xy 62.804604 -404.235603) (xy 62.84029 -404.194416)
			(xy 62.881474 -404.158726) (xy 62.927317 -404.12926) (xy 62.976887 -404.106618) (xy 63.029175 -404.091261)
			(xy 63.083116 -404.083501) (xy 63.110364 -404.083012) (xy 63.973964 -404.083012) (xy 64.00122 -404.083432)
			(xy 64.055178 -404.091186) (xy 64.107483 -404.106539) (xy 64.15707 -404.129181) (xy 64.20293 -404.15865)
			(xy 64.244129 -404.194345) (xy 64.279829 -404.235541) (xy 64.309302 -404.281398) (xy 64.331948 -404.330984)
			(xy 64.347307 -404.383287) (xy 64.355065 -404.437244) (xy 64.355065 -404.491752) (xy 65.792575 -404.491752)
			(xy 65.792575 -404.437248) (xy 65.800332 -404.3833) (xy 65.815687 -404.331005) (xy 65.838329 -404.281427)
			(xy 65.867796 -404.235576) (xy 65.903488 -404.194385) (xy 65.944679 -404.158693) (xy 65.99053 -404.129227)
			(xy 66.040108 -404.106586) (xy 66.092404 -404.091231) (xy 66.146352 -404.083475) (xy 66.173604 -404.083012)
			(xy 67.037204 -404.083012) (xy 67.064456 -404.083458) (xy 67.118407 -404.091215) (xy 67.170704 -404.106572)
			(xy 67.220283 -404.129214) (xy 67.266135 -404.158682) (xy 67.307327 -404.194376) (xy 67.34302 -404.235568)
			(xy 67.372488 -404.281421) (xy 67.39513 -404.331) (xy 67.410485 -404.383297) (xy 67.418242 -404.437248)
			(xy 67.418242 -404.491752) (xy 67.418242 -404.491753) (xy 68.855775 -404.491753) (xy 68.855775 -404.437247)
			(xy 68.863533 -404.383295) (xy 68.878891 -404.330996) (xy 68.901535 -404.281416) (xy 68.931006 -404.235563)
			(xy 68.966702 -404.194371) (xy 69.007898 -404.158679) (xy 69.053754 -404.129214) (xy 69.103337 -404.106575)
			(xy 69.155638 -404.091224) (xy 69.209591 -404.083472) (xy 69.236844 -404.083012) (xy 70.100444 -404.083012)
			(xy 70.127695 -404.083461) (xy 70.18164 -404.091223) (xy 70.233933 -404.106583) (xy 70.283507 -404.129227)
			(xy 70.329354 -404.158696) (xy 70.370541 -404.19439) (xy 70.40623 -404.235581) (xy 70.435694 -404.281432)
			(xy 70.458333 -404.331009) (xy 70.473687 -404.383303) (xy 70.481442 -404.437249) (xy 70.481442 -404.491749)
			(xy 71.919098 -404.491749) (xy 71.919098 -404.437251) (xy 71.926854 -404.383308) (xy 71.942207 -404.331017)
			(xy 71.964846 -404.281443) (xy 71.994309 -404.235596) (xy 72.029997 -404.194409) (xy 72.071183 -404.158719)
			(xy 72.117029 -404.129254) (xy 72.166602 -404.106613) (xy 72.218892 -404.091257) (xy 72.272835 -404.083499)
			(xy 72.300084 -404.083012) (xy 73.163684 -404.083012) (xy 73.190939 -404.083434) (xy 73.244895 -404.091189)
			(xy 73.297197 -404.106545) (xy 73.346782 -404.129188) (xy 73.39264 -404.158657) (xy 73.433836 -404.194352)
			(xy 73.469534 -404.235548) (xy 73.499005 -404.281404) (xy 73.52165 -404.330988) (xy 73.537007 -404.38329)
			(xy 73.544765 -404.437245) (xy 73.544765 -404.491753) (xy 74.982275 -404.491753) (xy 74.982275 -404.437247)
			(xy 74.990033 -404.383297) (xy 75.005389 -404.331) (xy 75.028032 -404.281421) (xy 75.057501 -404.235569)
			(xy 75.093195 -404.194378) (xy 75.134388 -404.158686) (xy 75.180242 -404.129221) (xy 75.229823 -404.106581)
			(xy 75.282121 -404.091227) (xy 75.336071 -404.083474) (xy 75.363324 -404.083012) (xy 76.226924 -404.083012)
			(xy 76.254176 -404.083459) (xy 76.308124 -404.091219) (xy 76.360418 -404.106577) (xy 76.409995 -404.129221)
			(xy 76.455845 -404.158689) (xy 76.497034 -404.194383) (xy 76.532725 -404.235575) (xy 76.562191 -404.281426)
			(xy 76.584831 -404.331004) (xy 76.600186 -404.3833) (xy 76.607942 -404.437248) (xy 76.607942 -404.491748)
			(xy 78.045598 -404.491748) (xy 78.045598 -404.437252) (xy 78.053353 -404.38331) (xy 78.068706 -404.331021)
			(xy 78.091343 -404.281449) (xy 78.120804 -404.235603) (xy 78.15649 -404.194416) (xy 78.197674 -404.158726)
			(xy 78.243517 -404.12926) (xy 78.293087 -404.106618) (xy 78.345375 -404.091261) (xy 78.399316 -404.083501)
			(xy 78.426564 -404.083012) (xy 79.290164 -404.083012) (xy 79.31742 -404.083432) (xy 79.371378 -404.091186)
			(xy 79.423683 -404.106539) (xy 79.47327 -404.129181) (xy 79.51913 -404.15865) (xy 79.560329 -404.194345)
			(xy 79.596029 -404.235541) (xy 79.625502 -404.281398) (xy 79.648148 -404.330984) (xy 79.663507 -404.383287)
			(xy 79.671265 -404.437244) (xy 79.671265 -404.491752) (xy 81.108775 -404.491752) (xy 81.108775 -404.437248)
			(xy 81.116532 -404.3833) (xy 81.131887 -404.331005) (xy 81.154529 -404.281427) (xy 81.183996 -404.235576)
			(xy 81.219688 -404.194385) (xy 81.260879 -404.158693) (xy 81.30673 -404.129227) (xy 81.356308 -404.106586)
			(xy 81.408604 -404.091231) (xy 81.462552 -404.083475) (xy 81.489804 -404.083012) (xy 82.353404 -404.083012)
			(xy 82.380656 -404.083458) (xy 82.434607 -404.091215) (xy 82.486904 -404.106572) (xy 82.536483 -404.129214)
			(xy 82.582335 -404.158682) (xy 82.623527 -404.194376) (xy 82.65922 -404.235568) (xy 82.688688 -404.281421)
			(xy 82.71133 -404.331) (xy 82.726685 -404.383297) (xy 82.734442 -404.437248) (xy 82.734442 -404.491752)
			(xy 82.734442 -404.491753) (xy 84.171975 -404.491753) (xy 84.171975 -404.437247) (xy 84.179733 -404.383295)
			(xy 84.195091 -404.330996) (xy 84.217735 -404.281416) (xy 84.247206 -404.235563) (xy 84.282902 -404.194371)
			(xy 84.324098 -404.158679) (xy 84.369954 -404.129214) (xy 84.419537 -404.106575) (xy 84.471838 -404.091224)
			(xy 84.525791 -404.083472) (xy 84.553044 -404.083012) (xy 85.416644 -404.083012) (xy 85.443895 -404.083461)
			(xy 85.49784 -404.091223) (xy 85.550133 -404.106583) (xy 85.599707 -404.129227) (xy 85.645554 -404.158696)
			(xy 85.686741 -404.19439) (xy 85.72243 -404.235581) (xy 85.751894 -404.281432) (xy 85.774533 -404.331009)
			(xy 85.789887 -404.383303) (xy 85.797642 -404.437249) (xy 85.797642 -404.491749) (xy 87.235298 -404.491749)
			(xy 87.235298 -404.437251) (xy 87.243054 -404.383308) (xy 87.258407 -404.331017) (xy 87.281046 -404.281443)
			(xy 87.310509 -404.235596) (xy 87.346197 -404.194409) (xy 87.387383 -404.158719) (xy 87.433229 -404.129254)
			(xy 87.482802 -404.106613) (xy 87.535092 -404.091257) (xy 87.589035 -404.083499) (xy 87.616284 -404.083012)
			(xy 88.479884 -404.083012) (xy 88.507139 -404.083434) (xy 88.561095 -404.091189) (xy 88.613397 -404.106545)
			(xy 88.662982 -404.129188) (xy 88.70884 -404.158657) (xy 88.750036 -404.194352) (xy 88.785734 -404.235548)
			(xy 88.815205 -404.281404) (xy 88.83785 -404.330988) (xy 88.853207 -404.38329) (xy 88.860965 -404.437245)
			(xy 88.860965 -404.491753) (xy 90.298475 -404.491753) (xy 90.298475 -404.437247) (xy 90.306233 -404.383297)
			(xy 90.321589 -404.331) (xy 90.344232 -404.281421) (xy 90.373701 -404.235569) (xy 90.409395 -404.194378)
			(xy 90.450588 -404.158686) (xy 90.496442 -404.129221) (xy 90.546023 -404.106581) (xy 90.598321 -404.091227)
			(xy 90.652271 -404.083474) (xy 90.679524 -404.083012) (xy 91.543124 -404.083012) (xy 91.570376 -404.083459)
			(xy 91.624324 -404.091219) (xy 91.676618 -404.106577) (xy 91.726195 -404.129221) (xy 91.772045 -404.158689)
			(xy 91.813234 -404.194383) (xy 91.848925 -404.235575) (xy 91.878391 -404.281426) (xy 91.901031 -404.331004)
			(xy 91.916386 -404.3833) (xy 91.924142 -404.437248) (xy 91.924142 -404.491748) (xy 93.361798 -404.491748)
			(xy 93.361798 -404.437252) (xy 93.369553 -404.38331) (xy 93.384906 -404.331021) (xy 93.407543 -404.281449)
			(xy 93.437004 -404.235603) (xy 93.47269 -404.194416) (xy 93.513874 -404.158726) (xy 93.559717 -404.12926)
			(xy 93.609287 -404.106618) (xy 93.661575 -404.091261) (xy 93.715516 -404.083501) (xy 93.742764 -404.083012)
			(xy 94.606364 -404.083012) (xy 94.63362 -404.083432) (xy 94.687578 -404.091186) (xy 94.739883 -404.106539)
			(xy 94.78947 -404.129181) (xy 94.83533 -404.15865) (xy 94.876529 -404.194345) (xy 94.912229 -404.235541)
			(xy 94.941702 -404.281398) (xy 94.964348 -404.330984) (xy 94.979707 -404.383287) (xy 94.987465 -404.437244)
			(xy 94.987465 -404.491752) (xy 114.513075 -404.491752) (xy 114.513075 -404.437248) (xy 114.520832 -404.3833)
			(xy 114.536188 -404.331004) (xy 114.558829 -404.281426) (xy 114.588296 -404.235575) (xy 114.623989 -404.194384)
			(xy 114.66518 -404.158693) (xy 114.711031 -404.129226) (xy 114.76061 -404.106585) (xy 114.812906 -404.091231)
			(xy 114.866854 -404.083475) (xy 114.894106 -404.083012) (xy 115.757706 -404.083012) (xy 115.784958 -404.083458)
			(xy 115.838908 -404.091216) (xy 115.891205 -404.106572) (xy 115.940784 -404.129215) (xy 115.986636 -404.158683)
			(xy 116.027828 -404.194376) (xy 116.063521 -404.235569) (xy 116.092988 -404.281421) (xy 116.11563 -404.331001)
			(xy 116.130985 -404.383298) (xy 116.138742 -404.437248) (xy 116.138742 -404.491752) (xy 116.138742 -404.491754)
			(xy 117.576275 -404.491754) (xy 117.576275 -404.437246) (xy 117.584033 -404.383294) (xy 117.599391 -404.330996)
			(xy 117.622035 -404.281415) (xy 117.651506 -404.235562) (xy 117.687203 -404.19437) (xy 117.728399 -404.158679)
			(xy 117.774255 -404.129213) (xy 117.823839 -404.106575) (xy 117.876139 -404.091223) (xy 117.930092 -404.083472)
			(xy 117.957346 -404.083012) (xy 118.820946 -404.083012) (xy 118.848197 -404.083461) (xy 118.902142 -404.091223)
			(xy 118.954434 -404.106583) (xy 119.004008 -404.129228) (xy 119.049855 -404.158697) (xy 119.091042 -404.194391)
			(xy 119.12673 -404.235582) (xy 119.156194 -404.281432) (xy 119.178833 -404.331009) (xy 119.194187 -404.383303)
			(xy 119.201942 -404.437249) (xy 119.201942 -404.491749) (xy 120.639598 -404.491749) (xy 120.639598 -404.437251)
			(xy 120.647354 -404.383307) (xy 120.662708 -404.331016) (xy 120.685346 -404.281443) (xy 120.71481 -404.235596)
			(xy 120.750498 -404.194408) (xy 120.791684 -404.158718) (xy 120.83753 -404.129253) (xy 120.887103 -404.106612)
			(xy 120.939394 -404.091257) (xy 120.993337 -404.083499) (xy 121.020586 -404.083012) (xy 121.884186 -404.083012)
			(xy 121.911441 -404.083434) (xy 121.965396 -404.09119) (xy 122.017699 -404.106545) (xy 122.067283 -404.129188)
			(xy 122.113141 -404.158657) (xy 122.154337 -404.194353) (xy 122.190034 -404.235548) (xy 122.219505 -404.281405)
			(xy 122.24215 -404.330988) (xy 122.257507 -404.38329) (xy 122.265265 -404.437245) (xy 122.265265 -404.491753)
			(xy 123.702775 -404.491753) (xy 123.702775 -404.437247) (xy 123.710533 -404.383297) (xy 123.725889 -404.331)
			(xy 123.748532 -404.281421) (xy 123.778001 -404.235569) (xy 123.813696 -404.194377) (xy 123.854889 -404.158686)
			(xy 123.900743 -404.12922) (xy 123.950324 -404.10658) (xy 124.002622 -404.091227) (xy 124.056573 -404.083474)
			(xy 124.083826 -404.083012) (xy 124.947426 -404.083012) (xy 124.974677 -404.08346) (xy 125.028625 -404.09122)
			(xy 125.08092 -404.106578) (xy 125.130496 -404.129222) (xy 125.176346 -404.15869) (xy 125.217535 -404.194383)
			(xy 125.253226 -404.235575) (xy 125.282691 -404.281427) (xy 125.305331 -404.331005) (xy 125.320686 -404.3833)
			(xy 125.328442 -404.437249) (xy 125.328442 -404.491748) (xy 126.766098 -404.491748) (xy 126.766098 -404.437252)
			(xy 126.773853 -404.38331) (xy 126.789206 -404.331021) (xy 126.811843 -404.281448) (xy 126.841305 -404.235602)
			(xy 126.876991 -404.194415) (xy 126.918175 -404.158725) (xy 126.964018 -404.12926) (xy 127.013589 -404.106618)
			(xy 127.065877 -404.091261) (xy 127.119818 -404.083501) (xy 127.147066 -404.083012) (xy 128.010666 -404.083012)
			(xy 128.037922 -404.083433) (xy 128.091879 -404.091186) (xy 128.144184 -404.10654) (xy 128.193771 -404.129182)
			(xy 128.239631 -404.15865) (xy 128.28083 -404.194346) (xy 128.316529 -404.235542) (xy 128.346002 -404.281399)
			(xy 128.368648 -404.330984) (xy 128.384007 -404.383287) (xy 128.391765 -404.437244) (xy 128.391765 -404.491752)
			(xy 129.829275 -404.491752) (xy 129.829275 -404.437248) (xy 129.837032 -404.3833) (xy 129.852388 -404.331004)
			(xy 129.875029 -404.281426) (xy 129.904496 -404.235575) (xy 129.940189 -404.194384) (xy 129.98138 -404.158693)
			(xy 130.027231 -404.129226) (xy 130.07681 -404.106585) (xy 130.129106 -404.091231) (xy 130.183054 -404.083475)
			(xy 130.210306 -404.083012) (xy 131.073906 -404.083012) (xy 131.101158 -404.083458) (xy 131.155108 -404.091216)
			(xy 131.207405 -404.106572) (xy 131.256984 -404.129215) (xy 131.302836 -404.158683) (xy 131.344028 -404.194376)
			(xy 131.379721 -404.235569) (xy 131.409188 -404.281421) (xy 131.43183 -404.331001) (xy 131.447185 -404.383298)
			(xy 131.454942 -404.437248) (xy 131.454942 -404.491752) (xy 131.454942 -404.491754) (xy 132.892475 -404.491754)
			(xy 132.892475 -404.437246) (xy 132.900233 -404.383294) (xy 132.915591 -404.330996) (xy 132.938235 -404.281415)
			(xy 132.967706 -404.235562) (xy 133.003403 -404.19437) (xy 133.044599 -404.158679) (xy 133.090455 -404.129213)
			(xy 133.140039 -404.106575) (xy 133.192339 -404.091223) (xy 133.246292 -404.083472) (xy 133.273546 -404.083012)
			(xy 134.137146 -404.083012) (xy 134.164397 -404.083461) (xy 134.218342 -404.091223) (xy 134.270634 -404.106583)
			(xy 134.320208 -404.129228) (xy 134.366055 -404.158697) (xy 134.407242 -404.194391) (xy 134.44293 -404.235582)
			(xy 134.472394 -404.281432) (xy 134.495033 -404.331009) (xy 134.510387 -404.383303) (xy 134.518142 -404.437249)
			(xy 134.518142 -404.491749) (xy 135.955798 -404.491749) (xy 135.955798 -404.437251) (xy 135.963554 -404.383307)
			(xy 135.978908 -404.331016) (xy 136.001546 -404.281443) (xy 136.03101 -404.235596) (xy 136.066698 -404.194408)
			(xy 136.107884 -404.158718) (xy 136.15373 -404.129253) (xy 136.203303 -404.106612) (xy 136.255594 -404.091257)
			(xy 136.309537 -404.083499) (xy 136.336786 -404.083012) (xy 137.200386 -404.083012) (xy 137.227641 -404.083434)
			(xy 137.281596 -404.09119) (xy 137.333899 -404.106545) (xy 137.383483 -404.129188) (xy 137.429341 -404.158657)
			(xy 137.470537 -404.194353) (xy 137.506234 -404.235548) (xy 137.535705 -404.281405) (xy 137.55835 -404.330988)
			(xy 137.573707 -404.38329) (xy 137.581465 -404.437245) (xy 137.581465 -404.491753) (xy 139.018975 -404.491753)
			(xy 139.018975 -404.437247) (xy 139.026733 -404.383297) (xy 139.042089 -404.331) (xy 139.064732 -404.281421)
			(xy 139.094201 -404.235569) (xy 139.129896 -404.194377) (xy 139.171089 -404.158686) (xy 139.216943 -404.12922)
			(xy 139.266524 -404.10658) (xy 139.318822 -404.091227) (xy 139.372773 -404.083474) (xy 139.400026 -404.083012)
			(xy 140.263626 -404.083012) (xy 140.290877 -404.08346) (xy 140.344825 -404.09122) (xy 140.39712 -404.106578)
			(xy 140.446696 -404.129222) (xy 140.492546 -404.15869) (xy 140.533735 -404.194383) (xy 140.569426 -404.235575)
			(xy 140.598891 -404.281427) (xy 140.621531 -404.331005) (xy 140.636886 -404.3833) (xy 140.644642 -404.437249)
			(xy 140.644642 -404.491748) (xy 142.082298 -404.491748) (xy 142.082298 -404.437252) (xy 142.090053 -404.38331)
			(xy 142.105406 -404.331021) (xy 142.128043 -404.281448) (xy 142.157505 -404.235602) (xy 142.193191 -404.194415)
			(xy 142.234375 -404.158725) (xy 142.280218 -404.12926) (xy 142.329789 -404.106618) (xy 142.382077 -404.091261)
			(xy 142.436018 -404.083501) (xy 142.463266 -404.083012) (xy 143.326866 -404.083012) (xy 143.354122 -404.083433)
			(xy 143.408079 -404.091186) (xy 143.460384 -404.10654) (xy 143.509971 -404.129182) (xy 143.555831 -404.15865)
			(xy 143.59703 -404.194346) (xy 143.632729 -404.235542) (xy 143.662202 -404.281399) (xy 143.684848 -404.330984)
			(xy 143.700207 -404.383287) (xy 143.707965 -404.437244) (xy 143.707965 -404.491752) (xy 145.145475 -404.491752)
			(xy 145.145475 -404.437248) (xy 145.153232 -404.3833) (xy 145.168588 -404.331004) (xy 145.191229 -404.281426)
			(xy 145.220696 -404.235575) (xy 145.256389 -404.194384) (xy 145.29758 -404.158693) (xy 145.343431 -404.129226)
			(xy 145.39301 -404.106585) (xy 145.445306 -404.091231) (xy 145.499254 -404.083475) (xy 145.526506 -404.083012)
			(xy 146.390106 -404.083012) (xy 146.417358 -404.083458) (xy 146.471308 -404.091216) (xy 146.523605 -404.106572)
			(xy 146.573184 -404.129215) (xy 146.619036 -404.158683) (xy 146.660228 -404.194376) (xy 146.695921 -404.235569)
			(xy 146.725388 -404.281421) (xy 146.74803 -404.331001) (xy 146.763385 -404.383298) (xy 146.771142 -404.437248)
			(xy 146.771142 -404.491752) (xy 146.771142 -404.491754) (xy 148.208675 -404.491754) (xy 148.208675 -404.437246)
			(xy 148.216433 -404.383294) (xy 148.231791 -404.330996) (xy 148.254435 -404.281415) (xy 148.283906 -404.235562)
			(xy 148.319603 -404.19437) (xy 148.360799 -404.158679) (xy 148.406655 -404.129213) (xy 148.456239 -404.106575)
			(xy 148.508539 -404.091223) (xy 148.562492 -404.083472) (xy 148.589746 -404.083012) (xy 149.453346 -404.083012)
			(xy 149.480597 -404.083461) (xy 149.534542 -404.091223) (xy 149.586834 -404.106583) (xy 149.636408 -404.129228)
			(xy 149.682255 -404.158697) (xy 149.723442 -404.194391) (xy 149.75913 -404.235582) (xy 149.788594 -404.281432)
			(xy 149.811233 -404.331009) (xy 149.826587 -404.383303) (xy 149.834342 -404.437249) (xy 149.834342 -404.491749)
			(xy 151.271998 -404.491749) (xy 151.271998 -404.437251) (xy 151.279754 -404.383307) (xy 151.295108 -404.331016)
			(xy 151.317746 -404.281443) (xy 151.34721 -404.235596) (xy 151.382898 -404.194408) (xy 151.424084 -404.158718)
			(xy 151.46993 -404.129253) (xy 151.519503 -404.106612) (xy 151.571794 -404.091257) (xy 151.625737 -404.083499)
			(xy 151.652986 -404.083012) (xy 152.516586 -404.083012) (xy 152.543841 -404.083434) (xy 152.597796 -404.09119)
			(xy 152.650099 -404.106545) (xy 152.699683 -404.129188) (xy 152.745541 -404.158657) (xy 152.786737 -404.194353)
			(xy 152.822434 -404.235548) (xy 152.851905 -404.281405) (xy 152.87455 -404.330988) (xy 152.889907 -404.38329)
			(xy 152.897665 -404.437245) (xy 152.897665 -404.491753) (xy 154.335175 -404.491753) (xy 154.335175 -404.437247)
			(xy 154.342933 -404.383297) (xy 154.358289 -404.331) (xy 154.380932 -404.281421) (xy 154.410401 -404.235569)
			(xy 154.446096 -404.194377) (xy 154.487289 -404.158686) (xy 154.533143 -404.12922) (xy 154.582724 -404.10658)
			(xy 154.635022 -404.091227) (xy 154.688973 -404.083474) (xy 154.716226 -404.083012) (xy 155.579826 -404.083012)
			(xy 155.607077 -404.08346) (xy 155.661025 -404.09122) (xy 155.71332 -404.106578) (xy 155.762896 -404.129222)
			(xy 155.808746 -404.15869) (xy 155.849935 -404.194383) (xy 155.885626 -404.235575) (xy 155.915091 -404.281427)
			(xy 155.937731 -404.331005) (xy 155.953086 -404.3833) (xy 155.960842 -404.437249) (xy 155.960842 -404.491748)
			(xy 157.398498 -404.491748) (xy 157.398498 -404.437252) (xy 157.406253 -404.38331) (xy 157.421606 -404.331021)
			(xy 157.444243 -404.281448) (xy 157.473705 -404.235602) (xy 157.509391 -404.194415) (xy 157.550575 -404.158725)
			(xy 157.596418 -404.12926) (xy 157.645989 -404.106618) (xy 157.698277 -404.091261) (xy 157.752218 -404.083501)
			(xy 157.779466 -404.083012) (xy 158.643066 -404.083012) (xy 158.670322 -404.083433) (xy 158.724279 -404.091186)
			(xy 158.776584 -404.10654) (xy 158.826171 -404.129182) (xy 158.872031 -404.15865) (xy 158.91323 -404.194346)
			(xy 158.948929 -404.235542) (xy 158.978402 -404.281399) (xy 159.001048 -404.330984) (xy 159.016407 -404.383287)
			(xy 159.024165 -404.437244) (xy 159.024165 -404.491752) (xy 160.461675 -404.491752) (xy 160.461675 -404.437248)
			(xy 160.469432 -404.3833) (xy 160.484788 -404.331004) (xy 160.507429 -404.281426) (xy 160.536896 -404.235575)
			(xy 160.572589 -404.194384) (xy 160.61378 -404.158693) (xy 160.659631 -404.129226) (xy 160.70921 -404.106585)
			(xy 160.761506 -404.091231) (xy 160.815454 -404.083475) (xy 160.842706 -404.083012) (xy 161.706306 -404.083012)
			(xy 161.733558 -404.083458) (xy 161.787508 -404.091216) (xy 161.839805 -404.106572) (xy 161.889384 -404.129215)
			(xy 161.935236 -404.158683) (xy 161.976428 -404.194376) (xy 162.012121 -404.235569) (xy 162.041588 -404.281421)
			(xy 162.06423 -404.331001) (xy 162.079585 -404.383298) (xy 162.087342 -404.437248) (xy 162.087342 -404.491752)
			(xy 162.079585 -404.545702) (xy 162.06423 -404.597999) (xy 162.041588 -404.647579) (xy 162.012121 -404.693431)
			(xy 161.976428 -404.734624) (xy 161.935236 -404.770317) (xy 161.904774 -404.789894) (xy 166.998662 -404.789894)
			(xy 167.002634 -404.611651) (xy 167.014542 -404.433762) (xy 167.034363 -404.25658) (xy 167.062057 -404.080456)
			(xy 167.097569 -403.905741) (xy 167.140829 -403.732782) (xy 167.191751 -403.561921) (xy 167.250234 -403.393499)
			(xy 167.316161 -403.227849) (xy 167.389402 -403.0653) (xy 167.469812 -402.906175) (xy 167.55723 -402.75079)
			(xy 167.651483 -402.599454) (xy 167.752384 -402.452466) (xy 167.859733 -402.310119) (xy 167.973316 -402.172696)
			(xy 168.092909 -402.040469) (xy 168.218273 -401.9137) (xy 168.34916 -401.792642) (xy 168.485309 -401.677535)
			(xy 168.626451 -401.568607) (xy 168.772306 -401.466075) (xy 168.922583 -401.370141) (xy 169.076984 -401.280998)
			(xy 169.235203 -401.198821) (xy 169.396926 -401.123773) (xy 169.561831 -401.056005) (xy 169.729592 -400.995649)
			(xy 169.899875 -400.942827) (xy 170.072342 -400.897643) (xy 170.24665 -400.860186) (xy 170.422454 -400.830532)
			(xy 170.599404 -400.808739) (xy 170.77715 -400.794849) (xy 170.955337 -400.788892) (xy 171.133614 -400.790878)
			(xy 171.311625 -400.800804) (xy 171.489017 -400.81865) (xy 171.665437 -400.84438) (xy 171.840537 -400.877944)
			(xy 172.013968 -400.919274) (xy 172.185385 -400.96829) (xy 172.354448 -401.024892) (xy 172.520823 -401.08897)
			(xy 172.684177 -401.160396) (xy 172.844188 -401.239028) (xy 173.000537 -401.324709) (xy 173.152914 -401.417271)
			(xy 173.301017 -401.516528) (xy 173.444551 -401.622285) (xy 173.583231 -401.73433) (xy 173.716782 -401.852442)
			(xy 173.844939 -401.976386) (xy 173.967448 -402.105916) (xy 174.084065 -402.240775) (xy 174.194558 -402.380695)
			(xy 174.298709 -402.525398) (xy 174.396311 -402.674597) (xy 174.487169 -402.827996) (xy 174.571103 -402.98529)
			(xy 174.647948 -403.146166) (xy 174.680622 -403.223222) (xy 183.966612 -403.223222) (xy 183.966612 -403.222714)
			(xy 183.967041 -403.181385) (xy 183.974705 -403.099084) (xy 183.989967 -403.017847) (xy 184.012697 -402.938376)
			(xy 184.042698 -402.861355) (xy 184.079712 -402.787448) (xy 184.12342 -402.717292) (xy 184.173445 -402.651491)
			(xy 184.201054 -402.620734) (xy 184.207126 -402.613482) (xy 184.214027 -402.59589) (xy 184.214516 -402.586444)
			(xy 184.214516 -402.555964) (xy 184.214137 -402.546498) (xy 184.207208 -402.528878) (xy 184.201054 -402.521674)
			(xy 184.173435 -402.490923) (xy 184.123404 -402.425124) (xy 184.07969 -402.354969) (xy 184.042671 -402.281062)
			(xy 184.012666 -402.20404) (xy 183.989932 -402.124568) (xy 183.974667 -402.043329) (xy 183.967002 -401.961026)
			(xy 183.967002 -401.878366) (xy 183.974668 -401.796062) (xy 183.989934 -401.714824) (xy 184.012668 -401.635352)
			(xy 184.042675 -401.55833) (xy 184.079695 -401.484423) (xy 184.123409 -401.414268) (xy 184.173441 -401.34847)
			(xy 184.201054 -401.317714) (xy 184.207134 -401.310468) (xy 184.214031 -401.292871) (xy 184.214516 -401.283424)
			(xy 184.214516 -401.252944) (xy 184.214097 -401.243482) (xy 184.207196 -401.225862) (xy 184.201054 -401.218654)
			(xy 184.173435 -401.187907) (xy 184.12342 -401.1221) (xy 184.079722 -401.05194) (xy 184.042717 -400.97803)
			(xy 184.012723 -400.901008) (xy 183.989999 -400.821537) (xy 183.974741 -400.740302) (xy 183.967081 -400.658002)
			(xy 183.966612 -400.616674) (xy 183.967088 -400.575568) (xy 183.974674 -400.493705) (xy 183.98978 -400.412892)
			(xy 184.012276 -400.333817) (xy 184.041971 -400.257154) (xy 184.078611 -400.183558) (xy 184.121884 -400.113655)
			(xy 184.171421 -400.048042) (xy 184.226799 -399.987279) (xy 184.287547 -399.931883) (xy 184.353145 -399.882327)
			(xy 184.423036 -399.839034) (xy 184.496622 -399.802373) (xy 184.573276 -399.772657) (xy 184.652345 -399.750138)
			(xy 184.733154 -399.735009) (xy 184.815014 -399.727399) (xy 184.85612 -399.726912) (xy 184.900625 -399.727439)
			(xy 184.989189 -399.736331) (xy 185.076422 -399.754024) (xy 185.161452 -399.780341) (xy 185.243428 -399.815019)
			(xy 185.321531 -399.857711) (xy 185.394979 -399.90799) (xy 185.463038 -399.965354) (xy 185.494422 -399.996914)
			(xy 185.501871 -400.003965) (xy 185.52075 -400.011949) (xy 185.530998 -400.012408) (xy 185.603642 -400.012408)
			(xy 185.613891 -400.011949) (xy 185.632766 -400.003963) (xy 185.640218 -399.996914) (xy 185.671594 -399.965346)
			(xy 185.739655 -399.907985) (xy 185.813105 -399.857708) (xy 185.891209 -399.815019) (xy 185.973186 -399.780344)
			(xy 186.058217 -399.75403) (xy 186.145451 -399.736341) (xy 186.234015 -399.727453) (xy 186.27852 -399.726912)
			(xy 186.32201 -399.727445) (xy 186.408572 -399.735955) (xy 186.493892 -399.752871) (xy 186.577152 -399.778033)
			(xy 186.65756 -399.811201) (xy 186.734348 -399.852056) (xy 186.806782 -399.900211) (xy 186.874171 -399.955204)
			(xy 186.905392 -399.985484) (xy 186.905646 -399.985738) (xy 186.913054 -399.992282) (xy 186.931335 -399.999743)
			(xy 186.941206 -400.000216) (xy 187.012834 -400.000216) (xy 187.022717 -399.999799) (xy 187.041016 -399.992329)
			(xy 187.048394 -399.985738) (xy 187.048648 -399.985484) (xy 187.079882 -399.955217) (xy 187.14727 -399.900227)
			(xy 187.219703 -399.852074) (xy 187.296489 -399.811218) (xy 187.376895 -399.77805) (xy 187.460154 -399.752886)
			(xy 187.54547 -399.735966) (xy 187.632031 -399.727452) (xy 187.67552 -399.726912) (xy 187.716616 -399.727347)
			(xy 187.798457 -399.734931) (xy 187.87925 -399.750033) (xy 187.958305 -399.772524) (xy 188.034948 -399.802212)
			(xy 188.108525 -399.838843) (xy 188.178409 -399.882106) (xy 188.244005 -399.931632) (xy 188.304751 -399.986997)
			(xy 188.360132 -400.047731) (xy 188.409673 -400.113314) (xy 188.452953 -400.183188) (xy 188.489602 -400.256756)
			(xy 188.519308 -400.333392) (xy 188.541818 -400.412442) (xy 188.556939 -400.493231) (xy 188.564543 -400.57507)
			(xy 188.565028 -400.616166) (xy 188.565028 -400.616674) (xy 188.564581 -400.658002) (xy 188.556919 -400.740303)
			(xy 188.541658 -400.821539) (xy 188.518931 -400.901009) (xy 188.488932 -400.97803) (xy 188.451921 -401.051937)
			(xy 188.408216 -401.122094) (xy 188.358194 -401.187896) (xy 188.330586 -401.218654) (xy 188.324524 -401.225913)
			(xy 188.317616 -401.2435) (xy 188.317124 -401.252944) (xy 188.317124 -401.283424) (xy 188.3175 -401.292891)
			(xy 188.32443 -401.310511) (xy 188.330586 -401.317714) (xy 188.358194 -401.348474) (xy 188.408229 -401.414271)
			(xy 188.451946 -401.484425) (xy 188.488968 -401.558331) (xy 188.518976 -401.635351) (xy 188.541712 -401.714823)
			(xy 188.556979 -401.796062) (xy 188.564645 -401.878365) (xy 188.564646 -401.961026) (xy 188.55698 -402.04333)
			(xy 188.541714 -402.124568) (xy 188.518979 -402.20404) (xy 188.488972 -402.281061) (xy 188.45195 -402.354968)
			(xy 188.408234 -402.425122) (xy 188.3582 -402.490919) (xy 188.330586 -402.521674) (xy 188.324516 -402.528927)
			(xy 188.317612 -402.546518) (xy 188.317124 -402.555964) (xy 188.317124 -402.586444) (xy 188.31749 -402.595912)
			(xy 188.324426 -402.613532) (xy 188.330586 -402.620734) (xy 188.358206 -402.65148) (xy 188.40822 -402.717288)
			(xy 188.451917 -402.787448) (xy 188.488922 -402.861358) (xy 188.518915 -402.93838) (xy 188.541639 -403.017851)
			(xy 188.556897 -403.099086) (xy 188.564559 -403.181386) (xy 188.565028 -403.222714) (xy 188.56457 -403.265938)
			(xy 188.556182 -403.351979) (xy 188.539486 -403.436801) (xy 188.514639 -403.519602) (xy 188.481877 -403.599602)
			(xy 188.441508 -403.676046) (xy 188.393913 -403.748214) (xy 188.339541 -403.815423) (xy 188.278905 -403.87704)
			(xy 188.212577 -403.932484) (xy 188.17717 -403.957282) (xy 188.169401 -403.962991) (xy 188.158572 -403.978928)
			(xy 188.15443 -403.997746) (xy 188.15558 -404.00732) (xy 188.172598 -404.112984) (xy 188.191902 -404.134828)
			(xy 188.20638 -404.138892) (xy 188.235359 -404.147534) (xy 188.292177 -404.168255) (xy 188.319918 -404.180294)
			(xy 188.32986 -404.1841) (xy 188.351124 -404.1841) (xy 188.361066 -404.180294) (xy 188.403727 -404.162032)
			(xy 188.492015 -404.133439) (xy 188.582798 -404.114182) (xy 188.675091 -404.104469) (xy 188.721492 -404.10384)
			(xy 188.767894 -404.104473) (xy 188.860191 -404.114162) (xy 188.950976 -404.133414) (xy 189.039262 -404.162019)
			(xy 189.081918 -404.180294) (xy 189.09186 -404.1841) (xy 189.113124 -404.1841) (xy 189.123066 -404.180294)
			(xy 189.165727 -404.162032) (xy 189.254015 -404.133439) (xy 189.344798 -404.114182) (xy 189.437091 -404.104469)
			(xy 189.483492 -404.10384) (xy 189.524604 -404.10426) (xy 189.606477 -404.111848) (xy 189.6873 -404.126959)
			(xy 189.766384 -404.149465) (xy 189.843053 -404.179173) (xy 189.916654 -404.21583) (xy 189.986557 -404.259123)
			(xy 190.052166 -404.308683) (xy 190.112922 -404.364086) (xy 190.168305 -404.42486) (xy 190.217843 -404.490486)
			(xy 190.261113 -404.560403) (xy 190.297746 -404.634016) (xy 190.327429 -404.710695) (xy 190.349908 -404.789786)
			(xy 190.364993 -404.870614) (xy 190.372553 -404.95249) (xy 190.373 -404.993602) (xy 190.372419 -405.039998)
			(xy 190.362773 -405.132286) (xy 190.343577 -405.22307) (xy 190.315038 -405.311363) (xy 190.2968 -405.354028)
			(xy 190.292994 -405.36397) (xy 190.292995 -405.385234) (xy 190.2968 -405.395176) (xy 190.315045 -405.437838)
			(xy 190.343589 -405.52613) (xy 190.362782 -405.616916) (xy 190.372415 -405.709206) (xy 190.373 -405.755602)
			(xy 190.372419 -405.801998) (xy 190.362773 -405.894286) (xy 190.343577 -405.98507) (xy 190.315038 -406.073363)
			(xy 190.2968 -406.116028) (xy 190.292994 -406.12597) (xy 190.292995 -406.147234) (xy 190.2968 -406.157176)
			(xy 190.315045 -406.199838) (xy 190.343589 -406.28813) (xy 190.362782 -406.378916) (xy 190.372415 -406.471206)
			(xy 190.373 -406.517602) (xy 190.37258 -406.55737) (xy 190.365551 -406.636594) (xy 190.351469 -406.714872)
			(xy 190.330446 -406.791578) (xy 190.302651 -406.866098) (xy 190.285878 -406.902158) (xy 190.281544 -406.912659)
			(xy 190.281545 -406.935345) (xy 190.285878 -406.945846) (xy 190.302637 -406.981911) (xy 190.330411 -407.056437)
			(xy 190.351429 -407.133142) (xy 190.365522 -407.211416) (xy 190.372579 -407.290635) (xy 190.373 -407.330402)
			(xy 190.372419 -407.376798) (xy 190.362773 -407.469086) (xy 190.343577 -407.55987) (xy 190.315038 -407.648163)
			(xy 190.2968 -407.690828) (xy 190.292994 -407.70077) (xy 190.292995 -407.722034) (xy 190.2968 -407.731976)
			(xy 190.315022 -407.774579) (xy 190.34354 -407.862746) (xy 190.362733 -407.953402) (xy 190.372392 -408.045562)
			(xy 190.372573 -408.059382) (xy 196.354192 -408.059382) (xy 196.354769 -408.012986) (xy 196.364415 -407.920698)
			(xy 196.383613 -407.829914) (xy 196.412153 -407.741621) (xy 196.430392 -407.698956) (xy 196.434208 -407.689017)
			(xy 196.434201 -407.66775) (xy 196.430392 -407.657808) (xy 196.412141 -407.615148) (xy 196.383599 -407.526855)
			(xy 196.364407 -407.436069) (xy 196.354776 -407.343778) (xy 196.354192 -407.297382) (xy 196.354769 -407.250986)
			(xy 196.364415 -407.158698) (xy 196.383613 -407.067914) (xy 196.412153 -406.979621) (xy 196.430392 -406.936956)
			(xy 196.434208 -406.927017) (xy 196.434201 -406.90575) (xy 196.430392 -406.895808) (xy 196.412141 -406.853148)
			(xy 196.383599 -406.764855) (xy 196.364407 -406.674069) (xy 196.354776 -406.581778) (xy 196.354192 -406.535382)
			(xy 196.354769 -406.488986) (xy 196.364415 -406.396698) (xy 196.383613 -406.305914) (xy 196.412153 -406.217621)
			(xy 196.430392 -406.174956) (xy 196.434208 -406.165017) (xy 196.434201 -406.14375) (xy 196.430392 -406.133808)
			(xy 196.412141 -406.091148) (xy 196.383599 -406.002855) (xy 196.364407 -405.912069) (xy 196.354776 -405.819778)
			(xy 196.354192 -405.773382) (xy 196.354769 -405.726986) (xy 196.364415 -405.634698) (xy 196.383613 -405.543914)
			(xy 196.412153 -405.455621) (xy 196.430392 -405.412956) (xy 196.434208 -405.403017) (xy 196.434201 -405.38175)
			(xy 196.430392 -405.371808) (xy 196.412164 -405.329208) (xy 196.383648 -405.241039) (xy 196.364457 -405.150383)
			(xy 196.354799 -405.058222) (xy 196.354192 -405.01189) (xy 196.354192 -405.011382) (xy 196.354695 -404.970276)
			(xy 196.362281 -404.888416) (xy 196.377385 -404.807604) (xy 196.39988 -404.72853) (xy 196.429573 -404.651868)
			(xy 196.466212 -404.578272) (xy 196.509483 -404.50837) (xy 196.559018 -404.442758) (xy 196.614395 -404.381994)
			(xy 196.67514 -404.326599) (xy 196.740737 -404.277043) (xy 196.810626 -404.233749) (xy 196.88421 -404.197087)
			(xy 196.960862 -404.16737) (xy 197.039929 -404.14485) (xy 197.120736 -404.12972) (xy 197.202594 -404.122108)
			(xy 197.2437 -404.12162) (xy 197.290102 -404.122252) (xy 197.382399 -404.131941) (xy 197.473184 -404.151193)
			(xy 197.56147 -404.179799) (xy 197.604126 -404.198074) (xy 197.614068 -404.20188) (xy 197.635332 -404.20188)
			(xy 197.645274 -404.198074) (xy 197.673976 -404.185882) (xy 197.682795 -404.181969) (xy 197.696833 -404.168752)
			(xy 197.704997 -404.151285) (xy 197.70598 -404.141686) (xy 197.711314 -404.049992) (xy 197.711428 -404.040421)
			(xy 197.705477 -404.022248) (xy 197.693313 -404.007492) (xy 197.685152 -404.002494) (xy 197.647554 -403.981253)
			(xy 197.576288 -403.932477) (xy 197.510083 -403.877025) (xy 197.449561 -403.81542) (xy 197.395292 -403.748241)
			(xy 197.347788 -403.67612) (xy 197.307493 -403.599737) (xy 197.274789 -403.519809) (xy 197.249982 -403.437088)
			(xy 197.233306 -403.352354) (xy 197.224918 -403.266402) (xy 197.224396 -403.223222) (xy 197.224864 -403.181887)
			(xy 197.232535 -403.099572) (xy 197.247812 -403.018325) (xy 197.270564 -402.938847) (xy 197.300593 -402.861823)
			(xy 197.337642 -402.787918) (xy 197.38139 -402.717771) (xy 197.431459 -402.651987) (xy 197.459092 -402.621242)
			(xy 197.465153 -402.613982) (xy 197.472063 -402.596396) (xy 197.472554 -402.586952) (xy 197.472554 -402.556472)
			(xy 197.472185 -402.547004) (xy 197.465251 -402.529384) (xy 197.459092 -402.522182) (xy 197.431443 -402.491454)
			(xy 197.3814 -402.425653) (xy 197.337673 -402.355495) (xy 197.300638 -402.281587) (xy 197.270614 -402.204563)
			(xy 197.24786 -402.125088) (xy 197.232571 -402.043846) (xy 197.22488 -401.961536) (xy 197.224396 -401.920202)
			(xy 197.224852 -401.878866) (xy 197.232524 -401.796552) (xy 197.247803 -401.715304) (xy 197.270556 -401.635826)
			(xy 197.300588 -401.558802) (xy 197.337638 -401.484897) (xy 197.381388 -401.414751) (xy 197.431459 -401.348967)
			(xy 197.459092 -401.318222) (xy 197.465161 -401.310968) (xy 197.472066 -401.293378) (xy 197.472554 -401.283932)
			(xy 197.472554 -401.253452) (xy 197.472146 -401.243989) (xy 197.465239 -401.226367) (xy 197.459092 -401.219162)
			(xy 197.431482 -401.1884) (xy 197.381436 -401.122604) (xy 197.337705 -401.052453) (xy 197.300666 -400.978549)
			(xy 197.270637 -400.90153) (xy 197.247877 -400.82206) (xy 197.232582 -400.740821) (xy 197.224883 -400.658515)
			(xy 197.224396 -400.617182) (xy 197.224896 -400.576069) (xy 197.232484 -400.494193) (xy 197.247594 -400.413367)
			(xy 197.270097 -400.334279) (xy 197.299801 -400.257605) (xy 197.336453 -400.183999) (xy 197.379739 -400.114089)
			(xy 197.429291 -400.04847) (xy 197.484686 -399.987703) (xy 197.545451 -399.932307) (xy 197.611069 -399.882753)
			(xy 197.680978 -399.839464) (xy 197.754583 -399.802811) (xy 197.831256 -399.773105) (xy 197.910343 -399.7506)
			(xy 197.991169 -399.735487) (xy 198.073045 -399.727897) (xy 198.114158 -399.72742) (xy 198.158662 -399.727949)
			(xy 198.247226 -399.736844) (xy 198.334458 -399.754538) (xy 198.419487 -399.780856) (xy 198.501463 -399.815534)
			(xy 198.579565 -399.858225) (xy 198.653014 -399.908502) (xy 198.721075 -399.965864) (xy 198.75246 -399.997422)
			(xy 198.759931 -400.004447) (xy 198.778793 -400.012446) (xy 198.789036 -400.012916) (xy 198.86168 -400.012916)
			(xy 198.871931 -400.012475) (xy 198.890805 -400.004477) (xy 198.898256 -399.997422) (xy 198.929663 -399.965886)
			(xy 198.997719 -399.908523) (xy 199.071164 -399.858243) (xy 199.149263 -399.81555) (xy 199.231236 -399.780871)
			(xy 199.316263 -399.754552) (xy 199.403493 -399.736858) (xy 199.492055 -399.727964) (xy 199.536558 -399.72742)
			(xy 199.580049 -399.727926) (xy 199.666612 -399.736439) (xy 199.751932 -399.75336) (xy 199.835193 -399.778526)
			(xy 199.915601 -399.811696) (xy 199.992388 -399.852556) (xy 200.064821 -399.900714) (xy 200.132209 -399.95571)
			(xy 200.16343 -399.985992) (xy 200.163684 -399.986246) (xy 200.171078 -399.992808) (xy 200.189369 -400.000258)
			(xy 200.199244 -400.000724) (xy 200.270872 -400.000724) (xy 200.280751 -400.000273) (xy 200.29905 -399.992827)
			(xy 200.306432 -399.986246) (xy 200.306686 -399.985992) (xy 200.337904 -399.955708) (xy 200.405295 -399.900719)
			(xy 200.47773 -399.852567) (xy 200.554518 -399.811713) (xy 200.634927 -399.778547) (xy 200.718187 -399.753386)
			(xy 200.803506 -399.736469) (xy 200.890068 -399.727958) (xy 200.933558 -399.72742) (xy 200.974672 -399.727938)
			(xy 201.056549 -399.735522) (xy 201.137376 -399.750627) (xy 201.216466 -399.773127) (xy 201.293142 -399.802827)
			(xy 201.36675 -399.839476) (xy 201.436663 -399.882761) (xy 201.502283 -399.932312) (xy 201.563052 -399.987706)
			(xy 201.61845 -400.04847) (xy 201.668005 -400.114088) (xy 201.711294 -400.183998) (xy 201.747948 -400.257603)
			(xy 201.777654 -400.334277) (xy 201.800159 -400.413365) (xy 201.81527 -400.494192) (xy 201.822859 -400.576068)
			(xy 201.82332 -400.617182) (xy 201.82285 -400.658517) (xy 201.815179 -400.740831) (xy 201.799902 -400.822078)
			(xy 201.777151 -400.901557) (xy 201.747121 -400.978581) (xy 201.710073 -401.052485) (xy 201.666325 -401.122632)
			(xy 201.616256 -401.188416) (xy 201.588624 -401.219162) (xy 201.582551 -401.226413) (xy 201.575651 -401.244006)
			(xy 201.575162 -401.253452) (xy 201.575162 -401.283932) (xy 201.575549 -401.293397) (xy 201.582473 -401.311017)
			(xy 201.588624 -401.318222) (xy 201.61626 -401.348962) (xy 201.666306 -401.41476) (xy 201.710036 -401.484914)
			(xy 201.747073 -401.558821) (xy 201.777099 -401.635843) (xy 201.799855 -401.715317) (xy 201.815145 -401.796559)
			(xy 201.822837 -401.878868) (xy 201.82332 -401.920202) (xy 201.822863 -401.961538) (xy 201.81519 -402.043852)
			(xy 201.799911 -402.125099) (xy 201.777158 -402.204578) (xy 201.747126 -402.281602) (xy 201.710076 -402.355506)
			(xy 201.666327 -402.425653) (xy 201.616257 -402.491437) (xy 201.588624 -402.522182) (xy 201.582543 -402.529427)
			(xy 201.575647 -402.547025) (xy 201.575162 -402.556472) (xy 201.575162 -402.586952) (xy 201.575589 -402.596413)
			(xy 201.582485 -402.614033) (xy 201.588624 -402.621242) (xy 201.616222 -402.652015) (xy 201.66627 -402.717808)
			(xy 201.710004 -402.787957) (xy 201.747046 -402.861859) (xy 201.777077 -402.938876) (xy 201.799838 -403.018346)
			(xy 201.815134 -403.099584) (xy 201.822833 -403.18189) (xy 201.82332 -403.223222) (xy 201.822801 -403.266183)
			(xy 201.814523 -403.351705) (xy 201.798036 -403.43603) (xy 201.773494 -403.518372) (xy 201.741125 -403.597963)
			(xy 201.701232 -403.674062) (xy 201.654186 -403.745959) (xy 201.600426 -403.812984) (xy 201.540453 -403.874513)
			(xy 201.474826 -403.929971) (xy 201.404156 -403.978842) (xy 201.366882 -404.000208) (xy 201.35873 -404.005265)
			(xy 201.346612 -404.020117) (xy 201.34076 -404.03837) (xy 201.340974 -404.04796) (xy 201.348086 -404.154386)
			(xy 201.365358 -404.178008) (xy 201.379328 -404.183342) (xy 201.417266 -404.198729) (xy 201.490382 -404.235572)
			(xy 201.559803 -404.27898) (xy 201.62494 -404.328584) (xy 201.685242 -404.383965) (xy 201.740199 -404.444654)
			(xy 201.789346 -404.510137) (xy 201.832266 -404.57986) (xy 201.868597 -404.653232) (xy 201.89803 -404.729633)
			(xy 201.920317 -404.808416) (xy 201.935269 -404.888913) (xy 201.942758 -404.970445) (xy 201.943208 -405.011382)
			(xy 201.942619 -405.057777) (xy 201.932976 -405.150066) (xy 201.913781 -405.240849) (xy 201.885245 -405.329143)
			(xy 201.867008 -405.371808) (xy 201.863213 -405.381753) (xy 201.863206 -405.403014) (xy 201.867008 -405.412956)
			(xy 201.885247 -405.455621) (xy 201.913792 -405.543912) (xy 201.932987 -405.634696) (xy 201.942622 -405.726986)
			(xy 201.943208 -405.773382) (xy 201.942619 -405.819777) (xy 201.932976 -405.912066) (xy 201.913781 -406.002849)
			(xy 201.885245 -406.091143) (xy 201.867008 -406.133808) (xy 201.863213 -406.143753) (xy 201.863206 -406.165014)
			(xy 201.867008 -406.174956) (xy 201.885247 -406.217621) (xy 201.913792 -406.305912) (xy 201.932987 -406.396696)
			(xy 201.942622 -406.488986) (xy 201.943208 -406.535382) (xy 201.942619 -406.581777) (xy 201.932976 -406.674066)
			(xy 201.913781 -406.764849) (xy 201.885245 -406.853143) (xy 201.867008 -406.895808) (xy 201.863213 -406.905753)
			(xy 201.863206 -406.927014) (xy 201.867008 -406.936956) (xy 201.885247 -406.979621) (xy 201.913792 -407.067912)
			(xy 201.932987 -407.158696) (xy 201.942622 -407.250986) (xy 201.943208 -407.297382) (xy 201.942619 -407.343777)
			(xy 201.932976 -407.436066) (xy 201.913781 -407.526849) (xy 201.885245 -407.615143) (xy 201.867008 -407.657808)
			(xy 201.863213 -407.667753) (xy 201.863206 -407.689014) (xy 201.867008 -407.698956) (xy 201.885224 -407.741561)
			(xy 201.913743 -407.829728) (xy 201.932938 -407.920383) (xy 201.942599 -408.012542) (xy 201.943208 -408.058874)
			(xy 201.943208 -408.059382) (xy 201.943201 -408.05989) (xy 206.260192 -408.05989) (xy 206.260192 -408.059382)
			(xy 206.260717 -408.017997) (xy 206.268406 -407.935585) (xy 206.283716 -407.854244) (xy 206.306513 -407.774675)
			(xy 206.336602 -407.697568) (xy 206.373723 -407.623589) (xy 206.417553 -407.553377) (xy 206.467715 -407.487539)
			(xy 206.523774 -407.426645) (xy 206.585247 -407.37122) (xy 206.651602 -407.321743) (xy 206.722265 -407.278644)
			(xy 206.796625 -407.242293) (xy 206.87404 -407.213005) (xy 206.953841 -407.191034) (xy 206.994506 -407.183336)
			(xy 207.004634 -407.181051) (xy 207.021956 -407.169641) (xy 207.033359 -407.152314) (xy 207.035654 -407.142188)
			(xy 207.043393 -407.101149) (xy 207.065607 -407.020638) (xy 207.095268 -406.942562) (xy 207.132115 -406.86761)
			(xy 207.175825 -406.796441) (xy 207.226012 -406.729682) (xy 207.282235 -406.66792) (xy 207.343998 -406.611699)
			(xy 207.410759 -406.561513) (xy 207.481929 -406.517805) (xy 207.556881 -406.48096) (xy 207.634957 -406.4513)
			(xy 207.715469 -406.429089) (xy 207.756506 -406.421336) (xy 207.766634 -406.419051) (xy 207.783956 -406.407641)
			(xy 207.795359 -406.390314) (xy 207.797654 -406.380188) (xy 207.804281 -406.344944) (xy 207.822478 -406.275571)
			(xy 207.846186 -406.207884) (xy 207.860392 -406.174956) (xy 207.864208 -406.165017) (xy 207.864201 -406.14375)
			(xy 207.860392 -406.133808) (xy 207.842141 -406.091148) (xy 207.813599 -406.002855) (xy 207.794407 -405.912069)
			(xy 207.784776 -405.819778) (xy 207.784192 -405.773382) (xy 207.784769 -405.726986) (xy 207.794415 -405.634698)
			(xy 207.813613 -405.543914) (xy 207.842153 -405.455621) (xy 207.860392 -405.412956) (xy 207.864208 -405.403017)
			(xy 207.864201 -405.38175) (xy 207.860392 -405.371808) (xy 207.842164 -405.329208) (xy 207.813648 -405.241039)
			(xy 207.794457 -405.150383) (xy 207.784799 -405.058222) (xy 207.784192 -405.01189) (xy 207.784192 -405.011382)
			(xy 207.784669 -404.970705) (xy 207.792097 -404.889692) (xy 207.80689 -404.809694) (xy 207.828923 -404.731381)
			(xy 207.858013 -404.655407) (xy 207.893918 -404.582405) (xy 207.936336 -404.512985) (xy 207.984914 -404.447728)
			(xy 208.039247 -404.387177) (xy 208.09888 -404.33184) (xy 208.163316 -404.282176) (xy 208.232016 -404.238603)
			(xy 208.304407 -404.201482) (xy 208.341976 -404.185882) (xy 208.350795 -404.181969) (xy 208.364833 -404.168752)
			(xy 208.372997 -404.151285) (xy 208.37398 -404.141686) (xy 208.379314 -404.049992) (xy 208.379428 -404.040421)
			(xy 208.373477 -404.022248) (xy 208.361313 -404.007492) (xy 208.353152 -404.002494) (xy 208.315554 -403.981253)
			(xy 208.244288 -403.932477) (xy 208.178083 -403.877025) (xy 208.117561 -403.81542) (xy 208.063292 -403.748241)
			(xy 208.015788 -403.67612) (xy 207.975493 -403.599737) (xy 207.942789 -403.519809) (xy 207.917982 -403.437088)
			(xy 207.901306 -403.352354) (xy 207.892918 -403.266402) (xy 207.892396 -403.223222) (xy 207.892864 -403.181887)
			(xy 207.900535 -403.099572) (xy 207.915812 -403.018325) (xy 207.938564 -402.938847) (xy 207.968593 -402.861823)
			(xy 208.005642 -402.787918) (xy 208.04939 -402.717771) (xy 208.099459 -402.651987) (xy 208.127092 -402.621242)
			(xy 208.133153 -402.613982) (xy 208.140063 -402.596396) (xy 208.140554 -402.586952) (xy 208.140554 -402.556472)
			(xy 208.140185 -402.547004) (xy 208.133251 -402.529384) (xy 208.127092 -402.522182) (xy 208.099443 -402.491454)
			(xy 208.0494 -402.425653) (xy 208.005673 -402.355495) (xy 207.968638 -402.281587) (xy 207.938614 -402.204563)
			(xy 207.91586 -402.125088) (xy 207.900571 -402.043846) (xy 207.89288 -401.961536) (xy 207.892396 -401.920202)
			(xy 207.892852 -401.878866) (xy 207.900524 -401.796552) (xy 207.915803 -401.715304) (xy 207.938556 -401.635826)
			(xy 207.968588 -401.558802) (xy 208.005638 -401.484897) (xy 208.049388 -401.414751) (xy 208.099459 -401.348967)
			(xy 208.127092 -401.318222) (xy 208.133161 -401.310968) (xy 208.140066 -401.293378) (xy 208.140554 -401.283932)
			(xy 208.140554 -401.253452) (xy 208.140146 -401.243989) (xy 208.133239 -401.226367) (xy 208.127092 -401.219162)
			(xy 208.099482 -401.1884) (xy 208.049436 -401.122604) (xy 208.005705 -401.052453) (xy 207.968666 -400.978549)
			(xy 207.938637 -400.90153) (xy 207.915877 -400.82206) (xy 207.900582 -400.740821) (xy 207.892883 -400.658515)
			(xy 207.892396 -400.617182) (xy 207.892896 -400.576069) (xy 207.900484 -400.494193) (xy 207.915594 -400.413367)
			(xy 207.938097 -400.334279) (xy 207.967801 -400.257605) (xy 208.004453 -400.183999) (xy 208.047739 -400.114089)
			(xy 208.097291 -400.04847) (xy 208.152686 -399.987703) (xy 208.213451 -399.932307) (xy 208.279069 -399.882753)
			(xy 208.348978 -399.839464) (xy 208.422583 -399.802811) (xy 208.499256 -399.773105) (xy 208.578343 -399.7506)
			(xy 208.659169 -399.735487) (xy 208.741045 -399.727897) (xy 208.782158 -399.72742) (xy 208.826662 -399.727949)
			(xy 208.915226 -399.736844) (xy 209.002458 -399.754538) (xy 209.087487 -399.780856) (xy 209.169463 -399.815534)
			(xy 209.247565 -399.858225) (xy 209.321014 -399.908502) (xy 209.389075 -399.965864) (xy 209.42046 -399.997422)
			(xy 209.427931 -400.004447) (xy 209.446793 -400.012446) (xy 209.457036 -400.012916) (xy 209.52968 -400.012916)
			(xy 209.539931 -400.012475) (xy 209.558805 -400.004477) (xy 209.566256 -399.997422) (xy 209.597663 -399.965886)
			(xy 209.665719 -399.908523) (xy 209.739164 -399.858243) (xy 209.817263 -399.81555) (xy 209.899236 -399.780871)
			(xy 209.984263 -399.754552) (xy 210.071493 -399.736858) (xy 210.160055 -399.727964) (xy 210.204558 -399.72742)
			(xy 210.248049 -399.727926) (xy 210.334612 -399.736439) (xy 210.419932 -399.75336) (xy 210.503193 -399.778526)
			(xy 210.583601 -399.811696) (xy 210.660388 -399.852556) (xy 210.732821 -399.900714) (xy 210.800209 -399.95571)
			(xy 210.83143 -399.985992) (xy 210.831684 -399.986246) (xy 210.839078 -399.992808) (xy 210.857369 -400.000258)
			(xy 210.867244 -400.000724) (xy 210.938872 -400.000724) (xy 210.948751 -400.000273) (xy 210.96705 -399.992827)
			(xy 210.974432 -399.986246) (xy 210.974686 -399.985992) (xy 211.005904 -399.955708) (xy 211.073295 -399.900719)
			(xy 211.14573 -399.852567) (xy 211.222518 -399.811713) (xy 211.302927 -399.778547) (xy 211.386187 -399.753386)
			(xy 211.471506 -399.736469) (xy 211.558068 -399.727958) (xy 211.601558 -399.72742) (xy 211.642672 -399.727938)
			(xy 211.724549 -399.735522) (xy 211.805376 -399.750627) (xy 211.884466 -399.773127) (xy 211.961142 -399.802827)
			(xy 212.03475 -399.839476) (xy 212.104663 -399.882761) (xy 212.170283 -399.932312) (xy 212.231052 -399.987706)
			(xy 212.28645 -400.04847) (xy 212.336005 -400.114088) (xy 212.379294 -400.183998) (xy 212.415948 -400.257603)
			(xy 212.445654 -400.334277) (xy 212.468159 -400.413365) (xy 212.48327 -400.494192) (xy 212.490859 -400.576068)
			(xy 212.49132 -400.617182) (xy 212.49085 -400.658517) (xy 212.483179 -400.740831) (xy 212.467902 -400.822078)
			(xy 212.445151 -400.901557) (xy 212.415121 -400.978581) (xy 212.378073 -401.052485) (xy 212.334325 -401.122632)
			(xy 212.284256 -401.188416) (xy 212.256624 -401.219162) (xy 212.250551 -401.226413) (xy 212.243651 -401.244006)
			(xy 212.243162 -401.253452) (xy 212.243162 -401.283932) (xy 212.243549 -401.293397) (xy 212.250473 -401.311017)
			(xy 212.256624 -401.318222) (xy 212.28426 -401.348962) (xy 212.334306 -401.41476) (xy 212.378036 -401.484914)
			(xy 212.415073 -401.558821) (xy 212.445099 -401.635843) (xy 212.467855 -401.715317) (xy 212.483145 -401.796559)
			(xy 212.490837 -401.878868) (xy 212.49132 -401.920202) (xy 212.490863 -401.961538) (xy 212.48319 -402.043852)
			(xy 212.467911 -402.125099) (xy 212.445158 -402.204578) (xy 212.415126 -402.281602) (xy 212.378076 -402.355506)
			(xy 212.334327 -402.425653) (xy 212.284257 -402.491437) (xy 212.256624 -402.522182) (xy 212.250543 -402.529427)
			(xy 212.243647 -402.547025) (xy 212.243162 -402.556472) (xy 212.243162 -402.586952) (xy 212.243589 -402.596413)
			(xy 212.250485 -402.614033) (xy 212.256624 -402.621242) (xy 212.284222 -402.652015) (xy 212.33427 -402.717808)
			(xy 212.378004 -402.787957) (xy 212.415046 -402.861859) (xy 212.445077 -402.938876) (xy 212.467838 -403.018346)
			(xy 212.483134 -403.099584) (xy 212.490833 -403.18189) (xy 212.49132 -403.223222) (xy 212.490801 -403.266183)
			(xy 212.482523 -403.351705) (xy 212.466036 -403.43603) (xy 212.441494 -403.518372) (xy 212.409125 -403.597963)
			(xy 212.369232 -403.674062) (xy 212.322186 -403.745959) (xy 212.268426 -403.812984) (xy 212.208453 -403.874513)
			(xy 212.142826 -403.929971) (xy 212.072156 -403.978842) (xy 212.034882 -404.000208) (xy 212.02673 -404.005265)
			(xy 212.014612 -404.020117) (xy 212.00876 -404.03837) (xy 212.008974 -404.04796) (xy 212.016086 -404.154386)
			(xy 212.033358 -404.178008) (xy 212.047328 -404.183342) (xy 212.085266 -404.198729) (xy 212.158382 -404.235572)
			(xy 212.227803 -404.27898) (xy 212.29294 -404.328584) (xy 212.353242 -404.383965) (xy 212.408199 -404.444654)
			(xy 212.457346 -404.510137) (xy 212.500266 -404.57986) (xy 212.536597 -404.653232) (xy 212.56603 -404.729633)
			(xy 212.588317 -404.808416) (xy 212.603269 -404.888913) (xy 212.610758 -404.970445) (xy 212.611208 -405.011382)
			(xy 212.610619 -405.057777) (xy 212.600976 -405.150066) (xy 212.581781 -405.240849) (xy 212.553245 -405.329143)
			(xy 212.535008 -405.371808) (xy 212.531213 -405.381753) (xy 212.531206 -405.403014) (xy 212.535008 -405.412956)
			(xy 212.553247 -405.455621) (xy 212.581792 -405.543912) (xy 212.600987 -405.634696) (xy 212.610622 -405.726986)
			(xy 212.611208 -405.773382) (xy 212.610619 -405.819777) (xy 212.600976 -405.912066) (xy 212.581781 -406.002849)
			(xy 212.553245 -406.091143) (xy 212.535008 -406.133808) (xy 212.531213 -406.143753) (xy 212.531206 -406.165014)
			(xy 212.535008 -406.174956) (xy 212.549234 -406.207876) (xy 212.572955 -406.275561) (xy 212.591136 -406.34494)
			(xy 212.597746 -406.380188) (xy 212.600055 -406.390309) (xy 212.611454 -406.407631) (xy 212.628772 -406.419037)
			(xy 212.638894 -406.421336) (xy 212.679556 -406.42906) (xy 212.75936 -406.451024) (xy 212.83678 -406.480305)
			(xy 212.911146 -406.51665) (xy 212.981814 -406.559745) (xy 213.048174 -406.609217) (xy 213.109652 -406.66464)
			(xy 213.165716 -406.725533) (xy 213.215883 -406.791369) (xy 213.259718 -406.861581) (xy 213.296841 -406.935561)
			(xy 213.326933 -407.012669) (xy 213.349733 -407.092239) (xy 213.365045 -407.173582) (xy 213.372734 -407.255996)
			(xy 213.373208 -407.297382) (xy 213.373208 -407.29789) (xy 213.372596 -407.344222) (xy 213.362926 -407.436379)
			(xy 213.343732 -407.527034) (xy 213.315222 -407.615202) (xy 213.297008 -407.657808) (xy 213.293213 -407.667753)
			(xy 213.293206 -407.689014) (xy 213.297008 -407.698956) (xy 213.315224 -407.741561) (xy 213.343743 -407.829728)
			(xy 213.362938 -407.920383) (xy 213.372599 -408.012542) (xy 213.373208 -408.058874) (xy 213.373208 -408.059382)
			(xy 213.373201 -408.05989) (xy 216.928192 -408.05989) (xy 216.928192 -408.059382) (xy 216.928717 -408.017997)
			(xy 216.936406 -407.935585) (xy 216.951716 -407.854244) (xy 216.974513 -407.774675) (xy 217.004602 -407.697568)
			(xy 217.041723 -407.623589) (xy 217.085553 -407.553377) (xy 217.135715 -407.487539) (xy 217.191774 -407.426645)
			(xy 217.253247 -407.37122) (xy 217.319602 -407.321743) (xy 217.390265 -407.278644) (xy 217.464625 -407.242293)
			(xy 217.54204 -407.213005) (xy 217.621841 -407.191034) (xy 217.662506 -407.183336) (xy 217.672634 -407.181051)
			(xy 217.689956 -407.169641) (xy 217.701359 -407.152314) (xy 217.703654 -407.142188) (xy 217.711393 -407.101149)
			(xy 217.733607 -407.020638) (xy 217.763268 -406.942562) (xy 217.800115 -406.86761) (xy 217.843825 -406.796441)
			(xy 217.894012 -406.729682) (xy 217.950235 -406.66792) (xy 218.011998 -406.611699) (xy 218.078759 -406.561513)
			(xy 218.149929 -406.517805) (xy 218.224881 -406.48096) (xy 218.302957 -406.4513) (xy 218.383469 -406.429089)
			(xy 218.424506 -406.421336) (xy 218.434634 -406.419051) (xy 218.451956 -406.407641) (xy 218.463359 -406.390314)
			(xy 218.465654 -406.380188) (xy 218.472281 -406.344944) (xy 218.490478 -406.275571) (xy 218.514186 -406.207884)
			(xy 218.528392 -406.174956) (xy 218.532208 -406.165017) (xy 218.532201 -406.14375) (xy 218.528392 -406.133808)
			(xy 218.510141 -406.091148) (xy 218.481599 -406.002855) (xy 218.462407 -405.912069) (xy 218.452776 -405.819778)
			(xy 218.452192 -405.773382) (xy 218.452769 -405.726986) (xy 218.462415 -405.634698) (xy 218.481613 -405.543914)
			(xy 218.510153 -405.455621) (xy 218.528392 -405.412956) (xy 218.532208 -405.403017) (xy 218.532201 -405.38175)
			(xy 218.528392 -405.371808) (xy 218.510164 -405.329208) (xy 218.481648 -405.241039) (xy 218.462457 -405.150383)
			(xy 218.452799 -405.058222) (xy 218.452192 -405.01189) (xy 218.452192 -405.011382) (xy 218.452669 -404.970705)
			(xy 218.460097 -404.889692) (xy 218.47489 -404.809694) (xy 218.496923 -404.731381) (xy 218.526013 -404.655407)
			(xy 218.561918 -404.582405) (xy 218.604336 -404.512985) (xy 218.652914 -404.447728) (xy 218.707247 -404.387177)
			(xy 218.76688 -404.33184) (xy 218.831316 -404.282176) (xy 218.900016 -404.238603) (xy 218.972407 -404.201482)
			(xy 219.009976 -404.185882) (xy 219.018795 -404.181969) (xy 219.032833 -404.168752) (xy 219.040997 -404.151285)
			(xy 219.04198 -404.141686) (xy 219.047314 -404.049992) (xy 219.047428 -404.040421) (xy 219.041477 -404.022248)
			(xy 219.029313 -404.007492) (xy 219.021152 -404.002494) (xy 218.983554 -403.981253) (xy 218.912288 -403.932477)
			(xy 218.846083 -403.877025) (xy 218.785561 -403.81542) (xy 218.731292 -403.748241) (xy 218.683788 -403.67612)
			(xy 218.643493 -403.599737) (xy 218.610789 -403.519809) (xy 218.585982 -403.437088) (xy 218.569306 -403.352354)
			(xy 218.560918 -403.266402) (xy 218.560396 -403.223222) (xy 218.560864 -403.181887) (xy 218.568535 -403.099572)
			(xy 218.583812 -403.018325) (xy 218.606564 -402.938847) (xy 218.636593 -402.861823) (xy 218.673642 -402.787918)
			(xy 218.71739 -402.717771) (xy 218.767459 -402.651987) (xy 218.795092 -402.621242) (xy 218.801153 -402.613982)
			(xy 218.808063 -402.596396) (xy 218.808554 -402.586952) (xy 218.808554 -402.556472) (xy 218.808185 -402.547004)
			(xy 218.801251 -402.529384) (xy 218.795092 -402.522182) (xy 218.767443 -402.491454) (xy 218.7174 -402.425653)
			(xy 218.673673 -402.355495) (xy 218.636638 -402.281587) (xy 218.606614 -402.204563) (xy 218.58386 -402.125088)
			(xy 218.568571 -402.043846) (xy 218.56088 -401.961536) (xy 218.560396 -401.920202) (xy 218.560852 -401.878866)
			(xy 218.568524 -401.796552) (xy 218.583803 -401.715304) (xy 218.606556 -401.635826) (xy 218.636588 -401.558802)
			(xy 218.673638 -401.484897) (xy 218.717388 -401.414751) (xy 218.767459 -401.348967) (xy 218.795092 -401.318222)
			(xy 218.801161 -401.310968) (xy 218.808066 -401.293378) (xy 218.808554 -401.283932) (xy 218.808554 -401.253452)
			(xy 218.808146 -401.243989) (xy 218.801239 -401.226367) (xy 218.795092 -401.219162) (xy 218.767482 -401.1884)
			(xy 218.717436 -401.122604) (xy 218.673705 -401.052453) (xy 218.636666 -400.978549) (xy 218.606637 -400.90153)
			(xy 218.583877 -400.82206) (xy 218.568582 -400.740821) (xy 218.560883 -400.658515) (xy 218.560396 -400.617182)
			(xy 218.560896 -400.576069) (xy 218.568484 -400.494193) (xy 218.583594 -400.413367) (xy 218.606097 -400.334279)
			(xy 218.635801 -400.257605) (xy 218.672453 -400.183999) (xy 218.715739 -400.114089) (xy 218.765291 -400.04847)
			(xy 218.820686 -399.987703) (xy 218.881451 -399.932307) (xy 218.947069 -399.882753) (xy 219.016978 -399.839464)
			(xy 219.090583 -399.802811) (xy 219.167256 -399.773105) (xy 219.246343 -399.7506) (xy 219.327169 -399.735487)
			(xy 219.409045 -399.727897) (xy 219.450158 -399.72742) (xy 219.494662 -399.727949) (xy 219.583226 -399.736844)
			(xy 219.670458 -399.754538) (xy 219.755487 -399.780856) (xy 219.837463 -399.815534) (xy 219.915565 -399.858225)
			(xy 219.989014 -399.908502) (xy 220.057075 -399.965864) (xy 220.08846 -399.997422) (xy 220.095931 -400.004447)
			(xy 220.114793 -400.012446) (xy 220.125036 -400.012916) (xy 220.19768 -400.012916) (xy 220.207931 -400.012475)
			(xy 220.226805 -400.004477) (xy 220.234256 -399.997422) (xy 220.265663 -399.965886) (xy 220.333719 -399.908523)
			(xy 220.407164 -399.858243) (xy 220.485263 -399.81555) (xy 220.567236 -399.780871) (xy 220.652263 -399.754552)
			(xy 220.739493 -399.736858) (xy 220.828055 -399.727964) (xy 220.872558 -399.72742) (xy 220.916049 -399.727926)
			(xy 221.002612 -399.736439) (xy 221.087932 -399.75336) (xy 221.171193 -399.778526) (xy 221.251601 -399.811696)
			(xy 221.328388 -399.852556) (xy 221.400821 -399.900714) (xy 221.468209 -399.95571) (xy 221.49943 -399.985992)
			(xy 221.499684 -399.986246) (xy 221.507078 -399.992808) (xy 221.525369 -400.000258) (xy 221.535244 -400.000724)
			(xy 221.606872 -400.000724) (xy 221.616751 -400.000273) (xy 221.63505 -399.992827) (xy 221.642432 -399.986246)
			(xy 221.642686 -399.985992) (xy 221.673904 -399.955708) (xy 221.741295 -399.900719) (xy 221.81373 -399.852567)
			(xy 221.890518 -399.811713) (xy 221.970927 -399.778547) (xy 222.054187 -399.753386) (xy 222.139506 -399.736469)
			(xy 222.226068 -399.727958) (xy 222.269558 -399.72742) (xy 222.310672 -399.727938) (xy 222.392549 -399.735522)
			(xy 222.473376 -399.750627) (xy 222.552466 -399.773127) (xy 222.629142 -399.802827) (xy 222.70275 -399.839476)
			(xy 222.772663 -399.882761) (xy 222.838283 -399.932312) (xy 222.899052 -399.987706) (xy 222.95445 -400.04847)
			(xy 223.004005 -400.114088) (xy 223.047294 -400.183998) (xy 223.083948 -400.257603) (xy 223.113654 -400.334277)
			(xy 223.136159 -400.413365) (xy 223.15127 -400.494192) (xy 223.158859 -400.576068) (xy 223.15932 -400.617182)
			(xy 223.15885 -400.658517) (xy 223.151179 -400.740831) (xy 223.135902 -400.822078) (xy 223.113151 -400.901557)
			(xy 223.083121 -400.978581) (xy 223.046073 -401.052485) (xy 223.002325 -401.122632) (xy 222.952256 -401.188416)
			(xy 222.924624 -401.219162) (xy 222.918551 -401.226413) (xy 222.911651 -401.244006) (xy 222.911162 -401.253452)
			(xy 222.911162 -401.283932) (xy 222.911549 -401.293397) (xy 222.918473 -401.311017) (xy 222.924624 -401.318222)
			(xy 222.95226 -401.348962) (xy 223.002306 -401.41476) (xy 223.046036 -401.484914) (xy 223.083073 -401.558821)
			(xy 223.113099 -401.635843) (xy 223.135855 -401.715317) (xy 223.151145 -401.796559) (xy 223.158837 -401.878868)
			(xy 223.15932 -401.920202) (xy 223.158863 -401.961538) (xy 223.15119 -402.043852) (xy 223.135911 -402.125099)
			(xy 223.113158 -402.204578) (xy 223.083126 -402.281602) (xy 223.046076 -402.355506) (xy 223.002327 -402.425653)
			(xy 222.952257 -402.491437) (xy 222.924624 -402.522182) (xy 222.918543 -402.529427) (xy 222.911647 -402.547025)
			(xy 222.911162 -402.556472) (xy 222.911162 -402.586952) (xy 222.911589 -402.596413) (xy 222.918485 -402.614033)
			(xy 222.924624 -402.621242) (xy 222.952222 -402.652015) (xy 223.00227 -402.717808) (xy 223.046004 -402.787957)
			(xy 223.083046 -402.861859) (xy 223.113077 -402.938876) (xy 223.135838 -403.018346) (xy 223.151134 -403.099584)
			(xy 223.158833 -403.18189) (xy 223.15932 -403.223222) (xy 223.158801 -403.266183) (xy 223.150523 -403.351705)
			(xy 223.134036 -403.43603) (xy 223.109494 -403.518372) (xy 223.077125 -403.597963) (xy 223.037232 -403.674062)
			(xy 222.990186 -403.745959) (xy 222.936426 -403.812984) (xy 222.876453 -403.874513) (xy 222.810826 -403.929971)
			(xy 222.740156 -403.978842) (xy 222.702882 -404.000208) (xy 222.69473 -404.005265) (xy 222.682612 -404.020117)
			(xy 222.67676 -404.03837) (xy 222.676974 -404.04796) (xy 222.684086 -404.154386) (xy 222.701358 -404.178008)
			(xy 222.715328 -404.183342) (xy 222.753266 -404.198729) (xy 222.826382 -404.235572) (xy 222.895803 -404.27898)
			(xy 222.96094 -404.328584) (xy 223.021242 -404.383965) (xy 223.076199 -404.444654) (xy 223.125346 -404.510137)
			(xy 223.168266 -404.57986) (xy 223.204597 -404.653232) (xy 223.23403 -404.729633) (xy 223.256317 -404.808416)
			(xy 223.271269 -404.888913) (xy 223.278758 -404.970445) (xy 223.279208 -405.011382) (xy 223.278619 -405.057777)
			(xy 223.268976 -405.150066) (xy 223.249781 -405.240849) (xy 223.221245 -405.329143) (xy 223.203008 -405.371808)
			(xy 223.199213 -405.381753) (xy 223.199206 -405.403014) (xy 223.203008 -405.412956) (xy 223.221247 -405.455621)
			(xy 223.249792 -405.543912) (xy 223.268987 -405.634696) (xy 223.278622 -405.726986) (xy 223.279208 -405.773382)
			(xy 223.278619 -405.819777) (xy 223.268976 -405.912066) (xy 223.249781 -406.002849) (xy 223.221245 -406.091143)
			(xy 223.203008 -406.133808) (xy 223.199213 -406.143753) (xy 223.199206 -406.165014) (xy 223.203008 -406.174956)
			(xy 223.217234 -406.207876) (xy 223.240955 -406.275561) (xy 223.259136 -406.34494) (xy 223.265746 -406.380188)
			(xy 223.268055 -406.390309) (xy 223.279454 -406.407631) (xy 223.296772 -406.419037) (xy 223.306894 -406.421336)
			(xy 223.347556 -406.42906) (xy 223.42736 -406.451024) (xy 223.50478 -406.480305) (xy 223.579146 -406.51665)
			(xy 223.649814 -406.559745) (xy 223.716174 -406.609217) (xy 223.777652 -406.66464) (xy 223.833716 -406.725533)
			(xy 223.883883 -406.791369) (xy 223.927718 -406.861581) (xy 223.964841 -406.935561) (xy 223.994933 -407.012669)
			(xy 224.017733 -407.092239) (xy 224.033045 -407.173582) (xy 224.040734 -407.255996) (xy 224.041208 -407.297382)
			(xy 224.041208 -407.29789) (xy 224.040596 -407.344222) (xy 224.030926 -407.436379) (xy 224.011732 -407.527034)
			(xy 223.983222 -407.615202) (xy 223.965008 -407.657808) (xy 223.961213 -407.667753) (xy 223.961206 -407.689014)
			(xy 223.965008 -407.698956) (xy 223.983224 -407.741561) (xy 224.011743 -407.829728) (xy 224.030938 -407.920383)
			(xy 224.040599 -408.012542) (xy 224.041208 -408.058874) (xy 224.041208 -408.059382) (xy 224.041201 -408.05989)
			(xy 227.596192 -408.05989) (xy 227.596192 -408.059382) (xy 227.596717 -408.017997) (xy 227.604406 -407.935585)
			(xy 227.619716 -407.854244) (xy 227.642513 -407.774675) (xy 227.672602 -407.697568) (xy 227.709723 -407.623589)
			(xy 227.753553 -407.553377) (xy 227.803715 -407.487539) (xy 227.859774 -407.426645) (xy 227.921247 -407.37122)
			(xy 227.987602 -407.321743) (xy 228.058265 -407.278644) (xy 228.132625 -407.242293) (xy 228.21004 -407.213005)
			(xy 228.289841 -407.191034) (xy 228.330506 -407.183336) (xy 228.340634 -407.181051) (xy 228.357956 -407.169641)
			(xy 228.369359 -407.152314) (xy 228.371654 -407.142188) (xy 228.379393 -407.101149) (xy 228.401607 -407.020638)
			(xy 228.431268 -406.942562) (xy 228.468115 -406.86761) (xy 228.511825 -406.796441) (xy 228.562012 -406.729682)
			(xy 228.618235 -406.66792) (xy 228.679998 -406.611699) (xy 228.746759 -406.561513) (xy 228.817929 -406.517805)
			(xy 228.892881 -406.48096) (xy 228.970957 -406.4513) (xy 229.051469 -406.429089) (xy 229.092506 -406.421336)
			(xy 229.102634 -406.419051) (xy 229.119956 -406.407641) (xy 229.131359 -406.390314) (xy 229.133654 -406.380188)
			(xy 229.140281 -406.344944) (xy 229.158478 -406.275571) (xy 229.182186 -406.207884) (xy 229.196392 -406.174956)
			(xy 229.200208 -406.165017) (xy 229.200201 -406.14375) (xy 229.196392 -406.133808) (xy 229.178141 -406.091148)
			(xy 229.149599 -406.002855) (xy 229.130407 -405.912069) (xy 229.120776 -405.819778) (xy 229.120192 -405.773382)
			(xy 229.120769 -405.726986) (xy 229.130415 -405.634698) (xy 229.149613 -405.543914) (xy 229.178153 -405.455621)
			(xy 229.196392 -405.412956) (xy 229.200208 -405.403017) (xy 229.200201 -405.38175) (xy 229.196392 -405.371808)
			(xy 229.178164 -405.329208) (xy 229.149648 -405.241039) (xy 229.130457 -405.150383) (xy 229.120799 -405.058222)
			(xy 229.120192 -405.01189) (xy 229.120192 -405.011382) (xy 229.120669 -404.970705) (xy 229.128097 -404.889692)
			(xy 229.14289 -404.809694) (xy 229.164923 -404.731381) (xy 229.194013 -404.655407) (xy 229.229918 -404.582405)
			(xy 229.272336 -404.512985) (xy 229.320914 -404.447728) (xy 229.375247 -404.387177) (xy 229.43488 -404.33184)
			(xy 229.499316 -404.282176) (xy 229.568016 -404.238603) (xy 229.640407 -404.201482) (xy 229.677976 -404.185882)
			(xy 229.686795 -404.181969) (xy 229.700833 -404.168752) (xy 229.708997 -404.151285) (xy 229.70998 -404.141686)
			(xy 229.715314 -404.049992) (xy 229.715428 -404.040421) (xy 229.709477 -404.022248) (xy 229.697313 -404.007492)
			(xy 229.689152 -404.002494) (xy 229.651554 -403.981253) (xy 229.580288 -403.932477) (xy 229.514083 -403.877025)
			(xy 229.453561 -403.81542) (xy 229.399292 -403.748241) (xy 229.351788 -403.67612) (xy 229.311493 -403.599737)
			(xy 229.278789 -403.519809) (xy 229.253982 -403.437088) (xy 229.237306 -403.352354) (xy 229.228918 -403.266402)
			(xy 229.228396 -403.223222) (xy 229.228864 -403.181887) (xy 229.236535 -403.099572) (xy 229.251812 -403.018325)
			(xy 229.274564 -402.938847) (xy 229.304593 -402.861823) (xy 229.341642 -402.787918) (xy 229.38539 -402.717771)
			(xy 229.435459 -402.651987) (xy 229.463092 -402.621242) (xy 229.469153 -402.613982) (xy 229.476063 -402.596396)
			(xy 229.476554 -402.586952) (xy 229.476554 -402.556472) (xy 229.476185 -402.547004) (xy 229.469251 -402.529384)
			(xy 229.463092 -402.522182) (xy 229.435443 -402.491454) (xy 229.3854 -402.425653) (xy 229.341673 -402.355495)
			(xy 229.304638 -402.281587) (xy 229.274614 -402.204563) (xy 229.25186 -402.125088) (xy 229.236571 -402.043846)
			(xy 229.22888 -401.961536) (xy 229.228396 -401.920202) (xy 229.228852 -401.878866) (xy 229.236524 -401.796552)
			(xy 229.251803 -401.715304) (xy 229.274556 -401.635826) (xy 229.304588 -401.558802) (xy 229.341638 -401.484897)
			(xy 229.385388 -401.414751) (xy 229.435459 -401.348967) (xy 229.463092 -401.318222) (xy 229.469161 -401.310968)
			(xy 229.476066 -401.293378) (xy 229.476554 -401.283932) (xy 229.476554 -401.253452) (xy 229.476146 -401.243989)
			(xy 229.469239 -401.226367) (xy 229.463092 -401.219162) (xy 229.435482 -401.1884) (xy 229.385436 -401.122604)
			(xy 229.341705 -401.052453) (xy 229.304666 -400.978549) (xy 229.274637 -400.90153) (xy 229.251877 -400.82206)
			(xy 229.236582 -400.740821) (xy 229.228883 -400.658515) (xy 229.228396 -400.617182) (xy 229.228896 -400.576069)
			(xy 229.236484 -400.494193) (xy 229.251594 -400.413367) (xy 229.274097 -400.334279) (xy 229.303801 -400.257605)
			(xy 229.340453 -400.183999) (xy 229.383739 -400.114089) (xy 229.433291 -400.04847) (xy 229.488686 -399.987703)
			(xy 229.549451 -399.932307) (xy 229.615069 -399.882753) (xy 229.684978 -399.839464) (xy 229.758583 -399.802811)
			(xy 229.835256 -399.773105) (xy 229.914343 -399.7506) (xy 229.995169 -399.735487) (xy 230.077045 -399.727897)
			(xy 230.118158 -399.72742) (xy 230.162662 -399.727949) (xy 230.251226 -399.736844) (xy 230.338458 -399.754538)
			(xy 230.423487 -399.780856) (xy 230.505463 -399.815534) (xy 230.583565 -399.858225) (xy 230.657014 -399.908502)
			(xy 230.725075 -399.965864) (xy 230.75646 -399.997422) (xy 230.763931 -400.004447) (xy 230.782793 -400.012446)
			(xy 230.793036 -400.012916) (xy 230.86568 -400.012916) (xy 230.875931 -400.012475) (xy 230.894805 -400.004477)
			(xy 230.902256 -399.997422) (xy 230.933663 -399.965886) (xy 231.001719 -399.908523) (xy 231.075164 -399.858243)
			(xy 231.153263 -399.81555) (xy 231.235236 -399.780871) (xy 231.320263 -399.754552) (xy 231.407493 -399.736858)
			(xy 231.496055 -399.727964) (xy 231.540558 -399.72742) (xy 231.584049 -399.727926) (xy 231.670612 -399.736439)
			(xy 231.755932 -399.75336) (xy 231.839193 -399.778526) (xy 231.919601 -399.811696) (xy 231.996388 -399.852556)
			(xy 232.068821 -399.900714) (xy 232.136209 -399.95571) (xy 232.16743 -399.985992) (xy 232.167684 -399.986246)
			(xy 232.175078 -399.992808) (xy 232.193369 -400.000258) (xy 232.203244 -400.000724) (xy 232.274872 -400.000724)
			(xy 232.284751 -400.000273) (xy 232.30305 -399.992827) (xy 232.310432 -399.986246) (xy 232.310686 -399.985992)
			(xy 232.341904 -399.955708) (xy 232.409295 -399.900719) (xy 232.48173 -399.852567) (xy 232.558518 -399.811713)
			(xy 232.638927 -399.778547) (xy 232.722187 -399.753386) (xy 232.807506 -399.736469) (xy 232.894068 -399.727958)
			(xy 232.937558 -399.72742) (xy 232.978672 -399.727938) (xy 233.060549 -399.735522) (xy 233.141376 -399.750627)
			(xy 233.220466 -399.773127) (xy 233.297142 -399.802827) (xy 233.37075 -399.839476) (xy 233.440663 -399.882761)
			(xy 233.506283 -399.932312) (xy 233.567052 -399.987706) (xy 233.62245 -400.04847) (xy 233.672005 -400.114088)
			(xy 233.715294 -400.183998) (xy 233.751948 -400.257603) (xy 233.781654 -400.334277) (xy 233.804159 -400.413365)
			(xy 233.81927 -400.494192) (xy 233.826859 -400.576068) (xy 233.82732 -400.617182) (xy 233.82685 -400.658517)
			(xy 233.819179 -400.740831) (xy 233.803902 -400.822078) (xy 233.781151 -400.901557) (xy 233.751121 -400.978581)
			(xy 233.714073 -401.052485) (xy 233.670325 -401.122632) (xy 233.620256 -401.188416) (xy 233.592624 -401.219162)
			(xy 233.586551 -401.226413) (xy 233.579651 -401.244006) (xy 233.579162 -401.253452) (xy 233.579162 -401.283932)
			(xy 233.579549 -401.293397) (xy 233.586473 -401.311017) (xy 233.592624 -401.318222) (xy 233.62026 -401.348962)
			(xy 233.670306 -401.41476) (xy 233.714036 -401.484914) (xy 233.751073 -401.558821) (xy 233.781099 -401.635843)
			(xy 233.803855 -401.715317) (xy 233.819145 -401.796559) (xy 233.826837 -401.878868) (xy 233.82732 -401.920202)
			(xy 233.826863 -401.961538) (xy 233.81919 -402.043852) (xy 233.803911 -402.125099) (xy 233.781158 -402.204578)
			(xy 233.751126 -402.281602) (xy 233.714076 -402.355506) (xy 233.670327 -402.425653) (xy 233.620257 -402.491437)
			(xy 233.592624 -402.522182) (xy 233.586543 -402.529427) (xy 233.579647 -402.547025) (xy 233.579162 -402.556472)
			(xy 233.579162 -402.586952) (xy 233.579589 -402.596413) (xy 233.586485 -402.614033) (xy 233.592624 -402.621242)
			(xy 233.620222 -402.652015) (xy 233.67027 -402.717808) (xy 233.714004 -402.787957) (xy 233.751046 -402.861859)
			(xy 233.781077 -402.938876) (xy 233.803838 -403.018346) (xy 233.819134 -403.099584) (xy 233.826833 -403.18189)
			(xy 233.82732 -403.223222) (xy 233.826801 -403.266183) (xy 233.818523 -403.351705) (xy 233.802036 -403.43603)
			(xy 233.777494 -403.518372) (xy 233.745125 -403.597963) (xy 233.705232 -403.674062) (xy 233.658186 -403.745959)
			(xy 233.604426 -403.812984) (xy 233.544453 -403.874513) (xy 233.478826 -403.929971) (xy 233.408156 -403.978842)
			(xy 233.370882 -404.000208) (xy 233.36273 -404.005265) (xy 233.350612 -404.020117) (xy 233.34476 -404.03837)
			(xy 233.344974 -404.04796) (xy 233.352086 -404.154386) (xy 233.369358 -404.178008) (xy 233.383328 -404.183342)
			(xy 233.421266 -404.198729) (xy 233.494382 -404.235572) (xy 233.563803 -404.27898) (xy 233.62894 -404.328584)
			(xy 233.689242 -404.383965) (xy 233.744199 -404.444654) (xy 233.793346 -404.510137) (xy 233.836266 -404.57986)
			(xy 233.872597 -404.653232) (xy 233.90203 -404.729633) (xy 233.924317 -404.808416) (xy 233.939269 -404.888913)
			(xy 233.946758 -404.970445) (xy 233.947208 -405.011382) (xy 233.946619 -405.057777) (xy 233.936976 -405.150066)
			(xy 233.917781 -405.240849) (xy 233.889245 -405.329143) (xy 233.871008 -405.371808) (xy 233.867213 -405.381753)
			(xy 233.867206 -405.403014) (xy 233.871008 -405.412956) (xy 233.889247 -405.455621) (xy 233.917792 -405.543912)
			(xy 233.936987 -405.634696) (xy 233.946622 -405.726986) (xy 233.947208 -405.773382) (xy 233.946619 -405.819777)
			(xy 233.936976 -405.912066) (xy 233.917781 -406.002849) (xy 233.889245 -406.091143) (xy 233.871008 -406.133808)
			(xy 233.867213 -406.143753) (xy 233.867206 -406.165014) (xy 233.871008 -406.174956) (xy 233.885234 -406.207876)
			(xy 233.908955 -406.275561) (xy 233.927136 -406.34494) (xy 233.933746 -406.380188) (xy 233.936055 -406.390309)
			(xy 233.947454 -406.407631) (xy 233.964772 -406.419037) (xy 233.974894 -406.421336) (xy 234.015556 -406.42906)
			(xy 234.09536 -406.451024) (xy 234.17278 -406.480305) (xy 234.247146 -406.51665) (xy 234.317814 -406.559745)
			(xy 234.384174 -406.609217) (xy 234.445652 -406.66464) (xy 234.501716 -406.725533) (xy 234.551883 -406.791369)
			(xy 234.595718 -406.861581) (xy 234.632841 -406.935561) (xy 234.662933 -407.012669) (xy 234.685733 -407.092239)
			(xy 234.701045 -407.173582) (xy 234.708734 -407.255996) (xy 234.709208 -407.297382) (xy 234.709208 -407.29789)
			(xy 234.708596 -407.344222) (xy 234.698926 -407.436379) (xy 234.679732 -407.527034) (xy 234.651222 -407.615202)
			(xy 234.633008 -407.657808) (xy 234.629213 -407.667753) (xy 234.629206 -407.689014) (xy 234.633008 -407.698956)
			(xy 234.651224 -407.741561) (xy 234.679743 -407.829728) (xy 234.698938 -407.920383) (xy 234.708599 -408.012542)
			(xy 234.709208 -408.058874) (xy 234.709208 -408.059382) (xy 234.70867 -408.100487) (xy 234.701088 -408.182347)
			(xy 234.685987 -408.263158) (xy 234.663495 -408.342232) (xy 234.633804 -408.418893) (xy 234.597168 -408.492489)
			(xy 234.5539 -408.562391) (xy 234.504367 -408.628004) (xy 234.448992 -408.688767) (xy 234.388249 -408.744164)
			(xy 234.322654 -408.79372) (xy 234.252767 -408.837014) (xy 234.179184 -408.873676) (xy 234.102533 -408.903394)
			(xy 234.023468 -408.925914) (xy 233.942662 -408.941044) (xy 233.860805 -408.948656) (xy 233.8197 -408.949144)
			(xy 233.773298 -408.948515) (xy 233.681001 -408.938826) (xy 233.590215 -408.919572) (xy 233.50193 -408.890965)
			(xy 233.459274 -408.87269) (xy 233.449332 -408.868884) (xy 233.428068 -408.868884) (xy 233.418126 -408.87269)
			(xy 233.375466 -408.890954) (xy 233.287177 -408.919546) (xy 233.196394 -408.938803) (xy 233.104101 -408.948515)
			(xy 233.0577 -408.949144) (xy 233.011298 -408.948515) (xy 232.919001 -408.938826) (xy 232.828215 -408.919572)
			(xy 232.73993 -408.890965) (xy 232.697274 -408.87269) (xy 232.687332 -408.868884) (xy 232.666068 -408.868884)
			(xy 232.656126 -408.87269) (xy 232.613466 -408.890954) (xy 232.525177 -408.919546) (xy 232.434394 -408.938803)
			(xy 232.342101 -408.948515) (xy 232.2957 -408.949144) (xy 232.249298 -408.948515) (xy 232.157001 -408.938826)
			(xy 232.066215 -408.919572) (xy 231.97793 -408.890965) (xy 231.935274 -408.87269) (xy 231.925332 -408.868884)
			(xy 231.904068 -408.868884) (xy 231.894126 -408.87269) (xy 231.851466 -408.890954) (xy 231.763177 -408.919546)
			(xy 231.672394 -408.938803) (xy 231.580101 -408.948515) (xy 231.5337 -408.949144) (xy 231.487298 -408.948515)
			(xy 231.395001 -408.938826) (xy 231.304215 -408.919572) (xy 231.21593 -408.890965) (xy 231.173274 -408.87269)
			(xy 231.163332 -408.868884) (xy 231.142068 -408.868884) (xy 231.132126 -408.87269) (xy 231.089466 -408.890954)
			(xy 231.001177 -408.919546) (xy 230.910394 -408.938803) (xy 230.818101 -408.948515) (xy 230.7717 -408.949144)
			(xy 230.725298 -408.948515) (xy 230.633001 -408.938826) (xy 230.542215 -408.919572) (xy 230.45393 -408.890965)
			(xy 230.411274 -408.87269) (xy 230.401332 -408.868884) (xy 230.380068 -408.868884) (xy 230.370126 -408.87269)
			(xy 230.327466 -408.890954) (xy 230.239177 -408.919546) (xy 230.148394 -408.938803) (xy 230.056101 -408.948515)
			(xy 230.0097 -408.949144) (xy 229.963298 -408.948515) (xy 229.871001 -408.938826) (xy 229.780215 -408.919572)
			(xy 229.69193 -408.890965) (xy 229.649274 -408.87269) (xy 229.639332 -408.868884) (xy 229.618068 -408.868884)
			(xy 229.608126 -408.87269) (xy 229.565466 -408.890954) (xy 229.477177 -408.919546) (xy 229.386394 -408.938803)
			(xy 229.294101 -408.948515) (xy 229.2477 -408.949144) (xy 229.201298 -408.948515) (xy 229.109001 -408.938826)
			(xy 229.018215 -408.919572) (xy 228.92993 -408.890965) (xy 228.887274 -408.87269) (xy 228.877332 -408.868884)
			(xy 228.856068 -408.868884) (xy 228.846126 -408.87269) (xy 228.803466 -408.890954) (xy 228.715177 -408.919546)
			(xy 228.624394 -408.938803) (xy 228.532101 -408.948515) (xy 228.4857 -408.949144) (xy 228.444606 -408.948634)
			(xy 228.362769 -408.941052) (xy 228.281979 -408.925953) (xy 228.202928 -408.903466) (xy 228.126287 -408.873782)
			(xy 228.052712 -408.837155) (xy 227.98283 -408.793896) (xy 227.917236 -408.744376) (xy 227.85649 -408.689016)
			(xy 227.801109 -408.628288) (xy 227.751568 -408.56271) (xy 227.708286 -408.492841) (xy 227.671635 -408.419278)
			(xy 227.641926 -408.342647) (xy 227.619413 -408.263603) (xy 227.604288 -408.182819) (xy 227.59668 -408.100984)
			(xy 227.596192 -408.05989) (xy 224.041201 -408.05989) (xy 224.04067 -408.100487) (xy 224.033088 -408.182347)
			(xy 224.017987 -408.263158) (xy 223.995495 -408.342232) (xy 223.965804 -408.418893) (xy 223.929168 -408.492489)
			(xy 223.8859 -408.562391) (xy 223.836367 -408.628004) (xy 223.780992 -408.688767) (xy 223.720249 -408.744164)
			(xy 223.654654 -408.79372) (xy 223.584767 -408.837014) (xy 223.511184 -408.873676) (xy 223.434533 -408.903394)
			(xy 223.355468 -408.925914) (xy 223.274662 -408.941044) (xy 223.192805 -408.948656) (xy 223.1517 -408.949144)
			(xy 223.105298 -408.948515) (xy 223.013001 -408.938826) (xy 222.922215 -408.919572) (xy 222.83393 -408.890965)
			(xy 222.791274 -408.87269) (xy 222.781332 -408.868884) (xy 222.760068 -408.868884) (xy 222.750126 -408.87269)
			(xy 222.707466 -408.890954) (xy 222.619177 -408.919546) (xy 222.528394 -408.938803) (xy 222.436101 -408.948515)
			(xy 222.3897 -408.949144) (xy 222.343298 -408.948515) (xy 222.251001 -408.938826) (xy 222.160215 -408.919572)
			(xy 222.07193 -408.890965) (xy 222.029274 -408.87269) (xy 222.019332 -408.868884) (xy 221.998068 -408.868884)
			(xy 221.988126 -408.87269) (xy 221.945466 -408.890954) (xy 221.857177 -408.919546) (xy 221.766394 -408.938803)
			(xy 221.674101 -408.948515) (xy 221.6277 -408.949144) (xy 221.581298 -408.948515) (xy 221.489001 -408.938826)
			(xy 221.398215 -408.919572) (xy 221.30993 -408.890965) (xy 221.267274 -408.87269) (xy 221.257332 -408.868884)
			(xy 221.236068 -408.868884) (xy 221.226126 -408.87269) (xy 221.183466 -408.890954) (xy 221.095177 -408.919546)
			(xy 221.004394 -408.938803) (xy 220.912101 -408.948515) (xy 220.8657 -408.949144) (xy 220.819298 -408.948515)
			(xy 220.727001 -408.938826) (xy 220.636215 -408.919572) (xy 220.54793 -408.890965) (xy 220.505274 -408.87269)
			(xy 220.495332 -408.868884) (xy 220.474068 -408.868884) (xy 220.464126 -408.87269) (xy 220.421466 -408.890954)
			(xy 220.333177 -408.919546) (xy 220.242394 -408.938803) (xy 220.150101 -408.948515) (xy 220.1037 -408.949144)
			(xy 220.057298 -408.948515) (xy 219.965001 -408.938826) (xy 219.874215 -408.919572) (xy 219.78593 -408.890965)
			(xy 219.743274 -408.87269) (xy 219.733332 -408.868884) (xy 219.712068 -408.868884) (xy 219.702126 -408.87269)
			(xy 219.659466 -408.890954) (xy 219.571177 -408.919546) (xy 219.480394 -408.938803) (xy 219.388101 -408.948515)
			(xy 219.3417 -408.949144) (xy 219.295298 -408.948515) (xy 219.203001 -408.938826) (xy 219.112215 -408.919572)
			(xy 219.02393 -408.890965) (xy 218.981274 -408.87269) (xy 218.971332 -408.868884) (xy 218.950068 -408.868884)
			(xy 218.940126 -408.87269) (xy 218.897466 -408.890954) (xy 218.809177 -408.919546) (xy 218.718394 -408.938803)
			(xy 218.626101 -408.948515) (xy 218.5797 -408.949144) (xy 218.533298 -408.948515) (xy 218.441001 -408.938826)
			(xy 218.350215 -408.919572) (xy 218.26193 -408.890965) (xy 218.219274 -408.87269) (xy 218.209332 -408.868884)
			(xy 218.188068 -408.868884) (xy 218.178126 -408.87269) (xy 218.135466 -408.890954) (xy 218.047177 -408.919546)
			(xy 217.956394 -408.938803) (xy 217.864101 -408.948515) (xy 217.8177 -408.949144) (xy 217.776606 -408.948634)
			(xy 217.694769 -408.941052) (xy 217.613979 -408.925953) (xy 217.534928 -408.903466) (xy 217.458287 -408.873782)
			(xy 217.384712 -408.837155) (xy 217.31483 -408.793896) (xy 217.249236 -408.744376) (xy 217.18849 -408.689016)
			(xy 217.133109 -408.628288) (xy 217.083568 -408.56271) (xy 217.040286 -408.492841) (xy 217.003635 -408.419278)
			(xy 216.973926 -408.342647) (xy 216.951413 -408.263603) (xy 216.936288 -408.182819) (xy 216.92868 -408.100984)
			(xy 216.928192 -408.05989) (xy 213.373201 -408.05989) (xy 213.37267 -408.100487) (xy 213.365088 -408.182347)
			(xy 213.349987 -408.263158) (xy 213.327495 -408.342232) (xy 213.297804 -408.418893) (xy 213.261168 -408.492489)
			(xy 213.2179 -408.562391) (xy 213.168367 -408.628004) (xy 213.112992 -408.688767) (xy 213.052249 -408.744164)
			(xy 212.986654 -408.79372) (xy 212.916767 -408.837014) (xy 212.843184 -408.873676) (xy 212.766533 -408.903394)
			(xy 212.687468 -408.925914) (xy 212.606662 -408.941044) (xy 212.524805 -408.948656) (xy 212.4837 -408.949144)
			(xy 212.437298 -408.948515) (xy 212.345001 -408.938826) (xy 212.254215 -408.919572) (xy 212.16593 -408.890965)
			(xy 212.123274 -408.87269) (xy 212.113332 -408.868884) (xy 212.092068 -408.868884) (xy 212.082126 -408.87269)
			(xy 212.039466 -408.890954) (xy 211.951177 -408.919546) (xy 211.860394 -408.938803) (xy 211.768101 -408.948515)
			(xy 211.7217 -408.949144) (xy 211.675298 -408.948515) (xy 211.583001 -408.938826) (xy 211.492215 -408.919572)
			(xy 211.40393 -408.890965) (xy 211.361274 -408.87269) (xy 211.351332 -408.868884) (xy 211.330068 -408.868884)
			(xy 211.320126 -408.87269) (xy 211.277466 -408.890954) (xy 211.189177 -408.919546) (xy 211.098394 -408.938803)
			(xy 211.006101 -408.948515) (xy 210.9597 -408.949144) (xy 210.913298 -408.948515) (xy 210.821001 -408.938826)
			(xy 210.730215 -408.919572) (xy 210.64193 -408.890965) (xy 210.599274 -408.87269) (xy 210.589332 -408.868884)
			(xy 210.568068 -408.868884) (xy 210.558126 -408.87269) (xy 210.515466 -408.890954) (xy 210.427177 -408.919546)
			(xy 210.336394 -408.938803) (xy 210.244101 -408.948515) (xy 210.1977 -408.949144) (xy 210.151298 -408.948515)
			(xy 210.059001 -408.938826) (xy 209.968215 -408.919572) (xy 209.87993 -408.890965) (xy 209.837274 -408.87269)
			(xy 209.827332 -408.868884) (xy 209.806068 -408.868884) (xy 209.796126 -408.87269) (xy 209.753466 -408.890954)
			(xy 209.665177 -408.919546) (xy 209.574394 -408.938803) (xy 209.482101 -408.948515) (xy 209.4357 -408.949144)
			(xy 209.389298 -408.948515) (xy 209.297001 -408.938826) (xy 209.206215 -408.919572) (xy 209.11793 -408.890965)
			(xy 209.075274 -408.87269) (xy 209.065332 -408.868884) (xy 209.044068 -408.868884) (xy 209.034126 -408.87269)
			(xy 208.991466 -408.890954) (xy 208.903177 -408.919546) (xy 208.812394 -408.938803) (xy 208.720101 -408.948515)
			(xy 208.6737 -408.949144) (xy 208.627298 -408.948515) (xy 208.535001 -408.938826) (xy 208.444215 -408.919572)
			(xy 208.35593 -408.890965) (xy 208.313274 -408.87269) (xy 208.303332 -408.868884) (xy 208.282068 -408.868884)
			(xy 208.272126 -408.87269) (xy 208.229466 -408.890954) (xy 208.141177 -408.919546) (xy 208.050394 -408.938803)
			(xy 207.958101 -408.948515) (xy 207.9117 -408.949144) (xy 207.865298 -408.948515) (xy 207.773001 -408.938826)
			(xy 207.682215 -408.919572) (xy 207.59393 -408.890965) (xy 207.551274 -408.87269) (xy 207.541332 -408.868884)
			(xy 207.520068 -408.868884) (xy 207.510126 -408.87269) (xy 207.467466 -408.890954) (xy 207.379177 -408.919546)
			(xy 207.288394 -408.938803) (xy 207.196101 -408.948515) (xy 207.1497 -408.949144) (xy 207.108606 -408.948634)
			(xy 207.026769 -408.941052) (xy 206.945979 -408.925953) (xy 206.866928 -408.903466) (xy 206.790287 -408.873782)
			(xy 206.716712 -408.837155) (xy 206.64683 -408.793896) (xy 206.581236 -408.744376) (xy 206.52049 -408.689016)
			(xy 206.465109 -408.628288) (xy 206.415568 -408.56271) (xy 206.372286 -408.492841) (xy 206.335635 -408.419278)
			(xy 206.305926 -408.342647) (xy 206.283413 -408.263603) (xy 206.268288 -408.182819) (xy 206.26068 -408.100984)
			(xy 206.260192 -408.05989) (xy 201.943201 -408.05989) (xy 201.94267 -408.100487) (xy 201.935088 -408.182347)
			(xy 201.919987 -408.263158) (xy 201.897495 -408.342232) (xy 201.867804 -408.418893) (xy 201.831168 -408.492489)
			(xy 201.7879 -408.562391) (xy 201.738367 -408.628004) (xy 201.682992 -408.688767) (xy 201.622249 -408.744164)
			(xy 201.556654 -408.79372) (xy 201.486767 -408.837014) (xy 201.413184 -408.873676) (xy 201.336533 -408.903394)
			(xy 201.257468 -408.925914) (xy 201.176662 -408.941044) (xy 201.094805 -408.948656) (xy 201.0537 -408.949144)
			(xy 201.007298 -408.948515) (xy 200.915001 -408.938826) (xy 200.824215 -408.919572) (xy 200.73593 -408.890965)
			(xy 200.693274 -408.87269) (xy 200.683332 -408.868884) (xy 200.662068 -408.868884) (xy 200.652126 -408.87269)
			(xy 200.609466 -408.890954) (xy 200.521177 -408.919546) (xy 200.430394 -408.938803) (xy 200.338101 -408.948515)
			(xy 200.2917 -408.949144) (xy 200.245298 -408.948515) (xy 200.153001 -408.938826) (xy 200.062215 -408.919572)
			(xy 199.97393 -408.890965) (xy 199.931274 -408.87269) (xy 199.921332 -408.868884) (xy 199.900068 -408.868884)
			(xy 199.890126 -408.87269) (xy 199.847466 -408.890954) (xy 199.759177 -408.919546) (xy 199.668394 -408.938803)
			(xy 199.576101 -408.948515) (xy 199.5297 -408.949144) (xy 199.483298 -408.948515) (xy 199.391001 -408.938826)
			(xy 199.300215 -408.919572) (xy 199.21193 -408.890965) (xy 199.169274 -408.87269) (xy 199.159332 -408.868884)
			(xy 199.138068 -408.868884) (xy 199.128126 -408.87269) (xy 199.085466 -408.890954) (xy 198.997177 -408.919546)
			(xy 198.906394 -408.938803) (xy 198.814101 -408.948515) (xy 198.7677 -408.949144) (xy 198.721298 -408.948515)
			(xy 198.629001 -408.938826) (xy 198.538215 -408.919572) (xy 198.44993 -408.890965) (xy 198.407274 -408.87269)
			(xy 198.397332 -408.868884) (xy 198.376068 -408.868884) (xy 198.366126 -408.87269) (xy 198.323466 -408.890954)
			(xy 198.235177 -408.919546) (xy 198.144394 -408.938803) (xy 198.052101 -408.948515) (xy 198.0057 -408.949144)
			(xy 197.959298 -408.948515) (xy 197.867001 -408.938826) (xy 197.776215 -408.919572) (xy 197.68793 -408.890965)
			(xy 197.645274 -408.87269) (xy 197.635332 -408.868884) (xy 197.614068 -408.868884) (xy 197.604126 -408.87269)
			(xy 197.561466 -408.890954) (xy 197.473177 -408.919546) (xy 197.382394 -408.938803) (xy 197.290101 -408.948515)
			(xy 197.2437 -408.949144) (xy 197.20259 -408.948648) (xy 197.120722 -408.94106) (xy 197.039903 -408.92595)
			(xy 196.960824 -408.903446) (xy 196.884158 -408.873741) (xy 196.810562 -408.837087) (xy 196.740661 -408.793799)
			(xy 196.675054 -408.744244) (xy 196.6143 -408.688846) (xy 196.558917 -408.628078) (xy 196.509378 -408.562459)
			(xy 196.466106 -408.492548) (xy 196.429471 -408.418942) (xy 196.399784 -408.342269) (xy 196.3773 -408.263184)
			(xy 196.36221 -408.182362) (xy 196.354642 -408.100492) (xy 196.354192 -408.059382) (xy 190.372573 -408.059382)
			(xy 190.373 -408.091894) (xy 190.373 -408.092402) (xy 190.372489 -408.133508) (xy 190.364905 -408.215368)
			(xy 190.349802 -408.296181) (xy 190.327308 -408.375255) (xy 190.297616 -408.451917) (xy 190.260978 -408.525513)
			(xy 190.217707 -408.595415) (xy 190.168173 -408.661028) (xy 190.112797 -408.721791) (xy 190.052051 -408.777187)
			(xy 189.986455 -408.826743) (xy 189.916566 -408.870037) (xy 189.842982 -408.906699) (xy 189.76633 -408.936416)
			(xy 189.687263 -408.958936) (xy 189.606456 -408.974065) (xy 189.524598 -408.981676) (xy 189.483492 -408.982164)
			(xy 189.43709 -408.981537) (xy 189.344793 -408.971846) (xy 189.254007 -408.952593) (xy 189.165722 -408.923985)
			(xy 189.123066 -408.90571) (xy 189.113124 -408.901904) (xy 189.09186 -408.901904) (xy 189.081918 -408.90571)
			(xy 189.039259 -408.923977) (xy 188.95097 -408.952569) (xy 188.860187 -408.971824) (xy 188.767893 -408.981535)
			(xy 188.721492 -408.982164) (xy 188.67509 -408.981537) (xy 188.582793 -408.971846) (xy 188.492007 -408.952593)
			(xy 188.403722 -408.923985) (xy 188.361066 -408.90571) (xy 188.351124 -408.901904) (xy 188.32986 -408.901904)
			(xy 188.319918 -408.90571) (xy 188.277259 -408.923977) (xy 188.18897 -408.952569) (xy 188.098187 -408.971824)
			(xy 188.005893 -408.981535) (xy 187.959492 -408.982164) (xy 187.91309 -408.981537) (xy 187.820793 -408.971846)
			(xy 187.730007 -408.952593) (xy 187.641722 -408.923985) (xy 187.599066 -408.90571) (xy 187.589124 -408.901904)
			(xy 187.56786 -408.901904) (xy 187.557918 -408.90571) (xy 187.515259 -408.923977) (xy 187.42697 -408.952569)
			(xy 187.336187 -408.971824) (xy 187.243893 -408.981535) (xy 187.197492 -408.982164) (xy 187.15109 -408.981537)
			(xy 187.058793 -408.971846) (xy 186.968007 -408.952593) (xy 186.879722 -408.923985) (xy 186.837066 -408.90571)
			(xy 186.827124 -408.901904) (xy 186.80586 -408.901904) (xy 186.795918 -408.90571) (xy 186.753259 -408.923977)
			(xy 186.66497 -408.952569) (xy 186.574187 -408.971824) (xy 186.481893 -408.981535) (xy 186.435492 -408.982164)
			(xy 186.38909 -408.981537) (xy 186.296793 -408.971846) (xy 186.206007 -408.952593) (xy 186.117722 -408.923985)
			(xy 186.075066 -408.90571) (xy 186.065124 -408.901904) (xy 186.04386 -408.901904) (xy 186.033918 -408.90571)
			(xy 185.991259 -408.923977) (xy 185.90297 -408.952569) (xy 185.812187 -408.971824) (xy 185.719893 -408.981535)
			(xy 185.673492 -408.982164) (xy 185.63238 -408.981755) (xy 185.550507 -408.974166) (xy 185.469683 -408.959054)
			(xy 185.3906 -408.936547) (xy 185.31393 -408.906837) (xy 185.24033 -408.870179) (xy 185.170427 -408.826885)
			(xy 185.104818 -408.777325) (xy 185.044063 -408.721921) (xy 184.98868 -408.661146) (xy 184.939142 -408.59552)
			(xy 184.895872 -408.525602) (xy 184.859239 -408.451989) (xy 184.829556 -408.37531) (xy 184.807076 -408.296219)
			(xy 184.791992 -408.21539) (xy 184.784431 -408.133514) (xy 184.783984 -408.092402) (xy 184.784568 -408.046006)
			(xy 184.794213 -407.953718) (xy 184.813409 -407.862934) (xy 184.841946 -407.774641) (xy 184.860184 -407.731976)
			(xy 184.863989 -407.722034) (xy 184.86399 -407.70077) (xy 184.860184 -407.690828) (xy 184.841939 -407.648166)
			(xy 184.813395 -407.559873) (xy 184.794202 -407.469088) (xy 184.784569 -407.376798) (xy 184.783984 -407.330402)
			(xy 184.784407 -407.290634) (xy 184.791436 -407.211411) (xy 184.805517 -407.133132) (xy 184.826539 -407.056426)
			(xy 184.854333 -406.981906) (xy 184.871106 -406.945846) (xy 184.875438 -406.935345) (xy 184.875439 -406.912659)
			(xy 184.871106 -406.902158) (xy 184.854347 -406.866093) (xy 184.826573 -406.791567) (xy 184.805556 -406.714862)
			(xy 184.791462 -406.636588) (xy 184.784405 -406.557369) (xy 184.783984 -406.517602) (xy 184.784568 -406.471206)
			(xy 184.794213 -406.378918) (xy 184.813409 -406.288134) (xy 184.841946 -406.199841) (xy 184.860184 -406.157176)
			(xy 184.863989 -406.147234) (xy 184.86399 -406.12597) (xy 184.860184 -406.116028) (xy 184.841939 -406.073366)
			(xy 184.813395 -405.985073) (xy 184.794202 -405.894288) (xy 184.784569 -405.801998) (xy 184.783984 -405.755602)
			(xy 184.784568 -405.709206) (xy 184.794213 -405.616918) (xy 184.813409 -405.526134) (xy 184.841946 -405.437841)
			(xy 184.860184 -405.395176) (xy 184.863989 -405.385234) (xy 184.86399 -405.36397) (xy 184.860184 -405.354028)
			(xy 184.841962 -405.311425) (xy 184.813445 -405.223258) (xy 184.794252 -405.132602) (xy 184.784592 -405.040442)
			(xy 184.783984 -404.99411) (xy 184.783984 -404.993602) (xy 184.784497 -404.950127) (xy 184.792981 -404.863592)
			(xy 184.809868 -404.778298) (xy 184.834996 -404.695058) (xy 184.868127 -404.614668) (xy 184.908943 -404.537893)
			(xy 184.957056 -404.465468) (xy 185.012005 -404.398082) (xy 185.073268 -404.33638) (xy 185.140259 -404.28095)
			(xy 185.212338 -404.232321) (xy 185.288819 -404.190956) (xy 185.368971 -404.157252) (xy 185.452028 -404.131529)
			(xy 185.5372 -404.114033) (xy 185.623672 -404.104931) (xy 185.667142 -404.104094) (xy 185.677625 -404.103496)
			(xy 185.6968 -404.094996) (xy 185.710988 -404.07955) (xy 185.714894 -404.069804) (xy 185.745882 -403.978872)
			(xy 185.748725 -403.96876) (xy 185.74698 -403.947853) (xy 185.737043 -403.929376) (xy 185.729118 -403.922484)
			(xy 185.70573 -403.903812) (xy 185.661243 -403.863772) (xy 185.640218 -403.842474) (xy 185.632756 -403.835439)
			(xy 185.613887 -403.827446) (xy 185.603642 -403.82698) (xy 185.530998 -403.82698) (xy 185.520746 -403.827411)
			(xy 185.501872 -403.835417) (xy 185.494422 -403.842474) (xy 185.463025 -403.87402) (xy 185.394968 -403.931383)
			(xy 185.321521 -403.981662) (xy 185.24342 -404.024354) (xy 185.161446 -404.059031) (xy 185.076418 -404.085348)
			(xy 184.989186 -404.103041) (xy 184.900624 -404.111933) (xy 184.85612 -404.112476) (xy 184.815024 -404.112015)
			(xy 184.733183 -404.104434) (xy 184.652391 -404.089335) (xy 184.573336 -404.066848) (xy 184.496692 -404.037162)
			(xy 184.423115 -404.000533) (xy 184.35323 -403.957272) (xy 184.287634 -403.907749) (xy 184.226887 -403.852384)
			(xy 184.171506 -403.791652) (xy 184.121965 -403.72607) (xy 184.078685 -403.656197) (xy 184.042035 -403.582629)
			(xy 184.012329 -403.505994) (xy 183.98982 -403.426945) (xy 183.9747 -403.346156) (xy 183.967097 -403.264318)
			(xy 183.966612 -403.223222) (xy 174.680622 -403.223222) (xy 174.717549 -403.310307) (xy 174.77977 -403.477384)
			(xy 174.834486 -403.647068) (xy 174.881588 -403.819021) (xy 174.920984 -403.992901) (xy 174.952595 -404.168364)
			(xy 174.976359 -404.34506) (xy 174.992227 -404.52264) (xy 175.000169 -404.70075) (xy 175.000666 -404.789894)
			(xy 175.000169 -404.879038) (xy 174.992227 -405.057148) (xy 174.976359 -405.234728) (xy 174.952595 -405.411424)
			(xy 174.920984 -405.586887) (xy 174.881588 -405.760767) (xy 174.834486 -405.93272) (xy 174.77977 -406.102404)
			(xy 174.717549 -406.269481) (xy 174.647948 -406.433622) (xy 174.571103 -406.594498) (xy 174.487169 -406.751792)
			(xy 174.396311 -406.905191) (xy 174.298709 -407.05439) (xy 174.194558 -407.199093) (xy 174.084065 -407.339013)
			(xy 173.967448 -407.473872) (xy 173.844939 -407.603402) (xy 173.716782 -407.727346) (xy 173.583231 -407.845458)
			(xy 173.444551 -407.957503) (xy 173.301017 -408.06326) (xy 173.152914 -408.162517) (xy 173.000537 -408.255079)
			(xy 172.844188 -408.34076) (xy 172.684177 -408.419392) (xy 172.520823 -408.490818) (xy 172.354448 -408.554896)
			(xy 172.185385 -408.611498) (xy 172.013968 -408.660514) (xy 171.840537 -408.701844) (xy 171.665437 -408.735408)
			(xy 171.489017 -408.761138) (xy 171.311625 -408.778984) (xy 171.133614 -408.78891) (xy 170.955337 -408.790896)
			(xy 170.77715 -408.784939) (xy 170.599404 -408.771049) (xy 170.422454 -408.749256) (xy 170.24665 -408.719602)
			(xy 170.072342 -408.682145) (xy 169.899875 -408.636961) (xy 169.729592 -408.584139) (xy 169.561831 -408.523783)
			(xy 169.396926 -408.456015) (xy 169.235203 -408.380967) (xy 169.076984 -408.29879) (xy 168.922583 -408.209647)
			(xy 168.772306 -408.113713) (xy 168.626451 -408.011181) (xy 168.485309 -407.902253) (xy 168.34916 -407.787146)
			(xy 168.218273 -407.666088) (xy 168.092909 -407.539319) (xy 167.973316 -407.407092) (xy 167.859733 -407.269669)
			(xy 167.752384 -407.127322) (xy 167.651483 -406.980334) (xy 167.55723 -406.828998) (xy 167.469812 -406.673613)
			(xy 167.389402 -406.514488) (xy 167.316161 -406.351939) (xy 167.250234 -406.186289) (xy 167.191751 -406.017867)
			(xy 167.140829 -405.847006) (xy 167.097569 -405.674047) (xy 167.062057 -405.499332) (xy 167.034363 -405.323208)
			(xy 167.014542 -405.146026) (xy 167.002634 -404.968137) (xy 166.998662 -404.789894) (xy 161.904774 -404.789894)
			(xy 161.889384 -404.799785) (xy 161.839805 -404.822428) (xy 161.787508 -404.837784) (xy 161.733558 -404.845542)
			(xy 161.706306 -404.846028) (xy 160.842706 -404.846028) (xy 160.815454 -404.845525) (xy 160.761506 -404.837769)
			(xy 160.70921 -404.822415) (xy 160.659631 -404.799774) (xy 160.61378 -404.770307) (xy 160.572589 -404.734616)
			(xy 160.536896 -404.693425) (xy 160.507429 -404.647574) (xy 160.484788 -404.597996) (xy 160.469432 -404.5457)
			(xy 160.461675 -404.491752) (xy 159.024165 -404.491752) (xy 159.024165 -404.491756) (xy 159.016407 -404.545713)
			(xy 159.001048 -404.598016) (xy 158.978402 -404.647601) (xy 158.948929 -404.693458) (xy 158.91323 -404.734654)
			(xy 158.872031 -404.77035) (xy 158.826171 -404.799818) (xy 158.776584 -404.82246) (xy 158.724279 -404.837814)
			(xy 158.670322 -404.845567) (xy 158.643066 -404.846028) (xy 157.779466 -404.846028) (xy 157.752218 -404.845499)
			(xy 157.698277 -404.837739) (xy 157.645989 -404.822382) (xy 157.596418 -404.79974) (xy 157.550575 -404.770275)
			(xy 157.509391 -404.734585) (xy 157.473705 -404.693398) (xy 157.444243 -404.647552) (xy 157.421606 -404.597979)
			(xy 157.406253 -404.54569) (xy 157.398498 -404.491748) (xy 155.960842 -404.491748) (xy 155.960842 -404.491751)
			(xy 155.953086 -404.5457) (xy 155.937731 -404.597995) (xy 155.915091 -404.647573) (xy 155.885626 -404.693425)
			(xy 155.849935 -404.734617) (xy 155.808746 -404.77031) (xy 155.762896 -404.799778) (xy 155.71332 -404.822422)
			(xy 155.661025 -404.83778) (xy 155.607077 -404.84554) (xy 155.579826 -404.846028) (xy 154.716226 -404.846028)
			(xy 154.688973 -404.845526) (xy 154.635022 -404.837773) (xy 154.582724 -404.82242) (xy 154.533143 -404.79978)
			(xy 154.487289 -404.770314) (xy 154.446096 -404.734623) (xy 154.410401 -404.693431) (xy 154.380932 -404.647579)
			(xy 154.358289 -404.598) (xy 154.342933 -404.545703) (xy 154.335175 -404.491753) (xy 152.897665 -404.491753)
			(xy 152.897665 -404.491755) (xy 152.889907 -404.54571) (xy 152.87455 -404.598012) (xy 152.851905 -404.647595)
			(xy 152.822434 -404.693452) (xy 152.786737 -404.734647) (xy 152.745541 -404.770343) (xy 152.699683 -404.799812)
			(xy 152.650099 -404.822455) (xy 152.597796 -404.83781) (xy 152.543841 -404.845566) (xy 152.516586 -404.846028)
			(xy 151.652986 -404.846028) (xy 151.625737 -404.845501) (xy 151.571794 -404.837743) (xy 151.519503 -404.822388)
			(xy 151.46993 -404.799747) (xy 151.424084 -404.770282) (xy 151.382898 -404.734592) (xy 151.34721 -404.693404)
			(xy 151.317746 -404.647557) (xy 151.295108 -404.597984) (xy 151.279754 -404.545693) (xy 151.271998 -404.491749)
			(xy 149.834342 -404.491749) (xy 149.834342 -404.491751) (xy 149.826587 -404.545697) (xy 149.811233 -404.597991)
			(xy 149.788594 -404.647568) (xy 149.75913 -404.693418) (xy 149.723442 -404.734609) (xy 149.682255 -404.770303)
			(xy 149.636408 -404.799772) (xy 149.586834 -404.822417) (xy 149.534542 -404.837777) (xy 149.480597 -404.845539)
			(xy 149.453346 -404.846028) (xy 148.589746 -404.846028) (xy 148.562492 -404.845528) (xy 148.508539 -404.837777)
			(xy 148.456239 -404.822425) (xy 148.406655 -404.799787) (xy 148.360799 -404.770321) (xy 148.319603 -404.73463)
			(xy 148.283906 -404.693438) (xy 148.254435 -404.647585) (xy 148.231791 -404.598004) (xy 148.216433 -404.545706)
			(xy 148.208675 -404.491754) (xy 146.771142 -404.491754) (xy 146.763385 -404.545702) (xy 146.74803 -404.597999)
			(xy 146.725388 -404.647579) (xy 146.695921 -404.693431) (xy 146.660228 -404.734624) (xy 146.619036 -404.770317)
			(xy 146.573184 -404.799785) (xy 146.523605 -404.822428) (xy 146.471308 -404.837784) (xy 146.417358 -404.845542)
			(xy 146.390106 -404.846028) (xy 145.526506 -404.846028) (xy 145.499254 -404.845525) (xy 145.445306 -404.837769)
			(xy 145.39301 -404.822415) (xy 145.343431 -404.799774) (xy 145.29758 -404.770307) (xy 145.256389 -404.734616)
			(xy 145.220696 -404.693425) (xy 145.191229 -404.647574) (xy 145.168588 -404.597996) (xy 145.153232 -404.5457)
			(xy 145.145475 -404.491752) (xy 143.707965 -404.491752) (xy 143.707965 -404.491756) (xy 143.700207 -404.545713)
			(xy 143.684848 -404.598016) (xy 143.662202 -404.647601) (xy 143.632729 -404.693458) (xy 143.59703 -404.734654)
			(xy 143.555831 -404.77035) (xy 143.509971 -404.799818) (xy 143.460384 -404.82246) (xy 143.408079 -404.837814)
			(xy 143.354122 -404.845567) (xy 143.326866 -404.846028) (xy 142.463266 -404.846028) (xy 142.436018 -404.845499)
			(xy 142.382077 -404.837739) (xy 142.329789 -404.822382) (xy 142.280218 -404.79974) (xy 142.234375 -404.770275)
			(xy 142.193191 -404.734585) (xy 142.157505 -404.693398) (xy 142.128043 -404.647552) (xy 142.105406 -404.597979)
			(xy 142.090053 -404.54569) (xy 142.082298 -404.491748) (xy 140.644642 -404.491748) (xy 140.644642 -404.491751)
			(xy 140.636886 -404.5457) (xy 140.621531 -404.597995) (xy 140.598891 -404.647573) (xy 140.569426 -404.693425)
			(xy 140.533735 -404.734617) (xy 140.492546 -404.77031) (xy 140.446696 -404.799778) (xy 140.39712 -404.822422)
			(xy 140.344825 -404.83778) (xy 140.290877 -404.84554) (xy 140.263626 -404.846028) (xy 139.400026 -404.846028)
			(xy 139.372773 -404.845526) (xy 139.318822 -404.837773) (xy 139.266524 -404.82242) (xy 139.216943 -404.79978)
			(xy 139.171089 -404.770314) (xy 139.129896 -404.734623) (xy 139.094201 -404.693431) (xy 139.064732 -404.647579)
			(xy 139.042089 -404.598) (xy 139.026733 -404.545703) (xy 139.018975 -404.491753) (xy 137.581465 -404.491753)
			(xy 137.581465 -404.491755) (xy 137.573707 -404.54571) (xy 137.55835 -404.598012) (xy 137.535705 -404.647595)
			(xy 137.506234 -404.693452) (xy 137.470537 -404.734647) (xy 137.429341 -404.770343) (xy 137.383483 -404.799812)
			(xy 137.333899 -404.822455) (xy 137.281596 -404.83781) (xy 137.227641 -404.845566) (xy 137.200386 -404.846028)
			(xy 136.336786 -404.846028) (xy 136.309537 -404.845501) (xy 136.255594 -404.837743) (xy 136.203303 -404.822388)
			(xy 136.15373 -404.799747) (xy 136.107884 -404.770282) (xy 136.066698 -404.734592) (xy 136.03101 -404.693404)
			(xy 136.001546 -404.647557) (xy 135.978908 -404.597984) (xy 135.963554 -404.545693) (xy 135.955798 -404.491749)
			(xy 134.518142 -404.491749) (xy 134.518142 -404.491751) (xy 134.510387 -404.545697) (xy 134.495033 -404.597991)
			(xy 134.472394 -404.647568) (xy 134.44293 -404.693418) (xy 134.407242 -404.734609) (xy 134.366055 -404.770303)
			(xy 134.320208 -404.799772) (xy 134.270634 -404.822417) (xy 134.218342 -404.837777) (xy 134.164397 -404.845539)
			(xy 134.137146 -404.846028) (xy 133.273546 -404.846028) (xy 133.246292 -404.845528) (xy 133.192339 -404.837777)
			(xy 133.140039 -404.822425) (xy 133.090455 -404.799787) (xy 133.044599 -404.770321) (xy 133.003403 -404.73463)
			(xy 132.967706 -404.693438) (xy 132.938235 -404.647585) (xy 132.915591 -404.598004) (xy 132.900233 -404.545706)
			(xy 132.892475 -404.491754) (xy 131.454942 -404.491754) (xy 131.447185 -404.545702) (xy 131.43183 -404.597999)
			(xy 131.409188 -404.647579) (xy 131.379721 -404.693431) (xy 131.344028 -404.734624) (xy 131.302836 -404.770317)
			(xy 131.256984 -404.799785) (xy 131.207405 -404.822428) (xy 131.155108 -404.837784) (xy 131.101158 -404.845542)
			(xy 131.073906 -404.846028) (xy 130.210306 -404.846028) (xy 130.183054 -404.845525) (xy 130.129106 -404.837769)
			(xy 130.07681 -404.822415) (xy 130.027231 -404.799774) (xy 129.98138 -404.770307) (xy 129.940189 -404.734616)
			(xy 129.904496 -404.693425) (xy 129.875029 -404.647574) (xy 129.852388 -404.597996) (xy 129.837032 -404.5457)
			(xy 129.829275 -404.491752) (xy 128.391765 -404.491752) (xy 128.391765 -404.491756) (xy 128.384007 -404.545713)
			(xy 128.368648 -404.598016) (xy 128.346002 -404.647601) (xy 128.316529 -404.693458) (xy 128.28083 -404.734654)
			(xy 128.239631 -404.77035) (xy 128.193771 -404.799818) (xy 128.144184 -404.82246) (xy 128.091879 -404.837814)
			(xy 128.037922 -404.845567) (xy 128.010666 -404.846028) (xy 127.147066 -404.846028) (xy 127.119818 -404.845499)
			(xy 127.065877 -404.837739) (xy 127.013589 -404.822382) (xy 126.964018 -404.79974) (xy 126.918175 -404.770275)
			(xy 126.876991 -404.734585) (xy 126.841305 -404.693398) (xy 126.811843 -404.647552) (xy 126.789206 -404.597979)
			(xy 126.773853 -404.54569) (xy 126.766098 -404.491748) (xy 125.328442 -404.491748) (xy 125.328442 -404.491751)
			(xy 125.320686 -404.5457) (xy 125.305331 -404.597995) (xy 125.282691 -404.647573) (xy 125.253226 -404.693425)
			(xy 125.217535 -404.734617) (xy 125.176346 -404.77031) (xy 125.130496 -404.799778) (xy 125.08092 -404.822422)
			(xy 125.028625 -404.83778) (xy 124.974677 -404.84554) (xy 124.947426 -404.846028) (xy 124.083826 -404.846028)
			(xy 124.056573 -404.845526) (xy 124.002622 -404.837773) (xy 123.950324 -404.82242) (xy 123.900743 -404.79978)
			(xy 123.854889 -404.770314) (xy 123.813696 -404.734623) (xy 123.778001 -404.693431) (xy 123.748532 -404.647579)
			(xy 123.725889 -404.598) (xy 123.710533 -404.545703) (xy 123.702775 -404.491753) (xy 122.265265 -404.491753)
			(xy 122.265265 -404.491755) (xy 122.257507 -404.54571) (xy 122.24215 -404.598012) (xy 122.219505 -404.647595)
			(xy 122.190034 -404.693452) (xy 122.154337 -404.734647) (xy 122.113141 -404.770343) (xy 122.067283 -404.799812)
			(xy 122.017699 -404.822455) (xy 121.965396 -404.83781) (xy 121.911441 -404.845566) (xy 121.884186 -404.846028)
			(xy 121.020586 -404.846028) (xy 120.993337 -404.845501) (xy 120.939394 -404.837743) (xy 120.887103 -404.822388)
			(xy 120.83753 -404.799747) (xy 120.791684 -404.770282) (xy 120.750498 -404.734592) (xy 120.71481 -404.693404)
			(xy 120.685346 -404.647557) (xy 120.662708 -404.597984) (xy 120.647354 -404.545693) (xy 120.639598 -404.491749)
			(xy 119.201942 -404.491749) (xy 119.201942 -404.491751) (xy 119.194187 -404.545697) (xy 119.178833 -404.597991)
			(xy 119.156194 -404.647568) (xy 119.12673 -404.693418) (xy 119.091042 -404.734609) (xy 119.049855 -404.770303)
			(xy 119.004008 -404.799772) (xy 118.954434 -404.822417) (xy 118.902142 -404.837777) (xy 118.848197 -404.845539)
			(xy 118.820946 -404.846028) (xy 117.957346 -404.846028) (xy 117.930092 -404.845528) (xy 117.876139 -404.837777)
			(xy 117.823839 -404.822425) (xy 117.774255 -404.799787) (xy 117.728399 -404.770321) (xy 117.687203 -404.73463)
			(xy 117.651506 -404.693438) (xy 117.622035 -404.647585) (xy 117.599391 -404.598004) (xy 117.584033 -404.545706)
			(xy 117.576275 -404.491754) (xy 116.138742 -404.491754) (xy 116.130985 -404.545702) (xy 116.11563 -404.597999)
			(xy 116.092988 -404.647579) (xy 116.063521 -404.693431) (xy 116.027828 -404.734624) (xy 115.986636 -404.770317)
			(xy 115.940784 -404.799785) (xy 115.891205 -404.822428) (xy 115.838908 -404.837784) (xy 115.784958 -404.845542)
			(xy 115.757706 -404.846028) (xy 114.894106 -404.846028) (xy 114.866854 -404.845525) (xy 114.812906 -404.837769)
			(xy 114.76061 -404.822415) (xy 114.711031 -404.799774) (xy 114.66518 -404.770307) (xy 114.623989 -404.734616)
			(xy 114.588296 -404.693425) (xy 114.558829 -404.647574) (xy 114.536188 -404.597996) (xy 114.520832 -404.5457)
			(xy 114.513075 -404.491752) (xy 94.987465 -404.491752) (xy 94.987465 -404.491756) (xy 94.979707 -404.545713)
			(xy 94.964348 -404.598016) (xy 94.941702 -404.647602) (xy 94.912229 -404.693459) (xy 94.876529 -404.734655)
			(xy 94.83533 -404.77035) (xy 94.78947 -404.799819) (xy 94.739883 -404.822461) (xy 94.687578 -404.837814)
			(xy 94.63362 -404.845568) (xy 94.606364 -404.846028) (xy 93.742764 -404.846028) (xy 93.715516 -404.845499)
			(xy 93.661575 -404.837739) (xy 93.609287 -404.822382) (xy 93.559717 -404.79974) (xy 93.513874 -404.770274)
			(xy 93.47269 -404.734584) (xy 93.437004 -404.693397) (xy 93.407543 -404.647551) (xy 93.384906 -404.597979)
			(xy 93.369553 -404.54569) (xy 93.361798 -404.491748) (xy 91.924142 -404.491748) (xy 91.924142 -404.491752)
			(xy 91.916386 -404.5457) (xy 91.901031 -404.597996) (xy 91.878391 -404.647574) (xy 91.848925 -404.693425)
			(xy 91.813234 -404.734617) (xy 91.772045 -404.770311) (xy 91.726195 -404.799779) (xy 91.676618 -404.822423)
			(xy 91.624324 -404.837781) (xy 91.570376 -404.845541) (xy 91.543124 -404.846028) (xy 90.679524 -404.846028)
			(xy 90.652271 -404.845526) (xy 90.598321 -404.837773) (xy 90.546023 -404.822419) (xy 90.496442 -404.799779)
			(xy 90.450588 -404.770314) (xy 90.409395 -404.734622) (xy 90.373701 -404.693431) (xy 90.344232 -404.647579)
			(xy 90.321589 -404.598) (xy 90.306233 -404.545703) (xy 90.298475 -404.491753) (xy 88.860965 -404.491753)
			(xy 88.860965 -404.491755) (xy 88.853207 -404.54571) (xy 88.83785 -404.598012) (xy 88.815205 -404.647596)
			(xy 88.785734 -404.693452) (xy 88.750036 -404.734648) (xy 88.70884 -404.770343) (xy 88.662982 -404.799812)
			(xy 88.613397 -404.822455) (xy 88.561095 -404.837811) (xy 88.507139 -404.845566) (xy 88.479884 -404.846028)
			(xy 87.616284 -404.846028) (xy 87.589035 -404.845501) (xy 87.535092 -404.837743) (xy 87.482802 -404.822387)
			(xy 87.433229 -404.799746) (xy 87.387383 -404.770281) (xy 87.346197 -404.734591) (xy 87.310509 -404.693404)
			(xy 87.281046 -404.647557) (xy 87.258407 -404.597983) (xy 87.243054 -404.545692) (xy 87.235298 -404.491749)
			(xy 85.797642 -404.491749) (xy 85.797642 -404.491751) (xy 85.789887 -404.545697) (xy 85.774533 -404.597991)
			(xy 85.751894 -404.647568) (xy 85.72243 -404.693419) (xy 85.686741 -404.73461) (xy 85.645554 -404.770304)
			(xy 85.599707 -404.799773) (xy 85.550133 -404.822417) (xy 85.49784 -404.837777) (xy 85.443895 -404.845539)
			(xy 85.416644 -404.846028) (xy 84.553044 -404.846028) (xy 84.525791 -404.845528) (xy 84.471838 -404.837776)
			(xy 84.419537 -404.822425) (xy 84.369954 -404.799786) (xy 84.324098 -404.770321) (xy 84.282902 -404.734629)
			(xy 84.247206 -404.693437) (xy 84.217735 -404.647584) (xy 84.195091 -404.598004) (xy 84.179733 -404.545705)
			(xy 84.171975 -404.491753) (xy 82.734442 -404.491753) (xy 82.726685 -404.545703) (xy 82.71133 -404.598)
			(xy 82.688688 -404.647579) (xy 82.65922 -404.693432) (xy 82.623527 -404.734624) (xy 82.582335 -404.770318)
			(xy 82.536483 -404.799786) (xy 82.486904 -404.822428) (xy 82.434607 -404.837785) (xy 82.380656 -404.845542)
			(xy 82.353404 -404.846028) (xy 81.489804 -404.846028) (xy 81.462552 -404.845525) (xy 81.408604 -404.837769)
			(xy 81.356308 -404.822414) (xy 81.30673 -404.799773) (xy 81.260879 -404.770307) (xy 81.219688 -404.734615)
			(xy 81.183996 -404.693424) (xy 81.154529 -404.647573) (xy 81.131887 -404.597995) (xy 81.116532 -404.5457)
			(xy 81.108775 -404.491752) (xy 79.671265 -404.491752) (xy 79.671265 -404.491756) (xy 79.663507 -404.545713)
			(xy 79.648148 -404.598016) (xy 79.625502 -404.647602) (xy 79.596029 -404.693459) (xy 79.560329 -404.734655)
			(xy 79.51913 -404.77035) (xy 79.47327 -404.799819) (xy 79.423683 -404.822461) (xy 79.371378 -404.837814)
			(xy 79.31742 -404.845568) (xy 79.290164 -404.846028) (xy 78.426564 -404.846028) (xy 78.399316 -404.845499)
			(xy 78.345375 -404.837739) (xy 78.293087 -404.822382) (xy 78.243517 -404.79974) (xy 78.197674 -404.770274)
			(xy 78.15649 -404.734584) (xy 78.120804 -404.693397) (xy 78.091343 -404.647551) (xy 78.068706 -404.597979)
			(xy 78.053353 -404.54569) (xy 78.045598 -404.491748) (xy 76.607942 -404.491748) (xy 76.607942 -404.491752)
			(xy 76.600186 -404.5457) (xy 76.584831 -404.597996) (xy 76.562191 -404.647574) (xy 76.532725 -404.693425)
			(xy 76.497034 -404.734617) (xy 76.455845 -404.770311) (xy 76.409995 -404.799779) (xy 76.360418 -404.822423)
			(xy 76.308124 -404.837781) (xy 76.254176 -404.845541) (xy 76.226924 -404.846028) (xy 75.363324 -404.846028)
			(xy 75.336071 -404.845526) (xy 75.282121 -404.837773) (xy 75.229823 -404.822419) (xy 75.180242 -404.799779)
			(xy 75.134388 -404.770314) (xy 75.093195 -404.734622) (xy 75.057501 -404.693431) (xy 75.028032 -404.647579)
			(xy 75.005389 -404.598) (xy 74.990033 -404.545703) (xy 74.982275 -404.491753) (xy 73.544765 -404.491753)
			(xy 73.544765 -404.491755) (xy 73.537007 -404.54571) (xy 73.52165 -404.598012) (xy 73.499005 -404.647596)
			(xy 73.469534 -404.693452) (xy 73.433836 -404.734648) (xy 73.39264 -404.770343) (xy 73.346782 -404.799812)
			(xy 73.297197 -404.822455) (xy 73.244895 -404.837811) (xy 73.190939 -404.845566) (xy 73.163684 -404.846028)
			(xy 72.300084 -404.846028) (xy 72.272835 -404.845501) (xy 72.218892 -404.837743) (xy 72.166602 -404.822387)
			(xy 72.117029 -404.799746) (xy 72.071183 -404.770281) (xy 72.029997 -404.734591) (xy 71.994309 -404.693404)
			(xy 71.964846 -404.647557) (xy 71.942207 -404.597983) (xy 71.926854 -404.545692) (xy 71.919098 -404.491749)
			(xy 70.481442 -404.491749) (xy 70.481442 -404.491751) (xy 70.473687 -404.545697) (xy 70.458333 -404.597991)
			(xy 70.435694 -404.647568) (xy 70.40623 -404.693419) (xy 70.370541 -404.73461) (xy 70.329354 -404.770304)
			(xy 70.283507 -404.799773) (xy 70.233933 -404.822417) (xy 70.18164 -404.837777) (xy 70.127695 -404.845539)
			(xy 70.100444 -404.846028) (xy 69.236844 -404.846028) (xy 69.209591 -404.845528) (xy 69.155638 -404.837776)
			(xy 69.103337 -404.822425) (xy 69.053754 -404.799786) (xy 69.007898 -404.770321) (xy 68.966702 -404.734629)
			(xy 68.931006 -404.693437) (xy 68.901535 -404.647584) (xy 68.878891 -404.598004) (xy 68.863533 -404.545705)
			(xy 68.855775 -404.491753) (xy 67.418242 -404.491753) (xy 67.410485 -404.545703) (xy 67.39513 -404.598)
			(xy 67.372488 -404.647579) (xy 67.34302 -404.693432) (xy 67.307327 -404.734624) (xy 67.266135 -404.770318)
			(xy 67.220283 -404.799786) (xy 67.170704 -404.822428) (xy 67.118407 -404.837785) (xy 67.064456 -404.845542)
			(xy 67.037204 -404.846028) (xy 66.173604 -404.846028) (xy 66.146352 -404.845525) (xy 66.092404 -404.837769)
			(xy 66.040108 -404.822414) (xy 65.99053 -404.799773) (xy 65.944679 -404.770307) (xy 65.903488 -404.734615)
			(xy 65.867796 -404.693424) (xy 65.838329 -404.647573) (xy 65.815687 -404.597995) (xy 65.800332 -404.5457)
			(xy 65.792575 -404.491752) (xy 64.355065 -404.491752) (xy 64.355065 -404.491756) (xy 64.347307 -404.545713)
			(xy 64.331948 -404.598016) (xy 64.309302 -404.647602) (xy 64.279829 -404.693459) (xy 64.244129 -404.734655)
			(xy 64.20293 -404.77035) (xy 64.15707 -404.799819) (xy 64.107483 -404.822461) (xy 64.055178 -404.837814)
			(xy 64.00122 -404.845568) (xy 63.973964 -404.846028) (xy 63.110364 -404.846028) (xy 63.083116 -404.845499)
			(xy 63.029175 -404.837739) (xy 62.976887 -404.822382) (xy 62.927317 -404.79974) (xy 62.881474 -404.770274)
			(xy 62.84029 -404.734584) (xy 62.804604 -404.693397) (xy 62.775143 -404.647551) (xy 62.752506 -404.597979)
			(xy 62.737153 -404.54569) (xy 62.729398 -404.491748) (xy 61.291742 -404.491748) (xy 61.291742 -404.491752)
			(xy 61.283986 -404.5457) (xy 61.268631 -404.597996) (xy 61.245991 -404.647574) (xy 61.216525 -404.693425)
			(xy 61.180834 -404.734617) (xy 61.139645 -404.770311) (xy 61.093795 -404.799779) (xy 61.044218 -404.822423)
			(xy 60.991924 -404.837781) (xy 60.937976 -404.845541) (xy 60.910724 -404.846028) (xy 60.047124 -404.846028)
			(xy 60.019871 -404.845526) (xy 59.965921 -404.837773) (xy 59.913623 -404.822419) (xy 59.864042 -404.799779)
			(xy 59.818188 -404.770314) (xy 59.776995 -404.734622) (xy 59.741301 -404.693431) (xy 59.711832 -404.647579)
			(xy 59.689189 -404.598) (xy 59.673833 -404.545703) (xy 59.666075 -404.491753) (xy 58.228565 -404.491753)
			(xy 58.228565 -404.491755) (xy 58.220807 -404.54571) (xy 58.20545 -404.598012) (xy 58.182805 -404.647596)
			(xy 58.153334 -404.693452) (xy 58.117636 -404.734648) (xy 58.07644 -404.770343) (xy 58.030582 -404.799812)
			(xy 57.980997 -404.822455) (xy 57.928695 -404.837811) (xy 57.874739 -404.845566) (xy 57.847484 -404.846028)
			(xy 56.983884 -404.846028) (xy 56.956635 -404.845501) (xy 56.902692 -404.837743) (xy 56.850402 -404.822387)
			(xy 56.800829 -404.799746) (xy 56.754983 -404.770281) (xy 56.713797 -404.734591) (xy 56.678109 -404.693404)
			(xy 56.648646 -404.647557) (xy 56.626007 -404.597983) (xy 56.610654 -404.545692) (xy 56.602898 -404.491749)
			(xy 55.165242 -404.491749) (xy 55.165242 -404.491751) (xy 55.157487 -404.545697) (xy 55.142133 -404.597991)
			(xy 55.119494 -404.647568) (xy 55.09003 -404.693419) (xy 55.054341 -404.73461) (xy 55.013154 -404.770304)
			(xy 54.967307 -404.799773) (xy 54.917733 -404.822417) (xy 54.86544 -404.837777) (xy 54.811495 -404.845539)
			(xy 54.784244 -404.846028) (xy 53.920644 -404.846028) (xy 53.893391 -404.845528) (xy 53.839438 -404.837776)
			(xy 53.787137 -404.822425) (xy 53.737554 -404.799786) (xy 53.691698 -404.770321) (xy 53.650502 -404.734629)
			(xy 53.614806 -404.693437) (xy 53.585335 -404.647584) (xy 53.562691 -404.598004) (xy 53.547333 -404.545705)
			(xy 53.539575 -404.491753) (xy 52.102042 -404.491753) (xy 52.094285 -404.545703) (xy 52.07893 -404.598)
			(xy 52.056288 -404.647579) (xy 52.02682 -404.693432) (xy 51.991127 -404.734624) (xy 51.949935 -404.770318)
			(xy 51.904083 -404.799786) (xy 51.854504 -404.822428) (xy 51.802207 -404.837785) (xy 51.748256 -404.845542)
			(xy 51.721004 -404.846028) (xy 50.857404 -404.846028) (xy 50.830152 -404.845525) (xy 50.776204 -404.837769)
			(xy 50.723908 -404.822414) (xy 50.67433 -404.799773) (xy 50.628479 -404.770307) (xy 50.587288 -404.734615)
			(xy 50.551596 -404.693424) (xy 50.522129 -404.647573) (xy 50.499487 -404.597995) (xy 50.484132 -404.5457)
			(xy 50.476375 -404.491752) (xy 49.038865 -404.491752) (xy 49.038865 -404.491756) (xy 49.031107 -404.545713)
			(xy 49.015748 -404.598016) (xy 48.993102 -404.647602) (xy 48.963629 -404.693459) (xy 48.927929 -404.734655)
			(xy 48.88673 -404.77035) (xy 48.84087 -404.799819) (xy 48.791283 -404.822461) (xy 48.738978 -404.837814)
			(xy 48.68502 -404.845568) (xy 48.657764 -404.846028) (xy 47.794164 -404.846028) (xy 47.766916 -404.845499)
			(xy 47.712975 -404.837739) (xy 47.660687 -404.822382) (xy 47.611117 -404.79974) (xy 47.565274 -404.770274)
			(xy 47.52409 -404.734584) (xy 47.488404 -404.693397) (xy 47.458943 -404.647551) (xy 47.436306 -404.597979)
			(xy 47.420953 -404.54569) (xy 47.413198 -404.491748) (xy 45.559703 -404.491748) (xy 45.562463 -404.52264)
			(xy 45.570405 -404.70075) (xy 45.570902 -404.789894) (xy 45.570405 -404.879038) (xy 45.562463 -405.057148)
			(xy 45.546595 -405.234728) (xy 45.522831 -405.411424) (xy 45.49122 -405.586887) (xy 45.479552 -405.638385)
			(xy 104.009796 -405.638385) (xy 104.013672 -405.584006) (xy 104.025246 -405.530732) (xy 104.044281 -405.479646)
			(xy 104.070391 -405.431789) (xy 104.103044 -405.388132) (xy 104.121966 -405.368506) (xy 104.732582 -404.757636)
			(xy 104.75423 -404.736857) (xy 104.802784 -404.701606) (xy 104.856253 -404.67438) (xy 104.91332 -404.655848)
			(xy 104.972583 -404.646465) (xy 105.002584 -404.645876) (xy 105.029856 -404.646316) (xy 105.083846 -404.654077)
			(xy 105.136181 -404.669444) (xy 105.185797 -404.692102) (xy 105.231683 -404.721592) (xy 105.272904 -404.757312)
			(xy 105.308622 -404.798535) (xy 105.338108 -404.844422) (xy 105.360764 -404.894039) (xy 105.376127 -404.946376)
			(xy 105.383885 -405.000366) (xy 105.384346 -405.027638) (xy 105.383744 -405.057639) (xy 105.374371 -405.116904)
			(xy 105.355845 -405.173974) (xy 105.328623 -405.227445) (xy 105.29971 -405.267273) (xy 106.824184 -405.267273)
			(xy 106.824184 -405.212727) (xy 106.831947 -405.158735) (xy 106.847315 -405.106398) (xy 106.869976 -405.05678)
			(xy 106.899467 -405.010893) (xy 106.935189 -404.969671) (xy 106.976414 -404.933951) (xy 107.022303 -404.904463)
			(xy 107.071922 -404.881806) (xy 107.12426 -404.866441) (xy 107.178252 -404.858682) (xy 107.205526 -404.85822)
			(xy 108.069126 -404.85822) (xy 108.096393 -404.858744) (xy 108.150371 -404.866508) (xy 108.202695 -404.881875)
			(xy 108.2523 -404.904532) (xy 108.298175 -404.934017) (xy 108.339388 -404.969731) (xy 108.375098 -405.010946)
			(xy 108.404581 -405.056823) (xy 108.427234 -405.106429) (xy 108.442597 -405.158754) (xy 108.450358 -405.212733)
			(xy 108.450358 -405.267267) (xy 108.442597 -405.321246) (xy 108.427234 -405.373571) (xy 108.404581 -405.423177)
			(xy 108.375098 -405.469054) (xy 108.339388 -405.510269) (xy 108.298175 -405.545983) (xy 108.2523 -405.575468)
			(xy 108.202695 -405.598125) (xy 108.150371 -405.613492) (xy 108.096393 -405.621256) (xy 108.069126 -405.621744)
			(xy 107.205526 -405.621744) (xy 107.178252 -405.621318) (xy 107.12426 -405.613559) (xy 107.071922 -405.598194)
			(xy 107.022303 -405.575537) (xy 106.976414 -405.546049) (xy 106.935189 -405.510329) (xy 106.899467 -405.469107)
			(xy 106.869976 -405.42322) (xy 106.847315 -405.373602) (xy 106.831947 -405.321265) (xy 106.824184 -405.267273)
			(xy 105.29971 -405.267273) (xy 105.293374 -405.276001) (xy 105.272586 -405.29764) (xy 104.661716 -405.908256)
			(xy 104.642167 -405.927256) (xy 104.598511 -405.959909) (xy 104.550654 -405.986019) (xy 104.499568 -406.005054)
			(xy 104.446294 -406.016628) (xy 104.391915 -406.020504) (xy 104.337538 -406.016603) (xy 104.284269 -406.005006)
			(xy 104.233192 -405.985949) (xy 104.185346 -405.959818) (xy 104.141704 -405.927145) (xy 104.103155 -405.888596)
			(xy 104.070482 -405.844954) (xy 104.044351 -405.797108) (xy 104.025294 -405.746031) (xy 104.013697 -405.692762)
			(xy 104.009796 -405.638385) (xy 45.479552 -405.638385) (xy 45.451824 -405.760767) (xy 45.404722 -405.93272)
			(xy 45.350006 -406.102404) (xy 45.287785 -406.269481) (xy 45.218184 -406.433622) (xy 45.141339 -406.594498)
			(xy 45.057405 -406.751792) (xy 44.966547 -406.905191) (xy 44.883756 -407.031749) (xy 48.944798 -407.031749)
			(xy 48.944798 -406.977251) (xy 48.952554 -406.923308) (xy 48.967907 -406.871017) (xy 48.990546 -406.821443)
			(xy 49.020009 -406.775596) (xy 49.055697 -406.734409) (xy 49.096883 -406.698719) (xy 49.142729 -406.669254)
			(xy 49.192302 -406.646613) (xy 49.244592 -406.631257) (xy 49.298535 -406.623499) (xy 49.325784 -406.623012)
			(xy 50.189384 -406.623012) (xy 50.216639 -406.623434) (xy 50.270595 -406.631189) (xy 50.322897 -406.646545)
			(xy 50.372482 -406.669188) (xy 50.41834 -406.698657) (xy 50.459536 -406.734352) (xy 50.495234 -406.775548)
			(xy 50.524705 -406.821404) (xy 50.54735 -406.870988) (xy 50.562707 -406.92329) (xy 50.570465 -406.977245)
			(xy 50.570465 -407.031753) (xy 52.007975 -407.031753) (xy 52.007975 -406.977247) (xy 52.015733 -406.923297)
			(xy 52.031089 -406.871) (xy 52.053732 -406.821421) (xy 52.083201 -406.775569) (xy 52.118895 -406.734378)
			(xy 52.160088 -406.698686) (xy 52.205942 -406.669221) (xy 52.255523 -406.646581) (xy 52.307821 -406.631227)
			(xy 52.361771 -406.623474) (xy 52.389024 -406.623012) (xy 53.252624 -406.623012) (xy 53.279876 -406.623459)
			(xy 53.333824 -406.631219) (xy 53.386118 -406.646577) (xy 53.435695 -406.669221) (xy 53.481545 -406.698689)
			(xy 53.522734 -406.734383) (xy 53.558425 -406.775575) (xy 53.587891 -406.821426) (xy 53.610531 -406.871004)
			(xy 53.625886 -406.9233) (xy 53.633642 -406.977248) (xy 53.633642 -407.031748) (xy 55.071298 -407.031748)
			(xy 55.071298 -406.977252) (xy 55.079053 -406.92331) (xy 55.094406 -406.871021) (xy 55.117043 -406.821449)
			(xy 55.146504 -406.775603) (xy 55.18219 -406.734416) (xy 55.223374 -406.698726) (xy 55.269217 -406.66926)
			(xy 55.318787 -406.646618) (xy 55.371075 -406.631261) (xy 55.425016 -406.623501) (xy 55.452264 -406.623012)
			(xy 56.315864 -406.623012) (xy 56.34312 -406.623432) (xy 56.397078 -406.631186) (xy 56.449383 -406.646539)
			(xy 56.49897 -406.669181) (xy 56.54483 -406.69865) (xy 56.586029 -406.734345) (xy 56.621729 -406.775541)
			(xy 56.651202 -406.821398) (xy 56.673848 -406.870984) (xy 56.689207 -406.923287) (xy 56.696965 -406.977244)
			(xy 56.696965 -407.031752) (xy 58.134475 -407.031752) (xy 58.134475 -406.977248) (xy 58.142232 -406.9233)
			(xy 58.157587 -406.871005) (xy 58.180229 -406.821427) (xy 58.209696 -406.775576) (xy 58.245388 -406.734385)
			(xy 58.286579 -406.698693) (xy 58.33243 -406.669227) (xy 58.382008 -406.646586) (xy 58.434304 -406.631231)
			(xy 58.488252 -406.623475) (xy 58.515504 -406.623012) (xy 59.379104 -406.623012) (xy 59.406356 -406.623458)
			(xy 59.460307 -406.631215) (xy 59.512604 -406.646572) (xy 59.562183 -406.669214) (xy 59.608035 -406.698682)
			(xy 59.649227 -406.734376) (xy 59.68492 -406.775568) (xy 59.714388 -406.821421) (xy 59.73703 -406.871)
			(xy 59.752385 -406.923297) (xy 59.760142 -406.977248) (xy 59.760142 -407.031752) (xy 59.760142 -407.031753)
			(xy 61.197675 -407.031753) (xy 61.197675 -406.977247) (xy 61.205433 -406.923295) (xy 61.220791 -406.870996)
			(xy 61.243435 -406.821416) (xy 61.272906 -406.775563) (xy 61.308602 -406.734371) (xy 61.349798 -406.698679)
			(xy 61.395654 -406.669214) (xy 61.445237 -406.646575) (xy 61.497538 -406.631224) (xy 61.551491 -406.623472)
			(xy 61.578744 -406.623012) (xy 62.442344 -406.623012) (xy 62.469595 -406.623461) (xy 62.52354 -406.631223)
			(xy 62.575833 -406.646583) (xy 62.625407 -406.669227) (xy 62.671254 -406.698696) (xy 62.712441 -406.73439)
			(xy 62.74813 -406.775581) (xy 62.777594 -406.821432) (xy 62.800233 -406.871009) (xy 62.815587 -406.923303)
			(xy 62.823342 -406.977249) (xy 62.823342 -407.031749) (xy 64.260998 -407.031749) (xy 64.260998 -406.977251)
			(xy 64.268754 -406.923308) (xy 64.284107 -406.871017) (xy 64.306746 -406.821443) (xy 64.336209 -406.775596)
			(xy 64.371897 -406.734409) (xy 64.413083 -406.698719) (xy 64.458929 -406.669254) (xy 64.508502 -406.646613)
			(xy 64.560792 -406.631257) (xy 64.614735 -406.623499) (xy 64.641984 -406.623012) (xy 65.505584 -406.623012)
			(xy 65.532839 -406.623434) (xy 65.586795 -406.631189) (xy 65.639097 -406.646545) (xy 65.688682 -406.669188)
			(xy 65.73454 -406.698657) (xy 65.775736 -406.734352) (xy 65.811434 -406.775548) (xy 65.840905 -406.821404)
			(xy 65.86355 -406.870988) (xy 65.878907 -406.92329) (xy 65.886665 -406.977245) (xy 65.886665 -407.031753)
			(xy 67.324175 -407.031753) (xy 67.324175 -406.977247) (xy 67.331933 -406.923297) (xy 67.347289 -406.871)
			(xy 67.369932 -406.821421) (xy 67.399401 -406.775569) (xy 67.435095 -406.734378) (xy 67.476288 -406.698686)
			(xy 67.522142 -406.669221) (xy 67.571723 -406.646581) (xy 67.624021 -406.631227) (xy 67.677971 -406.623474)
			(xy 67.705224 -406.623012) (xy 68.568824 -406.623012) (xy 68.596076 -406.623459) (xy 68.650024 -406.631219)
			(xy 68.702318 -406.646577) (xy 68.751895 -406.669221) (xy 68.797745 -406.698689) (xy 68.838934 -406.734383)
			(xy 68.874625 -406.775575) (xy 68.904091 -406.821426) (xy 68.926731 -406.871004) (xy 68.942086 -406.9233)
			(xy 68.949842 -406.977248) (xy 68.949842 -407.031748) (xy 70.387498 -407.031748) (xy 70.387498 -406.977252)
			(xy 70.395253 -406.92331) (xy 70.410606 -406.871021) (xy 70.433243 -406.821449) (xy 70.462704 -406.775603)
			(xy 70.49839 -406.734416) (xy 70.539574 -406.698726) (xy 70.585417 -406.66926) (xy 70.634987 -406.646618)
			(xy 70.687275 -406.631261) (xy 70.741216 -406.623501) (xy 70.768464 -406.623012) (xy 71.632064 -406.623012)
			(xy 71.65932 -406.623432) (xy 71.713278 -406.631186) (xy 71.765583 -406.646539) (xy 71.81517 -406.669181)
			(xy 71.86103 -406.69865) (xy 71.902229 -406.734345) (xy 71.937929 -406.775541) (xy 71.967402 -406.821398)
			(xy 71.990048 -406.870984) (xy 72.005407 -406.923287) (xy 72.013165 -406.977244) (xy 72.013165 -407.031752)
			(xy 73.450675 -407.031752) (xy 73.450675 -406.977248) (xy 73.458432 -406.9233) (xy 73.473787 -406.871005)
			(xy 73.496429 -406.821427) (xy 73.525896 -406.775576) (xy 73.561588 -406.734385) (xy 73.602779 -406.698693)
			(xy 73.64863 -406.669227) (xy 73.698208 -406.646586) (xy 73.750504 -406.631231) (xy 73.804452 -406.623475)
			(xy 73.831704 -406.623012) (xy 74.695304 -406.623012) (xy 74.722556 -406.623458) (xy 74.776507 -406.631215)
			(xy 74.828804 -406.646572) (xy 74.878383 -406.669214) (xy 74.924235 -406.698682) (xy 74.965427 -406.734376)
			(xy 75.00112 -406.775568) (xy 75.030588 -406.821421) (xy 75.05323 -406.871) (xy 75.068585 -406.923297)
			(xy 75.076342 -406.977248) (xy 75.076342 -407.031752) (xy 75.076342 -407.031753) (xy 76.513875 -407.031753)
			(xy 76.513875 -406.977247) (xy 76.521633 -406.923295) (xy 76.536991 -406.870996) (xy 76.559635 -406.821416)
			(xy 76.589106 -406.775563) (xy 76.624802 -406.734371) (xy 76.665998 -406.698679) (xy 76.711854 -406.669214)
			(xy 76.761437 -406.646575) (xy 76.813738 -406.631224) (xy 76.867691 -406.623472) (xy 76.894944 -406.623012)
			(xy 77.758544 -406.623012) (xy 77.785795 -406.623461) (xy 77.83974 -406.631223) (xy 77.892033 -406.646583)
			(xy 77.941607 -406.669227) (xy 77.987454 -406.698696) (xy 78.028641 -406.73439) (xy 78.06433 -406.775581)
			(xy 78.093794 -406.821432) (xy 78.116433 -406.871009) (xy 78.131787 -406.923303) (xy 78.139542 -406.977249)
			(xy 78.139542 -407.031749) (xy 79.577198 -407.031749) (xy 79.577198 -406.977251) (xy 79.584954 -406.923308)
			(xy 79.600307 -406.871017) (xy 79.622946 -406.821443) (xy 79.652409 -406.775596) (xy 79.688097 -406.734409)
			(xy 79.729283 -406.698719) (xy 79.775129 -406.669254) (xy 79.824702 -406.646613) (xy 79.876992 -406.631257)
			(xy 79.930935 -406.623499) (xy 79.958184 -406.623012) (xy 80.821784 -406.623012) (xy 80.849039 -406.623434)
			(xy 80.902995 -406.631189) (xy 80.955297 -406.646545) (xy 81.004882 -406.669188) (xy 81.05074 -406.698657)
			(xy 81.091936 -406.734352) (xy 81.127634 -406.775548) (xy 81.157105 -406.821404) (xy 81.17975 -406.870988)
			(xy 81.195107 -406.92329) (xy 81.202865 -406.977245) (xy 81.202865 -407.031753) (xy 82.640375 -407.031753)
			(xy 82.640375 -406.977247) (xy 82.648133 -406.923297) (xy 82.663489 -406.871) (xy 82.686132 -406.821421)
			(xy 82.715601 -406.775569) (xy 82.751295 -406.734378) (xy 82.792488 -406.698686) (xy 82.838342 -406.669221)
			(xy 82.887923 -406.646581) (xy 82.940221 -406.631227) (xy 82.994171 -406.623474) (xy 83.021424 -406.623012)
			(xy 83.885024 -406.623012) (xy 83.912276 -406.623459) (xy 83.966224 -406.631219) (xy 84.018518 -406.646577)
			(xy 84.068095 -406.669221) (xy 84.113945 -406.698689) (xy 84.155134 -406.734383) (xy 84.190825 -406.775575)
			(xy 84.220291 -406.821426) (xy 84.242931 -406.871004) (xy 84.258286 -406.9233) (xy 84.266042 -406.977248)
			(xy 84.266042 -407.031748) (xy 85.703698 -407.031748) (xy 85.703698 -406.977252) (xy 85.711453 -406.92331)
			(xy 85.726806 -406.871021) (xy 85.749443 -406.821449) (xy 85.778904 -406.775603) (xy 85.81459 -406.734416)
			(xy 85.855774 -406.698726) (xy 85.901617 -406.66926) (xy 85.951187 -406.646618) (xy 86.003475 -406.631261)
			(xy 86.057416 -406.623501) (xy 86.084664 -406.623012) (xy 86.948264 -406.623012) (xy 86.97552 -406.623432)
			(xy 87.029478 -406.631186) (xy 87.081783 -406.646539) (xy 87.13137 -406.669181) (xy 87.17723 -406.69865)
			(xy 87.218429 -406.734345) (xy 87.254129 -406.775541) (xy 87.283602 -406.821398) (xy 87.306248 -406.870984)
			(xy 87.321607 -406.923287) (xy 87.329365 -406.977244) (xy 87.329365 -407.031752) (xy 88.766875 -407.031752)
			(xy 88.766875 -406.977248) (xy 88.774632 -406.9233) (xy 88.789987 -406.871005) (xy 88.812629 -406.821427)
			(xy 88.842096 -406.775576) (xy 88.877788 -406.734385) (xy 88.918979 -406.698693) (xy 88.96483 -406.669227)
			(xy 89.014408 -406.646586) (xy 89.066704 -406.631231) (xy 89.120652 -406.623475) (xy 89.147904 -406.623012)
			(xy 90.011504 -406.623012) (xy 90.038756 -406.623458) (xy 90.092707 -406.631215) (xy 90.145004 -406.646572)
			(xy 90.194583 -406.669214) (xy 90.240435 -406.698682) (xy 90.281627 -406.734376) (xy 90.31732 -406.775568)
			(xy 90.346788 -406.821421) (xy 90.36943 -406.871) (xy 90.384785 -406.923297) (xy 90.392542 -406.977248)
			(xy 90.392542 -407.031752) (xy 90.392542 -407.031753) (xy 91.830075 -407.031753) (xy 91.830075 -406.977247)
			(xy 91.837833 -406.923295) (xy 91.853191 -406.870996) (xy 91.875835 -406.821416) (xy 91.905306 -406.775563)
			(xy 91.941002 -406.734371) (xy 91.982198 -406.698679) (xy 92.028054 -406.669214) (xy 92.077637 -406.646575)
			(xy 92.129938 -406.631224) (xy 92.183891 -406.623472) (xy 92.211144 -406.623012) (xy 93.074744 -406.623012)
			(xy 93.101995 -406.623461) (xy 93.15594 -406.631223) (xy 93.208233 -406.646583) (xy 93.257807 -406.669227)
			(xy 93.303654 -406.698696) (xy 93.344841 -406.73439) (xy 93.38053 -406.775581) (xy 93.409994 -406.821432)
			(xy 93.432633 -406.871009) (xy 93.447987 -406.923303) (xy 93.455742 -406.977249) (xy 93.455742 -407.031749)
			(xy 94.893398 -407.031749) (xy 94.893398 -406.977251) (xy 94.901154 -406.923308) (xy 94.916507 -406.871017)
			(xy 94.939146 -406.821443) (xy 94.968609 -406.775596) (xy 95.004297 -406.734409) (xy 95.045483 -406.698719)
			(xy 95.091329 -406.669254) (xy 95.140902 -406.646613) (xy 95.193192 -406.631257) (xy 95.247135 -406.623499)
			(xy 95.274384 -406.623012) (xy 96.137984 -406.623012) (xy 96.165239 -406.623434) (xy 96.219195 -406.631189)
			(xy 96.271497 -406.646545) (xy 96.321082 -406.669188) (xy 96.36694 -406.698657) (xy 96.408136 -406.734352)
			(xy 96.443834 -406.775548) (xy 96.473305 -406.821404) (xy 96.49595 -406.870988) (xy 96.511307 -406.92329)
			(xy 96.519065 -406.977245) (xy 96.519065 -407.031753) (xy 116.044675 -407.031753) (xy 116.044675 -406.977247)
			(xy 116.052433 -406.923297) (xy 116.067789 -406.871) (xy 116.090432 -406.821421) (xy 116.119901 -406.775569)
			(xy 116.155596 -406.734377) (xy 116.196789 -406.698686) (xy 116.242643 -406.66922) (xy 116.292224 -406.64658)
			(xy 116.344522 -406.631227) (xy 116.398473 -406.623474) (xy 116.425726 -406.623012) (xy 117.289326 -406.623012)
			(xy 117.316577 -406.62346) (xy 117.370525 -406.63122) (xy 117.42282 -406.646578) (xy 117.472396 -406.669222)
			(xy 117.518246 -406.69869) (xy 117.559435 -406.734383) (xy 117.595126 -406.775575) (xy 117.624591 -406.821427)
			(xy 117.647231 -406.871005) (xy 117.662586 -406.9233) (xy 117.670342 -406.977249) (xy 117.670342 -407.031748)
			(xy 119.107998 -407.031748) (xy 119.107998 -406.977252) (xy 119.115753 -406.92331) (xy 119.131106 -406.871021)
			(xy 119.153743 -406.821448) (xy 119.183205 -406.775602) (xy 119.218891 -406.734415) (xy 119.260075 -406.698725)
			(xy 119.305918 -406.66926) (xy 119.355489 -406.646618) (xy 119.407777 -406.631261) (xy 119.461718 -406.623501)
			(xy 119.488966 -406.623012) (xy 120.352566 -406.623012) (xy 120.379822 -406.623433) (xy 120.433779 -406.631186)
			(xy 120.486084 -406.64654) (xy 120.535671 -406.669182) (xy 120.581531 -406.69865) (xy 120.62273 -406.734346)
			(xy 120.658429 -406.775542) (xy 120.687902 -406.821399) (xy 120.710548 -406.870984) (xy 120.725907 -406.923287)
			(xy 120.733665 -406.977244) (xy 120.733665 -407.031752) (xy 122.171175 -407.031752) (xy 122.171175 -406.977248)
			(xy 122.178932 -406.9233) (xy 122.194288 -406.871004) (xy 122.216929 -406.821426) (xy 122.246396 -406.775575)
			(xy 122.282089 -406.734384) (xy 122.32328 -406.698693) (xy 122.369131 -406.669226) (xy 122.41871 -406.646585)
			(xy 122.471006 -406.631231) (xy 122.524954 -406.623475) (xy 122.552206 -406.623012) (xy 123.415806 -406.623012)
			(xy 123.443058 -406.623458) (xy 123.497008 -406.631216) (xy 123.549305 -406.646572) (xy 123.598884 -406.669215)
			(xy 123.644736 -406.698683) (xy 123.685928 -406.734376) (xy 123.721621 -406.775569) (xy 123.751088 -406.821421)
			(xy 123.77373 -406.871001) (xy 123.789085 -406.923298) (xy 123.796842 -406.977248) (xy 123.796842 -407.031752)
			(xy 123.796842 -407.031754) (xy 125.234375 -407.031754) (xy 125.234375 -406.977246) (xy 125.242133 -406.923294)
			(xy 125.257491 -406.870996) (xy 125.280135 -406.821415) (xy 125.309606 -406.775562) (xy 125.345303 -406.73437)
			(xy 125.386499 -406.698679) (xy 125.432355 -406.669213) (xy 125.481939 -406.646575) (xy 125.534239 -406.631223)
			(xy 125.588192 -406.623472) (xy 125.615446 -406.623012) (xy 126.479046 -406.623012) (xy 126.506297 -406.623461)
			(xy 126.560242 -406.631223) (xy 126.612534 -406.646583) (xy 126.662108 -406.669228) (xy 126.707955 -406.698697)
			(xy 126.749142 -406.734391) (xy 126.78483 -406.775582) (xy 126.814294 -406.821432) (xy 126.836933 -406.871009)
			(xy 126.852287 -406.923303) (xy 126.860042 -406.977249) (xy 126.860042 -407.031749) (xy 128.297698 -407.031749)
			(xy 128.297698 -406.977251) (xy 128.305454 -406.923307) (xy 128.320808 -406.871016) (xy 128.343446 -406.821443)
			(xy 128.37291 -406.775596) (xy 128.408598 -406.734408) (xy 128.449784 -406.698718) (xy 128.49563 -406.669253)
			(xy 128.545203 -406.646612) (xy 128.597494 -406.631257) (xy 128.651437 -406.623499) (xy 128.678686 -406.623012)
			(xy 129.542286 -406.623012) (xy 129.569541 -406.623434) (xy 129.623496 -406.63119) (xy 129.675799 -406.646545)
			(xy 129.725383 -406.669188) (xy 129.771241 -406.698657) (xy 129.812437 -406.734353) (xy 129.848134 -406.775548)
			(xy 129.877605 -406.821405) (xy 129.90025 -406.870988) (xy 129.915607 -406.92329) (xy 129.923365 -406.977245)
			(xy 129.923365 -407.031753) (xy 131.360875 -407.031753) (xy 131.360875 -406.977247) (xy 131.368633 -406.923297)
			(xy 131.383989 -406.871) (xy 131.406632 -406.821421) (xy 131.436101 -406.775569) (xy 131.471796 -406.734377)
			(xy 131.512989 -406.698686) (xy 131.558843 -406.66922) (xy 131.608424 -406.64658) (xy 131.660722 -406.631227)
			(xy 131.714673 -406.623474) (xy 131.741926 -406.623012) (xy 132.605526 -406.623012) (xy 132.632777 -406.62346)
			(xy 132.686725 -406.63122) (xy 132.73902 -406.646578) (xy 132.788596 -406.669222) (xy 132.834446 -406.69869)
			(xy 132.875635 -406.734383) (xy 132.911326 -406.775575) (xy 132.940791 -406.821427) (xy 132.963431 -406.871005)
			(xy 132.978786 -406.9233) (xy 132.986542 -406.977249) (xy 132.986542 -407.031748) (xy 134.424198 -407.031748)
			(xy 134.424198 -406.977252) (xy 134.431953 -406.92331) (xy 134.447306 -406.871021) (xy 134.469943 -406.821448)
			(xy 134.499405 -406.775602) (xy 134.535091 -406.734415) (xy 134.576275 -406.698725) (xy 134.622118 -406.66926)
			(xy 134.671689 -406.646618) (xy 134.723977 -406.631261) (xy 134.777918 -406.623501) (xy 134.805166 -406.623012)
			(xy 135.668766 -406.623012) (xy 135.696022 -406.623433) (xy 135.749979 -406.631186) (xy 135.802284 -406.64654)
			(xy 135.851871 -406.669182) (xy 135.897731 -406.69865) (xy 135.93893 -406.734346) (xy 135.974629 -406.775542)
			(xy 136.004102 -406.821399) (xy 136.026748 -406.870984) (xy 136.042107 -406.923287) (xy 136.049865 -406.977244)
			(xy 136.049865 -407.031752) (xy 137.487375 -407.031752) (xy 137.487375 -406.977248) (xy 137.495132 -406.9233)
			(xy 137.510488 -406.871004) (xy 137.533129 -406.821426) (xy 137.562596 -406.775575) (xy 137.598289 -406.734384)
			(xy 137.63948 -406.698693) (xy 137.685331 -406.669226) (xy 137.73491 -406.646585) (xy 137.787206 -406.631231)
			(xy 137.841154 -406.623475) (xy 137.868406 -406.623012) (xy 138.732006 -406.623012) (xy 138.759258 -406.623458)
			(xy 138.813208 -406.631216) (xy 138.865505 -406.646572) (xy 138.915084 -406.669215) (xy 138.960936 -406.698683)
			(xy 139.002128 -406.734376) (xy 139.037821 -406.775569) (xy 139.067288 -406.821421) (xy 139.08993 -406.871001)
			(xy 139.105285 -406.923298) (xy 139.113042 -406.977248) (xy 139.113042 -407.031752) (xy 139.113042 -407.031754)
			(xy 140.550575 -407.031754) (xy 140.550575 -406.977246) (xy 140.558333 -406.923294) (xy 140.573691 -406.870996)
			(xy 140.596335 -406.821415) (xy 140.625806 -406.775562) (xy 140.661503 -406.73437) (xy 140.702699 -406.698679)
			(xy 140.748555 -406.669213) (xy 140.798139 -406.646575) (xy 140.850439 -406.631223) (xy 140.904392 -406.623472)
			(xy 140.931646 -406.623012) (xy 141.795246 -406.623012) (xy 141.822497 -406.623461) (xy 141.876442 -406.631223)
			(xy 141.928734 -406.646583) (xy 141.978308 -406.669228) (xy 142.024155 -406.698697) (xy 142.065342 -406.734391)
			(xy 142.10103 -406.775582) (xy 142.130494 -406.821432) (xy 142.153133 -406.871009) (xy 142.168487 -406.923303)
			(xy 142.176242 -406.977249) (xy 142.176242 -407.031749) (xy 143.613898 -407.031749) (xy 143.613898 -406.977251)
			(xy 143.621654 -406.923307) (xy 143.637008 -406.871016) (xy 143.659646 -406.821443) (xy 143.68911 -406.775596)
			(xy 143.724798 -406.734408) (xy 143.765984 -406.698718) (xy 143.81183 -406.669253) (xy 143.861403 -406.646612)
			(xy 143.913694 -406.631257) (xy 143.967637 -406.623499) (xy 143.994886 -406.623012) (xy 144.858486 -406.623012)
			(xy 144.885741 -406.623434) (xy 144.939696 -406.63119) (xy 144.991999 -406.646545) (xy 145.041583 -406.669188)
			(xy 145.087441 -406.698657) (xy 145.128637 -406.734353) (xy 145.164334 -406.775548) (xy 145.193805 -406.821405)
			(xy 145.21645 -406.870988) (xy 145.231807 -406.92329) (xy 145.239565 -406.977245) (xy 145.239565 -407.031753)
			(xy 146.677075 -407.031753) (xy 146.677075 -406.977247) (xy 146.684833 -406.923297) (xy 146.700189 -406.871)
			(xy 146.722832 -406.821421) (xy 146.752301 -406.775569) (xy 146.787996 -406.734377) (xy 146.829189 -406.698686)
			(xy 146.875043 -406.66922) (xy 146.924624 -406.64658) (xy 146.976922 -406.631227) (xy 147.030873 -406.623474)
			(xy 147.058126 -406.623012) (xy 147.921726 -406.623012) (xy 147.948977 -406.62346) (xy 148.002925 -406.63122)
			(xy 148.05522 -406.646578) (xy 148.104796 -406.669222) (xy 148.150646 -406.69869) (xy 148.191835 -406.734383)
			(xy 148.227526 -406.775575) (xy 148.256991 -406.821427) (xy 148.279631 -406.871005) (xy 148.294986 -406.9233)
			(xy 148.302742 -406.977249) (xy 148.302742 -407.031748) (xy 149.740398 -407.031748) (xy 149.740398 -406.977252)
			(xy 149.748153 -406.92331) (xy 149.763506 -406.871021) (xy 149.786143 -406.821448) (xy 149.815605 -406.775602)
			(xy 149.851291 -406.734415) (xy 149.892475 -406.698725) (xy 149.938318 -406.66926) (xy 149.987889 -406.646618)
			(xy 150.040177 -406.631261) (xy 150.094118 -406.623501) (xy 150.121366 -406.623012) (xy 150.984966 -406.623012)
			(xy 151.012222 -406.623433) (xy 151.066179 -406.631186) (xy 151.118484 -406.64654) (xy 151.168071 -406.669182)
			(xy 151.213931 -406.69865) (xy 151.25513 -406.734346) (xy 151.290829 -406.775542) (xy 151.320302 -406.821399)
			(xy 151.342948 -406.870984) (xy 151.358307 -406.923287) (xy 151.366065 -406.977244) (xy 151.366065 -407.031752)
			(xy 152.803575 -407.031752) (xy 152.803575 -406.977248) (xy 152.811332 -406.9233) (xy 152.826688 -406.871004)
			(xy 152.849329 -406.821426) (xy 152.878796 -406.775575) (xy 152.914489 -406.734384) (xy 152.95568 -406.698693)
			(xy 153.001531 -406.669226) (xy 153.05111 -406.646585) (xy 153.103406 -406.631231) (xy 153.157354 -406.623475)
			(xy 153.184606 -406.623012) (xy 154.048206 -406.623012) (xy 154.075458 -406.623458) (xy 154.129408 -406.631216)
			(xy 154.181705 -406.646572) (xy 154.231284 -406.669215) (xy 154.277136 -406.698683) (xy 154.318328 -406.734376)
			(xy 154.354021 -406.775569) (xy 154.383488 -406.821421) (xy 154.40613 -406.871001) (xy 154.421485 -406.923298)
			(xy 154.429242 -406.977248) (xy 154.429242 -407.031752) (xy 154.429242 -407.031754) (xy 155.866775 -407.031754)
			(xy 155.866775 -406.977246) (xy 155.874533 -406.923294) (xy 155.889891 -406.870996) (xy 155.912535 -406.821415)
			(xy 155.942006 -406.775562) (xy 155.977703 -406.73437) (xy 156.018899 -406.698679) (xy 156.064755 -406.669213)
			(xy 156.114339 -406.646575) (xy 156.166639 -406.631223) (xy 156.220592 -406.623472) (xy 156.247846 -406.623012)
			(xy 157.111446 -406.623012) (xy 157.138697 -406.623461) (xy 157.192642 -406.631223) (xy 157.244934 -406.646583)
			(xy 157.294508 -406.669228) (xy 157.340355 -406.698697) (xy 157.381542 -406.734391) (xy 157.41723 -406.775582)
			(xy 157.446694 -406.821432) (xy 157.469333 -406.871009) (xy 157.484687 -406.923303) (xy 157.492442 -406.977249)
			(xy 157.492442 -407.031749) (xy 158.930098 -407.031749) (xy 158.930098 -406.977251) (xy 158.937854 -406.923307)
			(xy 158.953208 -406.871016) (xy 158.975846 -406.821443) (xy 159.00531 -406.775596) (xy 159.040998 -406.734408)
			(xy 159.082184 -406.698718) (xy 159.12803 -406.669253) (xy 159.177603 -406.646612) (xy 159.229894 -406.631257)
			(xy 159.283837 -406.623499) (xy 159.311086 -406.623012) (xy 160.174686 -406.623012) (xy 160.201941 -406.623434)
			(xy 160.255896 -406.63119) (xy 160.308199 -406.646545) (xy 160.357783 -406.669188) (xy 160.403641 -406.698657)
			(xy 160.444837 -406.734353) (xy 160.480534 -406.775548) (xy 160.510005 -406.821405) (xy 160.53265 -406.870988)
			(xy 160.548007 -406.92329) (xy 160.555765 -406.977245) (xy 160.555765 -407.031753) (xy 161.993275 -407.031753)
			(xy 161.993275 -406.977247) (xy 162.001033 -406.923297) (xy 162.016389 -406.871) (xy 162.039032 -406.821421)
			(xy 162.068501 -406.775569) (xy 162.104196 -406.734377) (xy 162.145389 -406.698686) (xy 162.191243 -406.66922)
			(xy 162.240824 -406.64658) (xy 162.293122 -406.631227) (xy 162.347073 -406.623474) (xy 162.374326 -406.623012)
			(xy 163.237926 -406.623012) (xy 163.265177 -406.62346) (xy 163.319125 -406.63122) (xy 163.37142 -406.646578)
			(xy 163.420996 -406.669222) (xy 163.466846 -406.69869) (xy 163.508035 -406.734383) (xy 163.543726 -406.775575)
			(xy 163.573191 -406.821427) (xy 163.595831 -406.871005) (xy 163.611186 -406.9233) (xy 163.618942 -406.977249)
			(xy 163.618942 -407.031751) (xy 163.611186 -407.0857) (xy 163.595831 -407.137995) (xy 163.573191 -407.187573)
			(xy 163.543726 -407.233425) (xy 163.508035 -407.274617) (xy 163.466846 -407.31031) (xy 163.420996 -407.339778)
			(xy 163.37142 -407.362422) (xy 163.319125 -407.37778) (xy 163.265177 -407.38554) (xy 163.237926 -407.386028)
			(xy 162.374326 -407.386028) (xy 162.347073 -407.385526) (xy 162.293122 -407.377773) (xy 162.240824 -407.36242)
			(xy 162.191243 -407.33978) (xy 162.145389 -407.310314) (xy 162.104196 -407.274623) (xy 162.068501 -407.233431)
			(xy 162.039032 -407.187579) (xy 162.016389 -407.138) (xy 162.001033 -407.085703) (xy 161.993275 -407.031753)
			(xy 160.555765 -407.031753) (xy 160.555765 -407.031755) (xy 160.548007 -407.08571) (xy 160.53265 -407.138012)
			(xy 160.510005 -407.187595) (xy 160.480534 -407.233452) (xy 160.444837 -407.274647) (xy 160.403641 -407.310343)
			(xy 160.357783 -407.339812) (xy 160.308199 -407.362455) (xy 160.255896 -407.37781) (xy 160.201941 -407.385566)
			(xy 160.174686 -407.386028) (xy 159.311086 -407.386028) (xy 159.283837 -407.385501) (xy 159.229894 -407.377743)
			(xy 159.177603 -407.362388) (xy 159.12803 -407.339747) (xy 159.082184 -407.310282) (xy 159.040998 -407.274592)
			(xy 159.00531 -407.233404) (xy 158.975846 -407.187557) (xy 158.953208 -407.137984) (xy 158.937854 -407.085693)
			(xy 158.930098 -407.031749) (xy 157.492442 -407.031749) (xy 157.492442 -407.031751) (xy 157.484687 -407.085697)
			(xy 157.469333 -407.137991) (xy 157.446694 -407.187568) (xy 157.41723 -407.233418) (xy 157.381542 -407.274609)
			(xy 157.340355 -407.310303) (xy 157.294508 -407.339772) (xy 157.244934 -407.362417) (xy 157.192642 -407.377777)
			(xy 157.138697 -407.385539) (xy 157.111446 -407.386028) (xy 156.247846 -407.386028) (xy 156.220592 -407.385528)
			(xy 156.166639 -407.377777) (xy 156.114339 -407.362425) (xy 156.064755 -407.339787) (xy 156.018899 -407.310321)
			(xy 155.977703 -407.27463) (xy 155.942006 -407.233438) (xy 155.912535 -407.187585) (xy 155.889891 -407.138004)
			(xy 155.874533 -407.085706) (xy 155.866775 -407.031754) (xy 154.429242 -407.031754) (xy 154.421485 -407.085702)
			(xy 154.40613 -407.137999) (xy 154.383488 -407.187579) (xy 154.354021 -407.233431) (xy 154.318328 -407.274624)
			(xy 154.277136 -407.310317) (xy 154.231284 -407.339785) (xy 154.181705 -407.362428) (xy 154.129408 -407.377784)
			(xy 154.075458 -407.385542) (xy 154.048206 -407.386028) (xy 153.184606 -407.386028) (xy 153.157354 -407.385525)
			(xy 153.103406 -407.377769) (xy 153.05111 -407.362415) (xy 153.001531 -407.339774) (xy 152.95568 -407.310307)
			(xy 152.914489 -407.274616) (xy 152.878796 -407.233425) (xy 152.849329 -407.187574) (xy 152.826688 -407.137996)
			(xy 152.811332 -407.0857) (xy 152.803575 -407.031752) (xy 151.366065 -407.031752) (xy 151.366065 -407.031756)
			(xy 151.358307 -407.085713) (xy 151.342948 -407.138016) (xy 151.320302 -407.187601) (xy 151.290829 -407.233458)
			(xy 151.25513 -407.274654) (xy 151.213931 -407.31035) (xy 151.168071 -407.339818) (xy 151.118484 -407.36246)
			(xy 151.066179 -407.377814) (xy 151.012222 -407.385567) (xy 150.984966 -407.386028) (xy 150.121366 -407.386028)
			(xy 150.094118 -407.385499) (xy 150.040177 -407.377739) (xy 149.987889 -407.362382) (xy 149.938318 -407.33974)
			(xy 149.892475 -407.310275) (xy 149.851291 -407.274585) (xy 149.815605 -407.233398) (xy 149.786143 -407.187552)
			(xy 149.763506 -407.137979) (xy 149.748153 -407.08569) (xy 149.740398 -407.031748) (xy 148.302742 -407.031748)
			(xy 148.302742 -407.031751) (xy 148.294986 -407.0857) (xy 148.279631 -407.137995) (xy 148.256991 -407.187573)
			(xy 148.227526 -407.233425) (xy 148.191835 -407.274617) (xy 148.150646 -407.31031) (xy 148.104796 -407.339778)
			(xy 148.05522 -407.362422) (xy 148.002925 -407.37778) (xy 147.948977 -407.38554) (xy 147.921726 -407.386028)
			(xy 147.058126 -407.386028) (xy 147.030873 -407.385526) (xy 146.976922 -407.377773) (xy 146.924624 -407.36242)
			(xy 146.875043 -407.33978) (xy 146.829189 -407.310314) (xy 146.787996 -407.274623) (xy 146.752301 -407.233431)
			(xy 146.722832 -407.187579) (xy 146.700189 -407.138) (xy 146.684833 -407.085703) (xy 146.677075 -407.031753)
			(xy 145.239565 -407.031753) (xy 145.239565 -407.031755) (xy 145.231807 -407.08571) (xy 145.21645 -407.138012)
			(xy 145.193805 -407.187595) (xy 145.164334 -407.233452) (xy 145.128637 -407.274647) (xy 145.087441 -407.310343)
			(xy 145.041583 -407.339812) (xy 144.991999 -407.362455) (xy 144.939696 -407.37781) (xy 144.885741 -407.385566)
			(xy 144.858486 -407.386028) (xy 143.994886 -407.386028) (xy 143.967637 -407.385501) (xy 143.913694 -407.377743)
			(xy 143.861403 -407.362388) (xy 143.81183 -407.339747) (xy 143.765984 -407.310282) (xy 143.724798 -407.274592)
			(xy 143.68911 -407.233404) (xy 143.659646 -407.187557) (xy 143.637008 -407.137984) (xy 143.621654 -407.085693)
			(xy 143.613898 -407.031749) (xy 142.176242 -407.031749) (xy 142.176242 -407.031751) (xy 142.168487 -407.085697)
			(xy 142.153133 -407.137991) (xy 142.130494 -407.187568) (xy 142.10103 -407.233418) (xy 142.065342 -407.274609)
			(xy 142.024155 -407.310303) (xy 141.978308 -407.339772) (xy 141.928734 -407.362417) (xy 141.876442 -407.377777)
			(xy 141.822497 -407.385539) (xy 141.795246 -407.386028) (xy 140.931646 -407.386028) (xy 140.904392 -407.385528)
			(xy 140.850439 -407.377777) (xy 140.798139 -407.362425) (xy 140.748555 -407.339787) (xy 140.702699 -407.310321)
			(xy 140.661503 -407.27463) (xy 140.625806 -407.233438) (xy 140.596335 -407.187585) (xy 140.573691 -407.138004)
			(xy 140.558333 -407.085706) (xy 140.550575 -407.031754) (xy 139.113042 -407.031754) (xy 139.105285 -407.085702)
			(xy 139.08993 -407.137999) (xy 139.067288 -407.187579) (xy 139.037821 -407.233431) (xy 139.002128 -407.274624)
			(xy 138.960936 -407.310317) (xy 138.915084 -407.339785) (xy 138.865505 -407.362428) (xy 138.813208 -407.377784)
			(xy 138.759258 -407.385542) (xy 138.732006 -407.386028) (xy 137.868406 -407.386028) (xy 137.841154 -407.385525)
			(xy 137.787206 -407.377769) (xy 137.73491 -407.362415) (xy 137.685331 -407.339774) (xy 137.63948 -407.310307)
			(xy 137.598289 -407.274616) (xy 137.562596 -407.233425) (xy 137.533129 -407.187574) (xy 137.510488 -407.137996)
			(xy 137.495132 -407.0857) (xy 137.487375 -407.031752) (xy 136.049865 -407.031752) (xy 136.049865 -407.031756)
			(xy 136.042107 -407.085713) (xy 136.026748 -407.138016) (xy 136.004102 -407.187601) (xy 135.974629 -407.233458)
			(xy 135.93893 -407.274654) (xy 135.897731 -407.31035) (xy 135.851871 -407.339818) (xy 135.802284 -407.36246)
			(xy 135.749979 -407.377814) (xy 135.696022 -407.385567) (xy 135.668766 -407.386028) (xy 134.805166 -407.386028)
			(xy 134.777918 -407.385499) (xy 134.723977 -407.377739) (xy 134.671689 -407.362382) (xy 134.622118 -407.33974)
			(xy 134.576275 -407.310275) (xy 134.535091 -407.274585) (xy 134.499405 -407.233398) (xy 134.469943 -407.187552)
			(xy 134.447306 -407.137979) (xy 134.431953 -407.08569) (xy 134.424198 -407.031748) (xy 132.986542 -407.031748)
			(xy 132.986542 -407.031751) (xy 132.978786 -407.0857) (xy 132.963431 -407.137995) (xy 132.940791 -407.187573)
			(xy 132.911326 -407.233425) (xy 132.875635 -407.274617) (xy 132.834446 -407.31031) (xy 132.788596 -407.339778)
			(xy 132.73902 -407.362422) (xy 132.686725 -407.37778) (xy 132.632777 -407.38554) (xy 132.605526 -407.386028)
			(xy 131.741926 -407.386028) (xy 131.714673 -407.385526) (xy 131.660722 -407.377773) (xy 131.608424 -407.36242)
			(xy 131.558843 -407.33978) (xy 131.512989 -407.310314) (xy 131.471796 -407.274623) (xy 131.436101 -407.233431)
			(xy 131.406632 -407.187579) (xy 131.383989 -407.138) (xy 131.368633 -407.085703) (xy 131.360875 -407.031753)
			(xy 129.923365 -407.031753) (xy 129.923365 -407.031755) (xy 129.915607 -407.08571) (xy 129.90025 -407.138012)
			(xy 129.877605 -407.187595) (xy 129.848134 -407.233452) (xy 129.812437 -407.274647) (xy 129.771241 -407.310343)
			(xy 129.725383 -407.339812) (xy 129.675799 -407.362455) (xy 129.623496 -407.37781) (xy 129.569541 -407.385566)
			(xy 129.542286 -407.386028) (xy 128.678686 -407.386028) (xy 128.651437 -407.385501) (xy 128.597494 -407.377743)
			(xy 128.545203 -407.362388) (xy 128.49563 -407.339747) (xy 128.449784 -407.310282) (xy 128.408598 -407.274592)
			(xy 128.37291 -407.233404) (xy 128.343446 -407.187557) (xy 128.320808 -407.137984) (xy 128.305454 -407.085693)
			(xy 128.297698 -407.031749) (xy 126.860042 -407.031749) (xy 126.860042 -407.031751) (xy 126.852287 -407.085697)
			(xy 126.836933 -407.137991) (xy 126.814294 -407.187568) (xy 126.78483 -407.233418) (xy 126.749142 -407.274609)
			(xy 126.707955 -407.310303) (xy 126.662108 -407.339772) (xy 126.612534 -407.362417) (xy 126.560242 -407.377777)
			(xy 126.506297 -407.385539) (xy 126.479046 -407.386028) (xy 125.615446 -407.386028) (xy 125.588192 -407.385528)
			(xy 125.534239 -407.377777) (xy 125.481939 -407.362425) (xy 125.432355 -407.339787) (xy 125.386499 -407.310321)
			(xy 125.345303 -407.27463) (xy 125.309606 -407.233438) (xy 125.280135 -407.187585) (xy 125.257491 -407.138004)
			(xy 125.242133 -407.085706) (xy 125.234375 -407.031754) (xy 123.796842 -407.031754) (xy 123.789085 -407.085702)
			(xy 123.77373 -407.137999) (xy 123.751088 -407.187579) (xy 123.721621 -407.233431) (xy 123.685928 -407.274624)
			(xy 123.644736 -407.310317) (xy 123.598884 -407.339785) (xy 123.549305 -407.362428) (xy 123.497008 -407.377784)
			(xy 123.443058 -407.385542) (xy 123.415806 -407.386028) (xy 122.552206 -407.386028) (xy 122.524954 -407.385525)
			(xy 122.471006 -407.377769) (xy 122.41871 -407.362415) (xy 122.369131 -407.339774) (xy 122.32328 -407.310307)
			(xy 122.282089 -407.274616) (xy 122.246396 -407.233425) (xy 122.216929 -407.187574) (xy 122.194288 -407.137996)
			(xy 122.178932 -407.0857) (xy 122.171175 -407.031752) (xy 120.733665 -407.031752) (xy 120.733665 -407.031756)
			(xy 120.725907 -407.085713) (xy 120.710548 -407.138016) (xy 120.687902 -407.187601) (xy 120.658429 -407.233458)
			(xy 120.62273 -407.274654) (xy 120.581531 -407.31035) (xy 120.535671 -407.339818) (xy 120.486084 -407.36246)
			(xy 120.433779 -407.377814) (xy 120.379822 -407.385567) (xy 120.352566 -407.386028) (xy 119.488966 -407.386028)
			(xy 119.461718 -407.385499) (xy 119.407777 -407.377739) (xy 119.355489 -407.362382) (xy 119.305918 -407.33974)
			(xy 119.260075 -407.310275) (xy 119.218891 -407.274585) (xy 119.183205 -407.233398) (xy 119.153743 -407.187552)
			(xy 119.131106 -407.137979) (xy 119.115753 -407.08569) (xy 119.107998 -407.031748) (xy 117.670342 -407.031748)
			(xy 117.670342 -407.031751) (xy 117.662586 -407.0857) (xy 117.647231 -407.137995) (xy 117.624591 -407.187573)
			(xy 117.595126 -407.233425) (xy 117.559435 -407.274617) (xy 117.518246 -407.31031) (xy 117.472396 -407.339778)
			(xy 117.42282 -407.362422) (xy 117.370525 -407.37778) (xy 117.316577 -407.38554) (xy 117.289326 -407.386028)
			(xy 116.425726 -407.386028) (xy 116.398473 -407.385526) (xy 116.344522 -407.377773) (xy 116.292224 -407.36242)
			(xy 116.242643 -407.33978) (xy 116.196789 -407.310314) (xy 116.155596 -407.274623) (xy 116.119901 -407.233431)
			(xy 116.090432 -407.187579) (xy 116.067789 -407.138) (xy 116.052433 -407.085703) (xy 116.044675 -407.031753)
			(xy 96.519065 -407.031753) (xy 96.519065 -407.031755) (xy 96.511307 -407.08571) (xy 96.49595 -407.138012)
			(xy 96.473305 -407.187596) (xy 96.443834 -407.233452) (xy 96.408136 -407.274648) (xy 96.36694 -407.310343)
			(xy 96.321082 -407.339812) (xy 96.271497 -407.362455) (xy 96.219195 -407.377811) (xy 96.165239 -407.385566)
			(xy 96.137984 -407.386028) (xy 95.274384 -407.386028) (xy 95.247135 -407.385501) (xy 95.193192 -407.377743)
			(xy 95.140902 -407.362387) (xy 95.091329 -407.339746) (xy 95.045483 -407.310281) (xy 95.004297 -407.274591)
			(xy 94.968609 -407.233404) (xy 94.939146 -407.187557) (xy 94.916507 -407.137983) (xy 94.901154 -407.085692)
			(xy 94.893398 -407.031749) (xy 93.455742 -407.031749) (xy 93.455742 -407.031751) (xy 93.447987 -407.085697)
			(xy 93.432633 -407.137991) (xy 93.409994 -407.187568) (xy 93.38053 -407.233419) (xy 93.344841 -407.27461)
			(xy 93.303654 -407.310304) (xy 93.257807 -407.339773) (xy 93.208233 -407.362417) (xy 93.15594 -407.377777)
			(xy 93.101995 -407.385539) (xy 93.074744 -407.386028) (xy 92.211144 -407.386028) (xy 92.183891 -407.385528)
			(xy 92.129938 -407.377776) (xy 92.077637 -407.362425) (xy 92.028054 -407.339786) (xy 91.982198 -407.310321)
			(xy 91.941002 -407.274629) (xy 91.905306 -407.233437) (xy 91.875835 -407.187584) (xy 91.853191 -407.138004)
			(xy 91.837833 -407.085705) (xy 91.830075 -407.031753) (xy 90.392542 -407.031753) (xy 90.384785 -407.085703)
			(xy 90.36943 -407.138) (xy 90.346788 -407.187579) (xy 90.31732 -407.233432) (xy 90.281627 -407.274624)
			(xy 90.240435 -407.310318) (xy 90.194583 -407.339786) (xy 90.145004 -407.362428) (xy 90.092707 -407.377785)
			(xy 90.038756 -407.385542) (xy 90.011504 -407.386028) (xy 89.147904 -407.386028) (xy 89.120652 -407.385525)
			(xy 89.066704 -407.377769) (xy 89.014408 -407.362414) (xy 88.96483 -407.339773) (xy 88.918979 -407.310307)
			(xy 88.877788 -407.274615) (xy 88.842096 -407.233424) (xy 88.812629 -407.187573) (xy 88.789987 -407.137995)
			(xy 88.774632 -407.0857) (xy 88.766875 -407.031752) (xy 87.329365 -407.031752) (xy 87.329365 -407.031756)
			(xy 87.321607 -407.085713) (xy 87.306248 -407.138016) (xy 87.283602 -407.187602) (xy 87.254129 -407.233459)
			(xy 87.218429 -407.274655) (xy 87.17723 -407.31035) (xy 87.13137 -407.339819) (xy 87.081783 -407.362461)
			(xy 87.029478 -407.377814) (xy 86.97552 -407.385568) (xy 86.948264 -407.386028) (xy 86.084664 -407.386028)
			(xy 86.057416 -407.385499) (xy 86.003475 -407.377739) (xy 85.951187 -407.362382) (xy 85.901617 -407.33974)
			(xy 85.855774 -407.310274) (xy 85.81459 -407.274584) (xy 85.778904 -407.233397) (xy 85.749443 -407.187551)
			(xy 85.726806 -407.137979) (xy 85.711453 -407.08569) (xy 85.703698 -407.031748) (xy 84.266042 -407.031748)
			(xy 84.266042 -407.031752) (xy 84.258286 -407.0857) (xy 84.242931 -407.137996) (xy 84.220291 -407.187574)
			(xy 84.190825 -407.233425) (xy 84.155134 -407.274617) (xy 84.113945 -407.310311) (xy 84.068095 -407.339779)
			(xy 84.018518 -407.362423) (xy 83.966224 -407.377781) (xy 83.912276 -407.385541) (xy 83.885024 -407.386028)
			(xy 83.021424 -407.386028) (xy 82.994171 -407.385526) (xy 82.940221 -407.377773) (xy 82.887923 -407.362419)
			(xy 82.838342 -407.339779) (xy 82.792488 -407.310314) (xy 82.751295 -407.274622) (xy 82.715601 -407.233431)
			(xy 82.686132 -407.187579) (xy 82.663489 -407.138) (xy 82.648133 -407.085703) (xy 82.640375 -407.031753)
			(xy 81.202865 -407.031753) (xy 81.202865 -407.031755) (xy 81.195107 -407.08571) (xy 81.17975 -407.138012)
			(xy 81.157105 -407.187596) (xy 81.127634 -407.233452) (xy 81.091936 -407.274648) (xy 81.05074 -407.310343)
			(xy 81.004882 -407.339812) (xy 80.955297 -407.362455) (xy 80.902995 -407.377811) (xy 80.849039 -407.385566)
			(xy 80.821784 -407.386028) (xy 79.958184 -407.386028) (xy 79.930935 -407.385501) (xy 79.876992 -407.377743)
			(xy 79.824702 -407.362387) (xy 79.775129 -407.339746) (xy 79.729283 -407.310281) (xy 79.688097 -407.274591)
			(xy 79.652409 -407.233404) (xy 79.622946 -407.187557) (xy 79.600307 -407.137983) (xy 79.584954 -407.085692)
			(xy 79.577198 -407.031749) (xy 78.139542 -407.031749) (xy 78.139542 -407.031751) (xy 78.131787 -407.085697)
			(xy 78.116433 -407.137991) (xy 78.093794 -407.187568) (xy 78.06433 -407.233419) (xy 78.028641 -407.27461)
			(xy 77.987454 -407.310304) (xy 77.941607 -407.339773) (xy 77.892033 -407.362417) (xy 77.83974 -407.377777)
			(xy 77.785795 -407.385539) (xy 77.758544 -407.386028) (xy 76.894944 -407.386028) (xy 76.867691 -407.385528)
			(xy 76.813738 -407.377776) (xy 76.761437 -407.362425) (xy 76.711854 -407.339786) (xy 76.665998 -407.310321)
			(xy 76.624802 -407.274629) (xy 76.589106 -407.233437) (xy 76.559635 -407.187584) (xy 76.536991 -407.138004)
			(xy 76.521633 -407.085705) (xy 76.513875 -407.031753) (xy 75.076342 -407.031753) (xy 75.068585 -407.085703)
			(xy 75.05323 -407.138) (xy 75.030588 -407.187579) (xy 75.00112 -407.233432) (xy 74.965427 -407.274624)
			(xy 74.924235 -407.310318) (xy 74.878383 -407.339786) (xy 74.828804 -407.362428) (xy 74.776507 -407.377785)
			(xy 74.722556 -407.385542) (xy 74.695304 -407.386028) (xy 73.831704 -407.386028) (xy 73.804452 -407.385525)
			(xy 73.750504 -407.377769) (xy 73.698208 -407.362414) (xy 73.64863 -407.339773) (xy 73.602779 -407.310307)
			(xy 73.561588 -407.274615) (xy 73.525896 -407.233424) (xy 73.496429 -407.187573) (xy 73.473787 -407.137995)
			(xy 73.458432 -407.0857) (xy 73.450675 -407.031752) (xy 72.013165 -407.031752) (xy 72.013165 -407.031756)
			(xy 72.005407 -407.085713) (xy 71.990048 -407.138016) (xy 71.967402 -407.187602) (xy 71.937929 -407.233459)
			(xy 71.902229 -407.274655) (xy 71.86103 -407.31035) (xy 71.81517 -407.339819) (xy 71.765583 -407.362461)
			(xy 71.713278 -407.377814) (xy 71.65932 -407.385568) (xy 71.632064 -407.386028) (xy 70.768464 -407.386028)
			(xy 70.741216 -407.385499) (xy 70.687275 -407.377739) (xy 70.634987 -407.362382) (xy 70.585417 -407.33974)
			(xy 70.539574 -407.310274) (xy 70.49839 -407.274584) (xy 70.462704 -407.233397) (xy 70.433243 -407.187551)
			(xy 70.410606 -407.137979) (xy 70.395253 -407.08569) (xy 70.387498 -407.031748) (xy 68.949842 -407.031748)
			(xy 68.949842 -407.031752) (xy 68.942086 -407.0857) (xy 68.926731 -407.137996) (xy 68.904091 -407.187574)
			(xy 68.874625 -407.233425) (xy 68.838934 -407.274617) (xy 68.797745 -407.310311) (xy 68.751895 -407.339779)
			(xy 68.702318 -407.362423) (xy 68.650024 -407.377781) (xy 68.596076 -407.385541) (xy 68.568824 -407.386028)
			(xy 67.705224 -407.386028) (xy 67.677971 -407.385526) (xy 67.624021 -407.377773) (xy 67.571723 -407.362419)
			(xy 67.522142 -407.339779) (xy 67.476288 -407.310314) (xy 67.435095 -407.274622) (xy 67.399401 -407.233431)
			(xy 67.369932 -407.187579) (xy 67.347289 -407.138) (xy 67.331933 -407.085703) (xy 67.324175 -407.031753)
			(xy 65.886665 -407.031753) (xy 65.886665 -407.031755) (xy 65.878907 -407.08571) (xy 65.86355 -407.138012)
			(xy 65.840905 -407.187596) (xy 65.811434 -407.233452) (xy 65.775736 -407.274648) (xy 65.73454 -407.310343)
			(xy 65.688682 -407.339812) (xy 65.639097 -407.362455) (xy 65.586795 -407.377811) (xy 65.532839 -407.385566)
			(xy 65.505584 -407.386028) (xy 64.641984 -407.386028) (xy 64.614735 -407.385501) (xy 64.560792 -407.377743)
			(xy 64.508502 -407.362387) (xy 64.458929 -407.339746) (xy 64.413083 -407.310281) (xy 64.371897 -407.274591)
			(xy 64.336209 -407.233404) (xy 64.306746 -407.187557) (xy 64.284107 -407.137983) (xy 64.268754 -407.085692)
			(xy 64.260998 -407.031749) (xy 62.823342 -407.031749) (xy 62.823342 -407.031751) (xy 62.815587 -407.085697)
			(xy 62.800233 -407.137991) (xy 62.777594 -407.187568) (xy 62.74813 -407.233419) (xy 62.712441 -407.27461)
			(xy 62.671254 -407.310304) (xy 62.625407 -407.339773) (xy 62.575833 -407.362417) (xy 62.52354 -407.377777)
			(xy 62.469595 -407.385539) (xy 62.442344 -407.386028) (xy 61.578744 -407.386028) (xy 61.551491 -407.385528)
			(xy 61.497538 -407.377776) (xy 61.445237 -407.362425) (xy 61.395654 -407.339786) (xy 61.349798 -407.310321)
			(xy 61.308602 -407.274629) (xy 61.272906 -407.233437) (xy 61.243435 -407.187584) (xy 61.220791 -407.138004)
			(xy 61.205433 -407.085705) (xy 61.197675 -407.031753) (xy 59.760142 -407.031753) (xy 59.752385 -407.085703)
			(xy 59.73703 -407.138) (xy 59.714388 -407.187579) (xy 59.68492 -407.233432) (xy 59.649227 -407.274624)
			(xy 59.608035 -407.310318) (xy 59.562183 -407.339786) (xy 59.512604 -407.362428) (xy 59.460307 -407.377785)
			(xy 59.406356 -407.385542) (xy 59.379104 -407.386028) (xy 58.515504 -407.386028) (xy 58.488252 -407.385525)
			(xy 58.434304 -407.377769) (xy 58.382008 -407.362414) (xy 58.33243 -407.339773) (xy 58.286579 -407.310307)
			(xy 58.245388 -407.274615) (xy 58.209696 -407.233424) (xy 58.180229 -407.187573) (xy 58.157587 -407.137995)
			(xy 58.142232 -407.0857) (xy 58.134475 -407.031752) (xy 56.696965 -407.031752) (xy 56.696965 -407.031756)
			(xy 56.689207 -407.085713) (xy 56.673848 -407.138016) (xy 56.651202 -407.187602) (xy 56.621729 -407.233459)
			(xy 56.586029 -407.274655) (xy 56.54483 -407.31035) (xy 56.49897 -407.339819) (xy 56.449383 -407.362461)
			(xy 56.397078 -407.377814) (xy 56.34312 -407.385568) (xy 56.315864 -407.386028) (xy 55.452264 -407.386028)
			(xy 55.425016 -407.385499) (xy 55.371075 -407.377739) (xy 55.318787 -407.362382) (xy 55.269217 -407.33974)
			(xy 55.223374 -407.310274) (xy 55.18219 -407.274584) (xy 55.146504 -407.233397) (xy 55.117043 -407.187551)
			(xy 55.094406 -407.137979) (xy 55.079053 -407.08569) (xy 55.071298 -407.031748) (xy 53.633642 -407.031748)
			(xy 53.633642 -407.031752) (xy 53.625886 -407.0857) (xy 53.610531 -407.137996) (xy 53.587891 -407.187574)
			(xy 53.558425 -407.233425) (xy 53.522734 -407.274617) (xy 53.481545 -407.310311) (xy 53.435695 -407.339779)
			(xy 53.386118 -407.362423) (xy 53.333824 -407.377781) (xy 53.279876 -407.385541) (xy 53.252624 -407.386028)
			(xy 52.389024 -407.386028) (xy 52.361771 -407.385526) (xy 52.307821 -407.377773) (xy 52.255523 -407.362419)
			(xy 52.205942 -407.339779) (xy 52.160088 -407.310314) (xy 52.118895 -407.274622) (xy 52.083201 -407.233431)
			(xy 52.053732 -407.187579) (xy 52.031089 -407.138) (xy 52.015733 -407.085703) (xy 52.007975 -407.031753)
			(xy 50.570465 -407.031753) (xy 50.570465 -407.031755) (xy 50.562707 -407.08571) (xy 50.54735 -407.138012)
			(xy 50.524705 -407.187596) (xy 50.495234 -407.233452) (xy 50.459536 -407.274648) (xy 50.41834 -407.310343)
			(xy 50.372482 -407.339812) (xy 50.322897 -407.362455) (xy 50.270595 -407.377811) (xy 50.216639 -407.385566)
			(xy 50.189384 -407.386028) (xy 49.325784 -407.386028) (xy 49.298535 -407.385501) (xy 49.244592 -407.377743)
			(xy 49.192302 -407.362387) (xy 49.142729 -407.339746) (xy 49.096883 -407.310281) (xy 49.055697 -407.274591)
			(xy 49.020009 -407.233404) (xy 48.990546 -407.187557) (xy 48.967907 -407.137983) (xy 48.952554 -407.085692)
			(xy 48.944798 -407.031749) (xy 44.883756 -407.031749) (xy 44.868945 -407.05439) (xy 44.764794 -407.199093)
			(xy 44.654301 -407.339013) (xy 44.537684 -407.473872) (xy 44.415175 -407.603402) (xy 44.287018 -407.727346)
			(xy 44.153467 -407.845458) (xy 44.014787 -407.957503) (xy 43.871253 -408.06326) (xy 43.72315 -408.162517)
			(xy 43.570773 -408.255079) (xy 43.414424 -408.34076) (xy 43.254413 -408.419392) (xy 43.091059 -408.490818)
			(xy 42.924684 -408.554896) (xy 42.755621 -408.611498) (xy 42.584204 -408.660514) (xy 42.410773 -408.701844)
			(xy 42.235673 -408.735408) (xy 42.059253 -408.761138) (xy 41.881861 -408.778984) (xy 41.70385 -408.78891)
			(xy 41.525573 -408.790896) (xy 41.347386 -408.784939) (xy 41.16964 -408.771049) (xy 40.99269 -408.749256)
			(xy 40.816886 -408.719602) (xy 40.642578 -408.682145) (xy 40.470111 -408.636961) (xy 40.299828 -408.584139)
			(xy 40.132067 -408.523783) (xy 39.967162 -408.456015) (xy 39.805439 -408.380967) (xy 39.64722 -408.29879)
			(xy 39.492819 -408.209647) (xy 39.342542 -408.113713) (xy 39.196687 -408.011181) (xy 39.055545 -407.902253)
			(xy 38.919396 -407.787146) (xy 38.788509 -407.666088) (xy 38.663145 -407.539319) (xy 38.543552 -407.407092)
			(xy 38.429969 -407.269669) (xy 38.32262 -407.127322) (xy 38.221719 -406.980334) (xy 38.127466 -406.828998)
			(xy 38.040048 -406.673613) (xy 37.959638 -406.514488) (xy 37.886397 -406.351939) (xy 37.82047 -406.186289)
			(xy 37.761987 -406.017867) (xy 37.711065 -405.847006) (xy 37.667805 -405.674047) (xy 37.632293 -405.499332)
			(xy 37.604599 -405.323208) (xy 37.584778 -405.146026) (xy 37.57287 -404.968137) (xy 37.568898 -404.789894)
			(xy 3.30962 -404.789894) (xy 6.274054 -407.754328) (xy 6.323479 -407.804444) (xy 6.417291 -407.909404)
			(xy 6.50507 -408.019459) (xy 6.58654 -408.134261) (xy 6.661445 -408.253452) (xy 6.72955 -408.376654)
			(xy 6.79064 -408.503481) (xy 6.844523 -408.633534) (xy 6.891029 -408.766403) (xy 6.930013 -408.901671)
			(xy 6.961351 -409.038912) (xy 6.984945 -409.177694) (xy 7.00072 -409.31758) (xy 7.008628 -409.458131)
			(xy 7.00913 -409.528518) (xy 7.00913 -409.563824) (xy 102.192836 -409.563824) (xy 102.192836 -408.700224)
			(xy 102.193322 -408.672955) (xy 102.201084 -408.618971) (xy 102.216449 -408.566641) (xy 102.239106 -408.517031)
			(xy 102.268592 -408.47115) (xy 102.304307 -408.429933) (xy 102.345524 -408.394218) (xy 102.391405 -408.364732)
			(xy 102.441015 -408.342075) (xy 102.493345 -408.32671) (xy 102.547329 -408.318948) (xy 102.601867 -408.318948)
			(xy 102.655851 -408.32671) (xy 102.708181 -408.342075) (xy 102.757791 -408.364732) (xy 102.803672 -408.394218)
			(xy 102.844889 -408.429933) (xy 102.880604 -408.47115) (xy 102.91009 -408.517031) (xy 102.932747 -408.566641)
			(xy 102.948112 -408.618971) (xy 102.955874 -408.672955) (xy 102.95636 -408.700224) (xy 102.95636 -409.563824)
			(xy 102.955874 -409.591093) (xy 102.948112 -409.645077) (xy 102.932747 -409.697407) (xy 102.91009 -409.747017)
			(xy 102.880604 -409.792898) (xy 102.844889 -409.834115) (xy 102.803672 -409.86983) (xy 102.757791 -409.899316)
			(xy 102.748244 -409.903676) (xy 110.559596 -409.903676) (xy 110.559596 -409.040076) (xy 110.560082 -409.012825)
			(xy 110.567838 -408.958877) (xy 110.583193 -408.906582) (xy 110.605835 -408.857005) (xy 110.635301 -408.811155)
			(xy 110.670992 -408.769964) (xy 110.712183 -408.734273) (xy 110.758033 -408.704807) (xy 110.80761 -408.682165)
			(xy 110.859905 -408.66681) (xy 110.913853 -408.659054) (xy 110.968355 -408.659054) (xy 111.022303 -408.66681)
			(xy 111.074598 -408.682165) (xy 111.124175 -408.704807) (xy 111.170025 -408.734273) (xy 111.211216 -408.769964)
			(xy 111.246907 -408.811155) (xy 111.276373 -408.857005) (xy 111.299015 -408.906582) (xy 111.31437 -408.958877)
			(xy 111.322126 -409.012825) (xy 111.322612 -409.040076) (xy 111.322612 -409.903676) (xy 111.322126 -409.930927)
			(xy 111.31437 -409.984875) (xy 111.299015 -410.03717) (xy 111.28975 -410.057456) (xy 116.044623 -410.057456)
			(xy 116.044623 -410.002944) (xy 116.052381 -409.948986) (xy 116.06774 -409.896681) (xy 116.090386 -409.847095)
			(xy 116.119859 -409.801237) (xy 116.155559 -409.76004) (xy 116.196758 -409.724344) (xy 116.242618 -409.694874)
			(xy 116.292206 -409.672231) (xy 116.344511 -409.656876) (xy 116.39847 -409.649121) (xy 116.425726 -409.64866)
			(xy 117.289326 -409.64866) (xy 117.316574 -409.649212) (xy 117.370514 -409.656971) (xy 117.422801 -409.672327)
			(xy 117.472371 -409.694968) (xy 117.518214 -409.724432) (xy 117.559398 -409.760121) (xy 117.595084 -409.801307)
			(xy 117.624545 -409.847152) (xy 117.647182 -409.896723) (xy 117.662535 -409.949011) (xy 117.67029 -410.002952)
			(xy 117.67029 -410.057448) (xy 117.670289 -410.057452) (xy 119.107946 -410.057452) (xy 119.107946 -410.002948)
			(xy 119.115702 -409.948999) (xy 119.131057 -409.896702) (xy 119.153697 -409.847123) (xy 119.183163 -409.801271)
			(xy 119.218854 -409.760078) (xy 119.260043 -409.724383) (xy 119.305893 -409.694914) (xy 119.35547 -409.672269)
			(xy 119.407765 -409.656909) (xy 119.461714 -409.649148) (xy 119.488966 -409.64866) (xy 120.352566 -409.64866)
			(xy 120.379818 -409.649185) (xy 120.433768 -409.656937) (xy 120.486066 -409.672289) (xy 120.535646 -409.694928)
			(xy 120.5815 -409.724392) (xy 120.622693 -409.760083) (xy 120.658387 -409.801273) (xy 120.687856 -409.847124)
			(xy 120.710499 -409.896702) (xy 120.725855 -409.948999) (xy 120.733613 -410.002948) (xy 120.733613 -410.057452)
			(xy 120.733613 -410.057455) (xy 122.171123 -410.057455) (xy 122.171123 -410.002945) (xy 122.178881 -409.948989)
			(xy 122.194238 -409.896686) (xy 122.216883 -409.847101) (xy 122.246354 -409.801244) (xy 122.282052 -409.760047)
			(xy 122.323249 -409.724351) (xy 122.369106 -409.69488) (xy 122.418691 -409.672236) (xy 122.470994 -409.656879)
			(xy 122.524951 -409.649123) (xy 122.552206 -409.64866) (xy 123.415806 -409.64866) (xy 123.443055 -409.649211)
			(xy 123.496997 -409.656967) (xy 123.549287 -409.672321) (xy 123.598859 -409.694961) (xy 123.644705 -409.724425)
			(xy 123.685891 -409.760113) (xy 123.721579 -409.8013) (xy 123.751042 -409.847146) (xy 123.773681 -409.896719)
			(xy 123.789034 -409.949009) (xy 123.79679 -410.002951) (xy 123.79679 -410.057449) (xy 123.796789 -410.057457)
			(xy 125.234323 -410.057457) (xy 125.234323 -410.002943) (xy 125.242082 -409.948983) (xy 125.257442 -409.896677)
			(xy 125.280089 -409.84709) (xy 125.309564 -409.801231) (xy 125.345266 -409.760033) (xy 125.386467 -409.724337)
			(xy 125.43233 -409.694867) (xy 125.48192 -409.672225) (xy 125.534228 -409.656872) (xy 125.588189 -409.64912)
			(xy 125.615446 -409.64866) (xy 126.479046 -409.64866) (xy 126.506293 -409.649213) (xy 126.560231 -409.656975)
			(xy 126.612516 -409.672332) (xy 126.662083 -409.694974) (xy 126.707924 -409.724439) (xy 126.749105 -409.760128)
			(xy 126.784788 -409.801313) (xy 126.814248 -409.847157) (xy 126.836884 -409.896727) (xy 126.852235 -409.949014)
			(xy 126.85999 -410.002953) (xy 126.85999 -410.057447) (xy 126.859989 -410.057453) (xy 128.297646 -410.057453)
			(xy 128.297646 -410.002947) (xy 128.305403 -409.948996) (xy 128.320758 -409.896698) (xy 128.3434 -409.847118)
			(xy 128.372868 -409.801264) (xy 128.408561 -409.760071) (xy 128.449753 -409.724376) (xy 128.495605 -409.694907)
			(xy 128.545185 -409.672263) (xy 128.597482 -409.656906) (xy 128.651433 -409.649147) (xy 128.678686 -409.64866)
			(xy 129.542286 -409.64866) (xy 129.569537 -409.649186) (xy 129.623485 -409.656941) (xy 129.67578 -409.672295)
			(xy 129.725358 -409.694934) (xy 129.771209 -409.724399) (xy 129.8124 -409.76009) (xy 129.848092 -409.80128)
			(xy 129.877559 -409.84713) (xy 129.900201 -409.896707) (xy 129.915556 -409.949001) (xy 129.923313 -410.002949)
			(xy 129.923313 -410.057451) (xy 129.923312 -410.057456) (xy 131.360823 -410.057456) (xy 131.360823 -410.002944)
			(xy 131.368581 -409.948986) (xy 131.38394 -409.896681) (xy 131.406586 -409.847095) (xy 131.436059 -409.801237)
			(xy 131.471759 -409.76004) (xy 131.512958 -409.724344) (xy 131.558818 -409.694874) (xy 131.608406 -409.672231)
			(xy 131.660711 -409.656876) (xy 131.71467 -409.649121) (xy 131.741926 -409.64866) (xy 132.605526 -409.64866)
			(xy 132.632774 -409.649212) (xy 132.686714 -409.656971) (xy 132.739001 -409.672327) (xy 132.788571 -409.694968)
			(xy 132.834414 -409.724432) (xy 132.875598 -409.760121) (xy 132.911284 -409.801307) (xy 132.940745 -409.847152)
			(xy 132.963382 -409.896723) (xy 132.978735 -409.949011) (xy 132.98649 -410.002952) (xy 132.98649 -410.057448)
			(xy 132.986489 -410.057452) (xy 134.424146 -410.057452) (xy 134.424146 -410.002948) (xy 134.431902 -409.948999)
			(xy 134.447257 -409.896702) (xy 134.469897 -409.847123) (xy 134.499363 -409.801271) (xy 134.535054 -409.760078)
			(xy 134.576243 -409.724383) (xy 134.622093 -409.694914) (xy 134.67167 -409.672269) (xy 134.723965 -409.656909)
			(xy 134.777914 -409.649148) (xy 134.805166 -409.64866) (xy 135.668766 -409.64866) (xy 135.696018 -409.649185)
			(xy 135.749968 -409.656937) (xy 135.802266 -409.672289) (xy 135.851846 -409.694928) (xy 135.8977 -409.724392)
			(xy 135.938893 -409.760083) (xy 135.974587 -409.801273) (xy 136.004056 -409.847124) (xy 136.026699 -409.896702)
			(xy 136.042055 -409.948999) (xy 136.049813 -410.002948) (xy 136.049813 -410.057452) (xy 136.049813 -410.057455)
			(xy 137.487323 -410.057455) (xy 137.487323 -410.002945) (xy 137.495081 -409.948989) (xy 137.510438 -409.896686)
			(xy 137.533083 -409.847101) (xy 137.562554 -409.801244) (xy 137.598252 -409.760047) (xy 137.639449 -409.724351)
			(xy 137.685306 -409.69488) (xy 137.734891 -409.672236) (xy 137.787194 -409.656879) (xy 137.841151 -409.649123)
			(xy 137.868406 -409.64866) (xy 138.732006 -409.64866) (xy 138.759255 -409.649211) (xy 138.813197 -409.656967)
			(xy 138.865487 -409.672321) (xy 138.915059 -409.694961) (xy 138.960905 -409.724425) (xy 139.002091 -409.760113)
			(xy 139.037779 -409.8013) (xy 139.067242 -409.847146) (xy 139.089881 -409.896719) (xy 139.105234 -409.949009)
			(xy 139.11299 -410.002951) (xy 139.11299 -410.057449) (xy 139.112989 -410.057457) (xy 140.550523 -410.057457)
			(xy 140.550523 -410.002943) (xy 140.558282 -409.948983) (xy 140.573642 -409.896677) (xy 140.596289 -409.84709)
			(xy 140.625764 -409.801231) (xy 140.661466 -409.760033) (xy 140.702667 -409.724337) (xy 140.74853 -409.694867)
			(xy 140.79812 -409.672225) (xy 140.850428 -409.656872) (xy 140.904389 -409.64912) (xy 140.931646 -409.64866)
			(xy 141.795246 -409.64866) (xy 141.822493 -409.649213) (xy 141.876431 -409.656975) (xy 141.928716 -409.672332)
			(xy 141.978283 -409.694974) (xy 142.024124 -409.724439) (xy 142.065305 -409.760128) (xy 142.100988 -409.801313)
			(xy 142.130448 -409.847157) (xy 142.153084 -409.896727) (xy 142.168435 -409.949014) (xy 142.17619 -410.002953)
			(xy 142.17619 -410.057447) (xy 142.176189 -410.057453) (xy 143.613846 -410.057453) (xy 143.613846 -410.002947)
			(xy 143.621603 -409.948996) (xy 143.636958 -409.896698) (xy 143.6596 -409.847118) (xy 143.689068 -409.801264)
			(xy 143.724761 -409.760071) (xy 143.765953 -409.724376) (xy 143.811805 -409.694907) (xy 143.861385 -409.672263)
			(xy 143.913682 -409.656906) (xy 143.967633 -409.649147) (xy 143.994886 -409.64866) (xy 144.858486 -409.64866)
			(xy 144.885737 -409.649186) (xy 144.939685 -409.656941) (xy 144.99198 -409.672295) (xy 145.041558 -409.694934)
			(xy 145.087409 -409.724399) (xy 145.1286 -409.76009) (xy 145.164292 -409.80128) (xy 145.193759 -409.84713)
			(xy 145.216401 -409.896707) (xy 145.231756 -409.949001) (xy 145.239513 -410.002949) (xy 145.239513 -410.057451)
			(xy 145.239512 -410.057456) (xy 146.677023 -410.057456) (xy 146.677023 -410.002944) (xy 146.684781 -409.948986)
			(xy 146.70014 -409.896681) (xy 146.722786 -409.847095) (xy 146.752259 -409.801237) (xy 146.787959 -409.76004)
			(xy 146.829158 -409.724344) (xy 146.875018 -409.694874) (xy 146.924606 -409.672231) (xy 146.976911 -409.656876)
			(xy 147.03087 -409.649121) (xy 147.058126 -409.64866) (xy 147.921726 -409.64866) (xy 147.948974 -409.649212)
			(xy 148.002914 -409.656971) (xy 148.055201 -409.672327) (xy 148.104771 -409.694968) (xy 148.150614 -409.724432)
			(xy 148.191798 -409.760121) (xy 148.227484 -409.801307) (xy 148.256945 -409.847152) (xy 148.279582 -409.896723)
			(xy 148.294935 -409.949011) (xy 148.30269 -410.002952) (xy 148.30269 -410.057448) (xy 148.302689 -410.057452)
			(xy 149.740346 -410.057452) (xy 149.740346 -410.002948) (xy 149.748102 -409.948999) (xy 149.763457 -409.896702)
			(xy 149.786097 -409.847123) (xy 149.815563 -409.801271) (xy 149.851254 -409.760078) (xy 149.892443 -409.724383)
			(xy 149.938293 -409.694914) (xy 149.98787 -409.672269) (xy 150.040165 -409.656909) (xy 150.094114 -409.649148)
			(xy 150.121366 -409.64866) (xy 150.984966 -409.64866) (xy 151.012218 -409.649185) (xy 151.066168 -409.656937)
			(xy 151.118466 -409.672289) (xy 151.168046 -409.694928) (xy 151.2139 -409.724392) (xy 151.255093 -409.760083)
			(xy 151.290787 -409.801273) (xy 151.320256 -409.847124) (xy 151.342899 -409.896702) (xy 151.358255 -409.948999)
			(xy 151.366013 -410.002948) (xy 151.366013 -410.057452) (xy 151.366013 -410.057455) (xy 152.803523 -410.057455)
			(xy 152.803523 -410.002945) (xy 152.811281 -409.948989) (xy 152.826638 -409.896686) (xy 152.849283 -409.847101)
			(xy 152.878754 -409.801244) (xy 152.914452 -409.760047) (xy 152.955649 -409.724351) (xy 153.001506 -409.69488)
			(xy 153.051091 -409.672236) (xy 153.103394 -409.656879) (xy 153.157351 -409.649123) (xy 153.184606 -409.64866)
			(xy 154.048206 -409.64866) (xy 154.075455 -409.649211) (xy 154.129397 -409.656967) (xy 154.181687 -409.672321)
			(xy 154.231259 -409.694961) (xy 154.277105 -409.724425) (xy 154.318291 -409.760113) (xy 154.353979 -409.8013)
			(xy 154.383442 -409.847146) (xy 154.406081 -409.896719) (xy 154.421434 -409.949009) (xy 154.42919 -410.002951)
			(xy 154.42919 -410.057449) (xy 154.429189 -410.057457) (xy 155.866723 -410.057457) (xy 155.866723 -410.002943)
			(xy 155.874482 -409.948983) (xy 155.889842 -409.896677) (xy 155.912489 -409.84709) (xy 155.941964 -409.801231)
			(xy 155.977666 -409.760033) (xy 156.018867 -409.724337) (xy 156.06473 -409.694867) (xy 156.11432 -409.672225)
			(xy 156.166628 -409.656872) (xy 156.220589 -409.64912) (xy 156.247846 -409.64866) (xy 157.111446 -409.64866)
			(xy 157.138693 -409.649213) (xy 157.192631 -409.656975) (xy 157.244916 -409.672332) (xy 157.294483 -409.694974)
			(xy 157.340324 -409.724439) (xy 157.381505 -409.760128) (xy 157.417188 -409.801313) (xy 157.446648 -409.847157)
			(xy 157.469284 -409.896727) (xy 157.484635 -409.949014) (xy 157.49239 -410.002953) (xy 157.49239 -410.057447)
			(xy 157.492389 -410.057453) (xy 158.930046 -410.057453) (xy 158.930046 -410.002947) (xy 158.937803 -409.948996)
			(xy 158.953158 -409.896698) (xy 158.9758 -409.847118) (xy 159.005268 -409.801264) (xy 159.040961 -409.760071)
			(xy 159.082153 -409.724376) (xy 159.128005 -409.694907) (xy 159.177585 -409.672263) (xy 159.229882 -409.656906)
			(xy 159.283833 -409.649147) (xy 159.311086 -409.64866) (xy 160.174686 -409.64866) (xy 160.201937 -409.649186)
			(xy 160.255885 -409.656941) (xy 160.30818 -409.672295) (xy 160.357758 -409.694934) (xy 160.403609 -409.724399)
			(xy 160.4448 -409.76009) (xy 160.480492 -409.80128) (xy 160.509959 -409.84713) (xy 160.532601 -409.896707)
			(xy 160.547956 -409.949001) (xy 160.555713 -410.002949) (xy 160.555713 -410.057451) (xy 160.555712 -410.057456)
			(xy 161.993223 -410.057456) (xy 161.993223 -410.002944) (xy 162.000981 -409.948986) (xy 162.01634 -409.896681)
			(xy 162.038986 -409.847095) (xy 162.068459 -409.801237) (xy 162.104159 -409.76004) (xy 162.145358 -409.724344)
			(xy 162.191218 -409.694874) (xy 162.240806 -409.672231) (xy 162.293111 -409.656876) (xy 162.34707 -409.649121)
			(xy 162.374326 -409.64866) (xy 163.237926 -409.64866) (xy 163.265174 -409.649212) (xy 163.319114 -409.656971)
			(xy 163.371401 -409.672327) (xy 163.420971 -409.694968) (xy 163.466814 -409.724432) (xy 163.507998 -409.760121)
			(xy 163.543684 -409.801307) (xy 163.573145 -409.847152) (xy 163.595782 -409.896723) (xy 163.611135 -409.949011)
			(xy 163.61889 -410.002952) (xy 163.61889 -410.057448) (xy 163.611135 -410.111389) (xy 163.595782 -410.163677)
			(xy 163.573145 -410.213248) (xy 163.543684 -410.259093) (xy 163.507998 -410.300279) (xy 163.466814 -410.335968)
			(xy 163.420971 -410.365432) (xy 163.371401 -410.388073) (xy 163.319114 -410.403429) (xy 163.265174 -410.411188)
			(xy 163.237926 -410.411676) (xy 162.374326 -410.411676) (xy 162.34707 -410.411279) (xy 162.293111 -410.403524)
			(xy 162.240806 -410.388169) (xy 162.191218 -410.365526) (xy 162.145358 -410.336056) (xy 162.104159 -410.30036)
			(xy 162.068459 -410.259163) (xy 162.038986 -410.213305) (xy 162.01634 -410.163719) (xy 162.000981 -410.111414)
			(xy 161.993223 -410.057456) (xy 160.555712 -410.057456) (xy 160.547956 -410.111399) (xy 160.532601 -410.163693)
			(xy 160.509959 -410.21327) (xy 160.480492 -410.25912) (xy 160.4448 -410.30031) (xy 160.403609 -410.336001)
			(xy 160.357758 -410.365466) (xy 160.30818 -410.388105) (xy 160.255885 -410.403459) (xy 160.201937 -410.411214)
			(xy 160.174686 -410.411676) (xy 159.311086 -410.411676) (xy 159.283833 -410.411253) (xy 159.229882 -410.403494)
			(xy 159.177585 -410.388137) (xy 159.128005 -410.365493) (xy 159.082153 -410.336024) (xy 159.040961 -410.300329)
			(xy 159.005268 -410.259136) (xy 158.9758 -410.213282) (xy 158.953158 -410.163702) (xy 158.937803 -410.111404)
			(xy 158.930046 -410.057453) (xy 157.492389 -410.057453) (xy 157.484635 -410.111386) (xy 157.469284 -410.163673)
			(xy 157.446648 -410.213243) (xy 157.417188 -410.259087) (xy 157.381505 -410.300272) (xy 157.340324 -410.335961)
			(xy 157.294483 -410.365426) (xy 157.244916 -410.388068) (xy 157.192631 -410.403425) (xy 157.138693 -410.411187)
			(xy 157.111446 -410.411676) (xy 156.247846 -410.411676) (xy 156.220589 -410.41128) (xy 156.166628 -410.403528)
			(xy 156.11432 -410.388175) (xy 156.06473 -410.365533) (xy 156.018867 -410.336063) (xy 155.977666 -410.300367)
			(xy 155.941964 -410.259169) (xy 155.912489 -410.21331) (xy 155.889842 -410.163723) (xy 155.874482 -410.111417)
			(xy 155.866723 -410.057457) (xy 154.429189 -410.057457) (xy 154.421434 -410.111391) (xy 154.406081 -410.163681)
			(xy 154.383442 -410.213254) (xy 154.353979 -410.2591) (xy 154.318291 -410.300287) (xy 154.277105 -410.335975)
			(xy 154.231259 -410.365439) (xy 154.181687 -410.388079) (xy 154.129397 -410.403433) (xy 154.075455 -410.411189)
			(xy 154.048206 -410.411676) (xy 153.184606 -410.411676) (xy 153.157351 -410.411277) (xy 153.103394 -410.403521)
			(xy 153.051091 -410.388164) (xy 153.001506 -410.36552) (xy 152.955649 -410.336049) (xy 152.914452 -410.300353)
			(xy 152.878754 -410.259156) (xy 152.849283 -410.213299) (xy 152.826638 -410.163714) (xy 152.811281 -410.111411)
			(xy 152.803523 -410.057455) (xy 151.366013 -410.057455) (xy 151.358255 -410.111402) (xy 151.342899 -410.163698)
			(xy 151.320256 -410.213276) (xy 151.290787 -410.259127) (xy 151.255093 -410.300317) (xy 151.2139 -410.336008)
			(xy 151.168046 -410.365472) (xy 151.118466 -410.388111) (xy 151.066168 -410.403463) (xy 151.012218 -410.411215)
			(xy 150.984966 -410.411676) (xy 150.121366 -410.411676) (xy 150.094114 -410.411252) (xy 150.040165 -410.403491)
			(xy 149.98787 -410.388131) (xy 149.938293 -410.365486) (xy 149.892443 -410.336017) (xy 149.851254 -410.300322)
			(xy 149.815563 -410.259129) (xy 149.786097 -410.213277) (xy 149.763457 -410.163698) (xy 149.748102 -410.111401)
			(xy 149.740346 -410.057452) (xy 148.302689 -410.057452) (xy 148.294935 -410.111389) (xy 148.279582 -410.163677)
			(xy 148.256945 -410.213248) (xy 148.227484 -410.259093) (xy 148.191798 -410.300279) (xy 148.150614 -410.335968)
			(xy 148.104771 -410.365432) (xy 148.055201 -410.388073) (xy 148.002914 -410.403429) (xy 147.948974 -410.411188)
			(xy 147.921726 -410.411676) (xy 147.058126 -410.411676) (xy 147.03087 -410.411279) (xy 146.976911 -410.403524)
			(xy 146.924606 -410.388169) (xy 146.875018 -410.365526) (xy 146.829158 -410.336056) (xy 146.787959 -410.30036)
			(xy 146.752259 -410.259163) (xy 146.722786 -410.213305) (xy 146.70014 -410.163719) (xy 146.684781 -410.111414)
			(xy 146.677023 -410.057456) (xy 145.239512 -410.057456) (xy 145.231756 -410.111399) (xy 145.216401 -410.163693)
			(xy 145.193759 -410.21327) (xy 145.164292 -410.25912) (xy 145.1286 -410.30031) (xy 145.087409 -410.336001)
			(xy 145.041558 -410.365466) (xy 144.99198 -410.388105) (xy 144.939685 -410.403459) (xy 144.885737 -410.411214)
			(xy 144.858486 -410.411676) (xy 143.994886 -410.411676) (xy 143.967633 -410.411253) (xy 143.913682 -410.403494)
			(xy 143.861385 -410.388137) (xy 143.811805 -410.365493) (xy 143.765953 -410.336024) (xy 143.724761 -410.300329)
			(xy 143.689068 -410.259136) (xy 143.6596 -410.213282) (xy 143.636958 -410.163702) (xy 143.621603 -410.111404)
			(xy 143.613846 -410.057453) (xy 142.176189 -410.057453) (xy 142.168435 -410.111386) (xy 142.153084 -410.163673)
			(xy 142.130448 -410.213243) (xy 142.100988 -410.259087) (xy 142.065305 -410.300272) (xy 142.024124 -410.335961)
			(xy 141.978283 -410.365426) (xy 141.928716 -410.388068) (xy 141.876431 -410.403425) (xy 141.822493 -410.411187)
			(xy 141.795246 -410.411676) (xy 140.931646 -410.411676) (xy 140.904389 -410.41128) (xy 140.850428 -410.403528)
			(xy 140.79812 -410.388175) (xy 140.74853 -410.365533) (xy 140.702667 -410.336063) (xy 140.661466 -410.300367)
			(xy 140.625764 -410.259169) (xy 140.596289 -410.21331) (xy 140.573642 -410.163723) (xy 140.558282 -410.111417)
			(xy 140.550523 -410.057457) (xy 139.112989 -410.057457) (xy 139.105234 -410.111391) (xy 139.089881 -410.163681)
			(xy 139.067242 -410.213254) (xy 139.037779 -410.2591) (xy 139.002091 -410.300287) (xy 138.960905 -410.335975)
			(xy 138.915059 -410.365439) (xy 138.865487 -410.388079) (xy 138.813197 -410.403433) (xy 138.759255 -410.411189)
			(xy 138.732006 -410.411676) (xy 137.868406 -410.411676) (xy 137.841151 -410.411277) (xy 137.787194 -410.403521)
			(xy 137.734891 -410.388164) (xy 137.685306 -410.36552) (xy 137.639449 -410.336049) (xy 137.598252 -410.300353)
			(xy 137.562554 -410.259156) (xy 137.533083 -410.213299) (xy 137.510438 -410.163714) (xy 137.495081 -410.111411)
			(xy 137.487323 -410.057455) (xy 136.049813 -410.057455) (xy 136.042055 -410.111402) (xy 136.026699 -410.163698)
			(xy 136.004056 -410.213276) (xy 135.974587 -410.259127) (xy 135.938893 -410.300317) (xy 135.8977 -410.336008)
			(xy 135.851846 -410.365472) (xy 135.802266 -410.388111) (xy 135.749968 -410.403463) (xy 135.696018 -410.411215)
			(xy 135.668766 -410.411676) (xy 134.805166 -410.411676) (xy 134.777914 -410.411252) (xy 134.723965 -410.403491)
			(xy 134.67167 -410.388131) (xy 134.622093 -410.365486) (xy 134.576243 -410.336017) (xy 134.535054 -410.300322)
			(xy 134.499363 -410.259129) (xy 134.469897 -410.213277) (xy 134.447257 -410.163698) (xy 134.431902 -410.111401)
			(xy 134.424146 -410.057452) (xy 132.986489 -410.057452) (xy 132.978735 -410.111389) (xy 132.963382 -410.163677)
			(xy 132.940745 -410.213248) (xy 132.911284 -410.259093) (xy 132.875598 -410.300279) (xy 132.834414 -410.335968)
			(xy 132.788571 -410.365432) (xy 132.739001 -410.388073) (xy 132.686714 -410.403429) (xy 132.632774 -410.411188)
			(xy 132.605526 -410.411676) (xy 131.741926 -410.411676) (xy 131.71467 -410.411279) (xy 131.660711 -410.403524)
			(xy 131.608406 -410.388169) (xy 131.558818 -410.365526) (xy 131.512958 -410.336056) (xy 131.471759 -410.30036)
			(xy 131.436059 -410.259163) (xy 131.406586 -410.213305) (xy 131.38394 -410.163719) (xy 131.368581 -410.111414)
			(xy 131.360823 -410.057456) (xy 129.923312 -410.057456) (xy 129.915556 -410.111399) (xy 129.900201 -410.163693)
			(xy 129.877559 -410.21327) (xy 129.848092 -410.25912) (xy 129.8124 -410.30031) (xy 129.771209 -410.336001)
			(xy 129.725358 -410.365466) (xy 129.67578 -410.388105) (xy 129.623485 -410.403459) (xy 129.569537 -410.411214)
			(xy 129.542286 -410.411676) (xy 128.678686 -410.411676) (xy 128.651433 -410.411253) (xy 128.597482 -410.403494)
			(xy 128.545185 -410.388137) (xy 128.495605 -410.365493) (xy 128.449753 -410.336024) (xy 128.408561 -410.300329)
			(xy 128.372868 -410.259136) (xy 128.3434 -410.213282) (xy 128.320758 -410.163702) (xy 128.305403 -410.111404)
			(xy 128.297646 -410.057453) (xy 126.859989 -410.057453) (xy 126.852235 -410.111386) (xy 126.836884 -410.163673)
			(xy 126.814248 -410.213243) (xy 126.784788 -410.259087) (xy 126.749105 -410.300272) (xy 126.707924 -410.335961)
			(xy 126.662083 -410.365426) (xy 126.612516 -410.388068) (xy 126.560231 -410.403425) (xy 126.506293 -410.411187)
			(xy 126.479046 -410.411676) (xy 125.615446 -410.411676) (xy 125.588189 -410.41128) (xy 125.534228 -410.403528)
			(xy 125.48192 -410.388175) (xy 125.43233 -410.365533) (xy 125.386467 -410.336063) (xy 125.345266 -410.300367)
			(xy 125.309564 -410.259169) (xy 125.280089 -410.21331) (xy 125.257442 -410.163723) (xy 125.242082 -410.111417)
			(xy 125.234323 -410.057457) (xy 123.796789 -410.057457) (xy 123.789034 -410.111391) (xy 123.773681 -410.163681)
			(xy 123.751042 -410.213254) (xy 123.721579 -410.2591) (xy 123.685891 -410.300287) (xy 123.644705 -410.335975)
			(xy 123.598859 -410.365439) (xy 123.549287 -410.388079) (xy 123.496997 -410.403433) (xy 123.443055 -410.411189)
			(xy 123.415806 -410.411676) (xy 122.552206 -410.411676) (xy 122.524951 -410.411277) (xy 122.470994 -410.403521)
			(xy 122.418691 -410.388164) (xy 122.369106 -410.36552) (xy 122.323249 -410.336049) (xy 122.282052 -410.300353)
			(xy 122.246354 -410.259156) (xy 122.216883 -410.213299) (xy 122.194238 -410.163714) (xy 122.178881 -410.111411)
			(xy 122.171123 -410.057455) (xy 120.733613 -410.057455) (xy 120.725855 -410.111402) (xy 120.710499 -410.163698)
			(xy 120.687856 -410.213276) (xy 120.658387 -410.259127) (xy 120.622693 -410.300317) (xy 120.5815 -410.336008)
			(xy 120.535646 -410.365472) (xy 120.486066 -410.388111) (xy 120.433768 -410.403463) (xy 120.379818 -410.411215)
			(xy 120.352566 -410.411676) (xy 119.488966 -410.411676) (xy 119.461714 -410.411252) (xy 119.407765 -410.403491)
			(xy 119.35547 -410.388131) (xy 119.305893 -410.365486) (xy 119.260043 -410.336017) (xy 119.218854 -410.300322)
			(xy 119.183163 -410.259129) (xy 119.153697 -410.213277) (xy 119.131057 -410.163698) (xy 119.115702 -410.111401)
			(xy 119.107946 -410.057452) (xy 117.670289 -410.057452) (xy 117.662535 -410.111389) (xy 117.647182 -410.163677)
			(xy 117.624545 -410.213248) (xy 117.595084 -410.259093) (xy 117.559398 -410.300279) (xy 117.518214 -410.335968)
			(xy 117.472371 -410.365432) (xy 117.422801 -410.388073) (xy 117.370514 -410.403429) (xy 117.316574 -410.411188)
			(xy 117.289326 -410.411676) (xy 116.425726 -410.411676) (xy 116.39847 -410.411279) (xy 116.344511 -410.403524)
			(xy 116.292206 -410.388169) (xy 116.242618 -410.365526) (xy 116.196758 -410.336056) (xy 116.155559 -410.30036)
			(xy 116.119859 -410.259163) (xy 116.090386 -410.213305) (xy 116.06774 -410.163719) (xy 116.052381 -410.111414)
			(xy 116.044623 -410.057456) (xy 111.28975 -410.057456) (xy 111.276373 -410.086747) (xy 111.246907 -410.132597)
			(xy 111.211216 -410.173788) (xy 111.170025 -410.209479) (xy 111.124175 -410.238945) (xy 111.074598 -410.261587)
			(xy 111.022303 -410.276942) (xy 110.968355 -410.284698) (xy 110.913853 -410.284698) (xy 110.859905 -410.276942)
			(xy 110.80761 -410.261587) (xy 110.758033 -410.238945) (xy 110.712183 -410.209479) (xy 110.670992 -410.173788)
			(xy 110.635301 -410.132597) (xy 110.605835 -410.086747) (xy 110.583193 -410.03717) (xy 110.567838 -409.984875)
			(xy 110.560082 -409.930927) (xy 110.559596 -409.903676) (xy 102.748244 -409.903676) (xy 102.708181 -409.921973)
			(xy 102.655851 -409.937338) (xy 102.601867 -409.9451) (xy 102.547329 -409.9451) (xy 102.493345 -409.937338)
			(xy 102.441015 -409.921973) (xy 102.391405 -409.899316) (xy 102.345524 -409.86983) (xy 102.304307 -409.834115)
			(xy 102.268592 -409.792898) (xy 102.239106 -409.747017) (xy 102.216449 -409.697407) (xy 102.201084 -409.645077)
			(xy 102.193322 -409.591093) (xy 102.192836 -409.563824) (xy 7.00913 -409.563824) (xy 7.00913 -410.057453)
			(xy 48.944746 -410.057453) (xy 48.944746 -410.002947) (xy 48.952503 -409.948996) (xy 48.967858 -409.896698)
			(xy 48.9905 -409.847118) (xy 49.019967 -409.801265) (xy 49.05566 -409.760071) (xy 49.096852 -409.724377)
			(xy 49.142704 -409.694908) (xy 49.192283 -409.672264) (xy 49.244581 -409.656906) (xy 49.298531 -409.649147)
			(xy 49.325784 -409.64866) (xy 50.189384 -409.64866) (xy 50.216635 -409.649186) (xy 50.270583 -409.656941)
			(xy 50.322879 -409.672294) (xy 50.372457 -409.694934) (xy 50.418308 -409.724399) (xy 50.459499 -409.760089)
			(xy 50.495192 -409.801279) (xy 50.524659 -409.847129) (xy 50.5473 -409.896706) (xy 50.562656 -409.949001)
			(xy 50.570413 -410.002949) (xy 50.570413 -410.057451) (xy 50.570412 -410.057456) (xy 52.007923 -410.057456)
			(xy 52.007923 -410.002944) (xy 52.015681 -409.948986) (xy 52.03104 -409.896682) (xy 52.053686 -409.847096)
			(xy 52.083159 -409.801238) (xy 52.118858 -409.760041) (xy 52.160057 -409.724344) (xy 52.205917 -409.694874)
			(xy 52.255504 -409.672231) (xy 52.30781 -409.656876) (xy 52.361768 -409.649121) (xy 52.389024 -409.64866)
			(xy 53.252624 -409.64866) (xy 53.279872 -409.649212) (xy 53.333812 -409.65697) (xy 53.3861 -409.672326)
			(xy 53.43567 -409.694967) (xy 53.481513 -409.724431) (xy 53.522697 -409.76012) (xy 53.558383 -409.801306)
			(xy 53.587845 -409.847151) (xy 53.610482 -409.896723) (xy 53.625835 -409.949011) (xy 53.63359 -410.002952)
			(xy 53.63359 -410.057448) (xy 53.633589 -410.057452) (xy 55.071246 -410.057452) (xy 55.071246 -410.002948)
			(xy 55.079002 -409.948999) (xy 55.094357 -409.896703) (xy 55.116997 -409.847124) (xy 55.146462 -409.801271)
			(xy 55.182153 -409.760079) (xy 55.223342 -409.724384) (xy 55.269192 -409.694914) (xy 55.318769 -409.672269)
			(xy 55.371064 -409.65691) (xy 55.425012 -409.649148) (xy 55.452264 -409.64866) (xy 56.315864 -409.64866)
			(xy 56.343116 -409.649185) (xy 56.397067 -409.656937) (xy 56.449364 -409.672289) (xy 56.498945 -409.694927)
			(xy 56.544799 -409.724392) (xy 56.585992 -409.760082) (xy 56.621687 -409.801273) (xy 56.651156 -409.847124)
			(xy 56.673799 -409.896702) (xy 56.689155 -409.948998) (xy 56.696913 -410.002948) (xy 56.696913 -410.057452)
			(xy 56.696913 -410.057455) (xy 58.134423 -410.057455) (xy 58.134423 -410.002945) (xy 58.142181 -409.948989)
			(xy 58.157538 -409.896686) (xy 58.180183 -409.847102) (xy 58.209654 -409.801244) (xy 58.245351 -409.760048)
			(xy 58.286548 -409.724351) (xy 58.332405 -409.694881) (xy 58.38199 -409.672237) (xy 58.434293 -409.65688)
			(xy 58.488249 -409.649123) (xy 58.515504 -409.64866) (xy 59.379104 -409.64866) (xy 59.406353 -409.64921)
			(xy 59.460295 -409.656967) (xy 59.512585 -409.672321) (xy 59.562158 -409.69496) (xy 59.608004 -409.724424)
			(xy 59.64919 -409.760113) (xy 59.684878 -409.801299) (xy 59.714342 -409.847146) (xy 59.73698 -409.896718)
			(xy 59.752334 -409.949008) (xy 59.76009 -410.002951) (xy 59.76009 -410.057449) (xy 59.760089 -410.057457)
			(xy 61.197623 -410.057457) (xy 61.197623 -410.002943) (xy 61.205382 -409.948983) (xy 61.220741 -409.896678)
			(xy 61.243389 -409.84709) (xy 61.272864 -409.801231) (xy 61.308565 -409.760034) (xy 61.349767 -409.724337)
			(xy 61.395629 -409.694868) (xy 61.445219 -409.672226) (xy 61.497527 -409.656872) (xy 61.551487 -409.64912)
			(xy 61.578744 -409.64866) (xy 62.442344 -409.64866) (xy 62.469591 -409.649213) (xy 62.523529 -409.656974)
			(xy 62.575814 -409.672332) (xy 62.625382 -409.694973) (xy 62.671223 -409.724438) (xy 62.712404 -409.760127)
			(xy 62.748088 -409.801313) (xy 62.777548 -409.847157) (xy 62.800184 -409.896727) (xy 62.815535 -409.949014)
			(xy 62.82329 -410.002953) (xy 62.82329 -410.057447) (xy 62.823289 -410.057453) (xy 64.260946 -410.057453)
			(xy 64.260946 -410.002947) (xy 64.268703 -409.948996) (xy 64.284058 -409.896698) (xy 64.3067 -409.847118)
			(xy 64.336167 -409.801265) (xy 64.37186 -409.760071) (xy 64.413052 -409.724377) (xy 64.458904 -409.694908)
			(xy 64.508483 -409.672264) (xy 64.560781 -409.656906) (xy 64.614731 -409.649147) (xy 64.641984 -409.64866)
			(xy 65.505584 -409.64866) (xy 65.532835 -409.649186) (xy 65.586783 -409.656941) (xy 65.639079 -409.672294)
			(xy 65.688657 -409.694934) (xy 65.734508 -409.724399) (xy 65.775699 -409.760089) (xy 65.811392 -409.801279)
			(xy 65.840859 -409.847129) (xy 65.8635 -409.896706) (xy 65.878856 -409.949001) (xy 65.886613 -410.002949)
			(xy 65.886613 -410.057451) (xy 65.886612 -410.057456) (xy 67.324123 -410.057456) (xy 67.324123 -410.002944)
			(xy 67.331881 -409.948986) (xy 67.34724 -409.896682) (xy 67.369886 -409.847096) (xy 67.399359 -409.801238)
			(xy 67.435058 -409.760041) (xy 67.476257 -409.724344) (xy 67.522117 -409.694874) (xy 67.571704 -409.672231)
			(xy 67.62401 -409.656876) (xy 67.677968 -409.649121) (xy 67.705224 -409.64866) (xy 68.568824 -409.64866)
			(xy 68.596072 -409.649212) (xy 68.650012 -409.65697) (xy 68.7023 -409.672326) (xy 68.75187 -409.694967)
			(xy 68.797713 -409.724431) (xy 68.838897 -409.76012) (xy 68.874583 -409.801306) (xy 68.904045 -409.847151)
			(xy 68.926682 -409.896723) (xy 68.942035 -409.949011) (xy 68.94979 -410.002952) (xy 68.94979 -410.057448)
			(xy 68.949789 -410.057452) (xy 70.387446 -410.057452) (xy 70.387446 -410.002948) (xy 70.395202 -409.948999)
			(xy 70.410557 -409.896703) (xy 70.433197 -409.847124) (xy 70.462662 -409.801271) (xy 70.498353 -409.760079)
			(xy 70.539542 -409.724384) (xy 70.585392 -409.694914) (xy 70.634969 -409.672269) (xy 70.687264 -409.65691)
			(xy 70.741212 -409.649148) (xy 70.768464 -409.64866) (xy 71.632064 -409.64866) (xy 71.659316 -409.649185)
			(xy 71.713267 -409.656937) (xy 71.765564 -409.672289) (xy 71.815145 -409.694927) (xy 71.860999 -409.724392)
			(xy 71.902192 -409.760082) (xy 71.937887 -409.801273) (xy 71.967356 -409.847124) (xy 71.989999 -409.896702)
			(xy 72.005355 -409.948998) (xy 72.013113 -410.002948) (xy 72.013113 -410.057452) (xy 72.013113 -410.057455)
			(xy 73.450623 -410.057455) (xy 73.450623 -410.002945) (xy 73.458381 -409.948989) (xy 73.473738 -409.896686)
			(xy 73.496383 -409.847102) (xy 73.525854 -409.801244) (xy 73.561551 -409.760048) (xy 73.602748 -409.724351)
			(xy 73.648605 -409.694881) (xy 73.69819 -409.672237) (xy 73.750493 -409.65688) (xy 73.804449 -409.649123)
			(xy 73.831704 -409.64866) (xy 74.695304 -409.64866) (xy 74.722553 -409.64921) (xy 74.776495 -409.656967)
			(xy 74.828785 -409.672321) (xy 74.878358 -409.69496) (xy 74.924204 -409.724424) (xy 74.96539 -409.760113)
			(xy 75.001078 -409.801299) (xy 75.030542 -409.847146) (xy 75.05318 -409.896718) (xy 75.068534 -409.949008)
			(xy 75.07629 -410.002951) (xy 75.07629 -410.057449) (xy 75.076289 -410.057457) (xy 76.513823 -410.057457)
			(xy 76.513823 -410.002943) (xy 76.521582 -409.948983) (xy 76.536941 -409.896678) (xy 76.559589 -409.84709)
			(xy 76.589064 -409.801231) (xy 76.624765 -409.760034) (xy 76.665967 -409.724337) (xy 76.711829 -409.694868)
			(xy 76.761419 -409.672226) (xy 76.813727 -409.656872) (xy 76.867687 -409.64912) (xy 76.894944 -409.64866)
			(xy 77.758544 -409.64866) (xy 77.785791 -409.649213) (xy 77.839729 -409.656974) (xy 77.892014 -409.672332)
			(xy 77.941582 -409.694973) (xy 77.987423 -409.724438) (xy 78.028604 -409.760127) (xy 78.064288 -409.801313)
			(xy 78.093748 -409.847157) (xy 78.116384 -409.896727) (xy 78.131735 -409.949014) (xy 78.13949 -410.002953)
			(xy 78.13949 -410.057447) (xy 78.139489 -410.057453) (xy 79.577146 -410.057453) (xy 79.577146 -410.002947)
			(xy 79.584903 -409.948996) (xy 79.600258 -409.896698) (xy 79.6229 -409.847118) (xy 79.652367 -409.801265)
			(xy 79.68806 -409.760071) (xy 79.729252 -409.724377) (xy 79.775104 -409.694908) (xy 79.824683 -409.672264)
			(xy 79.876981 -409.656906) (xy 79.930931 -409.649147) (xy 79.958184 -409.64866) (xy 80.821784 -409.64866)
			(xy 80.849035 -409.649186) (xy 80.902983 -409.656941) (xy 80.955279 -409.672294) (xy 81.004857 -409.694934)
			(xy 81.050708 -409.724399) (xy 81.091899 -409.760089) (xy 81.127592 -409.801279) (xy 81.157059 -409.847129)
			(xy 81.1797 -409.896706) (xy 81.195056 -409.949001) (xy 81.202813 -410.002949) (xy 81.202813 -410.057451)
			(xy 81.202812 -410.057456) (xy 82.640323 -410.057456) (xy 82.640323 -410.002944) (xy 82.648081 -409.948986)
			(xy 82.66344 -409.896682) (xy 82.686086 -409.847096) (xy 82.715559 -409.801238) (xy 82.751258 -409.760041)
			(xy 82.792457 -409.724344) (xy 82.838317 -409.694874) (xy 82.887904 -409.672231) (xy 82.94021 -409.656876)
			(xy 82.994168 -409.649121) (xy 83.021424 -409.64866) (xy 83.885024 -409.64866) (xy 83.912272 -409.649212)
			(xy 83.966212 -409.65697) (xy 84.0185 -409.672326) (xy 84.06807 -409.694967) (xy 84.113913 -409.724431)
			(xy 84.155097 -409.76012) (xy 84.190783 -409.801306) (xy 84.220245 -409.847151) (xy 84.242882 -409.896723)
			(xy 84.258235 -409.949011) (xy 84.26599 -410.002952) (xy 84.26599 -410.057448) (xy 84.265989 -410.057452)
			(xy 85.703646 -410.057452) (xy 85.703646 -410.002948) (xy 85.711402 -409.948999) (xy 85.726757 -409.896703)
			(xy 85.749397 -409.847124) (xy 85.778862 -409.801271) (xy 85.814553 -409.760079) (xy 85.855742 -409.724384)
			(xy 85.901592 -409.694914) (xy 85.951169 -409.672269) (xy 86.003464 -409.65691) (xy 86.057412 -409.649148)
			(xy 86.084664 -409.64866) (xy 86.948264 -409.64866) (xy 86.975516 -409.649185) (xy 87.029467 -409.656937)
			(xy 87.081764 -409.672289) (xy 87.131345 -409.694927) (xy 87.177199 -409.724392) (xy 87.218392 -409.760082)
			(xy 87.254087 -409.801273) (xy 87.283556 -409.847124) (xy 87.306199 -409.896702) (xy 87.321555 -409.948998)
			(xy 87.329313 -410.002948) (xy 87.329313 -410.057452) (xy 87.329313 -410.057455) (xy 88.766823 -410.057455)
			(xy 88.766823 -410.002945) (xy 88.774581 -409.948989) (xy 88.789938 -409.896686) (xy 88.812583 -409.847102)
			(xy 88.842054 -409.801244) (xy 88.877751 -409.760048) (xy 88.918948 -409.724351) (xy 88.964805 -409.694881)
			(xy 89.01439 -409.672237) (xy 89.066693 -409.65688) (xy 89.120649 -409.649123) (xy 89.147904 -409.64866)
			(xy 90.011504 -409.64866) (xy 90.038753 -409.64921) (xy 90.092695 -409.656967) (xy 90.144985 -409.672321)
			(xy 90.194558 -409.69496) (xy 90.240404 -409.724424) (xy 90.28159 -409.760113) (xy 90.317278 -409.801299)
			(xy 90.346742 -409.847146) (xy 90.36938 -409.896718) (xy 90.384734 -409.949008) (xy 90.39249 -410.002951)
			(xy 90.39249 -410.057449) (xy 90.392489 -410.057457) (xy 91.830023 -410.057457) (xy 91.830023 -410.002943)
			(xy 91.837782 -409.948983) (xy 91.853141 -409.896678) (xy 91.875789 -409.84709) (xy 91.905264 -409.801231)
			(xy 91.940965 -409.760034) (xy 91.982167 -409.724337) (xy 92.028029 -409.694868) (xy 92.077619 -409.672226)
			(xy 92.129927 -409.656872) (xy 92.183887 -409.64912) (xy 92.211144 -409.64866) (xy 93.074744 -409.64866)
			(xy 93.101991 -409.649213) (xy 93.155929 -409.656974) (xy 93.208214 -409.672332) (xy 93.257782 -409.694973)
			(xy 93.303623 -409.724438) (xy 93.344804 -409.760127) (xy 93.380488 -409.801313) (xy 93.409948 -409.847157)
			(xy 93.432584 -409.896727) (xy 93.447935 -409.949014) (xy 93.45569 -410.002953) (xy 93.45569 -410.057447)
			(xy 93.455689 -410.057453) (xy 94.893346 -410.057453) (xy 94.893346 -410.002947) (xy 94.901103 -409.948996)
			(xy 94.916458 -409.896698) (xy 94.9391 -409.847118) (xy 94.968567 -409.801265) (xy 95.00426 -409.760071)
			(xy 95.045452 -409.724377) (xy 95.091304 -409.694908) (xy 95.140883 -409.672264) (xy 95.193181 -409.656906)
			(xy 95.247131 -409.649147) (xy 95.274384 -409.64866) (xy 96.137984 -409.64866) (xy 96.165235 -409.649186)
			(xy 96.219183 -409.656941) (xy 96.271479 -409.672294) (xy 96.321057 -409.694934) (xy 96.366908 -409.724399)
			(xy 96.408099 -409.760089) (xy 96.443792 -409.801279) (xy 96.473259 -409.847129) (xy 96.4959 -409.896706)
			(xy 96.511256 -409.949001) (xy 96.519013 -410.002949) (xy 96.519013 -410.057451) (xy 96.511256 -410.111399)
			(xy 96.4959 -410.163694) (xy 96.473259 -410.213271) (xy 96.443792 -410.259121) (xy 96.408099 -410.300311)
			(xy 96.366908 -410.336001) (xy 96.321057 -410.365466) (xy 96.271479 -410.388106) (xy 96.219183 -410.403459)
			(xy 96.165235 -410.411214) (xy 96.137984 -410.411676) (xy 95.274384 -410.411676) (xy 95.247131 -410.411253)
			(xy 95.193181 -410.403494) (xy 95.140883 -410.388136) (xy 95.091304 -410.365492) (xy 95.045452 -410.336023)
			(xy 95.00426 -410.300329) (xy 94.968567 -410.259135) (xy 94.9391 -410.213282) (xy 94.916458 -410.163702)
			(xy 94.901103 -410.111404) (xy 94.893346 -410.057453) (xy 93.455689 -410.057453) (xy 93.447935 -410.111386)
			(xy 93.432584 -410.163673) (xy 93.409948 -410.213243) (xy 93.380488 -410.259087) (xy 93.344804 -410.300273)
			(xy 93.303623 -410.335962) (xy 93.257782 -410.365427) (xy 93.208214 -410.388068) (xy 93.155929 -410.403426)
			(xy 93.101991 -410.411187) (xy 93.074744 -410.411676) (xy 92.211144 -410.411676) (xy 92.183887 -410.41128)
			(xy 92.129927 -410.403528) (xy 92.077619 -410.388174) (xy 92.028029 -410.365532) (xy 91.982167 -410.336063)
			(xy 91.940965 -410.300366) (xy 91.905264 -410.259169) (xy 91.875789 -410.21331) (xy 91.853141 -410.163722)
			(xy 91.837782 -410.111417) (xy 91.830023 -410.057457) (xy 90.392489 -410.057457) (xy 90.384734 -410.111392)
			(xy 90.36938 -410.163682) (xy 90.346742 -410.213254) (xy 90.317278 -410.259101) (xy 90.28159 -410.300287)
			(xy 90.240404 -410.335976) (xy 90.194558 -410.36544) (xy 90.144985 -410.388079) (xy 90.092695 -410.403433)
			(xy 90.038753 -410.41119) (xy 90.011504 -410.411676) (xy 89.147904 -410.411676) (xy 89.120649 -410.411277)
			(xy 89.066693 -410.40352) (xy 89.01439 -410.388163) (xy 88.964805 -410.365519) (xy 88.918948 -410.336049)
			(xy 88.877751 -410.300352) (xy 88.842054 -410.259156) (xy 88.812583 -410.213298) (xy 88.789938 -410.163714)
			(xy 88.774581 -410.111411) (xy 88.766823 -410.057455) (xy 87.329313 -410.057455) (xy 87.321555 -410.111402)
			(xy 87.306199 -410.163698) (xy 87.283556 -410.213276) (xy 87.254087 -410.259127) (xy 87.218392 -410.300318)
			(xy 87.177199 -410.336008) (xy 87.131345 -410.365473) (xy 87.081764 -410.388111) (xy 87.029467 -410.403463)
			(xy 86.975516 -410.411215) (xy 86.948264 -410.411676) (xy 86.084664 -410.411676) (xy 86.057412 -410.411252)
			(xy 86.003464 -410.40349) (xy 85.951169 -410.388131) (xy 85.901592 -410.365486) (xy 85.855742 -410.336016)
			(xy 85.814553 -410.300321) (xy 85.778862 -410.259129) (xy 85.749397 -410.213276) (xy 85.726757 -410.163697)
			(xy 85.711402 -410.111401) (xy 85.703646 -410.057452) (xy 84.265989 -410.057452) (xy 84.258235 -410.111389)
			(xy 84.242882 -410.163677) (xy 84.220245 -410.213249) (xy 84.190783 -410.259094) (xy 84.155097 -410.30028)
			(xy 84.113913 -410.335969) (xy 84.06807 -410.365433) (xy 84.0185 -410.388074) (xy 83.966212 -410.40343)
			(xy 83.912272 -410.411188) (xy 83.885024 -410.411676) (xy 83.021424 -410.411676) (xy 82.994168 -410.411279)
			(xy 82.94021 -410.403524) (xy 82.887904 -410.388169) (xy 82.838317 -410.365526) (xy 82.792457 -410.336056)
			(xy 82.751258 -410.300359) (xy 82.715559 -410.259162) (xy 82.686086 -410.213304) (xy 82.66344 -410.163718)
			(xy 82.648081 -410.111414) (xy 82.640323 -410.057456) (xy 81.202812 -410.057456) (xy 81.195056 -410.111399)
			(xy 81.1797 -410.163694) (xy 81.157059 -410.213271) (xy 81.127592 -410.259121) (xy 81.091899 -410.300311)
			(xy 81.050708 -410.336001) (xy 81.004857 -410.365466) (xy 80.955279 -410.388106) (xy 80.902983 -410.403459)
			(xy 80.849035 -410.411214) (xy 80.821784 -410.411676) (xy 79.958184 -410.411676) (xy 79.930931 -410.411253)
			(xy 79.876981 -410.403494) (xy 79.824683 -410.388136) (xy 79.775104 -410.365492) (xy 79.729252 -410.336023)
			(xy 79.68806 -410.300329) (xy 79.652367 -410.259135) (xy 79.6229 -410.213282) (xy 79.600258 -410.163702)
			(xy 79.584903 -410.111404) (xy 79.577146 -410.057453) (xy 78.139489 -410.057453) (xy 78.131735 -410.111386)
			(xy 78.116384 -410.163673) (xy 78.093748 -410.213243) (xy 78.064288 -410.259087) (xy 78.028604 -410.300273)
			(xy 77.987423 -410.335962) (xy 77.941582 -410.365427) (xy 77.892014 -410.388068) (xy 77.839729 -410.403426)
			(xy 77.785791 -410.411187) (xy 77.758544 -410.411676) (xy 76.894944 -410.411676) (xy 76.867687 -410.41128)
			(xy 76.813727 -410.403528) (xy 76.761419 -410.388174) (xy 76.711829 -410.365532) (xy 76.665967 -410.336063)
			(xy 76.624765 -410.300366) (xy 76.589064 -410.259169) (xy 76.559589 -410.21331) (xy 76.536941 -410.163722)
			(xy 76.521582 -410.111417) (xy 76.513823 -410.057457) (xy 75.076289 -410.057457) (xy 75.068534 -410.111392)
			(xy 75.05318 -410.163682) (xy 75.030542 -410.213254) (xy 75.001078 -410.259101) (xy 74.96539 -410.300287)
			(xy 74.924204 -410.335976) (xy 74.878358 -410.36544) (xy 74.828785 -410.388079) (xy 74.776495 -410.403433)
			(xy 74.722553 -410.41119) (xy 74.695304 -410.411676) (xy 73.831704 -410.411676) (xy 73.804449 -410.411277)
			(xy 73.750493 -410.40352) (xy 73.69819 -410.388163) (xy 73.648605 -410.365519) (xy 73.602748 -410.336049)
			(xy 73.561551 -410.300352) (xy 73.525854 -410.259156) (xy 73.496383 -410.213298) (xy 73.473738 -410.163714)
			(xy 73.458381 -410.111411) (xy 73.450623 -410.057455) (xy 72.013113 -410.057455) (xy 72.005355 -410.111402)
			(xy 71.989999 -410.163698) (xy 71.967356 -410.213276) (xy 71.937887 -410.259127) (xy 71.902192 -410.300318)
			(xy 71.860999 -410.336008) (xy 71.815145 -410.365473) (xy 71.765564 -410.388111) (xy 71.713267 -410.403463)
			(xy 71.659316 -410.411215) (xy 71.632064 -410.411676) (xy 70.768464 -410.411676) (xy 70.741212 -410.411252)
			(xy 70.687264 -410.40349) (xy 70.634969 -410.388131) (xy 70.585392 -410.365486) (xy 70.539542 -410.336016)
			(xy 70.498353 -410.300321) (xy 70.462662 -410.259129) (xy 70.433197 -410.213276) (xy 70.410557 -410.163697)
			(xy 70.395202 -410.111401) (xy 70.387446 -410.057452) (xy 68.949789 -410.057452) (xy 68.942035 -410.111389)
			(xy 68.926682 -410.163677) (xy 68.904045 -410.213249) (xy 68.874583 -410.259094) (xy 68.838897 -410.30028)
			(xy 68.797713 -410.335969) (xy 68.75187 -410.365433) (xy 68.7023 -410.388074) (xy 68.650012 -410.40343)
			(xy 68.596072 -410.411188) (xy 68.568824 -410.411676) (xy 67.705224 -410.411676) (xy 67.677968 -410.411279)
			(xy 67.62401 -410.403524) (xy 67.571704 -410.388169) (xy 67.522117 -410.365526) (xy 67.476257 -410.336056)
			(xy 67.435058 -410.300359) (xy 67.399359 -410.259162) (xy 67.369886 -410.213304) (xy 67.34724 -410.163718)
			(xy 67.331881 -410.111414) (xy 67.324123 -410.057456) (xy 65.886612 -410.057456) (xy 65.878856 -410.111399)
			(xy 65.8635 -410.163694) (xy 65.840859 -410.213271) (xy 65.811392 -410.259121) (xy 65.775699 -410.300311)
			(xy 65.734508 -410.336001) (xy 65.688657 -410.365466) (xy 65.639079 -410.388106) (xy 65.586783 -410.403459)
			(xy 65.532835 -410.411214) (xy 65.505584 -410.411676) (xy 64.641984 -410.411676) (xy 64.614731 -410.411253)
			(xy 64.560781 -410.403494) (xy 64.508483 -410.388136) (xy 64.458904 -410.365492) (xy 64.413052 -410.336023)
			(xy 64.37186 -410.300329) (xy 64.336167 -410.259135) (xy 64.3067 -410.213282) (xy 64.284058 -410.163702)
			(xy 64.268703 -410.111404) (xy 64.260946 -410.057453) (xy 62.823289 -410.057453) (xy 62.815535 -410.111386)
			(xy 62.800184 -410.163673) (xy 62.777548 -410.213243) (xy 62.748088 -410.259087) (xy 62.712404 -410.300273)
			(xy 62.671223 -410.335962) (xy 62.625382 -410.365427) (xy 62.575814 -410.388068) (xy 62.523529 -410.403426)
			(xy 62.469591 -410.411187) (xy 62.442344 -410.411676) (xy 61.578744 -410.411676) (xy 61.551487 -410.41128)
			(xy 61.497527 -410.403528) (xy 61.445219 -410.388174) (xy 61.395629 -410.365532) (xy 61.349767 -410.336063)
			(xy 61.308565 -410.300366) (xy 61.272864 -410.259169) (xy 61.243389 -410.21331) (xy 61.220741 -410.163722)
			(xy 61.205382 -410.111417) (xy 61.197623 -410.057457) (xy 59.760089 -410.057457) (xy 59.752334 -410.111392)
			(xy 59.73698 -410.163682) (xy 59.714342 -410.213254) (xy 59.684878 -410.259101) (xy 59.64919 -410.300287)
			(xy 59.608004 -410.335976) (xy 59.562158 -410.36544) (xy 59.512585 -410.388079) (xy 59.460295 -410.403433)
			(xy 59.406353 -410.41119) (xy 59.379104 -410.411676) (xy 58.515504 -410.411676) (xy 58.488249 -410.411277)
			(xy 58.434293 -410.40352) (xy 58.38199 -410.388163) (xy 58.332405 -410.365519) (xy 58.286548 -410.336049)
			(xy 58.245351 -410.300352) (xy 58.209654 -410.259156) (xy 58.180183 -410.213298) (xy 58.157538 -410.163714)
			(xy 58.142181 -410.111411) (xy 58.134423 -410.057455) (xy 56.696913 -410.057455) (xy 56.689155 -410.111402)
			(xy 56.673799 -410.163698) (xy 56.651156 -410.213276) (xy 56.621687 -410.259127) (xy 56.585992 -410.300318)
			(xy 56.544799 -410.336008) (xy 56.498945 -410.365473) (xy 56.449364 -410.388111) (xy 56.397067 -410.403463)
			(xy 56.343116 -410.411215) (xy 56.315864 -410.411676) (xy 55.452264 -410.411676) (xy 55.425012 -410.411252)
			(xy 55.371064 -410.40349) (xy 55.318769 -410.388131) (xy 55.269192 -410.365486) (xy 55.223342 -410.336016)
			(xy 55.182153 -410.300321) (xy 55.146462 -410.259129) (xy 55.116997 -410.213276) (xy 55.094357 -410.163697)
			(xy 55.079002 -410.111401) (xy 55.071246 -410.057452) (xy 53.633589 -410.057452) (xy 53.625835 -410.111389)
			(xy 53.610482 -410.163677) (xy 53.587845 -410.213249) (xy 53.558383 -410.259094) (xy 53.522697 -410.30028)
			(xy 53.481513 -410.335969) (xy 53.43567 -410.365433) (xy 53.3861 -410.388074) (xy 53.333812 -410.40343)
			(xy 53.279872 -410.411188) (xy 53.252624 -410.411676) (xy 52.389024 -410.411676) (xy 52.361768 -410.411279)
			(xy 52.30781 -410.403524) (xy 52.255504 -410.388169) (xy 52.205917 -410.365526) (xy 52.160057 -410.336056)
			(xy 52.118858 -410.300359) (xy 52.083159 -410.259162) (xy 52.053686 -410.213304) (xy 52.03104 -410.163718)
			(xy 52.015681 -410.111414) (xy 52.007923 -410.057456) (xy 50.570412 -410.057456) (xy 50.562656 -410.111399)
			(xy 50.5473 -410.163694) (xy 50.524659 -410.213271) (xy 50.495192 -410.259121) (xy 50.459499 -410.300311)
			(xy 50.418308 -410.336001) (xy 50.372457 -410.365466) (xy 50.322879 -410.388106) (xy 50.270583 -410.403459)
			(xy 50.216635 -410.411214) (xy 50.189384 -410.411676) (xy 49.325784 -410.411676) (xy 49.298531 -410.411253)
			(xy 49.244581 -410.403494) (xy 49.192283 -410.388136) (xy 49.142704 -410.365492) (xy 49.096852 -410.336023)
			(xy 49.05566 -410.300329) (xy 49.019967 -410.259135) (xy 48.9905 -410.213282) (xy 48.967858 -410.163702)
			(xy 48.952503 -410.111404) (xy 48.944746 -410.057453) (xy 7.00913 -410.057453) (xy 7.00913 -413.4485)
			(xy 38.974268 -413.4485) (xy 38.974268 -412.5849) (xy 38.974754 -412.557631) (xy 38.982516 -412.503647)
			(xy 38.997881 -412.451317) (xy 39.020538 -412.401707) (xy 39.050024 -412.355826) (xy 39.085739 -412.314609)
			(xy 39.126956 -412.278894) (xy 39.172837 -412.249408) (xy 39.222447 -412.226751) (xy 39.274777 -412.211386)
			(xy 39.328761 -412.203624) (xy 39.383299 -412.203624) (xy 39.437283 -412.211386) (xy 39.489613 -412.226751)
			(xy 39.539223 -412.249408) (xy 39.585104 -412.278894) (xy 39.626321 -412.314609) (xy 39.662036 -412.355826)
			(xy 39.691522 -412.401707) (xy 39.714179 -412.451317) (xy 39.729544 -412.503647) (xy 39.737306 -412.557631)
			(xy 39.737792 -412.5849) (xy 39.737792 -412.597452) (xy 47.413146 -412.597452) (xy 47.413146 -412.542948)
			(xy 47.420902 -412.488999) (xy 47.436257 -412.436703) (xy 47.458897 -412.387124) (xy 47.488362 -412.341271)
			(xy 47.524053 -412.300079) (xy 47.565242 -412.264384) (xy 47.611092 -412.234914) (xy 47.660669 -412.212269)
			(xy 47.712964 -412.19691) (xy 47.766912 -412.189148) (xy 47.794164 -412.18866) (xy 48.657764 -412.18866)
			(xy 48.685016 -412.189185) (xy 48.738967 -412.196937) (xy 48.791264 -412.212289) (xy 48.840845 -412.234927)
			(xy 48.886699 -412.264392) (xy 48.927892 -412.300082) (xy 48.963587 -412.341273) (xy 48.993056 -412.387124)
			(xy 49.015699 -412.436702) (xy 49.031055 -412.488998) (xy 49.038813 -412.542948) (xy 49.038813 -412.597452)
			(xy 49.038813 -412.597455) (xy 50.476323 -412.597455) (xy 50.476323 -412.542945) (xy 50.484081 -412.488989)
			(xy 50.499438 -412.436686) (xy 50.522083 -412.387102) (xy 50.551554 -412.341244) (xy 50.587251 -412.300048)
			(xy 50.628448 -412.264351) (xy 50.674305 -412.234881) (xy 50.72389 -412.212237) (xy 50.776193 -412.19688)
			(xy 50.830149 -412.189123) (xy 50.857404 -412.18866) (xy 51.721004 -412.18866) (xy 51.748253 -412.18921)
			(xy 51.802195 -412.196967) (xy 51.854485 -412.212321) (xy 51.904058 -412.23496) (xy 51.949904 -412.264424)
			(xy 51.99109 -412.300113) (xy 52.026778 -412.341299) (xy 52.056242 -412.387146) (xy 52.07888 -412.436718)
			(xy 52.094234 -412.489008) (xy 52.10199 -412.542951) (xy 52.10199 -412.597449) (xy 52.101989 -412.597457)
			(xy 53.539523 -412.597457) (xy 53.539523 -412.542943) (xy 53.547282 -412.488983) (xy 53.562641 -412.436678)
			(xy 53.585289 -412.38709) (xy 53.614764 -412.341231) (xy 53.650465 -412.300034) (xy 53.691667 -412.264337)
			(xy 53.737529 -412.234868) (xy 53.787119 -412.212226) (xy 53.839427 -412.196872) (xy 53.893387 -412.18912)
			(xy 53.920644 -412.18866) (xy 54.784244 -412.18866) (xy 54.811491 -412.189213) (xy 54.865429 -412.196974)
			(xy 54.917714 -412.212332) (xy 54.967282 -412.234973) (xy 55.013123 -412.264438) (xy 55.054304 -412.300127)
			(xy 55.089988 -412.341313) (xy 55.119448 -412.387157) (xy 55.142084 -412.436727) (xy 55.157435 -412.489014)
			(xy 55.16519 -412.542953) (xy 55.16519 -412.597447) (xy 55.165189 -412.597453) (xy 56.602846 -412.597453)
			(xy 56.602846 -412.542947) (xy 56.610603 -412.488996) (xy 56.625958 -412.436698) (xy 56.6486 -412.387118)
			(xy 56.678067 -412.341265) (xy 56.71376 -412.300071) (xy 56.754952 -412.264377) (xy 56.800804 -412.234908)
			(xy 56.850383 -412.212264) (xy 56.902681 -412.196906) (xy 56.956631 -412.189147) (xy 56.983884 -412.18866)
			(xy 57.847484 -412.18866) (xy 57.874735 -412.189186) (xy 57.928683 -412.196941) (xy 57.980979 -412.212294)
			(xy 58.030557 -412.234934) (xy 58.076408 -412.264399) (xy 58.117599 -412.300089) (xy 58.153292 -412.341279)
			(xy 58.182759 -412.387129) (xy 58.2054 -412.436706) (xy 58.220756 -412.489001) (xy 58.228513 -412.542949)
			(xy 58.228513 -412.597451) (xy 58.228512 -412.597456) (xy 59.666023 -412.597456) (xy 59.666023 -412.542944)
			(xy 59.673781 -412.488986) (xy 59.68914 -412.436682) (xy 59.711786 -412.387096) (xy 59.741259 -412.341238)
			(xy 59.776958 -412.300041) (xy 59.818157 -412.264344) (xy 59.864017 -412.234874) (xy 59.913604 -412.212231)
			(xy 59.96591 -412.196876) (xy 60.019868 -412.189121) (xy 60.047124 -412.18866) (xy 60.910724 -412.18866)
			(xy 60.937972 -412.189212) (xy 60.991912 -412.19697) (xy 61.0442 -412.212326) (xy 61.09377 -412.234967)
			(xy 61.139613 -412.264431) (xy 61.180797 -412.30012) (xy 61.216483 -412.341306) (xy 61.245945 -412.387151)
			(xy 61.268582 -412.436723) (xy 61.283935 -412.489011) (xy 61.29169 -412.542952) (xy 61.29169 -412.597448)
			(xy 61.291689 -412.597452) (xy 62.729346 -412.597452) (xy 62.729346 -412.542948) (xy 62.737102 -412.488999)
			(xy 62.752457 -412.436703) (xy 62.775097 -412.387124) (xy 62.804562 -412.341271) (xy 62.840253 -412.300079)
			(xy 62.881442 -412.264384) (xy 62.927292 -412.234914) (xy 62.976869 -412.212269) (xy 63.029164 -412.19691)
			(xy 63.083112 -412.189148) (xy 63.110364 -412.18866) (xy 63.973964 -412.18866) (xy 64.001216 -412.189185)
			(xy 64.055167 -412.196937) (xy 64.107464 -412.212289) (xy 64.157045 -412.234927) (xy 64.202899 -412.264392)
			(xy 64.244092 -412.300082) (xy 64.279787 -412.341273) (xy 64.309256 -412.387124) (xy 64.331899 -412.436702)
			(xy 64.347255 -412.488998) (xy 64.355013 -412.542948) (xy 64.355013 -412.597452) (xy 64.355013 -412.597455)
			(xy 65.792523 -412.597455) (xy 65.792523 -412.542945) (xy 65.800281 -412.488989) (xy 65.815638 -412.436686)
			(xy 65.838283 -412.387102) (xy 65.867754 -412.341244) (xy 65.903451 -412.300048) (xy 65.944648 -412.264351)
			(xy 65.990505 -412.234881) (xy 66.04009 -412.212237) (xy 66.092393 -412.19688) (xy 66.146349 -412.189123)
			(xy 66.173604 -412.18866) (xy 67.037204 -412.18866) (xy 67.064453 -412.18921) (xy 67.118395 -412.196967)
			(xy 67.170685 -412.212321) (xy 67.220258 -412.23496) (xy 67.266104 -412.264424) (xy 67.30729 -412.300113)
			(xy 67.342978 -412.341299) (xy 67.372442 -412.387146) (xy 67.39508 -412.436718) (xy 67.410434 -412.489008)
			(xy 67.41819 -412.542951) (xy 67.41819 -412.597449) (xy 67.418189 -412.597457) (xy 68.855723 -412.597457)
			(xy 68.855723 -412.542943) (xy 68.863482 -412.488983) (xy 68.878841 -412.436678) (xy 68.901489 -412.38709)
			(xy 68.930964 -412.341231) (xy 68.966665 -412.300034) (xy 69.007867 -412.264337) (xy 69.053729 -412.234868)
			(xy 69.103319 -412.212226) (xy 69.155627 -412.196872) (xy 69.209587 -412.18912) (xy 69.236844 -412.18866)
			(xy 70.100444 -412.18866) (xy 70.127691 -412.189213) (xy 70.181629 -412.196974) (xy 70.233914 -412.212332)
			(xy 70.283482 -412.234973) (xy 70.329323 -412.264438) (xy 70.370504 -412.300127) (xy 70.406188 -412.341313)
			(xy 70.435648 -412.387157) (xy 70.458284 -412.436727) (xy 70.473635 -412.489014) (xy 70.48139 -412.542953)
			(xy 70.48139 -412.597447) (xy 70.481389 -412.597453) (xy 71.919046 -412.597453) (xy 71.919046 -412.542947)
			(xy 71.926803 -412.488996) (xy 71.942158 -412.436698) (xy 71.9648 -412.387118) (xy 71.994267 -412.341265)
			(xy 72.02996 -412.300071) (xy 72.071152 -412.264377) (xy 72.117004 -412.234908) (xy 72.166583 -412.212264)
			(xy 72.218881 -412.196906) (xy 72.272831 -412.189147) (xy 72.300084 -412.18866) (xy 73.163684 -412.18866)
			(xy 73.190935 -412.189186) (xy 73.244883 -412.196941) (xy 73.297179 -412.212294) (xy 73.346757 -412.234934)
			(xy 73.392608 -412.264399) (xy 73.433799 -412.300089) (xy 73.469492 -412.341279) (xy 73.498959 -412.387129)
			(xy 73.5216 -412.436706) (xy 73.536956 -412.489001) (xy 73.544713 -412.542949) (xy 73.544713 -412.597451)
			(xy 73.544712 -412.597456) (xy 74.982223 -412.597456) (xy 74.982223 -412.542944) (xy 74.989981 -412.488986)
			(xy 75.00534 -412.436682) (xy 75.027986 -412.387096) (xy 75.057459 -412.341238) (xy 75.093158 -412.300041)
			(xy 75.134357 -412.264344) (xy 75.180217 -412.234874) (xy 75.229804 -412.212231) (xy 75.28211 -412.196876)
			(xy 75.336068 -412.189121) (xy 75.363324 -412.18866) (xy 76.226924 -412.18866) (xy 76.254172 -412.189212)
			(xy 76.308112 -412.19697) (xy 76.3604 -412.212326) (xy 76.40997 -412.234967) (xy 76.455813 -412.264431)
			(xy 76.496997 -412.30012) (xy 76.532683 -412.341306) (xy 76.562145 -412.387151) (xy 76.584782 -412.436723)
			(xy 76.600135 -412.489011) (xy 76.60789 -412.542952) (xy 76.60789 -412.597448) (xy 76.607889 -412.597452)
			(xy 78.045546 -412.597452) (xy 78.045546 -412.542948) (xy 78.053302 -412.488999) (xy 78.068657 -412.436703)
			(xy 78.091297 -412.387124) (xy 78.120762 -412.341271) (xy 78.156453 -412.300079) (xy 78.197642 -412.264384)
			(xy 78.243492 -412.234914) (xy 78.293069 -412.212269) (xy 78.345364 -412.19691) (xy 78.399312 -412.189148)
			(xy 78.426564 -412.18866) (xy 79.290164 -412.18866) (xy 79.317416 -412.189185) (xy 79.371367 -412.196937)
			(xy 79.423664 -412.212289) (xy 79.473245 -412.234927) (xy 79.519099 -412.264392) (xy 79.560292 -412.300082)
			(xy 79.595987 -412.341273) (xy 79.625456 -412.387124) (xy 79.648099 -412.436702) (xy 79.663455 -412.488998)
			(xy 79.671213 -412.542948) (xy 79.671213 -412.597452) (xy 79.671213 -412.597455) (xy 81.108723 -412.597455)
			(xy 81.108723 -412.542945) (xy 81.116481 -412.488989) (xy 81.131838 -412.436686) (xy 81.154483 -412.387102)
			(xy 81.183954 -412.341244) (xy 81.219651 -412.300048) (xy 81.260848 -412.264351) (xy 81.306705 -412.234881)
			(xy 81.35629 -412.212237) (xy 81.408593 -412.19688) (xy 81.462549 -412.189123) (xy 81.489804 -412.18866)
			(xy 82.353404 -412.18866) (xy 82.380653 -412.18921) (xy 82.434595 -412.196967) (xy 82.486885 -412.212321)
			(xy 82.536458 -412.23496) (xy 82.582304 -412.264424) (xy 82.62349 -412.300113) (xy 82.659178 -412.341299)
			(xy 82.688642 -412.387146) (xy 82.71128 -412.436718) (xy 82.726634 -412.489008) (xy 82.73439 -412.542951)
			(xy 82.73439 -412.597449) (xy 82.734389 -412.597457) (xy 84.171923 -412.597457) (xy 84.171923 -412.542943)
			(xy 84.179682 -412.488983) (xy 84.195041 -412.436678) (xy 84.217689 -412.38709) (xy 84.247164 -412.341231)
			(xy 84.282865 -412.300034) (xy 84.324067 -412.264337) (xy 84.369929 -412.234868) (xy 84.419519 -412.212226)
			(xy 84.471827 -412.196872) (xy 84.525787 -412.18912) (xy 84.553044 -412.18866) (xy 85.416644 -412.18866)
			(xy 85.443891 -412.189213) (xy 85.497829 -412.196974) (xy 85.550114 -412.212332) (xy 85.599682 -412.234973)
			(xy 85.645523 -412.264438) (xy 85.686704 -412.300127) (xy 85.722388 -412.341313) (xy 85.751848 -412.387157)
			(xy 85.774484 -412.436727) (xy 85.789835 -412.489014) (xy 85.79759 -412.542953) (xy 85.79759 -412.597447)
			(xy 85.797589 -412.597453) (xy 87.235246 -412.597453) (xy 87.235246 -412.542947) (xy 87.243003 -412.488996)
			(xy 87.258358 -412.436698) (xy 87.281 -412.387118) (xy 87.310467 -412.341265) (xy 87.34616 -412.300071)
			(xy 87.387352 -412.264377) (xy 87.433204 -412.234908) (xy 87.482783 -412.212264) (xy 87.535081 -412.196906)
			(xy 87.589031 -412.189147) (xy 87.616284 -412.18866) (xy 88.479884 -412.18866) (xy 88.507135 -412.189186)
			(xy 88.561083 -412.196941) (xy 88.613379 -412.212294) (xy 88.662957 -412.234934) (xy 88.708808 -412.264399)
			(xy 88.749999 -412.300089) (xy 88.785692 -412.341279) (xy 88.815159 -412.387129) (xy 88.8378 -412.436706)
			(xy 88.853156 -412.489001) (xy 88.860913 -412.542949) (xy 88.860913 -412.597451) (xy 88.860912 -412.597456)
			(xy 90.298423 -412.597456) (xy 90.298423 -412.542944) (xy 90.306181 -412.488986) (xy 90.32154 -412.436682)
			(xy 90.344186 -412.387096) (xy 90.373659 -412.341238) (xy 90.409358 -412.300041) (xy 90.450557 -412.264344)
			(xy 90.496417 -412.234874) (xy 90.546004 -412.212231) (xy 90.59831 -412.196876) (xy 90.652268 -412.189121)
			(xy 90.679524 -412.18866) (xy 91.543124 -412.18866) (xy 91.570372 -412.189212) (xy 91.624312 -412.19697)
			(xy 91.6766 -412.212326) (xy 91.72617 -412.234967) (xy 91.772013 -412.264431) (xy 91.813197 -412.30012)
			(xy 91.848883 -412.341306) (xy 91.878345 -412.387151) (xy 91.900982 -412.436723) (xy 91.916335 -412.489011)
			(xy 91.92409 -412.542952) (xy 91.92409 -412.597448) (xy 91.924089 -412.597452) (xy 93.361746 -412.597452)
			(xy 93.361746 -412.542948) (xy 93.369502 -412.488999) (xy 93.384857 -412.436703) (xy 93.407497 -412.387124)
			(xy 93.436962 -412.341271) (xy 93.472653 -412.300079) (xy 93.513842 -412.264384) (xy 93.559692 -412.234914)
			(xy 93.609269 -412.212269) (xy 93.661564 -412.19691) (xy 93.715512 -412.189148) (xy 93.742764 -412.18866)
			(xy 94.606364 -412.18866) (xy 94.633616 -412.189185) (xy 94.687567 -412.196937) (xy 94.739864 -412.212289)
			(xy 94.789445 -412.234927) (xy 94.835299 -412.264392) (xy 94.876492 -412.300082) (xy 94.912187 -412.341273)
			(xy 94.941656 -412.387124) (xy 94.964299 -412.436702) (xy 94.979655 -412.488998) (xy 94.987413 -412.542948)
			(xy 94.987413 -412.597452) (xy 94.987413 -412.597455) (xy 114.513023 -412.597455) (xy 114.513023 -412.542945)
			(xy 114.520781 -412.488989) (xy 114.536138 -412.436686) (xy 114.558783 -412.387101) (xy 114.588254 -412.341244)
			(xy 114.623952 -412.300047) (xy 114.665149 -412.264351) (xy 114.711006 -412.23488) (xy 114.760591 -412.212236)
			(xy 114.812894 -412.196879) (xy 114.866851 -412.189123) (xy 114.894106 -412.18866) (xy 115.757706 -412.18866)
			(xy 115.784955 -412.189211) (xy 115.838897 -412.196967) (xy 115.891187 -412.212321) (xy 115.940759 -412.234961)
			(xy 115.986605 -412.264425) (xy 116.027791 -412.300113) (xy 116.063479 -412.3413) (xy 116.092942 -412.387146)
			(xy 116.115581 -412.436719) (xy 116.130934 -412.489009) (xy 116.13869 -412.542951) (xy 116.13869 -412.597449)
			(xy 116.138689 -412.597457) (xy 117.576223 -412.597457) (xy 117.576223 -412.542943) (xy 117.583982 -412.488983)
			(xy 117.599342 -412.436677) (xy 117.621989 -412.38709) (xy 117.651464 -412.341231) (xy 117.687166 -412.300033)
			(xy 117.728367 -412.264337) (xy 117.77423 -412.234867) (xy 117.82382 -412.212225) (xy 117.876128 -412.196872)
			(xy 117.930089 -412.18912) (xy 117.957346 -412.18866) (xy 118.820946 -412.18866) (xy 118.848193 -412.189213)
			(xy 118.902131 -412.196975) (xy 118.954416 -412.212332) (xy 119.003983 -412.234974) (xy 119.049824 -412.264439)
			(xy 119.091005 -412.300128) (xy 119.126688 -412.341313) (xy 119.156148 -412.387157) (xy 119.178784 -412.436727)
			(xy 119.194135 -412.489014) (xy 119.20189 -412.542953) (xy 119.20189 -412.597447) (xy 119.201889 -412.597453)
			(xy 120.639546 -412.597453) (xy 120.639546 -412.542947) (xy 120.647303 -412.488996) (xy 120.662658 -412.436698)
			(xy 120.6853 -412.387118) (xy 120.714768 -412.341264) (xy 120.750461 -412.300071) (xy 120.791653 -412.264376)
			(xy 120.837505 -412.234907) (xy 120.887085 -412.212263) (xy 120.939382 -412.196906) (xy 120.993333 -412.189147)
			(xy 121.020586 -412.18866) (xy 121.884186 -412.18866) (xy 121.911437 -412.189186) (xy 121.965385 -412.196941)
			(xy 122.01768 -412.212295) (xy 122.067258 -412.234934) (xy 122.113109 -412.264399) (xy 122.1543 -412.30009)
			(xy 122.189992 -412.34128) (xy 122.219459 -412.38713) (xy 122.242101 -412.436707) (xy 122.257456 -412.489001)
			(xy 122.265213 -412.542949) (xy 122.265213 -412.597451) (xy 122.265212 -412.597456) (xy 123.702723 -412.597456)
			(xy 123.702723 -412.542944) (xy 123.710481 -412.488986) (xy 123.72584 -412.436681) (xy 123.748486 -412.387095)
			(xy 123.777959 -412.341237) (xy 123.813659 -412.30004) (xy 123.854858 -412.264344) (xy 123.900718 -412.234874)
			(xy 123.950306 -412.212231) (xy 124.002611 -412.196876) (xy 124.05657 -412.189121) (xy 124.083826 -412.18866)
			(xy 124.947426 -412.18866) (xy 124.974674 -412.189212) (xy 125.028614 -412.196971) (xy 125.080901 -412.212327)
			(xy 125.130471 -412.234968) (xy 125.176314 -412.264432) (xy 125.217498 -412.300121) (xy 125.253184 -412.341307)
			(xy 125.282645 -412.387152) (xy 125.305282 -412.436723) (xy 125.320635 -412.489011) (xy 125.32839 -412.542952)
			(xy 125.32839 -412.597448) (xy 125.328389 -412.597452) (xy 126.766046 -412.597452) (xy 126.766046 -412.542948)
			(xy 126.773802 -412.488999) (xy 126.789157 -412.436702) (xy 126.811797 -412.387123) (xy 126.841263 -412.341271)
			(xy 126.876954 -412.300078) (xy 126.918143 -412.264383) (xy 126.963993 -412.234914) (xy 127.01357 -412.212269)
			(xy 127.065865 -412.196909) (xy 127.119814 -412.189148) (xy 127.147066 -412.18866) (xy 128.010666 -412.18866)
			(xy 128.037918 -412.189185) (xy 128.091868 -412.196937) (xy 128.144166 -412.212289) (xy 128.193746 -412.234928)
			(xy 128.2396 -412.264392) (xy 128.280793 -412.300083) (xy 128.316487 -412.341273) (xy 128.345956 -412.387124)
			(xy 128.368599 -412.436702) (xy 128.383955 -412.488999) (xy 128.391713 -412.542948) (xy 128.391713 -412.597452)
			(xy 128.391713 -412.597455) (xy 129.829223 -412.597455) (xy 129.829223 -412.542945) (xy 129.836981 -412.488989)
			(xy 129.852338 -412.436686) (xy 129.874983 -412.387101) (xy 129.904454 -412.341244) (xy 129.940152 -412.300047)
			(xy 129.981349 -412.264351) (xy 130.027206 -412.23488) (xy 130.076791 -412.212236) (xy 130.129094 -412.196879)
			(xy 130.183051 -412.189123) (xy 130.210306 -412.18866) (xy 131.073906 -412.18866) (xy 131.101155 -412.189211)
			(xy 131.155097 -412.196967) (xy 131.207387 -412.212321) (xy 131.256959 -412.234961) (xy 131.302805 -412.264425)
			(xy 131.343991 -412.300113) (xy 131.379679 -412.3413) (xy 131.409142 -412.387146) (xy 131.431781 -412.436719)
			(xy 131.447134 -412.489009) (xy 131.45489 -412.542951) (xy 131.45489 -412.597449) (xy 131.454889 -412.597457)
			(xy 132.892423 -412.597457) (xy 132.892423 -412.542943) (xy 132.900182 -412.488983) (xy 132.915542 -412.436677)
			(xy 132.938189 -412.38709) (xy 132.967664 -412.341231) (xy 133.003366 -412.300033) (xy 133.044567 -412.264337)
			(xy 133.09043 -412.234867) (xy 133.14002 -412.212225) (xy 133.192328 -412.196872) (xy 133.246289 -412.18912)
			(xy 133.273546 -412.18866) (xy 134.137146 -412.18866) (xy 134.164393 -412.189213) (xy 134.218331 -412.196975)
			(xy 134.270616 -412.212332) (xy 134.320183 -412.234974) (xy 134.366024 -412.264439) (xy 134.407205 -412.300128)
			(xy 134.442888 -412.341313) (xy 134.472348 -412.387157) (xy 134.494984 -412.436727) (xy 134.510335 -412.489014)
			(xy 134.51809 -412.542953) (xy 134.51809 -412.597447) (xy 134.518089 -412.597453) (xy 135.955746 -412.597453)
			(xy 135.955746 -412.542947) (xy 135.963503 -412.488996) (xy 135.978858 -412.436698) (xy 136.0015 -412.387118)
			(xy 136.030968 -412.341264) (xy 136.066661 -412.300071) (xy 136.107853 -412.264376) (xy 136.153705 -412.234907)
			(xy 136.203285 -412.212263) (xy 136.255582 -412.196906) (xy 136.309533 -412.189147) (xy 136.336786 -412.18866)
			(xy 137.200386 -412.18866) (xy 137.227637 -412.189186) (xy 137.281585 -412.196941) (xy 137.33388 -412.212295)
			(xy 137.383458 -412.234934) (xy 137.429309 -412.264399) (xy 137.4705 -412.30009) (xy 137.506192 -412.34128)
			(xy 137.535659 -412.38713) (xy 137.558301 -412.436707) (xy 137.573656 -412.489001) (xy 137.581413 -412.542949)
			(xy 137.581413 -412.597451) (xy 137.581412 -412.597456) (xy 139.018923 -412.597456) (xy 139.018923 -412.542944)
			(xy 139.026681 -412.488986) (xy 139.04204 -412.436681) (xy 139.064686 -412.387095) (xy 139.094159 -412.341237)
			(xy 139.129859 -412.30004) (xy 139.171058 -412.264344) (xy 139.216918 -412.234874) (xy 139.266506 -412.212231)
			(xy 139.318811 -412.196876) (xy 139.37277 -412.189121) (xy 139.400026 -412.18866) (xy 140.263626 -412.18866)
			(xy 140.290874 -412.189212) (xy 140.344814 -412.196971) (xy 140.397101 -412.212327) (xy 140.446671 -412.234968)
			(xy 140.492514 -412.264432) (xy 140.533698 -412.300121) (xy 140.569384 -412.341307) (xy 140.598845 -412.387152)
			(xy 140.621482 -412.436723) (xy 140.636835 -412.489011) (xy 140.64459 -412.542952) (xy 140.64459 -412.597448)
			(xy 140.644589 -412.597452) (xy 142.082246 -412.597452) (xy 142.082246 -412.542948) (xy 142.090002 -412.488999)
			(xy 142.105357 -412.436702) (xy 142.127997 -412.387123) (xy 142.157463 -412.341271) (xy 142.193154 -412.300078)
			(xy 142.234343 -412.264383) (xy 142.280193 -412.234914) (xy 142.32977 -412.212269) (xy 142.382065 -412.196909)
			(xy 142.436014 -412.189148) (xy 142.463266 -412.18866) (xy 143.326866 -412.18866) (xy 143.354118 -412.189185)
			(xy 143.408068 -412.196937) (xy 143.460366 -412.212289) (xy 143.509946 -412.234928) (xy 143.5558 -412.264392)
			(xy 143.596993 -412.300083) (xy 143.632687 -412.341273) (xy 143.662156 -412.387124) (xy 143.684799 -412.436702)
			(xy 143.700155 -412.488999) (xy 143.707913 -412.542948) (xy 143.707913 -412.597452) (xy 143.707913 -412.597455)
			(xy 145.145423 -412.597455) (xy 145.145423 -412.542945) (xy 145.153181 -412.488989) (xy 145.168538 -412.436686)
			(xy 145.191183 -412.387101) (xy 145.220654 -412.341244) (xy 145.256352 -412.300047) (xy 145.297549 -412.264351)
			(xy 145.343406 -412.23488) (xy 145.392991 -412.212236) (xy 145.445294 -412.196879) (xy 145.499251 -412.189123)
			(xy 145.526506 -412.18866) (xy 146.390106 -412.18866) (xy 146.417355 -412.189211) (xy 146.471297 -412.196967)
			(xy 146.523587 -412.212321) (xy 146.573159 -412.234961) (xy 146.619005 -412.264425) (xy 146.660191 -412.300113)
			(xy 146.695879 -412.3413) (xy 146.725342 -412.387146) (xy 146.747981 -412.436719) (xy 146.763334 -412.489009)
			(xy 146.77109 -412.542951) (xy 146.77109 -412.597449) (xy 146.771089 -412.597457) (xy 148.208623 -412.597457)
			(xy 148.208623 -412.542943) (xy 148.216382 -412.488983) (xy 148.231742 -412.436677) (xy 148.254389 -412.38709)
			(xy 148.283864 -412.341231) (xy 148.319566 -412.300033) (xy 148.360767 -412.264337) (xy 148.40663 -412.234867)
			(xy 148.45622 -412.212225) (xy 148.508528 -412.196872) (xy 148.562489 -412.18912) (xy 148.589746 -412.18866)
			(xy 149.453346 -412.18866) (xy 149.480593 -412.189213) (xy 149.534531 -412.196975) (xy 149.586816 -412.212332)
			(xy 149.636383 -412.234974) (xy 149.682224 -412.264439) (xy 149.723405 -412.300128) (xy 149.759088 -412.341313)
			(xy 149.788548 -412.387157) (xy 149.811184 -412.436727) (xy 149.826535 -412.489014) (xy 149.83429 -412.542953)
			(xy 149.83429 -412.597447) (xy 149.834289 -412.597453) (xy 151.271946 -412.597453) (xy 151.271946 -412.542947)
			(xy 151.279703 -412.488996) (xy 151.295058 -412.436698) (xy 151.3177 -412.387118) (xy 151.347168 -412.341264)
			(xy 151.382861 -412.300071) (xy 151.424053 -412.264376) (xy 151.469905 -412.234907) (xy 151.519485 -412.212263)
			(xy 151.571782 -412.196906) (xy 151.625733 -412.189147) (xy 151.652986 -412.18866) (xy 152.516586 -412.18866)
			(xy 152.543837 -412.189186) (xy 152.597785 -412.196941) (xy 152.65008 -412.212295) (xy 152.699658 -412.234934)
			(xy 152.745509 -412.264399) (xy 152.7867 -412.30009) (xy 152.822392 -412.34128) (xy 152.851859 -412.38713)
			(xy 152.874501 -412.436707) (xy 152.889856 -412.489001) (xy 152.897613 -412.542949) (xy 152.897613 -412.597451)
			(xy 152.897612 -412.597456) (xy 154.335123 -412.597456) (xy 154.335123 -412.542944) (xy 154.342881 -412.488986)
			(xy 154.35824 -412.436681) (xy 154.380886 -412.387095) (xy 154.410359 -412.341237) (xy 154.446059 -412.30004)
			(xy 154.487258 -412.264344) (xy 154.533118 -412.234874) (xy 154.582706 -412.212231) (xy 154.635011 -412.196876)
			(xy 154.68897 -412.189121) (xy 154.716226 -412.18866) (xy 155.579826 -412.18866) (xy 155.607074 -412.189212)
			(xy 155.661014 -412.196971) (xy 155.713301 -412.212327) (xy 155.762871 -412.234968) (xy 155.808714 -412.264432)
			(xy 155.849898 -412.300121) (xy 155.885584 -412.341307) (xy 155.915045 -412.387152) (xy 155.937682 -412.436723)
			(xy 155.953035 -412.489011) (xy 155.96079 -412.542952) (xy 155.96079 -412.597448) (xy 155.960789 -412.597452)
			(xy 157.398446 -412.597452) (xy 157.398446 -412.542948) (xy 157.406202 -412.488999) (xy 157.421557 -412.436702)
			(xy 157.444197 -412.387123) (xy 157.473663 -412.341271) (xy 157.509354 -412.300078) (xy 157.550543 -412.264383)
			(xy 157.596393 -412.234914) (xy 157.64597 -412.212269) (xy 157.698265 -412.196909) (xy 157.752214 -412.189148)
			(xy 157.779466 -412.18866) (xy 158.643066 -412.18866) (xy 158.670318 -412.189185) (xy 158.724268 -412.196937)
			(xy 158.776566 -412.212289) (xy 158.826146 -412.234928) (xy 158.872 -412.264392) (xy 158.913193 -412.300083)
			(xy 158.948887 -412.341273) (xy 158.978356 -412.387124) (xy 159.000999 -412.436702) (xy 159.016355 -412.488999)
			(xy 159.024113 -412.542948) (xy 159.024113 -412.597452) (xy 159.024113 -412.597455) (xy 160.461623 -412.597455)
			(xy 160.461623 -412.542945) (xy 160.469381 -412.488989) (xy 160.484738 -412.436686) (xy 160.507383 -412.387101)
			(xy 160.536854 -412.341244) (xy 160.572552 -412.300047) (xy 160.613749 -412.264351) (xy 160.659606 -412.23488)
			(xy 160.709191 -412.212236) (xy 160.761494 -412.196879) (xy 160.815451 -412.189123) (xy 160.842706 -412.18866)
			(xy 161.706306 -412.18866) (xy 161.733555 -412.189211) (xy 161.787497 -412.196967) (xy 161.839787 -412.212321)
			(xy 161.889359 -412.234961) (xy 161.935205 -412.264425) (xy 161.976391 -412.300113) (xy 162.012079 -412.3413)
			(xy 162.041542 -412.387146) (xy 162.064181 -412.436719) (xy 162.079534 -412.489009) (xy 162.08729 -412.542951)
			(xy 162.08729 -412.597449) (xy 162.079534 -412.651391) (xy 162.064181 -412.703681) (xy 162.041542 -412.753254)
			(xy 162.012079 -412.7991) (xy 161.976391 -412.840287) (xy 161.935205 -412.875975) (xy 161.889359 -412.905439)
			(xy 161.839787 -412.928079) (xy 161.787497 -412.943433) (xy 161.733555 -412.951189) (xy 161.706306 -412.951676)
			(xy 160.842706 -412.951676) (xy 160.815451 -412.951277) (xy 160.761494 -412.943521) (xy 160.709191 -412.928164)
			(xy 160.659606 -412.90552) (xy 160.613749 -412.876049) (xy 160.572552 -412.840353) (xy 160.536854 -412.799156)
			(xy 160.507383 -412.753299) (xy 160.484738 -412.703714) (xy 160.469381 -412.651411) (xy 160.461623 -412.597455)
			(xy 159.024113 -412.597455) (xy 159.016355 -412.651402) (xy 159.000999 -412.703698) (xy 158.978356 -412.753276)
			(xy 158.948887 -412.799127) (xy 158.913193 -412.840317) (xy 158.872 -412.876008) (xy 158.826146 -412.905472)
			(xy 158.776566 -412.928111) (xy 158.724268 -412.943463) (xy 158.670318 -412.951215) (xy 158.643066 -412.951676)
			(xy 157.779466 -412.951676) (xy 157.752214 -412.951252) (xy 157.698265 -412.943491) (xy 157.64597 -412.928131)
			(xy 157.596393 -412.905486) (xy 157.550543 -412.876017) (xy 157.509354 -412.840322) (xy 157.473663 -412.799129)
			(xy 157.444197 -412.753277) (xy 157.421557 -412.703698) (xy 157.406202 -412.651401) (xy 157.398446 -412.597452)
			(xy 155.960789 -412.597452) (xy 155.953035 -412.651389) (xy 155.937682 -412.703677) (xy 155.915045 -412.753248)
			(xy 155.885584 -412.799093) (xy 155.849898 -412.840279) (xy 155.808714 -412.875968) (xy 155.762871 -412.905432)
			(xy 155.713301 -412.928073) (xy 155.661014 -412.943429) (xy 155.607074 -412.951188) (xy 155.579826 -412.951676)
			(xy 154.716226 -412.951676) (xy 154.68897 -412.951279) (xy 154.635011 -412.943524) (xy 154.582706 -412.928169)
			(xy 154.533118 -412.905526) (xy 154.487258 -412.876056) (xy 154.446059 -412.84036) (xy 154.410359 -412.799163)
			(xy 154.380886 -412.753305) (xy 154.35824 -412.703719) (xy 154.342881 -412.651414) (xy 154.335123 -412.597456)
			(xy 152.897612 -412.597456) (xy 152.889856 -412.651399) (xy 152.874501 -412.703693) (xy 152.851859 -412.75327)
			(xy 152.822392 -412.79912) (xy 152.7867 -412.84031) (xy 152.745509 -412.876001) (xy 152.699658 -412.905466)
			(xy 152.65008 -412.928105) (xy 152.597785 -412.943459) (xy 152.543837 -412.951214) (xy 152.516586 -412.951676)
			(xy 151.652986 -412.951676) (xy 151.625733 -412.951253) (xy 151.571782 -412.943494) (xy 151.519485 -412.928137)
			(xy 151.469905 -412.905493) (xy 151.424053 -412.876024) (xy 151.382861 -412.840329) (xy 151.347168 -412.799136)
			(xy 151.3177 -412.753282) (xy 151.295058 -412.703702) (xy 151.279703 -412.651404) (xy 151.271946 -412.597453)
			(xy 149.834289 -412.597453) (xy 149.826535 -412.651386) (xy 149.811184 -412.703673) (xy 149.788548 -412.753243)
			(xy 149.759088 -412.799087) (xy 149.723405 -412.840272) (xy 149.682224 -412.875961) (xy 149.636383 -412.905426)
			(xy 149.586816 -412.928068) (xy 149.534531 -412.943425) (xy 149.480593 -412.951187) (xy 149.453346 -412.951676)
			(xy 148.589746 -412.951676) (xy 148.562489 -412.95128) (xy 148.508528 -412.943528) (xy 148.45622 -412.928175)
			(xy 148.40663 -412.905533) (xy 148.360767 -412.876063) (xy 148.319566 -412.840367) (xy 148.283864 -412.799169)
			(xy 148.254389 -412.75331) (xy 148.231742 -412.703723) (xy 148.216382 -412.651417) (xy 148.208623 -412.597457)
			(xy 146.771089 -412.597457) (xy 146.763334 -412.651391) (xy 146.747981 -412.703681) (xy 146.725342 -412.753254)
			(xy 146.695879 -412.7991) (xy 146.660191 -412.840287) (xy 146.619005 -412.875975) (xy 146.573159 -412.905439)
			(xy 146.523587 -412.928079) (xy 146.471297 -412.943433) (xy 146.417355 -412.951189) (xy 146.390106 -412.951676)
			(xy 145.526506 -412.951676) (xy 145.499251 -412.951277) (xy 145.445294 -412.943521) (xy 145.392991 -412.928164)
			(xy 145.343406 -412.90552) (xy 145.297549 -412.876049) (xy 145.256352 -412.840353) (xy 145.220654 -412.799156)
			(xy 145.191183 -412.753299) (xy 145.168538 -412.703714) (xy 145.153181 -412.651411) (xy 145.145423 -412.597455)
			(xy 143.707913 -412.597455) (xy 143.700155 -412.651402) (xy 143.684799 -412.703698) (xy 143.662156 -412.753276)
			(xy 143.632687 -412.799127) (xy 143.596993 -412.840317) (xy 143.5558 -412.876008) (xy 143.509946 -412.905472)
			(xy 143.460366 -412.928111) (xy 143.408068 -412.943463) (xy 143.354118 -412.951215) (xy 143.326866 -412.951676)
			(xy 142.463266 -412.951676) (xy 142.436014 -412.951252) (xy 142.382065 -412.943491) (xy 142.32977 -412.928131)
			(xy 142.280193 -412.905486) (xy 142.234343 -412.876017) (xy 142.193154 -412.840322) (xy 142.157463 -412.799129)
			(xy 142.127997 -412.753277) (xy 142.105357 -412.703698) (xy 142.090002 -412.651401) (xy 142.082246 -412.597452)
			(xy 140.644589 -412.597452) (xy 140.636835 -412.651389) (xy 140.621482 -412.703677) (xy 140.598845 -412.753248)
			(xy 140.569384 -412.799093) (xy 140.533698 -412.840279) (xy 140.492514 -412.875968) (xy 140.446671 -412.905432)
			(xy 140.397101 -412.928073) (xy 140.344814 -412.943429) (xy 140.290874 -412.951188) (xy 140.263626 -412.951676)
			(xy 139.400026 -412.951676) (xy 139.37277 -412.951279) (xy 139.318811 -412.943524) (xy 139.266506 -412.928169)
			(xy 139.216918 -412.905526) (xy 139.171058 -412.876056) (xy 139.129859 -412.84036) (xy 139.094159 -412.799163)
			(xy 139.064686 -412.753305) (xy 139.04204 -412.703719) (xy 139.026681 -412.651414) (xy 139.018923 -412.597456)
			(xy 137.581412 -412.597456) (xy 137.573656 -412.651399) (xy 137.558301 -412.703693) (xy 137.535659 -412.75327)
			(xy 137.506192 -412.79912) (xy 137.4705 -412.84031) (xy 137.429309 -412.876001) (xy 137.383458 -412.905466)
			(xy 137.33388 -412.928105) (xy 137.281585 -412.943459) (xy 137.227637 -412.951214) (xy 137.200386 -412.951676)
			(xy 136.336786 -412.951676) (xy 136.309533 -412.951253) (xy 136.255582 -412.943494) (xy 136.203285 -412.928137)
			(xy 136.153705 -412.905493) (xy 136.107853 -412.876024) (xy 136.066661 -412.840329) (xy 136.030968 -412.799136)
			(xy 136.0015 -412.753282) (xy 135.978858 -412.703702) (xy 135.963503 -412.651404) (xy 135.955746 -412.597453)
			(xy 134.518089 -412.597453) (xy 134.510335 -412.651386) (xy 134.494984 -412.703673) (xy 134.472348 -412.753243)
			(xy 134.442888 -412.799087) (xy 134.407205 -412.840272) (xy 134.366024 -412.875961) (xy 134.320183 -412.905426)
			(xy 134.270616 -412.928068) (xy 134.218331 -412.943425) (xy 134.164393 -412.951187) (xy 134.137146 -412.951676)
			(xy 133.273546 -412.951676) (xy 133.246289 -412.95128) (xy 133.192328 -412.943528) (xy 133.14002 -412.928175)
			(xy 133.09043 -412.905533) (xy 133.044567 -412.876063) (xy 133.003366 -412.840367) (xy 132.967664 -412.799169)
			(xy 132.938189 -412.75331) (xy 132.915542 -412.703723) (xy 132.900182 -412.651417) (xy 132.892423 -412.597457)
			(xy 131.454889 -412.597457) (xy 131.447134 -412.651391) (xy 131.431781 -412.703681) (xy 131.409142 -412.753254)
			(xy 131.379679 -412.7991) (xy 131.343991 -412.840287) (xy 131.302805 -412.875975) (xy 131.256959 -412.905439)
			(xy 131.207387 -412.928079) (xy 131.155097 -412.943433) (xy 131.101155 -412.951189) (xy 131.073906 -412.951676)
			(xy 130.210306 -412.951676) (xy 130.183051 -412.951277) (xy 130.129094 -412.943521) (xy 130.076791 -412.928164)
			(xy 130.027206 -412.90552) (xy 129.981349 -412.876049) (xy 129.940152 -412.840353) (xy 129.904454 -412.799156)
			(xy 129.874983 -412.753299) (xy 129.852338 -412.703714) (xy 129.836981 -412.651411) (xy 129.829223 -412.597455)
			(xy 128.391713 -412.597455) (xy 128.383955 -412.651402) (xy 128.368599 -412.703698) (xy 128.345956 -412.753276)
			(xy 128.316487 -412.799127) (xy 128.280793 -412.840317) (xy 128.2396 -412.876008) (xy 128.193746 -412.905472)
			(xy 128.144166 -412.928111) (xy 128.091868 -412.943463) (xy 128.037918 -412.951215) (xy 128.010666 -412.951676)
			(xy 127.147066 -412.951676) (xy 127.119814 -412.951252) (xy 127.065865 -412.943491) (xy 127.01357 -412.928131)
			(xy 126.963993 -412.905486) (xy 126.918143 -412.876017) (xy 126.876954 -412.840322) (xy 126.841263 -412.799129)
			(xy 126.811797 -412.753277) (xy 126.789157 -412.703698) (xy 126.773802 -412.651401) (xy 126.766046 -412.597452)
			(xy 125.328389 -412.597452) (xy 125.320635 -412.651389) (xy 125.305282 -412.703677) (xy 125.282645 -412.753248)
			(xy 125.253184 -412.799093) (xy 125.217498 -412.840279) (xy 125.176314 -412.875968) (xy 125.130471 -412.905432)
			(xy 125.080901 -412.928073) (xy 125.028614 -412.943429) (xy 124.974674 -412.951188) (xy 124.947426 -412.951676)
			(xy 124.083826 -412.951676) (xy 124.05657 -412.951279) (xy 124.002611 -412.943524) (xy 123.950306 -412.928169)
			(xy 123.900718 -412.905526) (xy 123.854858 -412.876056) (xy 123.813659 -412.84036) (xy 123.777959 -412.799163)
			(xy 123.748486 -412.753305) (xy 123.72584 -412.703719) (xy 123.710481 -412.651414) (xy 123.702723 -412.597456)
			(xy 122.265212 -412.597456) (xy 122.257456 -412.651399) (xy 122.242101 -412.703693) (xy 122.219459 -412.75327)
			(xy 122.189992 -412.79912) (xy 122.1543 -412.84031) (xy 122.113109 -412.876001) (xy 122.067258 -412.905466)
			(xy 122.01768 -412.928105) (xy 121.965385 -412.943459) (xy 121.911437 -412.951214) (xy 121.884186 -412.951676)
			(xy 121.020586 -412.951676) (xy 120.993333 -412.951253) (xy 120.939382 -412.943494) (xy 120.887085 -412.928137)
			(xy 120.837505 -412.905493) (xy 120.791653 -412.876024) (xy 120.750461 -412.840329) (xy 120.714768 -412.799136)
			(xy 120.6853 -412.753282) (xy 120.662658 -412.703702) (xy 120.647303 -412.651404) (xy 120.639546 -412.597453)
			(xy 119.201889 -412.597453) (xy 119.194135 -412.651386) (xy 119.178784 -412.703673) (xy 119.156148 -412.753243)
			(xy 119.126688 -412.799087) (xy 119.091005 -412.840272) (xy 119.049824 -412.875961) (xy 119.003983 -412.905426)
			(xy 118.954416 -412.928068) (xy 118.902131 -412.943425) (xy 118.848193 -412.951187) (xy 118.820946 -412.951676)
			(xy 117.957346 -412.951676) (xy 117.930089 -412.95128) (xy 117.876128 -412.943528) (xy 117.82382 -412.928175)
			(xy 117.77423 -412.905533) (xy 117.728367 -412.876063) (xy 117.687166 -412.840367) (xy 117.651464 -412.799169)
			(xy 117.621989 -412.75331) (xy 117.599342 -412.703723) (xy 117.583982 -412.651417) (xy 117.576223 -412.597457)
			(xy 116.138689 -412.597457) (xy 116.130934 -412.651391) (xy 116.115581 -412.703681) (xy 116.092942 -412.753254)
			(xy 116.063479 -412.7991) (xy 116.027791 -412.840287) (xy 115.986605 -412.875975) (xy 115.940759 -412.905439)
			(xy 115.891187 -412.928079) (xy 115.838897 -412.943433) (xy 115.784955 -412.951189) (xy 115.757706 -412.951676)
			(xy 114.894106 -412.951676) (xy 114.866851 -412.951277) (xy 114.812894 -412.943521) (xy 114.760591 -412.928164)
			(xy 114.711006 -412.90552) (xy 114.665149 -412.876049) (xy 114.623952 -412.840353) (xy 114.588254 -412.799156)
			(xy 114.558783 -412.753299) (xy 114.536138 -412.703714) (xy 114.520781 -412.651411) (xy 114.513023 -412.597455)
			(xy 94.987413 -412.597455) (xy 94.979655 -412.651402) (xy 94.964299 -412.703698) (xy 94.941656 -412.753276)
			(xy 94.912187 -412.799127) (xy 94.876492 -412.840318) (xy 94.835299 -412.876008) (xy 94.789445 -412.905473)
			(xy 94.739864 -412.928111) (xy 94.687567 -412.943463) (xy 94.633616 -412.951215) (xy 94.606364 -412.951676)
			(xy 93.742764 -412.951676) (xy 93.715512 -412.951252) (xy 93.661564 -412.94349) (xy 93.609269 -412.928131)
			(xy 93.559692 -412.905486) (xy 93.513842 -412.876016) (xy 93.472653 -412.840321) (xy 93.436962 -412.799129)
			(xy 93.407497 -412.753276) (xy 93.384857 -412.703697) (xy 93.369502 -412.651401) (xy 93.361746 -412.597452)
			(xy 91.924089 -412.597452) (xy 91.916335 -412.651389) (xy 91.900982 -412.703677) (xy 91.878345 -412.753249)
			(xy 91.848883 -412.799094) (xy 91.813197 -412.84028) (xy 91.772013 -412.875969) (xy 91.72617 -412.905433)
			(xy 91.6766 -412.928074) (xy 91.624312 -412.94343) (xy 91.570372 -412.951188) (xy 91.543124 -412.951676)
			(xy 90.679524 -412.951676) (xy 90.652268 -412.951279) (xy 90.59831 -412.943524) (xy 90.546004 -412.928169)
			(xy 90.496417 -412.905526) (xy 90.450557 -412.876056) (xy 90.409358 -412.840359) (xy 90.373659 -412.799162)
			(xy 90.344186 -412.753304) (xy 90.32154 -412.703718) (xy 90.306181 -412.651414) (xy 90.298423 -412.597456)
			(xy 88.860912 -412.597456) (xy 88.853156 -412.651399) (xy 88.8378 -412.703694) (xy 88.815159 -412.753271)
			(xy 88.785692 -412.799121) (xy 88.749999 -412.840311) (xy 88.708808 -412.876001) (xy 88.662957 -412.905466)
			(xy 88.613379 -412.928106) (xy 88.561083 -412.943459) (xy 88.507135 -412.951214) (xy 88.479884 -412.951676)
			(xy 87.616284 -412.951676) (xy 87.589031 -412.951253) (xy 87.535081 -412.943494) (xy 87.482783 -412.928136)
			(xy 87.433204 -412.905492) (xy 87.387352 -412.876023) (xy 87.34616 -412.840329) (xy 87.310467 -412.799135)
			(xy 87.281 -412.753282) (xy 87.258358 -412.703702) (xy 87.243003 -412.651404) (xy 87.235246 -412.597453)
			(xy 85.797589 -412.597453) (xy 85.789835 -412.651386) (xy 85.774484 -412.703673) (xy 85.751848 -412.753243)
			(xy 85.722388 -412.799087) (xy 85.686704 -412.840273) (xy 85.645523 -412.875962) (xy 85.599682 -412.905427)
			(xy 85.550114 -412.928068) (xy 85.497829 -412.943426) (xy 85.443891 -412.951187) (xy 85.416644 -412.951676)
			(xy 84.553044 -412.951676) (xy 84.525787 -412.95128) (xy 84.471827 -412.943528) (xy 84.419519 -412.928174)
			(xy 84.369929 -412.905532) (xy 84.324067 -412.876063) (xy 84.282865 -412.840366) (xy 84.247164 -412.799169)
			(xy 84.217689 -412.75331) (xy 84.195041 -412.703722) (xy 84.179682 -412.651417) (xy 84.171923 -412.597457)
			(xy 82.734389 -412.597457) (xy 82.726634 -412.651392) (xy 82.71128 -412.703682) (xy 82.688642 -412.753254)
			(xy 82.659178 -412.799101) (xy 82.62349 -412.840287) (xy 82.582304 -412.875976) (xy 82.536458 -412.90544)
			(xy 82.486885 -412.928079) (xy 82.434595 -412.943433) (xy 82.380653 -412.95119) (xy 82.353404 -412.951676)
			(xy 81.489804 -412.951676) (xy 81.462549 -412.951277) (xy 81.408593 -412.94352) (xy 81.35629 -412.928163)
			(xy 81.306705 -412.905519) (xy 81.260848 -412.876049) (xy 81.219651 -412.840352) (xy 81.183954 -412.799156)
			(xy 81.154483 -412.753298) (xy 81.131838 -412.703714) (xy 81.116481 -412.651411) (xy 81.108723 -412.597455)
			(xy 79.671213 -412.597455) (xy 79.663455 -412.651402) (xy 79.648099 -412.703698) (xy 79.625456 -412.753276)
			(xy 79.595987 -412.799127) (xy 79.560292 -412.840318) (xy 79.519099 -412.876008) (xy 79.473245 -412.905473)
			(xy 79.423664 -412.928111) (xy 79.371367 -412.943463) (xy 79.317416 -412.951215) (xy 79.290164 -412.951676)
			(xy 78.426564 -412.951676) (xy 78.399312 -412.951252) (xy 78.345364 -412.94349) (xy 78.293069 -412.928131)
			(xy 78.243492 -412.905486) (xy 78.197642 -412.876016) (xy 78.156453 -412.840321) (xy 78.120762 -412.799129)
			(xy 78.091297 -412.753276) (xy 78.068657 -412.703697) (xy 78.053302 -412.651401) (xy 78.045546 -412.597452)
			(xy 76.607889 -412.597452) (xy 76.600135 -412.651389) (xy 76.584782 -412.703677) (xy 76.562145 -412.753249)
			(xy 76.532683 -412.799094) (xy 76.496997 -412.84028) (xy 76.455813 -412.875969) (xy 76.40997 -412.905433)
			(xy 76.3604 -412.928074) (xy 76.308112 -412.94343) (xy 76.254172 -412.951188) (xy 76.226924 -412.951676)
			(xy 75.363324 -412.951676) (xy 75.336068 -412.951279) (xy 75.28211 -412.943524) (xy 75.229804 -412.928169)
			(xy 75.180217 -412.905526) (xy 75.134357 -412.876056) (xy 75.093158 -412.840359) (xy 75.057459 -412.799162)
			(xy 75.027986 -412.753304) (xy 75.00534 -412.703718) (xy 74.989981 -412.651414) (xy 74.982223 -412.597456)
			(xy 73.544712 -412.597456) (xy 73.536956 -412.651399) (xy 73.5216 -412.703694) (xy 73.498959 -412.753271)
			(xy 73.469492 -412.799121) (xy 73.433799 -412.840311) (xy 73.392608 -412.876001) (xy 73.346757 -412.905466)
			(xy 73.297179 -412.928106) (xy 73.244883 -412.943459) (xy 73.190935 -412.951214) (xy 73.163684 -412.951676)
			(xy 72.300084 -412.951676) (xy 72.272831 -412.951253) (xy 72.218881 -412.943494) (xy 72.166583 -412.928136)
			(xy 72.117004 -412.905492) (xy 72.071152 -412.876023) (xy 72.02996 -412.840329) (xy 71.994267 -412.799135)
			(xy 71.9648 -412.753282) (xy 71.942158 -412.703702) (xy 71.926803 -412.651404) (xy 71.919046 -412.597453)
			(xy 70.481389 -412.597453) (xy 70.473635 -412.651386) (xy 70.458284 -412.703673) (xy 70.435648 -412.753243)
			(xy 70.406188 -412.799087) (xy 70.370504 -412.840273) (xy 70.329323 -412.875962) (xy 70.283482 -412.905427)
			(xy 70.233914 -412.928068) (xy 70.181629 -412.943426) (xy 70.127691 -412.951187) (xy 70.100444 -412.951676)
			(xy 69.236844 -412.951676) (xy 69.209587 -412.95128) (xy 69.155627 -412.943528) (xy 69.103319 -412.928174)
			(xy 69.053729 -412.905532) (xy 69.007867 -412.876063) (xy 68.966665 -412.840366) (xy 68.930964 -412.799169)
			(xy 68.901489 -412.75331) (xy 68.878841 -412.703722) (xy 68.863482 -412.651417) (xy 68.855723 -412.597457)
			(xy 67.418189 -412.597457) (xy 67.410434 -412.651392) (xy 67.39508 -412.703682) (xy 67.372442 -412.753254)
			(xy 67.342978 -412.799101) (xy 67.30729 -412.840287) (xy 67.266104 -412.875976) (xy 67.220258 -412.90544)
			(xy 67.170685 -412.928079) (xy 67.118395 -412.943433) (xy 67.064453 -412.95119) (xy 67.037204 -412.951676)
			(xy 66.173604 -412.951676) (xy 66.146349 -412.951277) (xy 66.092393 -412.94352) (xy 66.04009 -412.928163)
			(xy 65.990505 -412.905519) (xy 65.944648 -412.876049) (xy 65.903451 -412.840352) (xy 65.867754 -412.799156)
			(xy 65.838283 -412.753298) (xy 65.815638 -412.703714) (xy 65.800281 -412.651411) (xy 65.792523 -412.597455)
			(xy 64.355013 -412.597455) (xy 64.347255 -412.651402) (xy 64.331899 -412.703698) (xy 64.309256 -412.753276)
			(xy 64.279787 -412.799127) (xy 64.244092 -412.840318) (xy 64.202899 -412.876008) (xy 64.157045 -412.905473)
			(xy 64.107464 -412.928111) (xy 64.055167 -412.943463) (xy 64.001216 -412.951215) (xy 63.973964 -412.951676)
			(xy 63.110364 -412.951676) (xy 63.083112 -412.951252) (xy 63.029164 -412.94349) (xy 62.976869 -412.928131)
			(xy 62.927292 -412.905486) (xy 62.881442 -412.876016) (xy 62.840253 -412.840321) (xy 62.804562 -412.799129)
			(xy 62.775097 -412.753276) (xy 62.752457 -412.703697) (xy 62.737102 -412.651401) (xy 62.729346 -412.597452)
			(xy 61.291689 -412.597452) (xy 61.283935 -412.651389) (xy 61.268582 -412.703677) (xy 61.245945 -412.753249)
			(xy 61.216483 -412.799094) (xy 61.180797 -412.84028) (xy 61.139613 -412.875969) (xy 61.09377 -412.905433)
			(xy 61.0442 -412.928074) (xy 60.991912 -412.94343) (xy 60.937972 -412.951188) (xy 60.910724 -412.951676)
			(xy 60.047124 -412.951676) (xy 60.019868 -412.951279) (xy 59.96591 -412.943524) (xy 59.913604 -412.928169)
			(xy 59.864017 -412.905526) (xy 59.818157 -412.876056) (xy 59.776958 -412.840359) (xy 59.741259 -412.799162)
			(xy 59.711786 -412.753304) (xy 59.68914 -412.703718) (xy 59.673781 -412.651414) (xy 59.666023 -412.597456)
			(xy 58.228512 -412.597456) (xy 58.220756 -412.651399) (xy 58.2054 -412.703694) (xy 58.182759 -412.753271)
			(xy 58.153292 -412.799121) (xy 58.117599 -412.840311) (xy 58.076408 -412.876001) (xy 58.030557 -412.905466)
			(xy 57.980979 -412.928106) (xy 57.928683 -412.943459) (xy 57.874735 -412.951214) (xy 57.847484 -412.951676)
			(xy 56.983884 -412.951676) (xy 56.956631 -412.951253) (xy 56.902681 -412.943494) (xy 56.850383 -412.928136)
			(xy 56.800804 -412.905492) (xy 56.754952 -412.876023) (xy 56.71376 -412.840329) (xy 56.678067 -412.799135)
			(xy 56.6486 -412.753282) (xy 56.625958 -412.703702) (xy 56.610603 -412.651404) (xy 56.602846 -412.597453)
			(xy 55.165189 -412.597453) (xy 55.157435 -412.651386) (xy 55.142084 -412.703673) (xy 55.119448 -412.753243)
			(xy 55.089988 -412.799087) (xy 55.054304 -412.840273) (xy 55.013123 -412.875962) (xy 54.967282 -412.905427)
			(xy 54.917714 -412.928068) (xy 54.865429 -412.943426) (xy 54.811491 -412.951187) (xy 54.784244 -412.951676)
			(xy 53.920644 -412.951676) (xy 53.893387 -412.95128) (xy 53.839427 -412.943528) (xy 53.787119 -412.928174)
			(xy 53.737529 -412.905532) (xy 53.691667 -412.876063) (xy 53.650465 -412.840366) (xy 53.614764 -412.799169)
			(xy 53.585289 -412.75331) (xy 53.562641 -412.703722) (xy 53.547282 -412.651417) (xy 53.539523 -412.597457)
			(xy 52.101989 -412.597457) (xy 52.094234 -412.651392) (xy 52.07888 -412.703682) (xy 52.056242 -412.753254)
			(xy 52.026778 -412.799101) (xy 51.99109 -412.840287) (xy 51.949904 -412.875976) (xy 51.904058 -412.90544)
			(xy 51.854485 -412.928079) (xy 51.802195 -412.943433) (xy 51.748253 -412.95119) (xy 51.721004 -412.951676)
			(xy 50.857404 -412.951676) (xy 50.830149 -412.951277) (xy 50.776193 -412.94352) (xy 50.72389 -412.928163)
			(xy 50.674305 -412.905519) (xy 50.628448 -412.876049) (xy 50.587251 -412.840352) (xy 50.551554 -412.799156)
			(xy 50.522083 -412.753298) (xy 50.499438 -412.703714) (xy 50.484081 -412.651411) (xy 50.476323 -412.597455)
			(xy 49.038813 -412.597455) (xy 49.031055 -412.651402) (xy 49.015699 -412.703698) (xy 48.993056 -412.753276)
			(xy 48.963587 -412.799127) (xy 48.927892 -412.840318) (xy 48.886699 -412.876008) (xy 48.840845 -412.905473)
			(xy 48.791264 -412.928111) (xy 48.738967 -412.943463) (xy 48.685016 -412.951215) (xy 48.657764 -412.951676)
			(xy 47.794164 -412.951676) (xy 47.766912 -412.951252) (xy 47.712964 -412.94349) (xy 47.660669 -412.928131)
			(xy 47.611092 -412.905486) (xy 47.565242 -412.876016) (xy 47.524053 -412.840321) (xy 47.488362 -412.799129)
			(xy 47.458897 -412.753276) (xy 47.436257 -412.703697) (xy 47.420902 -412.651401) (xy 47.413146 -412.597452)
			(xy 39.737792 -412.597452) (xy 39.737792 -413.4485) (xy 39.737556 -413.461769) (xy 105.629431 -413.461769)
			(xy 105.629431 -413.407231) (xy 105.637193 -413.353247) (xy 105.652559 -413.300918) (xy 105.675215 -413.251308)
			(xy 105.704702 -413.205427) (xy 105.740417 -413.16421) (xy 105.781635 -413.128496) (xy 105.827517 -413.099011)
			(xy 105.877127 -413.076355) (xy 105.929457 -413.060991) (xy 105.983441 -413.053231) (xy 106.01071 -413.052768)
			(xy 106.87431 -413.052768) (xy 106.901581 -413.053195) (xy 106.955568 -413.060959) (xy 107.0079 -413.076326)
			(xy 107.057513 -413.098985) (xy 107.103396 -413.128473) (xy 107.144616 -413.164191) (xy 107.180333 -413.205412)
			(xy 107.20982 -413.251296) (xy 107.232477 -413.300909) (xy 107.247844 -413.353242) (xy 107.255606 -413.407229)
			(xy 107.255606 -413.461771) (xy 107.247844 -413.515758) (xy 107.232477 -413.568091) (xy 107.20982 -413.617704)
			(xy 107.180333 -413.663588) (xy 107.144616 -413.704809) (xy 107.103396 -413.740527) (xy 107.057513 -413.770015)
			(xy 107.0079 -413.792674) (xy 106.955568 -413.808041) (xy 106.901581 -413.815805) (xy 106.87431 -413.816292)
			(xy 106.01071 -413.816292) (xy 105.983441 -413.815769) (xy 105.929457 -413.808009) (xy 105.877127 -413.792645)
			(xy 105.827517 -413.769989) (xy 105.781635 -413.740504) (xy 105.740417 -413.70479) (xy 105.704702 -413.663573)
			(xy 105.675215 -413.617692) (xy 105.652559 -413.568082) (xy 105.637193 -413.515753) (xy 105.629431 -413.461769)
			(xy 39.737556 -413.461769) (xy 39.737306 -413.475769) (xy 39.729544 -413.529753) (xy 39.714179 -413.582083)
			(xy 39.691522 -413.631693) (xy 39.662036 -413.677574) (xy 39.626321 -413.718791) (xy 39.585104 -413.754506)
			(xy 39.539223 -413.783992) (xy 39.489613 -413.806649) (xy 39.437283 -413.822014) (xy 39.383299 -413.829776)
			(xy 39.328761 -413.829776) (xy 39.274777 -413.822014) (xy 39.222447 -413.806649) (xy 39.172837 -413.783992)
			(xy 39.126956 -413.754506) (xy 39.085739 -413.718791) (xy 39.050024 -413.677574) (xy 39.020538 -413.631693)
			(xy 38.997881 -413.582083) (xy 38.982516 -413.529753) (xy 38.974754 -413.475769) (xy 38.974268 -413.4485)
			(xy 7.00913 -413.4485) (xy 7.00913 -415.383726) (xy 41.206928 -415.383726) (xy 41.206928 -414.520126)
			(xy 41.207414 -414.492857) (xy 41.215176 -414.438873) (xy 41.230541 -414.386543) (xy 41.253198 -414.336933)
			(xy 41.282684 -414.291052) (xy 41.318399 -414.249835) (xy 41.359616 -414.21412) (xy 41.405497 -414.184634)
			(xy 41.455107 -414.161977) (xy 41.507437 -414.146612) (xy 41.561421 -414.13885) (xy 41.615959 -414.13885)
			(xy 41.669943 -414.146612) (xy 41.722273 -414.161977) (xy 41.771883 -414.184634) (xy 41.817764 -414.21412)
			(xy 41.858981 -414.249835) (xy 41.894696 -414.291052) (xy 41.924182 -414.336933) (xy 41.946839 -414.386543)
			(xy 41.962204 -414.438873) (xy 41.969966 -414.492857) (xy 41.970452 -414.520126) (xy 41.970452 -415.383726)
			(xy 41.969966 -415.410995) (xy 41.962204 -415.464979) (xy 41.946839 -415.517309) (xy 41.924182 -415.566919)
			(xy 41.894696 -415.6128) (xy 41.858981 -415.654017) (xy 41.817764 -415.689732) (xy 41.771883 -415.719218)
			(xy 41.722273 -415.741875) (xy 41.669943 -415.75724) (xy 41.615959 -415.765002) (xy 41.561421 -415.765002)
			(xy 41.507437 -415.75724) (xy 41.455107 -415.741875) (xy 41.405497 -415.719218) (xy 41.359616 -415.689732)
			(xy 41.318399 -415.654017) (xy 41.282684 -415.6128) (xy 41.253198 -415.566919) (xy 41.230541 -415.517309)
			(xy 41.215176 -415.464979) (xy 41.207414 -415.410995) (xy 41.206928 -415.383726) (xy 7.00913 -415.383726)
			(xy 7.00913 -417.465002) (xy 35.832796 -417.465002) (xy 35.832796 -416.601402) (xy 35.833282 -416.574151)
			(xy 35.841038 -416.520203) (xy 35.856393 -416.467908) (xy 35.879035 -416.418331) (xy 35.908501 -416.372481)
			(xy 35.944192 -416.33129) (xy 35.985383 -416.295599) (xy 36.031233 -416.266133) (xy 36.08081 -416.243491)
			(xy 36.133105 -416.228136) (xy 36.187053 -416.22038) (xy 36.241555 -416.22038) (xy 36.295503 -416.228136)
			(xy 36.347798 -416.243491) (xy 36.397375 -416.266133) (xy 36.443225 -416.295599) (xy 36.484416 -416.33129)
			(xy 36.520107 -416.372481) (xy 36.549573 -416.418331) (xy 36.572215 -416.467908) (xy 36.58757 -416.520203)
			(xy 36.595326 -416.574151) (xy 36.595812 -416.601402) (xy 36.595812 -417.436808) (xy 48.812704 -417.436808)
			(xy 48.812704 -416.573208) (xy 48.81319 -416.545939) (xy 48.820952 -416.491955) (xy 48.836317 -416.439625)
			(xy 48.858974 -416.390015) (xy 48.88846 -416.344134) (xy 48.924175 -416.302917) (xy 48.965392 -416.267202)
			(xy 49.011273 -416.237716) (xy 49.060883 -416.215059) (xy 49.113213 -416.199694) (xy 49.167197 -416.191932)
			(xy 49.221735 -416.191932) (xy 49.275719 -416.199694) (xy 49.328049 -416.215059) (xy 49.377659 -416.237716)
			(xy 49.42354 -416.267202) (xy 49.464757 -416.302917) (xy 49.500472 -416.344134) (xy 49.529958 -416.390015)
			(xy 49.552615 -416.439625) (xy 49.56798 -416.491955) (xy 49.575742 -416.545939) (xy 49.576228 -416.573208)
			(xy 49.576228 -417.436808) (xy 49.575742 -417.464077) (xy 49.56798 -417.518061) (xy 49.552615 -417.570391)
			(xy 49.529958 -417.620001) (xy 49.500472 -417.665882) (xy 49.464757 -417.707099) (xy 49.42354 -417.742814)
			(xy 49.377659 -417.7723) (xy 49.328049 -417.794957) (xy 49.275719 -417.810322) (xy 49.221735 -417.818084)
			(xy 49.167197 -417.818084) (xy 49.113213 -417.810322) (xy 49.060883 -417.794957) (xy 49.011273 -417.7723)
			(xy 48.965392 -417.742814) (xy 48.924175 -417.707099) (xy 48.88846 -417.665882) (xy 48.858974 -417.620001)
			(xy 48.836317 -417.570391) (xy 48.820952 -417.518061) (xy 48.81319 -417.464077) (xy 48.812704 -417.436808)
			(xy 36.595812 -417.436808) (xy 36.595812 -417.465002) (xy 36.595326 -417.492253) (xy 36.58757 -417.546201)
			(xy 36.572215 -417.598496) (xy 36.549573 -417.648073) (xy 36.520107 -417.693923) (xy 36.484416 -417.735114)
			(xy 36.443225 -417.770805) (xy 36.397375 -417.800271) (xy 36.347798 -417.822913) (xy 36.295503 -417.838268)
			(xy 36.241555 -417.846024) (xy 36.187053 -417.846024) (xy 36.133105 -417.838268) (xy 36.08081 -417.822913)
			(xy 36.031233 -417.800271) (xy 35.985383 -417.770805) (xy 35.944192 -417.735114) (xy 35.908501 -417.693923)
			(xy 35.879035 -417.648073) (xy 35.856393 -417.598496) (xy 35.841038 -417.546201) (xy 35.833282 -417.492253)
			(xy 35.832796 -417.465002) (xy 7.00913 -417.465002) (xy 7.00913 -419.64102) (xy 51.809904 -419.64102)
			(xy 51.809904 -418.77742) (xy 51.81039 -418.750151) (xy 51.818152 -418.696167) (xy 51.833517 -418.643837)
			(xy 51.856174 -418.594227) (xy 51.88566 -418.548346) (xy 51.921375 -418.507129) (xy 51.962592 -418.471414)
			(xy 52.008473 -418.441928) (xy 52.058083 -418.419271) (xy 52.110413 -418.403906) (xy 52.164397 -418.396144)
			(xy 52.218935 -418.396144) (xy 52.272919 -418.403906) (xy 52.325249 -418.419271) (xy 52.374859 -418.441928)
			(xy 52.42074 -418.471414) (xy 52.461957 -418.507129) (xy 52.497672 -418.548346) (xy 52.527158 -418.594227)
			(xy 52.549815 -418.643837) (xy 52.56518 -418.696167) (xy 52.572942 -418.750151) (xy 52.573428 -418.77742)
			(xy 52.573428 -419.64102) (xy 52.572942 -419.668289) (xy 52.56518 -419.722273) (xy 52.549815 -419.774603)
			(xy 52.527158 -419.824213) (xy 52.497672 -419.870094) (xy 52.461957 -419.911311) (xy 52.42074 -419.947026)
			(xy 52.374859 -419.976512) (xy 52.325249 -419.999169) (xy 52.272919 -420.014534) (xy 52.218935 -420.022296)
			(xy 52.164397 -420.022296) (xy 52.110413 -420.014534) (xy 52.058083 -419.999169) (xy 52.008473 -419.976512)
			(xy 51.962592 -419.947026) (xy 51.921375 -419.911311) (xy 51.88566 -419.870094) (xy 51.856174 -419.824213)
			(xy 51.833517 -419.774603) (xy 51.818152 -419.722273) (xy 51.81039 -419.668289) (xy 51.809904 -419.64102)
			(xy 7.00913 -419.64102) (xy 7.00913 -421.200326) (xy 10.01268 -421.200326) (xy 10.01268 -420.336726)
			(xy 10.013166 -420.309475) (xy 10.020922 -420.255527) (xy 10.036277 -420.203232) (xy 10.058919 -420.153655)
			(xy 10.088385 -420.107805) (xy 10.124076 -420.066614) (xy 10.165267 -420.030923) (xy 10.211117 -420.001457)
			(xy 10.260694 -419.978815) (xy 10.312989 -419.96346) (xy 10.366937 -419.955704) (xy 10.421439 -419.955704)
			(xy 10.475387 -419.96346) (xy 10.527682 -419.978815) (xy 10.577259 -420.001457) (xy 10.623109 -420.030923)
			(xy 10.6643 -420.066614) (xy 10.699991 -420.107805) (xy 10.729457 -420.153655) (xy 10.752099 -420.203232)
			(xy 10.767454 -420.255527) (xy 10.77521 -420.309475) (xy 10.775696 -420.336726) (xy 10.775696 -421.200326)
			(xy 10.77521 -421.227577) (xy 10.769122 -421.269922) (xy 21.420836 -421.269922) (xy 21.420836 -420.406322)
			(xy 21.421322 -420.379071) (xy 21.429078 -420.325123) (xy 21.444433 -420.272828) (xy 21.467075 -420.223251)
			(xy 21.496541 -420.177401) (xy 21.532232 -420.13621) (xy 21.573423 -420.100519) (xy 21.619273 -420.071053)
			(xy 21.66885 -420.048411) (xy 21.721145 -420.033056) (xy 21.775093 -420.0253) (xy 21.829595 -420.0253)
			(xy 21.883543 -420.033056) (xy 21.935838 -420.048411) (xy 21.985415 -420.071053) (xy 22.031265 -420.100519)
			(xy 22.072456 -420.13621) (xy 22.108147 -420.177401) (xy 22.137613 -420.223251) (xy 22.160255 -420.272828)
			(xy 22.17561 -420.325123) (xy 22.183366 -420.379071) (xy 22.183852 -420.406322) (xy 22.183852 -420.760398)
			(xy 58.141108 -420.760398) (xy 58.141108 -418.218874) (xy 58.141589 -418.206761) (xy 58.14908 -418.183722)
			(xy 58.16332 -418.164123) (xy 58.182918 -418.149882) (xy 58.205957 -418.14239) (xy 58.21807 -418.141912)
			(xy 59.15787 -418.141912) (xy 59.169989 -418.142385) (xy 59.193042 -418.149866) (xy 59.212655 -418.164105)
			(xy 59.226908 -418.183708) (xy 59.234406 -418.206756) (xy 59.234832 -418.218874) (xy 59.234832 -420.760398)
			(xy 59.234438 -420.772524) (xy 59.226942 -420.795587) (xy 59.212685 -420.815205) (xy 59.193062 -420.829455)
			(xy 59.169996 -420.836942) (xy 59.15787 -420.83736) (xy 58.21807 -420.83736) (xy 58.205954 -420.836914)
			(xy 58.182909 -420.829418) (xy 58.163308 -420.81517) (xy 58.149067 -420.795562) (xy 58.141581 -420.772515)
			(xy 58.141108 -420.760398) (xy 22.183852 -420.760398) (xy 22.183852 -421.269922) (xy 22.183366 -421.297173)
			(xy 22.17561 -421.351121) (xy 22.160255 -421.403416) (xy 22.137613 -421.452993) (xy 22.108147 -421.498843)
			(xy 22.072456 -421.540034) (xy 22.031265 -421.575725) (xy 21.985415 -421.605191) (xy 21.935838 -421.627833)
			(xy 21.883543 -421.643188) (xy 21.829595 -421.650944) (xy 21.775093 -421.650944) (xy 21.721145 -421.643188)
			(xy 21.66885 -421.627833) (xy 21.619273 -421.605191) (xy 21.573423 -421.575725) (xy 21.532232 -421.540034)
			(xy 21.496541 -421.498843) (xy 21.467075 -421.452993) (xy 21.444433 -421.403416) (xy 21.429078 -421.351121)
			(xy 21.421322 -421.297173) (xy 21.420836 -421.269922) (xy 10.769122 -421.269922) (xy 10.767454 -421.281525)
			(xy 10.752099 -421.33382) (xy 10.729457 -421.383397) (xy 10.699991 -421.429247) (xy 10.6643 -421.470438)
			(xy 10.623109 -421.506129) (xy 10.577259 -421.535595) (xy 10.527682 -421.558237) (xy 10.475387 -421.573592)
			(xy 10.421439 -421.581348) (xy 10.366937 -421.581348) (xy 10.312989 -421.573592) (xy 10.260694 -421.558237)
			(xy 10.211117 -421.535595) (xy 10.165267 -421.506129) (xy 10.124076 -421.470438) (xy 10.088385 -421.429247)
			(xy 10.058919 -421.383397) (xy 10.036277 -421.33382) (xy 10.020922 -421.281525) (xy 10.013166 -421.227577)
			(xy 10.01268 -421.200326) (xy 7.00913 -421.200326) (xy 7.00913 -422.130474) (xy 24.87676 -422.130474)
			(xy 24.87676 -421.266874) (xy 24.877246 -421.239605) (xy 24.885008 -421.185621) (xy 24.900373 -421.133291)
			(xy 24.92303 -421.083681) (xy 24.952516 -421.0378) (xy 24.988231 -420.996583) (xy 25.029448 -420.960868)
			(xy 25.075329 -420.931382) (xy 25.124939 -420.908725) (xy 25.177269 -420.89336) (xy 25.231253 -420.885598)
			(xy 25.285791 -420.885598) (xy 25.339775 -420.89336) (xy 25.392105 -420.908725) (xy 25.441715 -420.931382)
			(xy 25.487596 -420.960868) (xy 25.528813 -420.996583) (xy 25.564528 -421.0378) (xy 25.594014 -421.083681)
			(xy 25.616671 -421.133291) (xy 25.632036 -421.185621) (xy 25.639798 -421.239605) (xy 25.640284 -421.266874)
			(xy 25.640284 -421.726974) (xy 27.323192 -421.726974) (xy 27.323192 -421.672426) (xy 27.330955 -421.618434)
			(xy 27.346324 -421.566097) (xy 27.368985 -421.51648) (xy 27.398477 -421.470593) (xy 27.4342 -421.429371)
			(xy 27.475427 -421.393652) (xy 27.521317 -421.364165) (xy 27.570936 -421.341509) (xy 27.623276 -421.326146)
			(xy 27.677268 -421.318389) (xy 27.704542 -421.317928) (xy 28.568142 -421.317928) (xy 28.595409 -421.318437)
			(xy 28.649386 -421.326204) (xy 28.701709 -421.341572) (xy 28.751313 -421.36423) (xy 28.797187 -421.393716)
			(xy 28.838399 -421.429431) (xy 28.874109 -421.470646) (xy 28.90359 -421.516524) (xy 28.926243 -421.56613)
			(xy 28.941605 -421.618455) (xy 28.949366 -421.672433) (xy 28.949366 -421.726967) (xy 28.941605 -421.780945)
			(xy 28.926243 -421.83327) (xy 28.90359 -421.882876) (xy 28.874109 -421.928754) (xy 28.838399 -421.969969)
			(xy 28.797187 -422.005684) (xy 28.751313 -422.03517) (xy 28.701709 -422.057828) (xy 28.649386 -422.073196)
			(xy 28.595409 -422.080963) (xy 28.568142 -422.081452) (xy 27.704542 -422.081452) (xy 27.677268 -422.081011)
			(xy 27.623276 -422.073254) (xy 27.570936 -422.057891) (xy 27.521317 -422.035235) (xy 27.475427 -422.005748)
			(xy 27.4342 -421.970029) (xy 27.398477 -421.928807) (xy 27.368985 -421.88292) (xy 27.346324 -421.833303)
			(xy 27.330955 -421.780966) (xy 27.323192 -421.726974) (xy 25.640284 -421.726974) (xy 25.640284 -422.130474)
			(xy 25.639798 -422.157743) (xy 25.632036 -422.211727) (xy 25.616671 -422.264057) (xy 25.594014 -422.313667)
			(xy 25.564528 -422.359548) (xy 25.528813 -422.400765) (xy 25.487596 -422.43648) (xy 25.441715 -422.465966)
			(xy 25.392105 -422.488623) (xy 25.339775 -422.503988) (xy 25.285791 -422.51175) (xy 25.231253 -422.51175)
			(xy 25.177269 -422.503988) (xy 25.124939 -422.488623) (xy 25.075329 -422.465966) (xy 25.029448 -422.43648)
			(xy 24.988231 -422.400765) (xy 24.952516 -422.359548) (xy 24.92303 -422.313667) (xy 24.900373 -422.264057)
			(xy 24.885008 -422.211727) (xy 24.877246 -422.157743) (xy 24.87676 -422.130474) (xy 7.00913 -422.130474)
			(xy 7.00913 -422.66627) (xy 38.762906 -422.66627) (xy 38.762906 -422.61173) (xy 38.770668 -422.557744)
			(xy 38.786034 -422.505412) (xy 38.808691 -422.4558) (xy 38.838178 -422.409918) (xy 38.873894 -422.368698)
			(xy 38.915113 -422.332981) (xy 38.960995 -422.303494) (xy 39.010607 -422.280836) (xy 39.062938 -422.26547)
			(xy 39.116924 -422.257707) (xy 39.144194 -422.25722) (xy 40.007794 -422.25722) (xy 40.035064 -422.257719)
			(xy 40.089049 -422.26548) (xy 40.14138 -422.280845) (xy 40.190991 -422.303501) (xy 40.236874 -422.332987)
			(xy 40.278093 -422.368703) (xy 40.313809 -422.409921) (xy 40.343296 -422.455803) (xy 40.365953 -422.505414)
			(xy 40.381319 -422.557745) (xy 40.389081 -422.61173) (xy 40.389081 -422.66627) (xy 40.381319 -422.720255)
			(xy 40.365953 -422.772586) (xy 40.343296 -422.822197) (xy 40.313809 -422.868079) (xy 40.278093 -422.909297)
			(xy 40.236874 -422.945013) (xy 40.190991 -422.974499) (xy 40.14138 -422.997155) (xy 40.089049 -423.01252)
			(xy 40.035064 -423.020281) (xy 40.007794 -423.020744) (xy 39.144194 -423.020744) (xy 39.116924 -423.020293)
			(xy 39.062938 -423.01253) (xy 39.010607 -422.997164) (xy 38.960995 -422.974506) (xy 38.915113 -422.945019)
			(xy 38.873894 -422.909302) (xy 38.838178 -422.868082) (xy 38.808691 -422.8222) (xy 38.786034 -422.772588)
			(xy 38.770668 -422.720256) (xy 38.762906 -422.66627) (xy 7.00913 -422.66627) (xy 7.00913 -423.057828)
			(xy 41.652952 -423.057828) (xy 41.652952 -422.194228) (xy 41.653438 -422.166959) (xy 41.6612 -422.112975)
			(xy 41.676565 -422.060645) (xy 41.699222 -422.011035) (xy 41.728708 -421.965154) (xy 41.764423 -421.923937)
			(xy 41.80564 -421.888222) (xy 41.851521 -421.858736) (xy 41.901131 -421.836079) (xy 41.953461 -421.820714)
			(xy 42.007445 -421.812952) (xy 42.061983 -421.812952) (xy 42.115967 -421.820714) (xy 42.168297 -421.836079)
			(xy 42.217907 -421.858736) (xy 42.263788 -421.888222) (xy 42.305005 -421.923937) (xy 42.34072 -421.965154)
			(xy 42.370206 -422.011035) (xy 42.392863 -422.060645) (xy 42.408228 -422.112975) (xy 42.41599 -422.166959)
			(xy 42.416476 -422.194228) (xy 42.416476 -423.057828) (xy 42.41599 -423.085097) (xy 42.408228 -423.139081)
			(xy 42.392863 -423.191411) (xy 42.370206 -423.241021) (xy 42.34072 -423.286902) (xy 42.305005 -423.328119)
			(xy 42.263788 -423.363834) (xy 42.217907 -423.39332) (xy 42.168297 -423.415977) (xy 42.115967 -423.431342)
			(xy 42.061983 -423.439104) (xy 42.007445 -423.439104) (xy 41.953461 -423.431342) (xy 41.901131 -423.415977)
			(xy 41.851521 -423.39332) (xy 41.80564 -423.363834) (xy 41.764423 -423.328119) (xy 41.728708 -423.286902)
			(xy 41.699222 -423.241021) (xy 41.676565 -423.191411) (xy 41.6612 -423.139081) (xy 41.653438 -423.085097)
			(xy 41.652952 -423.057828) (xy 7.00913 -423.057828) (xy 7.00913 -425.887642) (xy 10.204704 -425.887642)
			(xy 10.204704 -425.024042) (xy 10.20519 -424.996773) (xy 10.212952 -424.942789) (xy 10.228317 -424.890459)
			(xy 10.250974 -424.840849) (xy 10.28046 -424.794968) (xy 10.316175 -424.753751) (xy 10.357392 -424.718036)
			(xy 10.403273 -424.68855) (xy 10.452883 -424.665893) (xy 10.505213 -424.650528) (xy 10.559197 -424.642766)
			(xy 10.613735 -424.642766) (xy 10.667719 -424.650528) (xy 10.720049 -424.665893) (xy 10.769659 -424.68855)
			(xy 10.81554 -424.718036) (xy 10.856757 -424.753751) (xy 10.892472 -424.794968) (xy 10.921958 -424.840849)
			(xy 10.944615 -424.890459) (xy 10.95998 -424.942789) (xy 10.967742 -424.996773) (xy 10.968228 -425.024042)
			(xy 10.968228 -425.328334) (xy 21.942552 -425.328334) (xy 21.942552 -424.464734) (xy 21.943038 -424.437465)
			(xy 21.9508 -424.383481) (xy 21.966165 -424.331151) (xy 21.988822 -424.281541) (xy 22.018308 -424.23566)
			(xy 22.054023 -424.194443) (xy 22.09524 -424.158728) (xy 22.141121 -424.129242) (xy 22.190731 -424.106585)
			(xy 22.243061 -424.09122) (xy 22.297045 -424.083458) (xy 22.351583 -424.083458) (xy 22.405567 -424.09122)
			(xy 22.457897 -424.106585) (xy 22.507507 -424.129242) (xy 22.553388 -424.158728) (xy 22.594605 -424.194443)
			(xy 22.63032 -424.23566) (xy 22.659806 -424.281541) (xy 22.682463 -424.331151) (xy 22.691108 -424.360594)
			(xy 58.141108 -424.360594) (xy 58.141108 -421.81907) (xy 58.141586 -421.806957) (xy 58.149077 -421.783918)
			(xy 58.163319 -421.764319) (xy 58.182918 -421.750077) (xy 58.205957 -421.742586) (xy 58.21807 -421.742108)
			(xy 59.15787 -421.742108) (xy 59.16998 -421.742637) (xy 59.193017 -421.750112) (xy 59.207184 -421.760396)
			(xy 60.141104 -421.760396) (xy 60.141104 -419.218872) (xy 60.141493 -419.206761) (xy 60.149 -419.183732)
			(xy 60.163269 -419.164159) (xy 60.182896 -419.149966) (xy 60.205954 -419.142547) (xy 60.218066 -419.142164)
			(xy 61.157866 -419.142164) (xy 61.169956 -419.142637) (xy 61.19296 -419.150087) (xy 61.212542 -419.164271)
			(xy 61.226793 -419.183805) (xy 61.234322 -419.206783) (xy 61.234828 -419.218872) (xy 61.234828 -421.760396)
			(xy 61.234381 -421.772502) (xy 61.226886 -421.795524) (xy 61.212631 -421.815095) (xy 61.193018 -421.829291)
			(xy 61.169973 -421.836717) (xy 61.157866 -421.837104) (xy 60.218066 -421.837104) (xy 60.205979 -421.836623)
			(xy 60.182985 -421.829162) (xy 60.163409 -421.814977) (xy 60.149158 -421.79545) (xy 60.141619 -421.772481)
			(xy 60.141104 -421.760396) (xy 59.207184 -421.760396) (xy 59.212617 -421.76434) (xy 59.22686 -421.783929)
			(xy 59.234354 -421.80696) (xy 59.234832 -421.81907) (xy 59.234832 -424.360594) (xy 62.1411 -424.360594)
			(xy 62.1411 -421.81907) (xy 62.141585 -421.806958) (xy 62.149076 -421.78392) (xy 62.163316 -421.764322)
			(xy 62.182913 -421.75008) (xy 62.20595 -421.742587) (xy 62.218062 -421.742108) (xy 63.157862 -421.742108)
			(xy 63.16998 -421.742592) (xy 63.193032 -421.75007) (xy 63.207258 -421.760396) (xy 68.141088 -421.760396)
			(xy 68.141088 -419.218872) (xy 68.141492 -419.206763) (xy 68.148998 -419.183737) (xy 68.163263 -419.164165)
			(xy 68.182886 -419.149971) (xy 68.205939 -419.142549) (xy 68.21805 -419.142164) (xy 69.15785 -419.142164)
			(xy 69.169939 -419.14265) (xy 69.192942 -419.150096) (xy 69.212525 -419.164277) (xy 69.226777 -419.183808)
			(xy 69.234306 -419.206784) (xy 69.234812 -419.218872) (xy 69.234812 -420.760398) (xy 70.141084 -420.760398)
			(xy 70.141084 -418.218874) (xy 70.141438 -418.206745) (xy 70.148943 -418.183678) (xy 70.16321 -418.164059)
			(xy 70.182842 -418.14981) (xy 70.205917 -418.142327) (xy 70.218046 -418.141912) (xy 71.157846 -418.141912)
			(xy 71.16996 -418.142372) (xy 71.193001 -418.149869) (xy 71.212599 -418.164115) (xy 71.22684 -418.183717)
			(xy 71.234331 -418.20676) (xy 71.234808 -418.218874) (xy 71.234808 -418.3761) (xy 77.661008 -418.3761)
			(xy 77.661008 -417.5125) (xy 77.661494 -417.485231) (xy 77.669256 -417.431247) (xy 77.684621 -417.378917)
			(xy 77.707278 -417.329307) (xy 77.736764 -417.283426) (xy 77.772479 -417.242209) (xy 77.813696 -417.206494)
			(xy 77.859577 -417.177008) (xy 77.909187 -417.154351) (xy 77.961517 -417.138986) (xy 78.015501 -417.131224)
			(xy 78.070039 -417.131224) (xy 78.124023 -417.138986) (xy 78.176353 -417.154351) (xy 78.225963 -417.177008)
			(xy 78.271844 -417.206494) (xy 78.313061 -417.242209) (xy 78.348776 -417.283426) (xy 78.378262 -417.329307)
			(xy 78.400919 -417.378917) (xy 78.416284 -417.431247) (xy 78.424046 -417.485231) (xy 78.424532 -417.5125)
			(xy 78.424532 -418.3761) (xy 78.424046 -418.403369) (xy 78.416284 -418.457353) (xy 78.400919 -418.509683)
			(xy 78.378262 -418.559293) (xy 78.348776 -418.605174) (xy 78.313061 -418.646391) (xy 78.271844 -418.682106)
			(xy 78.225963 -418.711592) (xy 78.176353 -418.734249) (xy 78.124023 -418.749614) (xy 78.070039 -418.757376)
			(xy 78.015501 -418.757376) (xy 77.961517 -418.749614) (xy 77.909187 -418.734249) (xy 77.859577 -418.711592)
			(xy 77.813696 -418.682106) (xy 77.772479 -418.646391) (xy 77.736764 -418.605174) (xy 77.707278 -418.559293)
			(xy 77.684621 -418.509683) (xy 77.669256 -418.457353) (xy 77.661494 -418.403369) (xy 77.661008 -418.3761)
			(xy 71.234808 -418.3761) (xy 71.234808 -420.760398) (xy 71.234287 -420.772508) (xy 71.226806 -420.795543)
			(xy 71.212575 -420.815141) (xy 71.192986 -420.829384) (xy 71.169956 -420.83688) (xy 71.157846 -420.83736)
			(xy 70.218046 -420.83736) (xy 70.205925 -420.836901) (xy 70.182868 -420.829421) (xy 70.163252 -420.81518)
			(xy 70.148999 -420.795572) (xy 70.141506 -420.772518) (xy 70.141084 -420.760398) (xy 69.234812 -420.760398)
			(xy 69.234812 -421.760396) (xy 69.234381 -421.772503) (xy 69.226884 -421.795529) (xy 69.212626 -421.815101)
			(xy 69.193008 -421.829296) (xy 69.169959 -421.836719) (xy 69.15785 -421.837104) (xy 68.21805 -421.837104)
			(xy 68.205967 -421.836551) (xy 68.182976 -421.829113) (xy 68.163399 -421.814947) (xy 68.149145 -421.795434)
			(xy 68.141604 -421.772476) (xy 68.141088 -421.760396) (xy 63.207258 -421.760396) (xy 63.212645 -421.764306)
			(xy 63.226899 -421.783907) (xy 63.234398 -421.806953) (xy 63.234824 -421.81907) (xy 63.234824 -424.360594)
			(xy 63.234434 -424.37272) (xy 63.226939 -424.395785) (xy 63.212681 -424.415404) (xy 63.193057 -424.429654)
			(xy 63.169988 -424.437139) (xy 63.157862 -424.437556) (xy 62.218062 -424.437556) (xy 62.205945 -424.437121)
			(xy 62.182899 -424.429622) (xy 62.163298 -424.415371) (xy 62.149058 -424.395761) (xy 62.141572 -424.372711)
			(xy 62.1411 -424.360594) (xy 59.234832 -424.360594) (xy 59.234434 -424.372719) (xy 59.22694 -424.395783)
			(xy 59.212684 -424.415401) (xy 59.193062 -424.429651) (xy 59.169996 -424.437138) (xy 59.15787 -424.437556)
			(xy 58.21807 -424.437556) (xy 58.205953 -424.437114) (xy 58.182908 -424.429618) (xy 58.163306 -424.415368)
			(xy 58.149066 -424.39576) (xy 58.14158 -424.372711) (xy 58.141108 -424.360594) (xy 22.691108 -424.360594)
			(xy 22.697828 -424.383481) (xy 22.70559 -424.437465) (xy 22.706076 -424.464734) (xy 22.706076 -425.328334)
			(xy 22.70559 -425.355603) (xy 22.697828 -425.409587) (xy 22.682463 -425.461917) (xy 22.659806 -425.511527)
			(xy 22.63032 -425.557408) (xy 22.594605 -425.598625) (xy 22.553388 -425.63434) (xy 22.507507 -425.663826)
			(xy 22.457897 -425.686483) (xy 22.405567 -425.701848) (xy 22.351583 -425.70961) (xy 22.297045 -425.70961)
			(xy 22.243061 -425.701848) (xy 22.190731 -425.686483) (xy 22.141121 -425.663826) (xy 22.09524 -425.63434)
			(xy 22.054023 -425.598625) (xy 22.018308 -425.557408) (xy 21.988822 -425.511527) (xy 21.966165 -425.461917)
			(xy 21.9508 -425.409587) (xy 21.943038 -425.355603) (xy 21.942552 -425.328334) (xy 10.968228 -425.328334)
			(xy 10.968228 -425.887642) (xy 10.967742 -425.914911) (xy 10.964527 -425.937273) (xy 38.737196 -425.937273)
			(xy 38.737196 -425.882727) (xy 38.744959 -425.828736) (xy 38.760327 -425.776399) (xy 38.782988 -425.726782)
			(xy 38.81248 -425.680896) (xy 38.848202 -425.639674) (xy 38.889428 -425.603956) (xy 38.935317 -425.574469)
			(xy 38.984936 -425.551813) (xy 39.037275 -425.53645) (xy 39.091267 -425.528693) (xy 39.11854 -425.528232)
			(xy 39.98214 -425.528232) (xy 40.009407 -425.528733) (xy 40.063385 -425.536499) (xy 40.115709 -425.551868)
			(xy 40.165314 -425.574526) (xy 40.211189 -425.604012) (xy 40.252401 -425.639727) (xy 40.288112 -425.680943)
			(xy 40.317593 -425.726821) (xy 40.340246 -425.776428) (xy 40.355609 -425.828754) (xy 40.36337 -425.882733)
			(xy 40.36337 -425.937267) (xy 40.355609 -425.991246) (xy 40.340246 -426.043572) (xy 40.317593 -426.093179)
			(xy 40.288112 -426.139057) (xy 40.252401 -426.180273) (xy 40.211189 -426.215988) (xy 40.165314 -426.245474)
			(xy 40.115709 -426.268132) (xy 40.063385 -426.283501) (xy 40.009407 -426.291267) (xy 39.98214 -426.291756)
			(xy 39.11854 -426.291756) (xy 39.091267 -426.291307) (xy 39.037275 -426.28355) (xy 38.984936 -426.268187)
			(xy 38.935317 -426.245531) (xy 38.889428 -426.216044) (xy 38.848202 -426.180326) (xy 38.81248 -426.139104)
			(xy 38.782988 -426.093218) (xy 38.760327 -426.043601) (xy 38.744959 -425.991264) (xy 38.737196 -425.937273)
			(xy 10.964527 -425.937273) (xy 10.95998 -425.968895) (xy 10.944615 -426.021225) (xy 10.921958 -426.070835)
			(xy 10.892472 -426.116716) (xy 10.856757 -426.157933) (xy 10.81554 -426.193648) (xy 10.769659 -426.223134)
			(xy 10.720049 -426.245791) (xy 10.667719 -426.261156) (xy 10.613735 -426.268918) (xy 10.559197 -426.268918)
			(xy 10.505213 -426.261156) (xy 10.452883 -426.245791) (xy 10.403273 -426.223134) (xy 10.357392 -426.193648)
			(xy 10.316175 -426.157933) (xy 10.28046 -426.116716) (xy 10.250974 -426.070835) (xy 10.228317 -426.021225)
			(xy 10.212952 -425.968895) (xy 10.20519 -425.914911) (xy 10.204704 -425.887642) (xy 7.00913 -425.887642)
			(xy 7.00913 -426.333158) (xy 41.613836 -426.333158) (xy 41.613836 -425.469558) (xy 41.614322 -425.442307)
			(xy 41.622078 -425.388359) (xy 41.637433 -425.336064) (xy 41.660075 -425.286487) (xy 41.689541 -425.240637)
			(xy 41.725232 -425.199446) (xy 41.766423 -425.163755) (xy 41.812273 -425.134289) (xy 41.86185 -425.111647)
			(xy 41.914145 -425.096292) (xy 41.968093 -425.088536) (xy 42.022595 -425.088536) (xy 42.076543 -425.096292)
			(xy 42.128838 -425.111647) (xy 42.178415 -425.134289) (xy 42.224265 -425.163755) (xy 42.265456 -425.199446)
			(xy 42.301147 -425.240637) (xy 42.330613 -425.286487) (xy 42.353255 -425.336064) (xy 42.36861 -425.388359)
			(xy 42.376366 -425.442307) (xy 42.376852 -425.469558) (xy 42.376852 -426.333158) (xy 42.376366 -426.360409)
			(xy 42.36861 -426.414357) (xy 42.353255 -426.466652) (xy 42.330613 -426.516229) (xy 42.301147 -426.562079)
			(xy 42.265456 -426.60327) (xy 42.224265 -426.638961) (xy 42.178415 -426.668427) (xy 42.128838 -426.691069)
			(xy 42.076543 -426.706424) (xy 42.022595 -426.71418) (xy 41.968093 -426.71418) (xy 41.914145 -426.706424)
			(xy 41.86185 -426.691069) (xy 41.812273 -426.668427) (xy 41.766423 -426.638961) (xy 41.725232 -426.60327)
			(xy 41.689541 -426.562079) (xy 41.660075 -426.516229) (xy 41.637433 -426.466652) (xy 41.622078 -426.414357)
			(xy 41.614322 -426.360409) (xy 41.613836 -426.333158) (xy 7.00913 -426.333158) (xy 7.00913 -428.615602)
			(xy 25.13076 -428.615602) (xy 25.13076 -427.752002) (xy 25.131246 -427.724733) (xy 25.139008 -427.670749)
			(xy 25.154373 -427.618419) (xy 25.17703 -427.568809) (xy 25.206516 -427.522928) (xy 25.242231 -427.481711)
			(xy 25.283448 -427.445996) (xy 25.329329 -427.41651) (xy 25.378939 -427.393853) (xy 25.431269 -427.378488)
			(xy 25.485253 -427.370726) (xy 25.539791 -427.370726) (xy 25.593775 -427.378488) (xy 25.646105 -427.393853)
			(xy 25.695715 -427.41651) (xy 25.741596 -427.445996) (xy 25.782813 -427.481711) (xy 25.818528 -427.522928)
			(xy 25.848014 -427.568809) (xy 25.870671 -427.618419) (xy 25.886036 -427.670749) (xy 25.893798 -427.724733)
			(xy 25.894284 -427.752002) (xy 25.894284 -428.211072) (xy 26.941204 -428.211072) (xy 26.941204 -428.156528)
			(xy 26.948966 -428.102539) (xy 26.964334 -428.050205) (xy 26.986993 -428.00059) (xy 27.016483 -427.954705)
			(xy 27.052203 -427.913485) (xy 27.093426 -427.877767) (xy 27.139313 -427.848281) (xy 27.188929 -427.825625)
			(xy 27.241265 -427.810261) (xy 27.295254 -427.802502) (xy 27.322526 -427.80204) (xy 28.186126 -427.80204)
			(xy 28.213394 -427.802524) (xy 28.267375 -427.810289) (xy 28.319702 -427.825657) (xy 28.369309 -427.848314)
			(xy 28.415187 -427.877801) (xy 28.456402 -427.913517) (xy 28.492114 -427.954734) (xy 28.495843 -427.960536)
			(xy 58.141108 -427.960536) (xy 58.141108 -425.419012) (xy 58.141527 -425.406903) (xy 58.149024 -425.383875)
			(xy 58.163285 -425.364301) (xy 58.182906 -425.350106) (xy 58.20596 -425.342687) (xy 58.21807 -425.342304)
			(xy 59.15787 -425.342304) (xy 59.169954 -425.342832) (xy 59.192948 -425.350276) (xy 59.212525 -425.364448)
			(xy 59.226778 -425.383967) (xy 59.234317 -425.40693) (xy 59.234832 -425.419012) (xy 59.234832 -427.960536)
			(xy 59.234415 -427.972644) (xy 59.226909 -427.995667) (xy 59.212647 -428.015236) (xy 59.193028 -428.029431)
			(xy 59.169979 -428.036856) (xy 59.15787 -428.037244) (xy 58.21807 -428.037244) (xy 58.205977 -428.036818)
			(xy 58.182973 -428.029351) (xy 58.163392 -428.015154) (xy 58.149143 -427.995612) (xy 58.141615 -427.972627)
			(xy 58.141108 -427.960536) (xy 28.495843 -427.960536) (xy 28.521598 -428.000614) (xy 28.544253 -428.050222)
			(xy 28.559617 -428.10255) (xy 28.567378 -428.156532) (xy 28.567378 -428.211068) (xy 28.559617 -428.26505)
			(xy 28.544253 -428.317378) (xy 28.521598 -428.366986) (xy 28.492114 -428.412866) (xy 28.456402 -428.454083)
			(xy 28.415187 -428.489799) (xy 28.369309 -428.519286) (xy 28.319702 -428.541943) (xy 28.267375 -428.557311)
			(xy 28.213394 -428.565076) (xy 28.186126 -428.565564) (xy 27.322526 -428.565564) (xy 27.295254 -428.565098)
			(xy 27.241265 -428.557339) (xy 27.188929 -428.541975) (xy 27.139313 -428.519319) (xy 27.093426 -428.489833)
			(xy 27.052203 -428.454115) (xy 27.016483 -428.412895) (xy 26.986993 -428.36701) (xy 26.964334 -428.317395)
			(xy 26.948966 -428.265061) (xy 26.941204 -428.211072) (xy 25.894284 -428.211072) (xy 25.894284 -428.615602)
			(xy 25.893798 -428.642871) (xy 25.886036 -428.696855) (xy 25.870671 -428.749185) (xy 25.848014 -428.798795)
			(xy 25.818528 -428.844676) (xy 25.782813 -428.885893) (xy 25.741596 -428.921608) (xy 25.695715 -428.951094)
			(xy 25.646105 -428.973751) (xy 25.593775 -428.989116) (xy 25.539791 -428.996878) (xy 25.485253 -428.996878)
			(xy 25.431269 -428.989116) (xy 25.378939 -428.973751) (xy 25.329329 -428.951094) (xy 25.283448 -428.921608)
			(xy 25.242231 -428.885893) (xy 25.206516 -428.844676) (xy 25.17703 -428.798795) (xy 25.154373 -428.749185)
			(xy 25.139008 -428.696855) (xy 25.131246 -428.642871) (xy 25.13076 -428.615602) (xy 7.00913 -428.615602)
			(xy 7.00913 -431.560478) (xy 58.141108 -431.560478) (xy 58.141108 -429.018954) (xy 58.141572 -429.00684)
			(xy 58.149068 -428.9838) (xy 58.163313 -428.964202) (xy 58.182915 -428.949961) (xy 58.205956 -428.94247)
			(xy 58.21807 -428.941992) (xy 59.15787 -428.941992) (xy 59.169978 -428.942537) (xy 59.193013 -428.95001)
			(xy 59.207512 -428.960534) (xy 60.141104 -428.960534) (xy 60.141104 -426.41901) (xy 60.14162 -426.406899)
			(xy 60.1491 -426.383862) (xy 60.163332 -426.364263) (xy 60.182923 -426.35002) (xy 60.205956 -426.342527)
			(xy 60.218066 -426.342048) (xy 61.157866 -426.342048) (xy 61.169988 -426.342489) (xy 61.193047 -426.349973)
			(xy 61.212664 -426.364219) (xy 61.226916 -426.383831) (xy 61.234407 -426.406888) (xy 61.234828 -426.41901)
			(xy 61.234828 -427.960536) (xy 62.1411 -427.960536) (xy 62.1411 -425.419012) (xy 62.141527 -425.406904)
			(xy 62.149023 -425.383877) (xy 62.163282 -425.364304) (xy 62.182901 -425.350109) (xy 62.205952 -425.342688)
			(xy 62.218062 -425.342304) (xy 63.157862 -425.342304) (xy 63.169946 -425.342839) (xy 63.192939 -425.350281)
			(xy 63.207185 -425.360592) (xy 64.141096 -425.360592) (xy 64.141096 -422.819068) (xy 64.141489 -422.806958)
			(xy 64.148997 -422.78393) (xy 64.163265 -422.764358) (xy 64.18289 -422.750164) (xy 64.205946 -422.742744)
			(xy 64.218058 -422.74236) (xy 65.157858 -422.74236) (xy 65.169947 -422.742843) (xy 65.19295 -422.750291)
			(xy 65.212532 -422.764473) (xy 65.226784 -422.784004) (xy 65.234313 -422.80698) (xy 65.23482 -422.819068)
			(xy 65.23482 -425.360592) (xy 65.234377 -425.372698) (xy 65.226883 -425.395722) (xy 65.212627 -425.415294)
			(xy 65.193012 -425.429489) (xy 65.169966 -425.436914) (xy 65.157858 -425.4373) (xy 64.218058 -425.4373)
			(xy 64.20597 -425.436829) (xy 64.182975 -425.429366) (xy 64.163399 -425.415179) (xy 64.149149 -425.395649)
			(xy 64.141611 -425.372678) (xy 64.141096 -425.360592) (xy 63.207185 -425.360592) (xy 63.212517 -425.364451)
			(xy 63.22677 -425.383968) (xy 63.234309 -425.40693) (xy 63.234824 -425.419012) (xy 63.234824 -427.960536)
			(xy 63.234415 -427.972644) (xy 63.226908 -427.995669) (xy 63.212644 -428.015239) (xy 63.193023 -428.029433)
			(xy 63.169972 -428.036857) (xy 63.157862 -428.037244) (xy 62.218062 -428.037244) (xy 62.205969 -428.036825)
			(xy 62.182964 -428.029356) (xy 62.163384 -428.015157) (xy 62.149135 -427.995613) (xy 62.141607 -427.972628)
			(xy 62.1411 -427.960536) (xy 61.234828 -427.960536) (xy 61.234828 -428.960534) (xy 61.234417 -428.972654)
			(xy 61.226916 -428.995704) (xy 61.21266 -429.015308) (xy 61.193043 -429.029547) (xy 61.169986 -429.037027)
			(xy 61.157866 -429.037496) (xy 60.218066 -429.037496) (xy 60.205953 -429.037018) (xy 60.182914 -429.029525)
			(xy 60.163316 -429.015284) (xy 60.149075 -428.995686) (xy 60.141582 -428.972647) (xy 60.141104 -428.960534)
			(xy 59.207512 -428.960534) (xy 59.212611 -428.964235) (xy 59.226855 -428.983819) (xy 59.234351 -429.006846)
			(xy 59.234832 -429.018954) (xy 59.234832 -431.560478) (xy 59.234421 -431.572603) (xy 59.226931 -431.595666)
			(xy 59.212678 -431.615284) (xy 59.193059 -431.629535) (xy 59.169995 -431.637022) (xy 59.15787 -431.63744)
			(xy 58.21807 -431.63744) (xy 58.205952 -431.637014) (xy 58.182904 -431.629515) (xy 58.163301 -431.615262)
			(xy 58.149061 -431.59565) (xy 58.141578 -431.572597) (xy 58.141108 -431.560478) (xy 7.00913 -431.560478)
			(xy 7.00913 -435.160674) (xy 58.141108 -435.160674) (xy 58.141108 -434.433726) (xy 58.141402 -434.424892)
			(xy 58.145508 -434.407704) (xy 58.149236 -434.39969) (xy 58.382662 -433.92344) (xy 58.38739 -433.912934)
			(xy 58.390866 -433.890169) (xy 58.387371 -433.867407) (xy 58.382662 -433.856892) (xy 58.149236 -433.380642)
			(xy 58.145463 -433.372644) (xy 58.141357 -433.355446) (xy 58.141108 -433.346606) (xy 58.141108 -432.61915)
			(xy 58.141569 -432.607036) (xy 58.149066 -432.583996) (xy 58.163312 -432.564398) (xy 58.182914 -432.550157)
			(xy 58.205956 -432.542666) (xy 58.21807 -432.542188) (xy 59.15787 -432.542188) (xy 59.169978 -432.542737)
			(xy 59.193012 -432.550209) (xy 59.207158 -432.560476) (xy 60.141104 -432.560476) (xy 60.141104 -430.018952)
			(xy 60.141476 -430.00684) (xy 60.148989 -429.983811) (xy 60.163262 -429.964238) (xy 60.182893 -429.950045)
			(xy 60.205953 -429.942626) (xy 60.218066 -429.942244) (xy 61.157866 -429.942244) (xy 61.169954 -429.942736)
			(xy 61.192954 -429.950184) (xy 61.212535 -429.964364) (xy 61.226787 -429.983893) (xy 61.234319 -430.006866)
			(xy 61.234828 -430.018952) (xy 61.234828 -431.560478) (xy 62.1411 -431.560478) (xy 62.1411 -429.018954)
			(xy 62.141572 -429.006841) (xy 62.149067 -428.983803) (xy 62.163311 -428.964205) (xy 62.18291 -428.949964)
			(xy 62.205949 -428.942471) (xy 62.218062 -428.941992) (xy 63.157862 -428.941992) (xy 63.16997 -428.942543)
			(xy 63.193004 -428.950015) (xy 63.207499 -428.960534) (xy 64.141096 -428.960534) (xy 64.141096 -426.41901)
			(xy 64.14162 -426.4069) (xy 64.149099 -426.383864) (xy 64.163329 -426.364266) (xy 64.182918 -426.350023)
			(xy 64.205948 -426.342528) (xy 64.218058 -426.342048) (xy 65.157858 -426.342048) (xy 65.16998 -426.342496)
			(xy 65.193039 -426.349978) (xy 65.212655 -426.364222) (xy 65.226908 -426.383833) (xy 65.234399 -426.406889)
			(xy 65.23482 -426.41901) (xy 65.23482 -427.960536) (xy 66.141092 -427.960536) (xy 66.141092 -425.419012)
			(xy 66.141527 -425.406905) (xy 66.149022 -425.383879) (xy 66.163279 -425.364307) (xy 66.182896 -425.350111)
			(xy 66.205945 -425.342689) (xy 66.218054 -425.342304) (xy 67.157854 -425.342304) (xy 67.169938 -425.342846)
			(xy 67.192931 -425.350286) (xy 67.207172 -425.360592) (xy 68.141088 -425.360592) (xy 68.141088 -422.819068)
			(xy 68.141489 -422.806959) (xy 68.148996 -422.783932) (xy 68.163262 -422.764361) (xy 68.182885 -422.750167)
			(xy 68.205939 -422.742745) (xy 68.21805 -422.74236) (xy 69.15785 -422.74236) (xy 69.169939 -422.74285)
			(xy 69.192941 -422.750296) (xy 69.212524 -422.764475) (xy 69.226775 -422.784006) (xy 69.234305 -422.806981)
			(xy 69.234812 -422.819068) (xy 69.234812 -424.360594) (xy 70.141084 -424.360594) (xy 70.141084 -421.81907)
			(xy 70.141435 -421.806941) (xy 70.148941 -421.783873) (xy 70.163209 -421.764255) (xy 70.182842 -421.750006)
			(xy 70.205917 -421.742523) (xy 70.218046 -421.742108) (xy 71.157846 -421.742108) (xy 71.16996 -421.742572)
			(xy 71.193 -421.750068) (xy 71.207209 -421.760396) (xy 72.14108 -421.760396) (xy 72.14108 -419.218872)
			(xy 72.141492 -419.206764) (xy 72.148997 -419.183739) (xy 72.16326 -419.164168) (xy 72.182881 -419.149974)
			(xy 72.205932 -419.14255) (xy 72.218042 -419.142164) (xy 73.157842 -419.142164) (xy 73.169936 -419.142572)
			(xy 73.192942 -419.150043) (xy 73.212524 -419.164244) (xy 73.226772 -419.183791) (xy 73.234298 -419.206779)
			(xy 73.234804 -419.218872) (xy 73.234804 -420.921688) (xy 75.13828 -420.921688) (xy 75.13828 -420.058088)
			(xy 75.138766 -420.030819) (xy 75.146528 -419.976835) (xy 75.161893 -419.924505) (xy 75.18455 -419.874895)
			(xy 75.214036 -419.829014) (xy 75.249751 -419.787797) (xy 75.290968 -419.752082) (xy 75.336849 -419.722596)
			(xy 75.386459 -419.699939) (xy 75.438789 -419.684574) (xy 75.492773 -419.676812) (xy 75.547311 -419.676812)
			(xy 75.601295 -419.684574) (xy 75.653625 -419.699939) (xy 75.703235 -419.722596) (xy 75.749116 -419.752082)
			(xy 75.790333 -419.787797) (xy 75.826048 -419.829014) (xy 75.855534 -419.874895) (xy 75.878191 -419.924505)
			(xy 75.893556 -419.976835) (xy 75.901318 -420.030819) (xy 75.901804 -420.058088) (xy 75.901804 -420.921688)
			(xy 75.901318 -420.948957) (xy 75.893556 -421.002941) (xy 75.878191 -421.055271) (xy 75.855534 -421.104881)
			(xy 75.844472 -421.122094) (xy 97.149412 -421.122094) (xy 97.149412 -414.328102) (xy 97.149934 -414.317948)
			(xy 97.157703 -414.299183) (xy 97.17206 -414.284819) (xy 97.19082 -414.27704) (xy 97.200974 -414.27654)
			(xy 102.099618 -414.27654) (xy 102.109777 -414.277018) (xy 102.128547 -414.284799) (xy 102.142912 -414.29917)
			(xy 102.150685 -414.317943) (xy 102.15118 -414.328102) (xy 102.15118 -420.700708) (xy 194.5894 -420.700708)
			(xy 194.5894 -413.816038) (xy 194.589861 -413.791087) (xy 194.597682 -413.741803) (xy 194.613107 -413.694345)
			(xy 194.635757 -413.649879) (xy 194.665075 -413.609499) (xy 194.682364 -413.591502) (xy 195.571364 -412.702502)
			(xy 195.589371 -412.685225) (xy 195.629744 -412.655899) (xy 195.674207 -412.633249) (xy 195.721665 -412.617832)
			(xy 195.77095 -412.610027) (xy 195.7959 -412.609538) (xy 226.776534 -412.609538) (xy 226.786607 -412.609147)
			(xy 226.805206 -412.601404) (xy 226.812602 -412.594552) (xy 229.318566 -410.088588) (xy 229.33657 -410.071308)
			(xy 229.376944 -410.041983) (xy 229.421407 -410.019333) (xy 229.468866 -410.003917) (xy 229.518152 -409.996113)
			(xy 229.543102 -409.995624) (xy 234.56646 -409.995624) (xy 234.57653 -409.995198) (xy 234.595129 -409.98748)
			(xy 234.602528 -409.980638) (xy 238.550196 -406.03297) (xy 238.557041 -406.025574) (xy 238.564758 -406.006972)
			(xy 238.565182 -405.996902) (xy 238.565182 -394.001498) (xy 238.565686 -393.976549) (xy 238.573497 -393.927266)
			(xy 238.588912 -393.879809) (xy 238.611553 -393.835343) (xy 238.640862 -393.79496) (xy 238.658146 -393.776962)
			(xy 238.727234 -393.707874) (xy 238.733961 -393.700496) (xy 238.741558 -393.682047) (xy 238.741546 -393.662096)
			(xy 238.733929 -393.643656) (xy 238.727234 -393.636246) (xy 238.579914 -393.488672) (xy 238.553014 -393.461125)
			(xy 238.504928 -393.400988) (xy 238.463885 -393.33584) (xy 238.430403 -393.266502) (xy 238.404904 -393.193848)
			(xy 238.387709 -393.118794) (xy 238.379036 -393.042285) (xy 238.378492 -393.003786) (xy 238.378492 -384.337306)
			(xy 238.379215 -384.306679) (xy 238.390978 -384.246564) (xy 238.40186 -384.217926) (xy 238.457994 -384.079496)
			(xy 238.466633 -384.059188) (xy 238.488684 -384.020961) (xy 238.515818 -383.986157) (xy 238.5314 -383.97053)
			(xy 238.583216 -383.920746) (xy 238.583724 -383.920238) (xy 239.05718 -383.446782) (xy 239.084743 -383.419899)
			(xy 239.144878 -383.371812) (xy 239.210023 -383.330768) (xy 239.279359 -383.297284) (xy 239.35201 -383.271782)
			(xy 239.427061 -383.254584) (xy 239.503568 -383.245906) (xy 239.542066 -383.24536) (xy 273.481546 -383.24536)
			(xy 273.512174 -383.24607) (xy 273.572289 -383.257841) (xy 273.600926 -383.268728) (xy 273.739356 -383.324862)
			(xy 273.759667 -383.333494) (xy 273.797892 -383.355549) (xy 273.832695 -383.382685) (xy 273.848322 -383.398268)
			(xy 273.898106 -383.450084) (xy 273.898614 -383.450592) (xy 274.11807 -383.670048) (xy 274.1422 -383.695194)
			(xy 274.149515 -383.702446) (xy 274.168248 -383.710967) (xy 274.178522 -383.711704) (xy 274.251674 -383.713482)
			(xy 274.262067 -383.713236) (xy 274.281342 -383.705512) (xy 274.289012 -383.698496) (xy 274.649184 -383.338324)
			(xy 274.667186 -383.321041) (xy 274.70756 -383.291715) (xy 274.752024 -383.269066) (xy 274.799483 -383.25365)
			(xy 274.84877 -383.245848) (xy 274.87372 -383.24536) (xy 280.202132 -383.24536) (xy 280.227081 -383.245851)
			(xy 280.276364 -383.253667) (xy 280.323821 -383.269085) (xy 280.368287 -383.291728) (xy 280.40867 -383.321039)
			(xy 280.426668 -383.338324) (xy 281.135836 -384.047492) (xy 281.153135 -384.065481) (xy 281.182465 -384.105856)
			(xy 281.205118 -384.150322) (xy 281.220536 -384.197785) (xy 281.228338 -384.247076) (xy 281.2288 -384.272028)
			(xy 281.2288 -384.869944) (xy 287.06878 -384.869944) (xy 287.072752 -384.691701) (xy 287.08466 -384.513812)
			(xy 287.104481 -384.33663) (xy 287.132175 -384.160506) (xy 287.167687 -383.985791) (xy 287.210947 -383.812832)
			(xy 287.261869 -383.641971) (xy 287.320352 -383.473549) (xy 287.386279 -383.307899) (xy 287.45952 -383.14535)
			(xy 287.53993 -382.986225) (xy 287.627348 -382.83084) (xy 287.721601 -382.679504) (xy 287.822502 -382.532516)
			(xy 287.929851 -382.390169) (xy 288.043434 -382.252746) (xy 288.163027 -382.120519) (xy 288.288391 -381.99375)
			(xy 288.419278 -381.872692) (xy 288.555427 -381.757585) (xy 288.696569 -381.648657) (xy 288.842424 -381.546125)
			(xy 288.992701 -381.450191) (xy 289.147102 -381.361048) (xy 289.305321 -381.278871) (xy 289.467044 -381.203823)
			(xy 289.631949 -381.136055) (xy 289.79971 -381.075699) (xy 289.969993 -381.022877) (xy 290.14246 -380.977693)
			(xy 290.316768 -380.940236) (xy 290.492572 -380.910582) (xy 290.669522 -380.888789) (xy 290.847268 -380.874899)
			(xy 291.025455 -380.868942) (xy 291.203732 -380.870928) (xy 291.381743 -380.880854) (xy 291.559135 -380.8987)
			(xy 291.735555 -380.92443) (xy 291.910655 -380.957994) (xy 292.084086 -380.999324) (xy 292.255503 -381.04834)
			(xy 292.424566 -381.104942) (xy 292.590941 -381.16902) (xy 292.754295 -381.240446) (xy 292.914306 -381.319078)
			(xy 293.070655 -381.404759) (xy 293.223032 -381.497321) (xy 293.371135 -381.596578) (xy 293.514669 -381.702335)
			(xy 293.653349 -381.81438) (xy 293.7869 -381.932492) (xy 293.915057 -382.056436) (xy 294.037566 -382.185966)
			(xy 294.154183 -382.320825) (xy 294.194727 -382.372167) (xy 303.739054 -382.372167) (xy 303.739054 -382.317633)
			(xy 303.746815 -382.263654) (xy 303.762179 -382.211329) (xy 303.784833 -382.161723) (xy 303.814317 -382.115846)
			(xy 303.850029 -382.074631) (xy 303.891242 -382.038919) (xy 303.937119 -382.009435) (xy 303.986725 -381.986781)
			(xy 304.03905 -381.971416) (xy 304.093029 -381.963655) (xy 304.120296 -381.963168) (xy 304.983896 -381.963168)
			(xy 305.011169 -381.963571) (xy 305.065161 -381.971334) (xy 305.117498 -381.986701) (xy 305.167116 -382.00936)
			(xy 305.213003 -382.03885) (xy 305.254227 -382.07457) (xy 305.289948 -382.115793) (xy 305.319438 -382.161681)
			(xy 305.342098 -382.211298) (xy 305.357466 -382.263635) (xy 305.365228 -382.317627) (xy 305.365228 -382.372167)
			(xy 310.546254 -382.372167) (xy 310.546254 -382.317633) (xy 310.554015 -382.263654) (xy 310.569379 -382.211329)
			(xy 310.592033 -382.161723) (xy 310.621517 -382.115846) (xy 310.657229 -382.074631) (xy 310.698442 -382.038919)
			(xy 310.744319 -382.009435) (xy 310.793925 -381.986781) (xy 310.84625 -381.971416) (xy 310.900229 -381.963655)
			(xy 310.927496 -381.963168) (xy 311.791096 -381.963168) (xy 311.818369 -381.963571) (xy 311.872361 -381.971334)
			(xy 311.924698 -381.986701) (xy 311.974316 -382.00936) (xy 312.020203 -382.03885) (xy 312.061427 -382.07457)
			(xy 312.097148 -382.115793) (xy 312.126638 -382.161681) (xy 312.149298 -382.211298) (xy 312.164666 -382.263635)
			(xy 312.172428 -382.317627) (xy 312.172428 -382.372167) (xy 317.353454 -382.372167) (xy 317.353454 -382.317633)
			(xy 317.361215 -382.263654) (xy 317.376579 -382.211329) (xy 317.399233 -382.161723) (xy 317.428717 -382.115846)
			(xy 317.464429 -382.074631) (xy 317.505642 -382.038919) (xy 317.551519 -382.009435) (xy 317.601125 -381.986781)
			(xy 317.65345 -381.971416) (xy 317.707429 -381.963655) (xy 317.734696 -381.963168) (xy 318.598296 -381.963168)
			(xy 318.625569 -381.963571) (xy 318.679561 -381.971334) (xy 318.731898 -381.986701) (xy 318.781516 -382.00936)
			(xy 318.827403 -382.03885) (xy 318.868627 -382.07457) (xy 318.904348 -382.115793) (xy 318.933838 -382.161681)
			(xy 318.956498 -382.211298) (xy 318.971866 -382.263635) (xy 318.979628 -382.317627) (xy 318.979628 -382.372171)
			(xy 336.266732 -382.372171) (xy 336.266732 -382.317629) (xy 336.274494 -382.263643) (xy 336.289861 -382.211311)
			(xy 336.312521 -382.161698) (xy 336.34201 -382.115816) (xy 336.377729 -382.074598) (xy 336.418951 -382.038884)
			(xy 336.464837 -382.009399) (xy 336.514452 -381.986746) (xy 336.566786 -381.971385) (xy 336.620773 -381.963628)
			(xy 336.648044 -381.963168) (xy 337.511644 -381.963168) (xy 337.538913 -381.963598) (xy 337.592897 -381.971365)
			(xy 337.645225 -381.986735) (xy 337.694833 -382.009396) (xy 337.740712 -382.038885) (xy 337.781928 -382.074603)
			(xy 337.817641 -382.115823) (xy 337.847125 -382.161705) (xy 337.86978 -382.211316) (xy 337.885144 -382.263647)
			(xy 337.892906 -382.31763) (xy 337.892906 -382.37217) (xy 337.892906 -382.372171) (xy 343.073932 -382.372171)
			(xy 343.073932 -382.317629) (xy 343.081694 -382.263643) (xy 343.097061 -382.211311) (xy 343.119721 -382.161698)
			(xy 343.14921 -382.115816) (xy 343.184929 -382.074598) (xy 343.226151 -382.038884) (xy 343.272037 -382.009399)
			(xy 343.321652 -381.986746) (xy 343.373986 -381.971385) (xy 343.427973 -381.963628) (xy 343.455244 -381.963168)
			(xy 344.318844 -381.963168) (xy 344.346113 -381.963598) (xy 344.400097 -381.971365) (xy 344.452425 -381.986735)
			(xy 344.502033 -382.009396) (xy 344.547912 -382.038885) (xy 344.589128 -382.074603) (xy 344.624841 -382.115823)
			(xy 344.654325 -382.161705) (xy 344.67698 -382.211316) (xy 344.692344 -382.263647) (xy 344.700106 -382.31763)
			(xy 344.700106 -382.37217) (xy 344.700106 -382.372171) (xy 349.881132 -382.372171) (xy 349.881132 -382.317629)
			(xy 349.888894 -382.263643) (xy 349.904261 -382.211311) (xy 349.926921 -382.161698) (xy 349.95641 -382.115816)
			(xy 349.992129 -382.074598) (xy 350.033351 -382.038884) (xy 350.079237 -382.009399) (xy 350.128852 -381.986746)
			(xy 350.181186 -381.971385) (xy 350.235173 -381.963628) (xy 350.262444 -381.963168) (xy 351.126044 -381.963168)
			(xy 351.153313 -381.963598) (xy 351.207297 -381.971365) (xy 351.259625 -381.986735) (xy 351.309233 -382.009396)
			(xy 351.355112 -382.038885) (xy 351.396328 -382.074603) (xy 351.432041 -382.115823) (xy 351.461525 -382.161705)
			(xy 351.48418 -382.211316) (xy 351.499544 -382.263647) (xy 351.507306 -382.31763) (xy 351.507306 -382.372167)
			(xy 370.839254 -382.372167) (xy 370.839254 -382.317633) (xy 370.847015 -382.263654) (xy 370.862379 -382.21133)
			(xy 370.885033 -382.161724) (xy 370.914516 -382.115847) (xy 370.950227 -382.074633) (xy 370.991441 -382.03892)
			(xy 371.037317 -382.009437) (xy 371.086922 -381.986782) (xy 371.139247 -381.971417) (xy 371.193225 -381.963655)
			(xy 371.220492 -381.963168) (xy 372.084092 -381.963168) (xy 372.111366 -381.963571) (xy 372.165357 -381.971333)
			(xy 372.217695 -381.9867) (xy 372.267313 -382.009359) (xy 372.313202 -382.038848) (xy 372.354426 -382.074568)
			(xy 372.390147 -382.115792) (xy 372.419638 -382.16168) (xy 372.442298 -382.211297) (xy 372.457665 -382.263635)
			(xy 372.465428 -382.317626) (xy 372.465428 -382.372167) (xy 377.646454 -382.372167) (xy 377.646454 -382.317633)
			(xy 377.654215 -382.263654) (xy 377.669579 -382.21133) (xy 377.692233 -382.161724) (xy 377.721716 -382.115847)
			(xy 377.757427 -382.074633) (xy 377.798641 -382.03892) (xy 377.844517 -382.009437) (xy 377.894122 -381.986782)
			(xy 377.946447 -381.971417) (xy 378.000425 -381.963655) (xy 378.027692 -381.963168) (xy 378.891292 -381.963168)
			(xy 378.918566 -381.963571) (xy 378.972557 -381.971333) (xy 379.024895 -381.9867) (xy 379.074513 -382.009359)
			(xy 379.120402 -382.038848) (xy 379.161626 -382.074568) (xy 379.197347 -382.115792) (xy 379.226838 -382.16168)
			(xy 379.249498 -382.211297) (xy 379.264865 -382.263635) (xy 379.272628 -382.317626) (xy 379.272628 -382.372167)
			(xy 384.453654 -382.372167) (xy 384.453654 -382.317633) (xy 384.461415 -382.263654) (xy 384.476779 -382.21133)
			(xy 384.499433 -382.161724) (xy 384.528916 -382.115847) (xy 384.564627 -382.074633) (xy 384.605841 -382.03892)
			(xy 384.651717 -382.009437) (xy 384.701322 -381.986782) (xy 384.753647 -381.971417) (xy 384.807625 -381.963655)
			(xy 384.834892 -381.963168) (xy 385.698492 -381.963168) (xy 385.725766 -381.963571) (xy 385.779757 -381.971333)
			(xy 385.832095 -381.9867) (xy 385.881713 -382.009359) (xy 385.927602 -382.038848) (xy 385.968826 -382.074568)
			(xy 386.004547 -382.115792) (xy 386.034038 -382.16168) (xy 386.056698 -382.211297) (xy 386.072065 -382.263635)
			(xy 386.079828 -382.317626) (xy 386.079828 -382.372171) (xy 403.366932 -382.372171) (xy 403.366932 -382.317629)
			(xy 403.374694 -382.263643) (xy 403.390061 -382.211311) (xy 403.41272 -382.161699) (xy 403.442209 -382.115817)
			(xy 403.477928 -382.0746) (xy 403.51915 -382.038885) (xy 403.565035 -382.009401) (xy 403.614649 -381.986747)
			(xy 403.666982 -381.971386) (xy 403.720969 -381.963629) (xy 403.74824 -381.963168) (xy 404.61184 -381.963168)
			(xy 404.63911 -381.963597) (xy 404.693093 -381.971364) (xy 404.745422 -381.986734) (xy 404.795031 -382.009394)
			(xy 404.840911 -382.038884) (xy 404.882127 -382.074602) (xy 404.91784 -382.115822) (xy 404.947325 -382.161704)
			(xy 404.96998 -382.211316) (xy 404.985344 -382.263646) (xy 404.993106 -382.31763) (xy 404.993106 -382.37217)
			(xy 404.993106 -382.372171) (xy 410.174132 -382.372171) (xy 410.174132 -382.317629) (xy 410.181894 -382.263643)
			(xy 410.197261 -382.211311) (xy 410.21992 -382.161699) (xy 410.249409 -382.115817) (xy 410.285128 -382.0746)
			(xy 410.32635 -382.038885) (xy 410.372235 -382.009401) (xy 410.421849 -381.986747) (xy 410.474182 -381.971386)
			(xy 410.528169 -381.963629) (xy 410.55544 -381.963168) (xy 411.41904 -381.963168) (xy 411.44631 -381.963597)
			(xy 411.500293 -381.971364) (xy 411.552622 -381.986734) (xy 411.602231 -382.009394) (xy 411.648111 -382.038884)
			(xy 411.689327 -382.074602) (xy 411.72504 -382.115822) (xy 411.754525 -382.161704) (xy 411.77718 -382.211316)
			(xy 411.792544 -382.263646) (xy 411.800306 -382.31763) (xy 411.800306 -382.37217) (xy 411.800306 -382.372171)
			(xy 416.981332 -382.372171) (xy 416.981332 -382.317629) (xy 416.989094 -382.263643) (xy 417.004461 -382.211311)
			(xy 417.02712 -382.161699) (xy 417.056609 -382.115817) (xy 417.092328 -382.0746) (xy 417.13355 -382.038885)
			(xy 417.179435 -382.009401) (xy 417.229049 -381.986747) (xy 417.281382 -381.971386) (xy 417.335369 -381.963629)
			(xy 417.36264 -381.963168) (xy 418.22624 -381.963168) (xy 418.25351 -381.963597) (xy 418.307493 -381.971364)
			(xy 418.359822 -381.986734) (xy 418.409431 -382.009394) (xy 418.455311 -382.038884) (xy 418.496527 -382.074602)
			(xy 418.53224 -382.115822) (xy 418.561725 -382.161704) (xy 418.58438 -382.211316) (xy 418.599744 -382.263646)
			(xy 418.607506 -382.31763) (xy 418.607506 -382.37217) (xy 418.599744 -382.426154) (xy 418.58438 -382.478484)
			(xy 418.561725 -382.528096) (xy 418.53224 -382.573978) (xy 418.496527 -382.615198) (xy 418.455311 -382.650916)
			(xy 418.409431 -382.680406) (xy 418.359822 -382.703066) (xy 418.307493 -382.718436) (xy 418.25351 -382.726203)
			(xy 418.22624 -382.726692) (xy 417.36264 -382.726692) (xy 417.335369 -382.726171) (xy 417.281382 -382.718414)
			(xy 417.229049 -382.703053) (xy 417.179435 -382.680399) (xy 417.13355 -382.650915) (xy 417.092328 -382.6152)
			(xy 417.056609 -382.573983) (xy 417.02712 -382.528101) (xy 417.004461 -382.478489) (xy 416.989094 -382.426157)
			(xy 416.981332 -382.372171) (xy 411.800306 -382.372171) (xy 411.792544 -382.426154) (xy 411.77718 -382.478484)
			(xy 411.754525 -382.528096) (xy 411.72504 -382.573978) (xy 411.689327 -382.615198) (xy 411.648111 -382.650916)
			(xy 411.602231 -382.680406) (xy 411.552622 -382.703066) (xy 411.500293 -382.718436) (xy 411.44631 -382.726203)
			(xy 411.41904 -382.726692) (xy 410.55544 -382.726692) (xy 410.528169 -382.726171) (xy 410.474182 -382.718414)
			(xy 410.421849 -382.703053) (xy 410.372235 -382.680399) (xy 410.32635 -382.650915) (xy 410.285128 -382.6152)
			(xy 410.249409 -382.573983) (xy 410.21992 -382.528101) (xy 410.197261 -382.478489) (xy 410.181894 -382.426157)
			(xy 410.174132 -382.372171) (xy 404.993106 -382.372171) (xy 404.985344 -382.426154) (xy 404.96998 -382.478484)
			(xy 404.947325 -382.528096) (xy 404.91784 -382.573978) (xy 404.882127 -382.615198) (xy 404.840911 -382.650916)
			(xy 404.795031 -382.680406) (xy 404.745422 -382.703066) (xy 404.693093 -382.718436) (xy 404.63911 -382.726203)
			(xy 404.61184 -382.726692) (xy 403.74824 -382.726692) (xy 403.720969 -382.726171) (xy 403.666982 -382.718414)
			(xy 403.614649 -382.703053) (xy 403.565035 -382.680399) (xy 403.51915 -382.650915) (xy 403.477928 -382.6152)
			(xy 403.442209 -382.573983) (xy 403.41272 -382.528101) (xy 403.390061 -382.478489) (xy 403.374694 -382.426157)
			(xy 403.366932 -382.372171) (xy 386.079828 -382.372171) (xy 386.079828 -382.372174) (xy 386.072065 -382.426165)
			(xy 386.056698 -382.478503) (xy 386.034038 -382.52812) (xy 386.004547 -382.574008) (xy 385.968826 -382.615232)
			(xy 385.927602 -382.650952) (xy 385.881713 -382.680441) (xy 385.832095 -382.7031) (xy 385.779757 -382.718467)
			(xy 385.725766 -382.726229) (xy 385.698492 -382.726692) (xy 384.834892 -382.726692) (xy 384.807625 -382.726145)
			(xy 384.753647 -382.718383) (xy 384.701322 -382.703018) (xy 384.651717 -382.680363) (xy 384.605841 -382.65088)
			(xy 384.564627 -382.615167) (xy 384.528916 -382.573953) (xy 384.499433 -382.528076) (xy 384.476779 -382.47847)
			(xy 384.461415 -382.426146) (xy 384.453654 -382.372167) (xy 379.272628 -382.372167) (xy 379.272628 -382.372174)
			(xy 379.264865 -382.426165) (xy 379.249498 -382.478503) (xy 379.226838 -382.52812) (xy 379.197347 -382.574008)
			(xy 379.161626 -382.615232) (xy 379.120402 -382.650952) (xy 379.074513 -382.680441) (xy 379.024895 -382.7031)
			(xy 378.972557 -382.718467) (xy 378.918566 -382.726229) (xy 378.891292 -382.726692) (xy 378.027692 -382.726692)
			(xy 378.000425 -382.726145) (xy 377.946447 -382.718383) (xy 377.894122 -382.703018) (xy 377.844517 -382.680363)
			(xy 377.798641 -382.65088) (xy 377.757427 -382.615167) (xy 377.721716 -382.573953) (xy 377.692233 -382.528076)
			(xy 377.669579 -382.47847) (xy 377.654215 -382.426146) (xy 377.646454 -382.372167) (xy 372.465428 -382.372167)
			(xy 372.465428 -382.372174) (xy 372.457665 -382.426165) (xy 372.442298 -382.478503) (xy 372.419638 -382.52812)
			(xy 372.390147 -382.574008) (xy 372.354426 -382.615232) (xy 372.313202 -382.650952) (xy 372.267313 -382.680441)
			(xy 372.217695 -382.7031) (xy 372.165357 -382.718467) (xy 372.111366 -382.726229) (xy 372.084092 -382.726692)
			(xy 371.220492 -382.726692) (xy 371.193225 -382.726145) (xy 371.139247 -382.718383) (xy 371.086922 -382.703018)
			(xy 371.037317 -382.680363) (xy 370.991441 -382.65088) (xy 370.950227 -382.615167) (xy 370.914516 -382.573953)
			(xy 370.885033 -382.528076) (xy 370.862379 -382.47847) (xy 370.847015 -382.426146) (xy 370.839254 -382.372167)
			(xy 351.507306 -382.372167) (xy 351.507306 -382.37217) (xy 351.499544 -382.426153) (xy 351.48418 -382.478484)
			(xy 351.461525 -382.528095) (xy 351.432041 -382.573977) (xy 351.396328 -382.615197) (xy 351.355112 -382.650915)
			(xy 351.309233 -382.680404) (xy 351.259625 -382.703065) (xy 351.207297 -382.718435) (xy 351.153313 -382.726202)
			(xy 351.126044 -382.726692) (xy 350.262444 -382.726692) (xy 350.235173 -382.726172) (xy 350.181186 -382.718415)
			(xy 350.128852 -382.703054) (xy 350.079237 -382.680401) (xy 350.033351 -382.650916) (xy 349.992129 -382.615202)
			(xy 349.95641 -382.573984) (xy 349.926921 -382.528102) (xy 349.904261 -382.478489) (xy 349.888894 -382.426157)
			(xy 349.881132 -382.372171) (xy 344.700106 -382.372171) (xy 344.692344 -382.426153) (xy 344.67698 -382.478484)
			(xy 344.654325 -382.528095) (xy 344.624841 -382.573977) (xy 344.589128 -382.615197) (xy 344.547912 -382.650915)
			(xy 344.502033 -382.680404) (xy 344.452425 -382.703065) (xy 344.400097 -382.718435) (xy 344.346113 -382.726202)
			(xy 344.318844 -382.726692) (xy 343.455244 -382.726692) (xy 343.427973 -382.726172) (xy 343.373986 -382.718415)
			(xy 343.321652 -382.703054) (xy 343.272037 -382.680401) (xy 343.226151 -382.650916) (xy 343.184929 -382.615202)
			(xy 343.14921 -382.573984) (xy 343.119721 -382.528102) (xy 343.097061 -382.478489) (xy 343.081694 -382.426157)
			(xy 343.073932 -382.372171) (xy 337.892906 -382.372171) (xy 337.885144 -382.426153) (xy 337.86978 -382.478484)
			(xy 337.847125 -382.528095) (xy 337.817641 -382.573977) (xy 337.781928 -382.615197) (xy 337.740712 -382.650915)
			(xy 337.694833 -382.680404) (xy 337.645225 -382.703065) (xy 337.592897 -382.718435) (xy 337.538913 -382.726202)
			(xy 337.511644 -382.726692) (xy 336.648044 -382.726692) (xy 336.620773 -382.726172) (xy 336.566786 -382.718415)
			(xy 336.514452 -382.703054) (xy 336.464837 -382.680401) (xy 336.418951 -382.650916) (xy 336.377729 -382.615202)
			(xy 336.34201 -382.573984) (xy 336.312521 -382.528102) (xy 336.289861 -382.478489) (xy 336.274494 -382.426157)
			(xy 336.266732 -382.372171) (xy 318.979628 -382.372171) (xy 318.979628 -382.372173) (xy 318.971866 -382.426165)
			(xy 318.956498 -382.478502) (xy 318.933838 -382.528119) (xy 318.904348 -382.574007) (xy 318.868627 -382.61523)
			(xy 318.827403 -382.65095) (xy 318.781516 -382.68044) (xy 318.731898 -382.703099) (xy 318.679561 -382.718466)
			(xy 318.625569 -382.726229) (xy 318.598296 -382.726692) (xy 317.734696 -382.726692) (xy 317.707429 -382.726145)
			(xy 317.65345 -382.718384) (xy 317.601125 -382.703019) (xy 317.551519 -382.680365) (xy 317.505642 -382.650881)
			(xy 317.464429 -382.615169) (xy 317.428717 -382.573954) (xy 317.399233 -382.528077) (xy 317.376579 -382.478471)
			(xy 317.361215 -382.426146) (xy 317.353454 -382.372167) (xy 312.172428 -382.372167) (xy 312.172428 -382.372173)
			(xy 312.164666 -382.426165) (xy 312.149298 -382.478502) (xy 312.126638 -382.528119) (xy 312.097148 -382.574007)
			(xy 312.061427 -382.61523) (xy 312.020203 -382.65095) (xy 311.974316 -382.68044) (xy 311.924698 -382.703099)
			(xy 311.872361 -382.718466) (xy 311.818369 -382.726229) (xy 311.791096 -382.726692) (xy 310.927496 -382.726692)
			(xy 310.900229 -382.726145) (xy 310.84625 -382.718384) (xy 310.793925 -382.703019) (xy 310.744319 -382.680365)
			(xy 310.698442 -382.650881) (xy 310.657229 -382.615169) (xy 310.621517 -382.573954) (xy 310.592033 -382.528077)
			(xy 310.569379 -382.478471) (xy 310.554015 -382.426146) (xy 310.546254 -382.372167) (xy 305.365228 -382.372167)
			(xy 305.365228 -382.372173) (xy 305.357466 -382.426165) (xy 305.342098 -382.478502) (xy 305.319438 -382.528119)
			(xy 305.289948 -382.574007) (xy 305.254227 -382.61523) (xy 305.213003 -382.65095) (xy 305.167116 -382.68044)
			(xy 305.117498 -382.703099) (xy 305.065161 -382.718466) (xy 305.011169 -382.726229) (xy 304.983896 -382.726692)
			(xy 304.120296 -382.726692) (xy 304.093029 -382.726145) (xy 304.03905 -382.718384) (xy 303.986725 -382.703019)
			(xy 303.937119 -382.680365) (xy 303.891242 -382.650881) (xy 303.850029 -382.615169) (xy 303.814317 -382.573954)
			(xy 303.784833 -382.528077) (xy 303.762179 -382.478471) (xy 303.746815 -382.426146) (xy 303.739054 -382.372167)
			(xy 294.194727 -382.372167) (xy 294.264676 -382.460745) (xy 294.368827 -382.605448) (xy 294.466429 -382.754647)
			(xy 294.557287 -382.908046) (xy 294.641221 -383.06534) (xy 294.718066 -383.226216) (xy 294.787667 -383.390357)
			(xy 294.849888 -383.557434) (xy 294.904604 -383.727118) (xy 294.951706 -383.899071) (xy 294.991102 -384.072951)
			(xy 295.022713 -384.248414) (xy 295.046477 -384.42511) (xy 295.062345 -384.60269) (xy 295.070287 -384.7808)
			(xy 295.070784 -384.869944) (xy 295.070287 -384.959088) (xy 295.062345 -385.137198) (xy 295.055495 -385.21386)
			(xy 297.048936 -385.21386) (xy 297.048936 -384.35026) (xy 297.049422 -384.323009) (xy 297.057178 -384.269061)
			(xy 297.072533 -384.216766) (xy 297.095175 -384.167189) (xy 297.124641 -384.121339) (xy 297.160332 -384.080148)
			(xy 297.201523 -384.044457) (xy 297.247373 -384.014991) (xy 297.29695 -383.992349) (xy 297.349245 -383.976994)
			(xy 297.403193 -383.969238) (xy 297.457695 -383.969238) (xy 297.511643 -383.976994) (xy 297.563938 -383.992349)
			(xy 297.613515 -384.014991) (xy 297.659365 -384.044457) (xy 297.700556 -384.080148) (xy 297.736247 -384.121339)
			(xy 297.765713 -384.167189) (xy 297.788355 -384.216766) (xy 297.80371 -384.269061) (xy 297.811466 -384.323009)
			(xy 297.811952 -384.35026) (xy 297.811952 -385.21386) (xy 297.811466 -385.241111) (xy 297.80371 -385.295059)
			(xy 297.790858 -385.338828) (xy 326.895968 -385.338828) (xy 326.895968 -384.475228) (xy 326.896454 -384.447977)
			(xy 326.90421 -384.394029) (xy 326.919565 -384.341734) (xy 326.942207 -384.292157) (xy 326.971673 -384.246307)
			(xy 327.007364 -384.205116) (xy 327.048555 -384.169425) (xy 327.094405 -384.139959) (xy 327.143982 -384.117317)
			(xy 327.196277 -384.101962) (xy 327.250225 -384.094206) (xy 327.304727 -384.094206) (xy 327.358675 -384.101962)
			(xy 327.41097 -384.117317) (xy 327.460547 -384.139959) (xy 327.506397 -384.169425) (xy 327.547588 -384.205116)
			(xy 327.583279 -384.246307) (xy 327.612745 -384.292157) (xy 327.635387 -384.341734) (xy 327.650742 -384.394029)
			(xy 327.658498 -384.447977) (xy 327.658984 -384.475228) (xy 327.658984 -385.21386) (xy 329.576684 -385.21386)
			(xy 329.576684 -384.35026) (xy 329.57717 -384.323009) (xy 329.584926 -384.269061) (xy 329.600281 -384.216766)
			(xy 329.622923 -384.167189) (xy 329.652389 -384.121339) (xy 329.68808 -384.080148) (xy 329.729271 -384.044457)
			(xy 329.775121 -384.014991) (xy 329.824698 -383.992349) (xy 329.876993 -383.976994) (xy 329.930941 -383.969238)
			(xy 329.985443 -383.969238) (xy 330.039391 -383.976994) (xy 330.091686 -383.992349) (xy 330.141263 -384.014991)
			(xy 330.187113 -384.044457) (xy 330.228304 -384.080148) (xy 330.263995 -384.121339) (xy 330.293461 -384.167189)
			(xy 330.316103 -384.216766) (xy 330.331458 -384.269061) (xy 330.339214 -384.323009) (xy 330.3397 -384.35026)
			(xy 330.3397 -385.21386) (xy 330.339214 -385.241111) (xy 330.331458 -385.295059) (xy 330.318606 -385.338828)
			(xy 359.423716 -385.338828) (xy 359.423716 -384.475228) (xy 359.424202 -384.447977) (xy 359.431958 -384.394029)
			(xy 359.447313 -384.341734) (xy 359.469955 -384.292157) (xy 359.499421 -384.246307) (xy 359.535112 -384.205116)
			(xy 359.576303 -384.169425) (xy 359.622153 -384.139959) (xy 359.67173 -384.117317) (xy 359.724025 -384.101962)
			(xy 359.777973 -384.094206) (xy 359.832475 -384.094206) (xy 359.886423 -384.101962) (xy 359.938718 -384.117317)
			(xy 359.988295 -384.139959) (xy 360.034145 -384.169425) (xy 360.075336 -384.205116) (xy 360.111027 -384.246307)
			(xy 360.140493 -384.292157) (xy 360.163135 -384.341734) (xy 360.17849 -384.394029) (xy 360.186246 -384.447977)
			(xy 360.186732 -384.475228) (xy 360.186732 -385.21386) (xy 364.149132 -385.21386) (xy 364.149132 -384.35026)
			(xy 364.149618 -384.323009) (xy 364.157374 -384.269061) (xy 364.172729 -384.216766) (xy 364.195371 -384.167189)
			(xy 364.224837 -384.121339) (xy 364.260528 -384.080148) (xy 364.301719 -384.044457) (xy 364.347569 -384.014991)
			(xy 364.397146 -383.992349) (xy 364.449441 -383.976994) (xy 364.503389 -383.969238) (xy 364.557891 -383.969238)
			(xy 364.611839 -383.976994) (xy 364.664134 -383.992349) (xy 364.713711 -384.014991) (xy 364.759561 -384.044457)
			(xy 364.800752 -384.080148) (xy 364.836443 -384.121339) (xy 364.865909 -384.167189) (xy 364.888551 -384.216766)
			(xy 364.903906 -384.269061) (xy 364.911662 -384.323009) (xy 364.912148 -384.35026) (xy 364.912148 -385.21386)
			(xy 364.911662 -385.241111) (xy 364.903906 -385.295059) (xy 364.891054 -385.338828) (xy 393.996164 -385.338828)
			(xy 393.996164 -384.475228) (xy 393.99665 -384.447977) (xy 394.004406 -384.394029) (xy 394.019761 -384.341734)
			(xy 394.042403 -384.292157) (xy 394.071869 -384.246307) (xy 394.10756 -384.205116) (xy 394.148751 -384.169425)
			(xy 394.194601 -384.139959) (xy 394.244178 -384.117317) (xy 394.296473 -384.101962) (xy 394.350421 -384.094206)
			(xy 394.404923 -384.094206) (xy 394.458871 -384.101962) (xy 394.511166 -384.117317) (xy 394.560743 -384.139959)
			(xy 394.606593 -384.169425) (xy 394.647784 -384.205116) (xy 394.683475 -384.246307) (xy 394.712941 -384.292157)
			(xy 394.735583 -384.341734) (xy 394.750938 -384.394029) (xy 394.758694 -384.447977) (xy 394.75918 -384.475228)
			(xy 394.75918 -385.21386) (xy 396.67688 -385.21386) (xy 396.67688 -384.35026) (xy 396.677366 -384.323009)
			(xy 396.685122 -384.269061) (xy 396.700477 -384.216766) (xy 396.723119 -384.167189) (xy 396.752585 -384.121339)
			(xy 396.788276 -384.080148) (xy 396.829467 -384.044457) (xy 396.875317 -384.014991) (xy 396.924894 -383.992349)
			(xy 396.977189 -383.976994) (xy 397.031137 -383.969238) (xy 397.085639 -383.969238) (xy 397.139587 -383.976994)
			(xy 397.191882 -383.992349) (xy 397.241459 -384.014991) (xy 397.287309 -384.044457) (xy 397.3285 -384.080148)
			(xy 397.364191 -384.121339) (xy 397.393657 -384.167189) (xy 397.416299 -384.216766) (xy 397.431654 -384.269061)
			(xy 397.43941 -384.323009) (xy 397.439896 -384.35026) (xy 397.439896 -385.21386) (xy 397.43941 -385.241111)
			(xy 397.431654 -385.295059) (xy 397.418802 -385.338828) (xy 426.523912 -385.338828) (xy 426.523912 -384.475228)
			(xy 426.524398 -384.447977) (xy 426.532154 -384.394029) (xy 426.547509 -384.341734) (xy 426.570151 -384.292157)
			(xy 426.599617 -384.246307) (xy 426.635308 -384.205116) (xy 426.676499 -384.169425) (xy 426.722349 -384.139959)
			(xy 426.771926 -384.117317) (xy 426.824221 -384.101962) (xy 426.878169 -384.094206) (xy 426.932671 -384.094206)
			(xy 426.986619 -384.101962) (xy 427.038914 -384.117317) (xy 427.088491 -384.139959) (xy 427.134341 -384.169425)
			(xy 427.175532 -384.205116) (xy 427.211223 -384.246307) (xy 427.240689 -384.292157) (xy 427.263331 -384.341734)
			(xy 427.278686 -384.394029) (xy 427.286442 -384.447977) (xy 427.286928 -384.475228) (xy 427.286928 -384.869944)
			(xy 429.498772 -384.869944) (xy 429.502744 -384.691701) (xy 429.514652 -384.513812) (xy 429.534473 -384.33663)
			(xy 429.562167 -384.160506) (xy 429.597679 -383.985791) (xy 429.640939 -383.812832) (xy 429.691861 -383.641971)
			(xy 429.750344 -383.473549) (xy 429.816271 -383.307899) (xy 429.889512 -383.14535) (xy 429.969922 -382.986225)
			(xy 430.05734 -382.83084) (xy 430.151593 -382.679504) (xy 430.252494 -382.532516) (xy 430.359843 -382.390169)
			(xy 430.473426 -382.252746) (xy 430.593019 -382.120519) (xy 430.718383 -381.99375) (xy 430.84927 -381.872692)
			(xy 430.985419 -381.757585) (xy 431.126561 -381.648657) (xy 431.272416 -381.546125) (xy 431.422693 -381.450191)
			(xy 431.577094 -381.361048) (xy 431.735313 -381.278871) (xy 431.897036 -381.203823) (xy 432.061941 -381.136055)
			(xy 432.229702 -381.075699) (xy 432.399985 -381.022877) (xy 432.572452 -380.977693) (xy 432.74676 -380.940236)
			(xy 432.922564 -380.910582) (xy 433.099514 -380.888789) (xy 433.27726 -380.874899) (xy 433.455447 -380.868942)
			(xy 433.633724 -380.870928) (xy 433.811735 -380.880854) (xy 433.989127 -380.8987) (xy 434.165547 -380.92443)
			(xy 434.340647 -380.957994) (xy 434.514078 -380.999324) (xy 434.685495 -381.04834) (xy 434.854558 -381.104942)
			(xy 435.020933 -381.16902) (xy 435.184287 -381.240446) (xy 435.344298 -381.319078) (xy 435.500647 -381.404759)
			(xy 435.653024 -381.497321) (xy 435.801127 -381.596578) (xy 435.944661 -381.702335) (xy 436.083341 -381.81438)
			(xy 436.216892 -381.932492) (xy 436.345049 -382.056436) (xy 436.467558 -382.185966) (xy 436.584175 -382.320825)
			(xy 436.694668 -382.460745) (xy 436.798819 -382.605448) (xy 436.896421 -382.754647) (xy 436.987279 -382.908046)
			(xy 437.071213 -383.06534) (xy 437.148058 -383.226216) (xy 437.217659 -383.390357) (xy 437.27988 -383.557434)
			(xy 437.334596 -383.727118) (xy 437.381698 -383.899071) (xy 437.421094 -384.072951) (xy 437.452705 -384.248414)
			(xy 437.476469 -384.42511) (xy 437.492337 -384.60269) (xy 437.500279 -384.7808) (xy 437.500776 -384.869944)
			(xy 437.500279 -384.959088) (xy 437.492337 -385.137198) (xy 437.476469 -385.314778) (xy 437.452705 -385.491474)
			(xy 437.421094 -385.666937) (xy 437.381698 -385.840817) (xy 437.334596 -386.01277) (xy 437.27988 -386.182454)
			(xy 437.217659 -386.349531) (xy 437.148058 -386.513672) (xy 437.071213 -386.674548) (xy 436.987279 -386.831842)
			(xy 436.896421 -386.985241) (xy 436.798819 -387.13444) (xy 436.694668 -387.279143) (xy 436.584175 -387.419063)
			(xy 436.467558 -387.553922) (xy 436.345049 -387.683452) (xy 436.216892 -387.807396) (xy 436.083341 -387.925508)
			(xy 435.944661 -388.037553) (xy 435.801127 -388.14331) (xy 435.653024 -388.242567) (xy 435.500647 -388.335129)
			(xy 435.344298 -388.42081) (xy 435.184287 -388.499442) (xy 435.020933 -388.570868) (xy 434.854558 -388.634946)
			(xy 434.685495 -388.691548) (xy 434.514078 -388.740564) (xy 434.340647 -388.781894) (xy 434.165547 -388.815458)
			(xy 433.989127 -388.841188) (xy 433.811735 -388.859034) (xy 433.633724 -388.86896) (xy 433.455447 -388.870946)
			(xy 433.27726 -388.864989) (xy 433.099514 -388.851099) (xy 432.922564 -388.829306) (xy 432.74676 -388.799652)
			(xy 432.572452 -388.762195) (xy 432.399985 -388.717011) (xy 432.229702 -388.664189) (xy 432.061941 -388.603833)
			(xy 431.897036 -388.536065) (xy 431.735313 -388.461017) (xy 431.577094 -388.37884) (xy 431.422693 -388.289697)
			(xy 431.272416 -388.193763) (xy 431.126561 -388.091231) (xy 430.985419 -387.982303) (xy 430.84927 -387.867196)
			(xy 430.718383 -387.746138) (xy 430.593019 -387.619369) (xy 430.473426 -387.487142) (xy 430.359843 -387.349719)
			(xy 430.252494 -387.207372) (xy 430.151593 -387.060384) (xy 430.05734 -386.909048) (xy 429.969922 -386.753663)
			(xy 429.889512 -386.594538) (xy 429.816271 -386.431989) (xy 429.750344 -386.266339) (xy 429.691861 -386.097917)
			(xy 429.640939 -385.927056) (xy 429.597679 -385.754097) (xy 429.562167 -385.579382) (xy 429.534473 -385.403258)
			(xy 429.514652 -385.226076) (xy 429.502744 -385.048187) (xy 429.498772 -384.869944) (xy 427.286928 -384.869944)
			(xy 427.286928 -385.338828) (xy 427.286442 -385.366079) (xy 427.278686 -385.420027) (xy 427.263331 -385.472322)
			(xy 427.240689 -385.521899) (xy 427.211223 -385.567749) (xy 427.175532 -385.60894) (xy 427.134341 -385.644631)
			(xy 427.088491 -385.674097) (xy 427.038914 -385.696739) (xy 426.986619 -385.712094) (xy 426.932671 -385.71985)
			(xy 426.878169 -385.71985) (xy 426.824221 -385.712094) (xy 426.771926 -385.696739) (xy 426.722349 -385.674097)
			(xy 426.676499 -385.644631) (xy 426.635308 -385.60894) (xy 426.599617 -385.567749) (xy 426.570151 -385.521899)
			(xy 426.547509 -385.472322) (xy 426.532154 -385.420027) (xy 426.524398 -385.366079) (xy 426.523912 -385.338828)
			(xy 397.418802 -385.338828) (xy 397.416299 -385.347354) (xy 397.393657 -385.396931) (xy 397.364191 -385.442781)
			(xy 397.3285 -385.483972) (xy 397.287309 -385.519663) (xy 397.241459 -385.549129) (xy 397.191882 -385.571771)
			(xy 397.139587 -385.587126) (xy 397.085639 -385.594882) (xy 397.031137 -385.594882) (xy 396.977189 -385.587126)
			(xy 396.924894 -385.571771) (xy 396.875317 -385.549129) (xy 396.829467 -385.519663) (xy 396.788276 -385.483972)
			(xy 396.752585 -385.442781) (xy 396.723119 -385.396931) (xy 396.700477 -385.347354) (xy 396.685122 -385.295059)
			(xy 396.677366 -385.241111) (xy 396.67688 -385.21386) (xy 394.75918 -385.21386) (xy 394.75918 -385.338828)
			(xy 394.758694 -385.366079) (xy 394.750938 -385.420027) (xy 394.735583 -385.472322) (xy 394.712941 -385.521899)
			(xy 394.683475 -385.567749) (xy 394.647784 -385.60894) (xy 394.606593 -385.644631) (xy 394.560743 -385.674097)
			(xy 394.511166 -385.696739) (xy 394.458871 -385.712094) (xy 394.404923 -385.71985) (xy 394.350421 -385.71985)
			(xy 394.296473 -385.712094) (xy 394.244178 -385.696739) (xy 394.194601 -385.674097) (xy 394.148751 -385.644631)
			(xy 394.10756 -385.60894) (xy 394.071869 -385.567749) (xy 394.042403 -385.521899) (xy 394.019761 -385.472322)
			(xy 394.004406 -385.420027) (xy 393.99665 -385.366079) (xy 393.996164 -385.338828) (xy 364.891054 -385.338828)
			(xy 364.888551 -385.347354) (xy 364.865909 -385.396931) (xy 364.836443 -385.442781) (xy 364.800752 -385.483972)
			(xy 364.759561 -385.519663) (xy 364.713711 -385.549129) (xy 364.664134 -385.571771) (xy 364.611839 -385.587126)
			(xy 364.557891 -385.594882) (xy 364.503389 -385.594882) (xy 364.449441 -385.587126) (xy 364.397146 -385.571771)
			(xy 364.347569 -385.549129) (xy 364.301719 -385.519663) (xy 364.260528 -385.483972) (xy 364.224837 -385.442781)
			(xy 364.195371 -385.396931) (xy 364.172729 -385.347354) (xy 364.157374 -385.295059) (xy 364.149618 -385.241111)
			(xy 364.149132 -385.21386) (xy 360.186732 -385.21386) (xy 360.186732 -385.338828) (xy 360.186246 -385.366079)
			(xy 360.17849 -385.420027) (xy 360.163135 -385.472322) (xy 360.140493 -385.521899) (xy 360.111027 -385.567749)
			(xy 360.075336 -385.60894) (xy 360.034145 -385.644631) (xy 359.988295 -385.674097) (xy 359.938718 -385.696739)
			(xy 359.886423 -385.712094) (xy 359.832475 -385.71985) (xy 359.777973 -385.71985) (xy 359.724025 -385.712094)
			(xy 359.67173 -385.696739) (xy 359.622153 -385.674097) (xy 359.576303 -385.644631) (xy 359.535112 -385.60894)
			(xy 359.499421 -385.567749) (xy 359.469955 -385.521899) (xy 359.447313 -385.472322) (xy 359.431958 -385.420027)
			(xy 359.424202 -385.366079) (xy 359.423716 -385.338828) (xy 330.318606 -385.338828) (xy 330.316103 -385.347354)
			(xy 330.293461 -385.396931) (xy 330.263995 -385.442781) (xy 330.228304 -385.483972) (xy 330.187113 -385.519663)
			(xy 330.141263 -385.549129) (xy 330.091686 -385.571771) (xy 330.039391 -385.587126) (xy 329.985443 -385.594882)
			(xy 329.930941 -385.594882) (xy 329.876993 -385.587126) (xy 329.824698 -385.571771) (xy 329.775121 -385.549129)
			(xy 329.729271 -385.519663) (xy 329.68808 -385.483972) (xy 329.652389 -385.442781) (xy 329.622923 -385.396931)
			(xy 329.600281 -385.347354) (xy 329.584926 -385.295059) (xy 329.57717 -385.241111) (xy 329.576684 -385.21386)
			(xy 327.658984 -385.21386) (xy 327.658984 -385.338828) (xy 327.658498 -385.366079) (xy 327.650742 -385.420027)
			(xy 327.635387 -385.472322) (xy 327.612745 -385.521899) (xy 327.583279 -385.567749) (xy 327.547588 -385.60894)
			(xy 327.506397 -385.644631) (xy 327.460547 -385.674097) (xy 327.41097 -385.696739) (xy 327.358675 -385.712094)
			(xy 327.304727 -385.71985) (xy 327.250225 -385.71985) (xy 327.196277 -385.712094) (xy 327.143982 -385.696739)
			(xy 327.094405 -385.674097) (xy 327.048555 -385.644631) (xy 327.007364 -385.60894) (xy 326.971673 -385.567749)
			(xy 326.942207 -385.521899) (xy 326.919565 -385.472322) (xy 326.90421 -385.420027) (xy 326.896454 -385.366079)
			(xy 326.895968 -385.338828) (xy 297.790858 -385.338828) (xy 297.788355 -385.347354) (xy 297.765713 -385.396931)
			(xy 297.736247 -385.442781) (xy 297.700556 -385.483972) (xy 297.659365 -385.519663) (xy 297.613515 -385.549129)
			(xy 297.563938 -385.571771) (xy 297.511643 -385.587126) (xy 297.457695 -385.594882) (xy 297.403193 -385.594882)
			(xy 297.349245 -385.587126) (xy 297.29695 -385.571771) (xy 297.247373 -385.549129) (xy 297.201523 -385.519663)
			(xy 297.160332 -385.483972) (xy 297.124641 -385.442781) (xy 297.095175 -385.396931) (xy 297.072533 -385.347354)
			(xy 297.057178 -385.295059) (xy 297.049422 -385.241111) (xy 297.048936 -385.21386) (xy 295.055495 -385.21386)
			(xy 295.046477 -385.314778) (xy 295.022713 -385.491474) (xy 294.991102 -385.666937) (xy 294.951706 -385.840817)
			(xy 294.904604 -386.01277) (xy 294.849888 -386.182454) (xy 294.787667 -386.349531) (xy 294.718066 -386.513672)
			(xy 294.641221 -386.674548) (xy 294.557287 -386.831842) (xy 294.466429 -386.985241) (xy 294.368827 -387.13444)
			(xy 294.264676 -387.279143) (xy 294.154183 -387.419063) (xy 294.037566 -387.553922) (xy 293.915057 -387.683452)
			(xy 293.7869 -387.807396) (xy 293.653349 -387.925508) (xy 293.514669 -388.037553) (xy 293.371135 -388.14331)
			(xy 293.223032 -388.242567) (xy 293.070655 -388.335129) (xy 292.914306 -388.42081) (xy 292.754295 -388.499442)
			(xy 292.590941 -388.570868) (xy 292.424566 -388.634946) (xy 292.255503 -388.691548) (xy 292.084086 -388.740564)
			(xy 292.076264 -388.742428) (xy 326.895968 -388.742428) (xy 326.895968 -387.878828) (xy 326.896454 -387.851577)
			(xy 326.90421 -387.797629) (xy 326.919565 -387.745334) (xy 326.942207 -387.695757) (xy 326.971673 -387.649907)
			(xy 327.007364 -387.608716) (xy 327.048555 -387.573025) (xy 327.094405 -387.543559) (xy 327.143982 -387.520917)
			(xy 327.196277 -387.505562) (xy 327.250225 -387.497806) (xy 327.304727 -387.497806) (xy 327.358675 -387.505562)
			(xy 327.41097 -387.520917) (xy 327.460547 -387.543559) (xy 327.506397 -387.573025) (xy 327.547588 -387.608716)
			(xy 327.583279 -387.649907) (xy 327.612745 -387.695757) (xy 327.635387 -387.745334) (xy 327.650742 -387.797629)
			(xy 327.658498 -387.851577) (xy 327.658984 -387.878828) (xy 327.658984 -388.742428) (xy 359.423716 -388.742428)
			(xy 359.423716 -387.878828) (xy 359.424202 -387.851577) (xy 359.431958 -387.797629) (xy 359.447313 -387.745334)
			(xy 359.469955 -387.695757) (xy 359.499421 -387.649907) (xy 359.535112 -387.608716) (xy 359.576303 -387.573025)
			(xy 359.622153 -387.543559) (xy 359.67173 -387.520917) (xy 359.724025 -387.505562) (xy 359.777973 -387.497806)
			(xy 359.832475 -387.497806) (xy 359.886423 -387.505562) (xy 359.938718 -387.520917) (xy 359.988295 -387.543559)
			(xy 360.034145 -387.573025) (xy 360.075336 -387.608716) (xy 360.111027 -387.649907) (xy 360.140493 -387.695757)
			(xy 360.163135 -387.745334) (xy 360.17849 -387.797629) (xy 360.186246 -387.851577) (xy 360.186732 -387.878828)
			(xy 360.186732 -388.742428) (xy 393.996164 -388.742428) (xy 393.996164 -387.878828) (xy 393.99665 -387.851577)
			(xy 394.004406 -387.797629) (xy 394.019761 -387.745334) (xy 394.042403 -387.695757) (xy 394.071869 -387.649907)
			(xy 394.10756 -387.608716) (xy 394.148751 -387.573025) (xy 394.194601 -387.543559) (xy 394.244178 -387.520917)
			(xy 394.296473 -387.505562) (xy 394.350421 -387.497806) (xy 394.404923 -387.497806) (xy 394.458871 -387.505562)
			(xy 394.511166 -387.520917) (xy 394.560743 -387.543559) (xy 394.606593 -387.573025) (xy 394.647784 -387.608716)
			(xy 394.683475 -387.649907) (xy 394.712941 -387.695757) (xy 394.735583 -387.745334) (xy 394.750938 -387.797629)
			(xy 394.758694 -387.851577) (xy 394.75918 -387.878828) (xy 394.75918 -388.742428) (xy 426.523912 -388.742428)
			(xy 426.523912 -387.878828) (xy 426.524398 -387.851577) (xy 426.532154 -387.797629) (xy 426.547509 -387.745334)
			(xy 426.570151 -387.695757) (xy 426.599617 -387.649907) (xy 426.635308 -387.608716) (xy 426.676499 -387.573025)
			(xy 426.722349 -387.543559) (xy 426.771926 -387.520917) (xy 426.824221 -387.505562) (xy 426.878169 -387.497806)
			(xy 426.932671 -387.497806) (xy 426.986619 -387.505562) (xy 427.038914 -387.520917) (xy 427.088491 -387.543559)
			(xy 427.134341 -387.573025) (xy 427.175532 -387.608716) (xy 427.211223 -387.649907) (xy 427.240689 -387.695757)
			(xy 427.263331 -387.745334) (xy 427.278686 -387.797629) (xy 427.286442 -387.851577) (xy 427.286928 -387.878828)
			(xy 427.286928 -388.742428) (xy 427.286442 -388.769679) (xy 427.278686 -388.823627) (xy 427.263331 -388.875922)
			(xy 427.240689 -388.925499) (xy 427.211223 -388.971349) (xy 427.175532 -389.01254) (xy 427.134341 -389.048231)
			(xy 427.088491 -389.077697) (xy 427.038914 -389.100339) (xy 426.986619 -389.115694) (xy 426.932671 -389.12345)
			(xy 426.878169 -389.12345) (xy 426.824221 -389.115694) (xy 426.771926 -389.100339) (xy 426.722349 -389.077697)
			(xy 426.676499 -389.048231) (xy 426.635308 -389.01254) (xy 426.599617 -388.971349) (xy 426.570151 -388.925499)
			(xy 426.547509 -388.875922) (xy 426.532154 -388.823627) (xy 426.524398 -388.769679) (xy 426.523912 -388.742428)
			(xy 394.75918 -388.742428) (xy 394.758694 -388.769679) (xy 394.750938 -388.823627) (xy 394.735583 -388.875922)
			(xy 394.712941 -388.925499) (xy 394.683475 -388.971349) (xy 394.647784 -389.01254) (xy 394.606593 -389.048231)
			(xy 394.560743 -389.077697) (xy 394.511166 -389.100339) (xy 394.458871 -389.115694) (xy 394.404923 -389.12345)
			(xy 394.350421 -389.12345) (xy 394.296473 -389.115694) (xy 394.244178 -389.100339) (xy 394.194601 -389.077697)
			(xy 394.148751 -389.048231) (xy 394.10756 -389.01254) (xy 394.071869 -388.971349) (xy 394.042403 -388.925499)
			(xy 394.019761 -388.875922) (xy 394.004406 -388.823627) (xy 393.99665 -388.769679) (xy 393.996164 -388.742428)
			(xy 360.186732 -388.742428) (xy 360.186246 -388.769679) (xy 360.17849 -388.823627) (xy 360.163135 -388.875922)
			(xy 360.140493 -388.925499) (xy 360.111027 -388.971349) (xy 360.075336 -389.01254) (xy 360.034145 -389.048231)
			(xy 359.988295 -389.077697) (xy 359.938718 -389.100339) (xy 359.886423 -389.115694) (xy 359.832475 -389.12345)
			(xy 359.777973 -389.12345) (xy 359.724025 -389.115694) (xy 359.67173 -389.100339) (xy 359.622153 -389.077697)
			(xy 359.576303 -389.048231) (xy 359.535112 -389.01254) (xy 359.499421 -388.971349) (xy 359.469955 -388.925499)
			(xy 359.447313 -388.875922) (xy 359.431958 -388.823627) (xy 359.424202 -388.769679) (xy 359.423716 -388.742428)
			(xy 327.658984 -388.742428) (xy 327.658498 -388.769679) (xy 327.650742 -388.823627) (xy 327.635387 -388.875922)
			(xy 327.612745 -388.925499) (xy 327.583279 -388.971349) (xy 327.547588 -389.01254) (xy 327.506397 -389.048231)
			(xy 327.460547 -389.077697) (xy 327.41097 -389.100339) (xy 327.358675 -389.115694) (xy 327.304727 -389.12345)
			(xy 327.250225 -389.12345) (xy 327.196277 -389.115694) (xy 327.143982 -389.100339) (xy 327.094405 -389.077697)
			(xy 327.048555 -389.048231) (xy 327.007364 -389.01254) (xy 326.971673 -388.971349) (xy 326.942207 -388.925499)
			(xy 326.919565 -388.875922) (xy 326.90421 -388.823627) (xy 326.896454 -388.769679) (xy 326.895968 -388.742428)
			(xy 292.076264 -388.742428) (xy 291.910655 -388.781894) (xy 291.735555 -388.815458) (xy 291.559135 -388.841188)
			(xy 291.381743 -388.859034) (xy 291.203732 -388.86896) (xy 291.025455 -388.870946) (xy 290.847268 -388.864989)
			(xy 290.669522 -388.851099) (xy 290.492572 -388.829306) (xy 290.316768 -388.799652) (xy 290.14246 -388.762195)
			(xy 289.969993 -388.717011) (xy 289.79971 -388.664189) (xy 289.631949 -388.603833) (xy 289.467044 -388.536065)
			(xy 289.305321 -388.461017) (xy 289.147102 -388.37884) (xy 288.992701 -388.289697) (xy 288.842424 -388.193763)
			(xy 288.696569 -388.091231) (xy 288.555427 -387.982303) (xy 288.419278 -387.867196) (xy 288.288391 -387.746138)
			(xy 288.163027 -387.619369) (xy 288.043434 -387.487142) (xy 287.929851 -387.349719) (xy 287.822502 -387.207372)
			(xy 287.721601 -387.060384) (xy 287.627348 -386.909048) (xy 287.53993 -386.753663) (xy 287.45952 -386.594538)
			(xy 287.386279 -386.431989) (xy 287.320352 -386.266339) (xy 287.261869 -386.097917) (xy 287.210947 -385.927056)
			(xy 287.167687 -385.754097) (xy 287.132175 -385.579382) (xy 287.104481 -385.403258) (xy 287.08466 -385.226076)
			(xy 287.072752 -385.048187) (xy 287.06878 -384.869944) (xy 281.2288 -384.869944) (xy 281.2288 -387.36016)
			(xy 281.229256 -387.369896) (xy 281.236578 -387.387944) (xy 281.250076 -387.401984) (xy 281.258772 -387.406388)
			(xy 281.283524 -387.41805) (xy 281.329666 -387.447457) (xy 281.371135 -387.483154) (xy 281.407078 -387.524408)
			(xy 281.43676 -387.570374) (xy 281.45957 -387.620109) (xy 281.475042 -387.672592) (xy 281.482858 -387.726748)
			(xy 281.482857 -387.781464) (xy 281.47504 -387.835619) (xy 281.459566 -387.888102) (xy 281.436754 -387.937836)
			(xy 281.407071 -387.983801) (xy 281.371126 -388.025055) (xy 281.329657 -388.06075) (xy 281.283514 -388.090155)
			(xy 281.258772 -388.10184) (xy 281.250056 -388.106224) (xy 281.23652 -388.120246) (xy 281.229232 -388.138322)
			(xy 281.2288 -388.148068) (xy 281.2288 -390.75106) (xy 297.048936 -390.75106) (xy 297.048936 -389.88746)
			(xy 297.049422 -389.860209) (xy 297.057178 -389.806261) (xy 297.072533 -389.753966) (xy 297.095175 -389.704389)
			(xy 297.124641 -389.658539) (xy 297.160332 -389.617348) (xy 297.201523 -389.581657) (xy 297.247373 -389.552191)
			(xy 297.29695 -389.529549) (xy 297.349245 -389.514194) (xy 297.403193 -389.506438) (xy 297.457695 -389.506438)
			(xy 297.511643 -389.514194) (xy 297.563938 -389.529549) (xy 297.613515 -389.552191) (xy 297.659365 -389.581657)
			(xy 297.700556 -389.617348) (xy 297.736247 -389.658539) (xy 297.765713 -389.704389) (xy 297.788355 -389.753966)
			(xy 297.80371 -389.806261) (xy 297.811466 -389.860209) (xy 297.811952 -389.88746) (xy 297.811952 -390.75106)
			(xy 329.576684 -390.75106) (xy 329.576684 -389.88746) (xy 329.57717 -389.860209) (xy 329.584926 -389.806261)
			(xy 329.600281 -389.753966) (xy 329.622923 -389.704389) (xy 329.652389 -389.658539) (xy 329.68808 -389.617348)
			(xy 329.729271 -389.581657) (xy 329.775121 -389.552191) (xy 329.824698 -389.529549) (xy 329.876993 -389.514194)
			(xy 329.930941 -389.506438) (xy 329.985443 -389.506438) (xy 330.039391 -389.514194) (xy 330.091686 -389.529549)
			(xy 330.141263 -389.552191) (xy 330.187113 -389.581657) (xy 330.228304 -389.617348) (xy 330.263995 -389.658539)
			(xy 330.293461 -389.704389) (xy 330.316103 -389.753966) (xy 330.331458 -389.806261) (xy 330.339214 -389.860209)
			(xy 330.3397 -389.88746) (xy 330.3397 -390.75106) (xy 364.149132 -390.75106) (xy 364.149132 -389.88746)
			(xy 364.149618 -389.860209) (xy 364.157374 -389.806261) (xy 364.172729 -389.753966) (xy 364.195371 -389.704389)
			(xy 364.224837 -389.658539) (xy 364.260528 -389.617348) (xy 364.301719 -389.581657) (xy 364.347569 -389.552191)
			(xy 364.397146 -389.529549) (xy 364.449441 -389.514194) (xy 364.503389 -389.506438) (xy 364.557891 -389.506438)
			(xy 364.611839 -389.514194) (xy 364.664134 -389.529549) (xy 364.713711 -389.552191) (xy 364.759561 -389.581657)
			(xy 364.800752 -389.617348) (xy 364.836443 -389.658539) (xy 364.865909 -389.704389) (xy 364.888551 -389.753966)
			(xy 364.903906 -389.806261) (xy 364.911662 -389.860209) (xy 364.912148 -389.88746) (xy 364.912148 -390.75106)
			(xy 396.67688 -390.75106) (xy 396.67688 -389.88746) (xy 396.677366 -389.860209) (xy 396.685122 -389.806261)
			(xy 396.700477 -389.753966) (xy 396.723119 -389.704389) (xy 396.752585 -389.658539) (xy 396.788276 -389.617348)
			(xy 396.829467 -389.581657) (xy 396.875317 -389.552191) (xy 396.924894 -389.529549) (xy 396.977189 -389.514194)
			(xy 397.031137 -389.506438) (xy 397.085639 -389.506438) (xy 397.139587 -389.514194) (xy 397.191882 -389.529549)
			(xy 397.241459 -389.552191) (xy 397.287309 -389.581657) (xy 397.3285 -389.617348) (xy 397.364191 -389.658539)
			(xy 397.393657 -389.704389) (xy 397.416299 -389.753966) (xy 397.431654 -389.806261) (xy 397.43941 -389.860209)
			(xy 397.439896 -389.88746) (xy 397.439896 -390.75106) (xy 397.43941 -390.778311) (xy 397.431654 -390.832259)
			(xy 397.416299 -390.884554) (xy 397.393657 -390.934131) (xy 397.364191 -390.979981) (xy 397.3285 -391.021172)
			(xy 397.287309 -391.056863) (xy 397.241459 -391.086329) (xy 397.191882 -391.108971) (xy 397.139587 -391.124326)
			(xy 397.085639 -391.132082) (xy 397.031137 -391.132082) (xy 396.977189 -391.124326) (xy 396.924894 -391.108971)
			(xy 396.875317 -391.086329) (xy 396.829467 -391.056863) (xy 396.788276 -391.021172) (xy 396.752585 -390.979981)
			(xy 396.723119 -390.934131) (xy 396.700477 -390.884554) (xy 396.685122 -390.832259) (xy 396.677366 -390.778311)
			(xy 396.67688 -390.75106) (xy 364.912148 -390.75106) (xy 364.911662 -390.778311) (xy 364.903906 -390.832259)
			(xy 364.888551 -390.884554) (xy 364.865909 -390.934131) (xy 364.836443 -390.979981) (xy 364.800752 -391.021172)
			(xy 364.759561 -391.056863) (xy 364.713711 -391.086329) (xy 364.664134 -391.108971) (xy 364.611839 -391.124326)
			(xy 364.557891 -391.132082) (xy 364.503389 -391.132082) (xy 364.449441 -391.124326) (xy 364.397146 -391.108971)
			(xy 364.347569 -391.086329) (xy 364.301719 -391.056863) (xy 364.260528 -391.021172) (xy 364.224837 -390.979981)
			(xy 364.195371 -390.934131) (xy 364.172729 -390.884554) (xy 364.157374 -390.832259) (xy 364.149618 -390.778311)
			(xy 364.149132 -390.75106) (xy 330.3397 -390.75106) (xy 330.339214 -390.778311) (xy 330.331458 -390.832259)
			(xy 330.316103 -390.884554) (xy 330.293461 -390.934131) (xy 330.263995 -390.979981) (xy 330.228304 -391.021172)
			(xy 330.187113 -391.056863) (xy 330.141263 -391.086329) (xy 330.091686 -391.108971) (xy 330.039391 -391.124326)
			(xy 329.985443 -391.132082) (xy 329.930941 -391.132082) (xy 329.876993 -391.124326) (xy 329.824698 -391.108971)
			(xy 329.775121 -391.086329) (xy 329.729271 -391.056863) (xy 329.68808 -391.021172) (xy 329.652389 -390.979981)
			(xy 329.622923 -390.934131) (xy 329.600281 -390.884554) (xy 329.584926 -390.832259) (xy 329.57717 -390.778311)
			(xy 329.576684 -390.75106) (xy 297.811952 -390.75106) (xy 297.811466 -390.778311) (xy 297.80371 -390.832259)
			(xy 297.788355 -390.884554) (xy 297.765713 -390.934131) (xy 297.736247 -390.979981) (xy 297.700556 -391.021172)
			(xy 297.659365 -391.056863) (xy 297.613515 -391.086329) (xy 297.563938 -391.108971) (xy 297.511643 -391.124326)
			(xy 297.457695 -391.132082) (xy 297.403193 -391.132082) (xy 297.349245 -391.124326) (xy 297.29695 -391.108971)
			(xy 297.247373 -391.086329) (xy 297.201523 -391.056863) (xy 297.160332 -391.021172) (xy 297.124641 -390.979981)
			(xy 297.095175 -390.934131) (xy 297.072533 -390.884554) (xy 297.057178 -390.832259) (xy 297.049422 -390.778311)
			(xy 297.048936 -390.75106) (xy 281.2288 -390.75106) (xy 281.2288 -392.180572) (xy 281.228283 -392.20552)
			(xy 281.220475 -392.254803) (xy 281.205064 -392.30226) (xy 281.182426 -392.346726) (xy 281.153119 -392.387109)
			(xy 281.135836 -392.405108) (xy 280.810462 -392.730482) (xy 280.803632 -392.73789) (xy 280.795908 -392.756483)
			(xy 280.795476 -392.76655) (xy 280.795476 -393.110974) (xy 280.794938 -393.135921) (xy 280.787132 -393.185202)
			(xy 280.771724 -393.232658) (xy 280.749092 -393.277124) (xy 280.719792 -393.31751) (xy 280.702512 -393.33551)
			(xy 280.345134 -393.692888) (xy 303.485804 -393.692888) (xy 303.485804 -393.69238) (xy 303.486244 -393.668388)
			(xy 303.493754 -393.620994) (xy 303.508585 -393.575359) (xy 303.530372 -393.532605) (xy 303.558579 -393.493786)
			(xy 303.592511 -393.459858) (xy 303.631333 -393.431655) (xy 303.674088 -393.409872) (xy 303.719725 -393.395046)
			(xy 303.76712 -393.387542) (xy 303.791112 -393.387072) (xy 303.815046 -393.38757) (xy 303.862329 -393.395022)
			(xy 303.907871 -393.409757) (xy 303.950558 -393.431416) (xy 303.989344 -393.459467) (xy 304.02328 -393.493224)
			(xy 304.051536 -393.531861) (xy 304.062892 -393.552934) (xy 304.0634 -393.55395) (xy 304.143706 -393.692888)
			(xy 304.6857 -393.692888) (xy 304.6857 -393.69238) (xy 304.686144 -393.668388) (xy 304.693654 -393.620995)
			(xy 304.708484 -393.57536) (xy 304.730271 -393.532606) (xy 304.758477 -393.493788) (xy 304.792409 -393.459859)
			(xy 304.83123 -393.431656) (xy 304.873986 -393.409873) (xy 304.919622 -393.395047) (xy 304.967016 -393.387542)
			(xy 304.991008 -393.387072) (xy 305.014941 -393.387573) (xy 305.062224 -393.395024) (xy 305.107767 -393.409759)
			(xy 305.150453 -393.431417) (xy 305.189239 -393.459468) (xy 305.223176 -393.493224) (xy 305.251432 -393.531861)
			(xy 305.262788 -393.552934) (xy 305.263296 -393.55395) (xy 305.343602 -393.692888) (xy 305.885596 -393.692888)
			(xy 305.885596 -393.69238) (xy 305.886021 -393.668373) (xy 305.893538 -393.620952) (xy 305.908385 -393.575292)
			(xy 305.930196 -393.532519) (xy 305.958432 -393.493686) (xy 305.992398 -393.459751) (xy 306.031256 -393.43155)
			(xy 306.07405 -393.409779) (xy 306.119723 -393.394973) (xy 306.167151 -393.387499) (xy 306.191158 -393.387072)
			(xy 306.215093 -393.387532) (xy 306.262378 -393.394992) (xy 306.307921 -393.409734) (xy 306.350607 -393.431398)
			(xy 306.389393 -393.459455) (xy 306.423328 -393.493217) (xy 306.451583 -393.531859) (xy 306.462938 -393.552934)
			(xy 306.463446 -393.55395) (xy 306.543752 -393.692888) (xy 307.085492 -393.692888) (xy 307.085492 -393.69238)
			(xy 307.085921 -393.668374) (xy 307.093438 -393.620953) (xy 307.108285 -393.575293) (xy 307.130095 -393.53252)
			(xy 307.158331 -393.493687) (xy 307.192296 -393.459752) (xy 307.231154 -393.431552) (xy 307.273947 -393.40978)
			(xy 307.31962 -393.394974) (xy 307.367047 -393.387499) (xy 307.391054 -393.387072) (xy 307.414989 -393.387536)
			(xy 307.462274 -393.394994) (xy 307.507817 -393.409736) (xy 307.550503 -393.4314) (xy 307.589289 -393.459456)
			(xy 307.623224 -393.493218) (xy 307.651479 -393.531859) (xy 307.662834 -393.552934) (xy 307.663342 -393.55395)
			(xy 307.743648 -393.692888) (xy 308.285388 -393.692888) (xy 308.285388 -393.69238) (xy 308.285821 -393.668374)
			(xy 308.293338 -393.620954) (xy 308.308185 -393.575294) (xy 308.329994 -393.532521) (xy 308.35823 -393.493689)
			(xy 308.392194 -393.459754) (xy 308.431052 -393.431553) (xy 308.473844 -393.409781) (xy 308.519517 -393.394975)
			(xy 308.566943 -393.3875) (xy 308.59095 -393.387072) (xy 308.614885 -393.387539) (xy 308.662169 -393.394997)
			(xy 308.707712 -393.409738) (xy 308.750399 -393.431401) (xy 308.789184 -393.459457) (xy 308.82312 -393.493218)
			(xy 308.851375 -393.531859) (xy 308.86273 -393.552934) (xy 308.863238 -393.55395) (xy 308.943544 -393.692888)
			(xy 309.485792 -393.692888) (xy 309.485792 -393.69238) (xy 309.486244 -393.668388) (xy 309.493753 -393.620996)
			(xy 309.508583 -393.575362) (xy 309.530369 -393.532609) (xy 309.558575 -393.49379) (xy 309.592506 -393.459862)
			(xy 309.631326 -393.431659) (xy 309.67408 -393.409876) (xy 309.719715 -393.395049) (xy 309.767108 -393.387543)
			(xy 309.7911 -393.387072) (xy 309.815033 -393.38758) (xy 309.862316 -393.39503) (xy 309.907858 -393.409764)
			(xy 309.950544 -393.43142) (xy 309.989331 -393.45947) (xy 310.023268 -393.493226) (xy 310.051524 -393.531862)
			(xy 310.06288 -393.552934) (xy 310.063388 -393.55395) (xy 310.143694 -393.692888) (xy 310.685688 -393.692888)
			(xy 310.685688 -393.69238) (xy 310.686144 -393.668388) (xy 310.693653 -393.620996) (xy 310.708483 -393.575362)
			(xy 310.730269 -393.53261) (xy 310.758474 -393.493792) (xy 310.792404 -393.459863) (xy 310.831224 -393.43166)
			(xy 310.873977 -393.409877) (xy 310.919612 -393.395049) (xy 310.967004 -393.387543) (xy 310.990996 -393.387072)
			(xy 311.014932 -393.387502) (xy 311.062218 -393.394966) (xy 311.107762 -393.409714) (xy 311.150449 -393.431384)
			(xy 311.189234 -393.459445) (xy 311.223168 -393.493212) (xy 311.251422 -393.531857) (xy 311.262776 -393.552934)
			(xy 311.263284 -393.55395) (xy 311.34359 -393.692888) (xy 311.885584 -393.692888) (xy 311.885584 -393.69238)
			(xy 311.886021 -393.668374) (xy 311.893538 -393.620954) (xy 311.908384 -393.575295) (xy 311.930194 -393.532522)
			(xy 311.958428 -393.49369) (xy 311.992393 -393.459755) (xy 312.03125 -393.431554) (xy 312.074041 -393.409782)
			(xy 312.119713 -393.394976) (xy 312.16714 -393.3875) (xy 312.191146 -393.387072) (xy 312.215081 -393.387542)
			(xy 312.262365 -393.394999) (xy 312.307908 -393.40974) (xy 312.350594 -393.431403) (xy 312.38938 -393.459458)
			(xy 312.423316 -393.493219) (xy 312.451571 -393.531859) (xy 312.462926 -393.552934) (xy 312.463434 -393.55395)
			(xy 312.54374 -393.692888) (xy 313.08548 -393.692888) (xy 313.08548 -393.69238) (xy 313.085921 -393.668374)
			(xy 313.093438 -393.620955) (xy 313.108284 -393.575296) (xy 313.130093 -393.532524) (xy 313.158327 -393.493692)
			(xy 313.192291 -393.459757) (xy 313.231147 -393.431556) (xy 313.273939 -393.409783) (xy 313.31961 -393.394977)
			(xy 313.367036 -393.3875) (xy 313.391042 -393.387072) (xy 313.391296 -393.387072) (xy 313.415232 -393.387502)
			(xy 313.462518 -393.394966) (xy 313.508062 -393.409714) (xy 313.550749 -393.431384) (xy 313.589534 -393.459445)
			(xy 313.623468 -393.493212) (xy 313.651722 -393.531857) (xy 313.663076 -393.552934) (xy 313.663584 -393.55395)
			(xy 313.74389 -393.692888) (xy 314.285376 -393.692888) (xy 314.285376 -393.69238) (xy 314.285821 -393.668374)
			(xy 314.293338 -393.620955) (xy 314.308183 -393.575297) (xy 314.329992 -393.532525) (xy 314.358226 -393.493693)
			(xy 314.392189 -393.459758) (xy 314.431045 -393.431557) (xy 314.473836 -393.409785) (xy 314.519507 -393.394977)
			(xy 314.566932 -393.3875) (xy 314.590938 -393.387072) (xy 314.591192 -393.387072) (xy 314.615128 -393.387505)
			(xy 314.662414 -393.394969) (xy 314.707958 -393.409716) (xy 314.750644 -393.431385) (xy 314.78943 -393.459446)
			(xy 314.823364 -393.493212) (xy 314.851618 -393.531857) (xy 314.862972 -393.552934) (xy 314.86348 -393.55395)
			(xy 314.943786 -393.692888) (xy 315.48578 -393.692888) (xy 315.48578 -393.69238) (xy 315.486244 -393.668389)
			(xy 315.493753 -393.620998) (xy 315.508582 -393.575364) (xy 315.530367 -393.532612) (xy 315.558571 -393.493795)
			(xy 315.592501 -393.459866) (xy 315.631319 -393.431663) (xy 315.674072 -393.409879) (xy 315.719705 -393.395051)
			(xy 315.767097 -393.387543) (xy 315.791088 -393.387072) (xy 315.791342 -393.387072) (xy 315.815276 -393.387545)
			(xy 315.862561 -393.395002) (xy 315.908103 -393.409742) (xy 315.95079 -393.431404) (xy 315.989576 -393.459459)
			(xy 316.023512 -393.49322) (xy 316.051767 -393.53186) (xy 316.063122 -393.552934) (xy 316.06363 -393.55395)
			(xy 316.143936 -393.692888) (xy 316.685676 -393.692888) (xy 316.685676 -393.69238) (xy 316.686144 -393.668389)
			(xy 316.693653 -393.620998) (xy 316.708482 -393.575365) (xy 316.730267 -393.532614) (xy 316.75847 -393.493796)
			(xy 316.792399 -393.459868) (xy 316.831217 -393.431664) (xy 316.873969 -393.40988) (xy 316.919602 -393.395052)
			(xy 316.966993 -393.387544) (xy 316.990984 -393.387072) (xy 316.991238 -393.387072) (xy 317.015172 -393.387549)
			(xy 317.062456 -393.395005) (xy 317.107999 -393.409744) (xy 317.150686 -393.431406) (xy 317.189472 -393.45946)
			(xy 317.223407 -393.49322) (xy 317.251663 -393.53186) (xy 317.263018 -393.552934) (xy 317.263526 -393.55395)
			(xy 317.343832 -393.692888) (xy 317.885572 -393.692888) (xy 317.885572 -393.69238) (xy 317.886021 -393.668375)
			(xy 317.893538 -393.620956) (xy 317.908383 -393.575298) (xy 317.930191 -393.532526) (xy 317.958425 -393.493694)
			(xy 317.992388 -393.45976) (xy 318.031243 -393.431558) (xy 318.074033 -393.409786) (xy 318.119703 -393.394978)
			(xy 318.167128 -393.387501) (xy 318.191134 -393.387072) (xy 318.215068 -393.387552) (xy 318.262352 -393.395007)
			(xy 318.307895 -393.409746) (xy 318.350581 -393.431407) (xy 318.389367 -393.459461) (xy 318.423303 -393.493221)
			(xy 318.451559 -393.53186) (xy 318.462914 -393.552934) (xy 318.463422 -393.55395) (xy 318.543728 -393.692888)
			(xy 319.085468 -393.692888) (xy 319.085468 -393.69238) (xy 319.085921 -393.668375) (xy 319.093437 -393.620957)
			(xy 319.108283 -393.575299) (xy 319.130091 -393.532527) (xy 319.158324 -393.493696) (xy 319.192286 -393.459761)
			(xy 319.231141 -393.43156) (xy 319.27393 -393.409787) (xy 319.3196 -393.394979) (xy 319.367024 -393.387501)
			(xy 319.39103 -393.387072) (xy 319.391284 -393.387072) (xy 319.41522 -393.387511) (xy 319.462506 -393.394974)
			(xy 319.508049 -393.40972) (xy 319.550736 -393.431388) (xy 319.589521 -393.459448) (xy 319.623456 -393.493214)
			(xy 319.65171 -393.531858) (xy 319.663064 -393.552934) (xy 319.663572 -393.55395) (xy 319.743878 -393.692888)
			(xy 320.285872 -393.692888) (xy 320.285872 -393.69238) (xy 320.286344 -393.668389) (xy 320.293853 -393.620999)
			(xy 320.308681 -393.575366) (xy 320.330466 -393.532615) (xy 320.358669 -393.493797) (xy 320.392597 -393.459869)
			(xy 320.431415 -393.431666) (xy 320.474166 -393.409881) (xy 320.519799 -393.395053) (xy 320.567189 -393.387544)
			(xy 320.59118 -393.387072) (xy 320.615116 -393.387515) (xy 320.662401 -393.394977) (xy 320.707945 -393.409722)
			(xy 320.750631 -393.43139) (xy 320.789417 -393.459449) (xy 320.823352 -393.493214) (xy 320.851606 -393.531858)
			(xy 320.86296 -393.552934) (xy 320.863468 -393.55395) (xy 320.943774 -393.692888) (xy 321.485768 -393.692888)
			(xy 321.485768 -393.69238) (xy 321.486244 -393.668389) (xy 321.493752 -393.620999) (xy 321.508581 -393.575367)
			(xy 321.530365 -393.532616) (xy 321.558568 -393.493799) (xy 321.592496 -393.459871) (xy 321.631313 -393.431667)
			(xy 321.674063 -393.409883) (xy 321.719695 -393.395053) (xy 321.767085 -393.387544) (xy 321.791076 -393.387072)
			(xy 321.79133 -393.387072) (xy 321.815264 -393.387555) (xy 321.862548 -393.39501) (xy 321.90809 -393.409748)
			(xy 321.950777 -393.431409) (xy 321.989563 -393.459462) (xy 322.023499 -393.493221) (xy 322.051755 -393.53186)
			(xy 322.06311 -393.552934) (xy 322.063618 -393.55395) (xy 322.143924 -393.692888) (xy 336.013552 -393.692888)
			(xy 336.013552 -393.69238) (xy 336.014044 -393.66839) (xy 336.021552 -393.621002) (xy 336.03638 -393.575371)
			(xy 336.058162 -393.532621) (xy 336.086363 -393.493804) (xy 336.120289 -393.459876) (xy 336.159104 -393.431673)
			(xy 336.201852 -393.409887) (xy 336.247482 -393.395057) (xy 336.29487 -393.387546) (xy 336.31886 -393.387072)
			(xy 336.342795 -393.387531) (xy 336.39008 -393.39499) (xy 336.435623 -393.409733) (xy 336.47831 -393.431398)
			(xy 336.517095 -393.459455) (xy 336.551031 -393.493217) (xy 336.579285 -393.531859) (xy 336.59064 -393.552934)
			(xy 336.591148 -393.55395) (xy 336.671454 -393.692888) (xy 337.213448 -393.692888) (xy 337.213448 -393.69238)
			(xy 337.213944 -393.66839) (xy 337.221452 -393.621002) (xy 337.236279 -393.575372) (xy 337.258061 -393.532622)
			(xy 337.286262 -393.493805) (xy 337.320187 -393.459878) (xy 337.359001 -393.431674) (xy 337.401749 -393.409888)
			(xy 337.447379 -393.395057) (xy 337.494766 -393.387546) (xy 337.518756 -393.387072) (xy 337.542691 -393.387534)
			(xy 337.589976 -393.394993) (xy 337.635519 -393.409735) (xy 337.678205 -393.431399) (xy 337.716991 -393.459456)
			(xy 337.750926 -393.493218) (xy 337.779181 -393.531859) (xy 337.790536 -393.552934) (xy 337.791044 -393.55395)
			(xy 337.87135 -393.692888) (xy 338.413344 -393.692888) (xy 338.413344 -393.69238) (xy 338.41382 -393.668376)
			(xy 338.421337 -393.62096) (xy 338.43618 -393.575304) (xy 338.457986 -393.532534) (xy 338.486217 -393.493704)
			(xy 338.520176 -393.45977) (xy 338.559027 -393.431568) (xy 338.601814 -393.409794) (xy 338.64748 -393.394984)
			(xy 338.694902 -393.387503) (xy 338.718906 -393.387072) (xy 338.742839 -393.387575) (xy 338.790122 -393.395026)
			(xy 338.835664 -393.40976) (xy 338.878351 -393.431418) (xy 338.917137 -393.459468) (xy 338.951074 -393.493225)
			(xy 338.97933 -393.531861) (xy 338.990686 -393.552934) (xy 338.991194 -393.55395) (xy 339.0715 -393.692888)
			(xy 339.61324 -393.692888) (xy 339.61324 -393.69238) (xy 339.613621 -393.668371) (xy 339.62114 -393.620946)
			(xy 339.63599 -393.575282) (xy 339.657804 -393.532506) (xy 339.686045 -393.493671) (xy 339.720016 -393.459735)
			(xy 339.758881 -393.431535) (xy 339.80168 -393.409766) (xy 339.84736 -393.394965) (xy 339.894793 -393.387496)
			(xy 339.918802 -393.387072) (xy 339.942735 -393.387578) (xy 339.990018 -393.395028) (xy 340.03556 -393.409763)
			(xy 340.078247 -393.43142) (xy 340.117033 -393.459469) (xy 340.15097 -393.493225) (xy 340.179226 -393.531861)
			(xy 340.190582 -393.552934) (xy 340.19109 -393.55395) (xy 340.271396 -393.692888) (xy 340.813136 -393.692888)
			(xy 340.813136 -393.69238) (xy 340.813521 -393.668371) (xy 340.82104 -393.620947) (xy 340.835889 -393.575283)
			(xy 340.857703 -393.532507) (xy 340.885944 -393.493672) (xy 340.919915 -393.459737) (xy 340.958779 -393.431537)
			(xy 341.001577 -393.409767) (xy 341.047256 -393.394965) (xy 341.094689 -393.387496) (xy 341.118698 -393.387072)
			(xy 341.142634 -393.3875) (xy 341.189921 -393.394965) (xy 341.235464 -393.409713) (xy 341.278151 -393.431383)
			(xy 341.316936 -393.459445) (xy 341.35087 -393.493212) (xy 341.379124 -393.531857) (xy 341.390478 -393.552934)
			(xy 341.390986 -393.55395) (xy 341.471292 -393.692888) (xy 342.01354 -393.692888) (xy 342.01354 -393.69238)
			(xy 342.01392 -393.668384) (xy 342.021431 -393.620983) (xy 342.036265 -393.575341) (xy 342.058057 -393.532582)
			(xy 342.08627 -393.493758) (xy 342.12021 -393.459826) (xy 342.15904 -393.431622) (xy 342.201804 -393.409839)
			(xy 342.247449 -393.395015) (xy 342.294852 -393.387515) (xy 342.318848 -393.387072) (xy 342.342783 -393.387541)
			(xy 342.390067 -393.394998) (xy 342.43561 -393.409739) (xy 342.478297 -393.431402) (xy 342.517082 -393.459458)
			(xy 342.551018 -393.493219) (xy 342.579273 -393.531859) (xy 342.590628 -393.552934) (xy 342.591136 -393.55395)
			(xy 342.671442 -393.692888) (xy 343.213436 -393.692888) (xy 343.213436 -393.69238) (xy 343.21382 -393.668384)
			(xy 343.221331 -393.620984) (xy 343.236165 -393.575342) (xy 343.257957 -393.532583) (xy 343.286169 -393.493759)
			(xy 343.320108 -393.459828) (xy 343.358938 -393.431623) (xy 343.401701 -393.40984) (xy 343.447346 -393.395016)
			(xy 343.494748 -393.387515) (xy 343.518744 -393.387072) (xy 343.542678 -393.387544) (xy 343.589963 -393.395001)
			(xy 343.635506 -393.409741) (xy 343.678192 -393.431404) (xy 343.716978 -393.459459) (xy 343.750914 -393.493219)
			(xy 343.779169 -393.53186) (xy 343.790524 -393.552934) (xy 343.791032 -393.55395) (xy 343.871338 -393.692888)
			(xy 344.413332 -393.692888) (xy 344.413332 -393.69238) (xy 344.413721 -393.668372) (xy 344.42124 -393.620947)
			(xy 344.436089 -393.575284) (xy 344.457902 -393.532508) (xy 344.486142 -393.493674) (xy 344.520113 -393.459738)
			(xy 344.558976 -393.431538) (xy 344.601775 -393.409769) (xy 344.647453 -393.394966) (xy 344.694885 -393.387496)
			(xy 344.718894 -393.387072) (xy 344.74283 -393.387503) (xy 344.790116 -393.394968) (xy 344.83566 -393.409715)
			(xy 344.878347 -393.431385) (xy 344.917132 -393.459446) (xy 344.951066 -393.493212) (xy 344.97932 -393.531857)
			(xy 344.990674 -393.552934) (xy 344.991182 -393.55395) (xy 345.071488 -393.692888) (xy 345.613228 -393.692888)
			(xy 345.613228 -393.69238) (xy 345.613621 -393.668372) (xy 345.621139 -393.620948) (xy 345.635988 -393.575285)
			(xy 345.657802 -393.532509) (xy 345.686041 -393.493675) (xy 345.720011 -393.45974) (xy 345.758874 -393.431539)
			(xy 345.801672 -393.40977) (xy 345.84735 -393.394967) (xy 345.894781 -393.387497) (xy 345.91879 -393.387072)
			(xy 345.942726 -393.387506) (xy 345.990012 -393.39497) (xy 346.035556 -393.409717) (xy 346.078242 -393.431386)
			(xy 346.117027 -393.459447) (xy 346.150962 -393.493213) (xy 346.179216 -393.531857) (xy 346.19057 -393.552934)
			(xy 346.191078 -393.55395) (xy 346.271384 -393.692888) (xy 346.813124 -393.692888) (xy 346.813124 -393.69238)
			(xy 346.813521 -393.668372) (xy 346.821039 -393.620948) (xy 346.835888 -393.575286) (xy 346.857701 -393.53251)
			(xy 346.88594 -393.493676) (xy 346.919909 -393.459741) (xy 346.958772 -393.431541) (xy 347.001569 -393.409771)
			(xy 347.047246 -393.394968) (xy 347.094678 -393.387497) (xy 347.118686 -393.387072) (xy 347.142622 -393.38751)
			(xy 347.189908 -393.394973) (xy 347.235451 -393.409719) (xy 347.278138 -393.431388) (xy 347.316923 -393.459448)
			(xy 347.350858 -393.493213) (xy 347.379112 -393.531858) (xy 347.390466 -393.552934) (xy 347.390974 -393.55395)
			(xy 347.47128 -393.692888) (xy 348.013528 -393.692888) (xy 348.013528 -393.69238) (xy 348.01392 -393.668385)
			(xy 348.021431 -393.620985) (xy 348.036264 -393.575344) (xy 348.058055 -393.532585) (xy 348.086267 -393.493762)
			(xy 348.120205 -393.45983) (xy 348.159033 -393.431626) (xy 348.201796 -393.409843) (xy 348.247439 -393.395018)
			(xy 348.29484 -393.387515) (xy 348.318836 -393.387072) (xy 348.34277 -393.38755) (xy 348.390054 -393.395006)
			(xy 348.435597 -393.409745) (xy 348.478284 -393.431407) (xy 348.517069 -393.459461) (xy 348.551005 -393.49322)
			(xy 348.579261 -393.53186) (xy 348.590616 -393.552934) (xy 348.591124 -393.55395) (xy 348.67143 -393.692888)
			(xy 349.213424 -393.692888) (xy 349.213424 -393.69238) (xy 349.21382 -393.668385) (xy 349.221331 -393.620985)
			(xy 349.236164 -393.575345) (xy 349.257954 -393.532586) (xy 349.286166 -393.493764) (xy 349.320103 -393.459832)
			(xy 349.358931 -393.431627) (xy 349.401693 -393.409844) (xy 349.447336 -393.395018) (xy 349.494737 -393.387516)
			(xy 349.518732 -393.387072) (xy 349.542666 -393.387554) (xy 349.58995 -393.395009) (xy 349.635493 -393.409747)
			(xy 349.678179 -393.431408) (xy 349.716965 -393.459462) (xy 349.750901 -393.493221) (xy 349.779157 -393.53186)
			(xy 349.790512 -393.552934) (xy 349.79102 -393.55395) (xy 349.871326 -393.692888) (xy 350.41332 -393.692888)
			(xy 350.41332 -393.69238) (xy 350.413721 -393.668372) (xy 350.421239 -393.620949) (xy 350.436088 -393.575287)
			(xy 350.4579 -393.532512) (xy 350.486139 -393.493678) (xy 350.520108 -393.459742) (xy 350.55897 -393.431542)
			(xy 350.601766 -393.409772) (xy 350.647443 -393.394969) (xy 350.694874 -393.387497) (xy 350.718882 -393.387072)
			(xy 350.742818 -393.387513) (xy 350.790103 -393.394976) (xy 350.835647 -393.409721) (xy 350.878334 -393.431389)
			(xy 350.917119 -393.459449) (xy 350.951054 -393.493214) (xy 350.979308 -393.531858) (xy 350.990662 -393.552934)
			(xy 350.99117 -393.55395) (xy 351.071476 -393.692888) (xy 351.613216 -393.692888) (xy 351.613216 -393.69238)
			(xy 351.613621 -393.668372) (xy 351.621139 -393.620949) (xy 351.635987 -393.575288) (xy 351.657799 -393.532513)
			(xy 351.686038 -393.493679) (xy 351.720006 -393.459744) (xy 351.758867 -393.431543) (xy 351.801664 -393.409773)
			(xy 351.84734 -393.394969) (xy 351.89477 -393.387497) (xy 351.918778 -393.387072) (xy 351.942713 -393.387516)
			(xy 351.989999 -393.394978) (xy 352.035543 -393.409723) (xy 352.078229 -393.431391) (xy 352.117015 -393.45945)
			(xy 352.150949 -393.493214) (xy 352.179204 -393.531858) (xy 352.190558 -393.552934) (xy 352.191066 -393.55395)
			(xy 352.271372 -393.692888) (xy 352.81362 -393.692888) (xy 352.81362 -393.69238) (xy 352.81402 -393.668385)
			(xy 352.82153 -393.620986) (xy 352.836363 -393.575346) (xy 352.858154 -393.532588) (xy 352.886365 -393.493765)
			(xy 352.920301 -393.459833) (xy 352.959129 -393.431629) (xy 353.00189 -393.409845) (xy 353.047533 -393.395019)
			(xy 353.094933 -393.387516) (xy 353.118928 -393.387072) (xy 353.142862 -393.387557) (xy 353.190146 -393.395011)
			(xy 353.235688 -393.409749) (xy 353.278375 -393.43141) (xy 353.317161 -393.459463) (xy 353.351097 -393.493222)
			(xy 353.379353 -393.53186) (xy 353.390708 -393.552934) (xy 353.391216 -393.55395) (xy 353.471522 -393.692888)
			(xy 354.013516 -393.692888) (xy 354.013516 -393.69238) (xy 354.01392 -393.668385) (xy 354.02143 -393.620987)
			(xy 354.036263 -393.575347) (xy 354.058053 -393.532589) (xy 354.086263 -393.493766) (xy 354.1202 -393.459835)
			(xy 354.159026 -393.43163) (xy 354.201787 -393.409846) (xy 354.247429 -393.39502) (xy 354.294829 -393.387516)
			(xy 354.318824 -393.387072) (xy 354.342758 -393.38756) (xy 354.390042 -393.395014) (xy 354.435584 -393.409751)
			(xy 354.478271 -393.431411) (xy 354.517057 -393.459464) (xy 354.550993 -393.493222) (xy 354.579249 -393.53186)
			(xy 354.590604 -393.552934) (xy 354.591112 -393.55395) (xy 354.671418 -393.692888) (xy 370.586 -393.692888)
			(xy 370.586 -393.69238) (xy 370.586444 -393.668388) (xy 370.593954 -393.620995) (xy 370.608784 -393.57536)
			(xy 370.630571 -393.532606) (xy 370.658777 -393.493788) (xy 370.692709 -393.459859) (xy 370.73153 -393.431656)
			(xy 370.774286 -393.409873) (xy 370.819922 -393.395047) (xy 370.867316 -393.387542) (xy 370.891308 -393.387072)
			(xy 370.915241 -393.387573) (xy 370.962524 -393.395024) (xy 371.008067 -393.409759) (xy 371.050753 -393.431417)
			(xy 371.089539 -393.459468) (xy 371.123476 -393.493224) (xy 371.151732 -393.531861) (xy 371.163088 -393.552934)
			(xy 371.163596 -393.55395) (xy 371.243902 -393.692888) (xy 371.785896 -393.692888) (xy 371.785896 -393.69238)
			(xy 371.786344 -393.668388) (xy 371.793853 -393.620995) (xy 371.808684 -393.575361) (xy 371.83047 -393.532608)
			(xy 371.858676 -393.493789) (xy 371.892607 -393.459861) (xy 371.931428 -393.431658) (xy 371.974183 -393.409875)
			(xy 372.019819 -393.395048) (xy 372.067212 -393.387542) (xy 372.091204 -393.387072) (xy 372.115137 -393.387576)
			(xy 372.16242 -393.395027) (xy 372.207962 -393.409762) (xy 372.250649 -393.431419) (xy 372.289435 -393.459469)
			(xy 372.323372 -393.493225) (xy 372.351628 -393.531861) (xy 372.362984 -393.552934) (xy 372.363492 -393.55395)
			(xy 372.443798 -393.692888) (xy 372.985792 -393.692888) (xy 372.985792 -393.69238) (xy 372.986244 -393.668388)
			(xy 372.993753 -393.620996) (xy 373.008583 -393.575362) (xy 373.030369 -393.532609) (xy 373.058575 -393.49379)
			(xy 373.092506 -393.459862) (xy 373.131326 -393.431659) (xy 373.17408 -393.409876) (xy 373.219715 -393.395049)
			(xy 373.267108 -393.387543) (xy 373.2911 -393.387072) (xy 373.315033 -393.38758) (xy 373.362316 -393.39503)
			(xy 373.407858 -393.409764) (xy 373.450544 -393.43142) (xy 373.489331 -393.45947) (xy 373.523268 -393.493226)
			(xy 373.551524 -393.531862) (xy 373.56288 -393.552934) (xy 373.563388 -393.55395) (xy 373.643694 -393.692888)
			(xy 374.185688 -393.692888) (xy 374.185688 -393.69238) (xy 374.186121 -393.668374) (xy 374.193638 -393.620954)
			(xy 374.208485 -393.575294) (xy 374.230294 -393.532521) (xy 374.25853 -393.493689) (xy 374.292494 -393.459754)
			(xy 374.331352 -393.431553) (xy 374.374144 -393.409781) (xy 374.419817 -393.394975) (xy 374.467243 -393.3875)
			(xy 374.49125 -393.387072) (xy 374.515185 -393.387539) (xy 374.562469 -393.394997) (xy 374.608012 -393.409738)
			(xy 374.650699 -393.431401) (xy 374.689484 -393.459457) (xy 374.72342 -393.493218) (xy 374.751675 -393.531859)
			(xy 374.76303 -393.552934) (xy 374.763538 -393.55395) (xy 374.843844 -393.692888) (xy 375.385584 -393.692888)
			(xy 375.385584 -393.69238) (xy 375.386021 -393.668374) (xy 375.393538 -393.620954) (xy 375.408384 -393.575295)
			(xy 375.430194 -393.532522) (xy 375.458428 -393.49369) (xy 375.492393 -393.459755) (xy 375.53125 -393.431554)
			(xy 375.574041 -393.409782) (xy 375.619713 -393.394976) (xy 375.66714 -393.3875) (xy 375.691146 -393.387072)
			(xy 375.715081 -393.387542) (xy 375.762365 -393.394999) (xy 375.807908 -393.40974) (xy 375.850594 -393.431403)
			(xy 375.88938 -393.459458) (xy 375.923316 -393.493219) (xy 375.951571 -393.531859) (xy 375.962926 -393.552934)
			(xy 375.963434 -393.55395) (xy 376.04374 -393.692888) (xy 376.585988 -393.692888) (xy 376.585988 -393.69238)
			(xy 376.586444 -393.668388) (xy 376.593953 -393.620996) (xy 376.608783 -393.575362) (xy 376.630569 -393.53261)
			(xy 376.658774 -393.493792) (xy 376.692704 -393.459863) (xy 376.731524 -393.43166) (xy 376.774277 -393.409877)
			(xy 376.819912 -393.395049) (xy 376.867304 -393.387543) (xy 376.891296 -393.387072) (xy 376.915232 -393.387502)
			(xy 376.962518 -393.394966) (xy 377.008062 -393.409714) (xy 377.050749 -393.431384) (xy 377.089534 -393.459445)
			(xy 377.123468 -393.493212) (xy 377.151722 -393.531857) (xy 377.163076 -393.552934) (xy 377.163584 -393.55395)
			(xy 377.24389 -393.692888) (xy 377.785884 -393.692888) (xy 377.785884 -393.69238) (xy 377.786344 -393.668389)
			(xy 377.793853 -393.620997) (xy 377.808683 -393.575363) (xy 377.830468 -393.532611) (xy 377.858673 -393.493793)
			(xy 377.892602 -393.459865) (xy 377.931421 -393.431662) (xy 377.974174 -393.409878) (xy 378.019809 -393.39505)
			(xy 378.067201 -393.387543) (xy 378.091192 -393.387072) (xy 378.115128 -393.387505) (xy 378.162414 -393.394969)
			(xy 378.207958 -393.409716) (xy 378.250644 -393.431385) (xy 378.28943 -393.459446) (xy 378.323364 -393.493212)
			(xy 378.351618 -393.531857) (xy 378.362972 -393.552934) (xy 378.36348 -393.55395) (xy 378.443786 -393.692888)
			(xy 378.98578 -393.692888) (xy 378.98578 -393.69238) (xy 378.986244 -393.668389) (xy 378.993753 -393.620998)
			(xy 379.008582 -393.575364) (xy 379.030367 -393.532612) (xy 379.058571 -393.493795) (xy 379.092501 -393.459866)
			(xy 379.131319 -393.431663) (xy 379.174072 -393.409879) (xy 379.219705 -393.395051) (xy 379.267097 -393.387543)
			(xy 379.291088 -393.387072) (xy 379.315024 -393.387508) (xy 379.36231 -393.394972) (xy 379.407853 -393.409718)
			(xy 379.45054 -393.431387) (xy 379.489325 -393.459447) (xy 379.52326 -393.493213) (xy 379.551514 -393.531858)
			(xy 379.562868 -393.552934) (xy 379.563376 -393.55395) (xy 379.643682 -393.692888) (xy 380.185676 -393.692888)
			(xy 380.185676 -393.69238) (xy 380.186121 -393.668374) (xy 380.193638 -393.620955) (xy 380.208483 -393.575297)
			(xy 380.230292 -393.532525) (xy 380.258526 -393.493693) (xy 380.292489 -393.459758) (xy 380.331345 -393.431557)
			(xy 380.374136 -393.409785) (xy 380.419807 -393.394977) (xy 380.467232 -393.3875) (xy 380.491238 -393.387072)
			(xy 380.515172 -393.387549) (xy 380.562456 -393.395005) (xy 380.607999 -393.409744) (xy 380.650686 -393.431406)
			(xy 380.689472 -393.45946) (xy 380.723407 -393.49322) (xy 380.751663 -393.53186) (xy 380.763018 -393.552934)
			(xy 380.763526 -393.55395) (xy 380.843832 -393.692888) (xy 381.385572 -393.692888) (xy 381.385572 -393.69238)
			(xy 381.386021 -393.668375) (xy 381.393538 -393.620956) (xy 381.408383 -393.575298) (xy 381.430191 -393.532526)
			(xy 381.458425 -393.493694) (xy 381.492388 -393.45976) (xy 381.531243 -393.431558) (xy 381.574033 -393.409786)
			(xy 381.619703 -393.394978) (xy 381.667128 -393.387501) (xy 381.691134 -393.387072) (xy 381.715068 -393.387552)
			(xy 381.762352 -393.395007) (xy 381.807895 -393.409746) (xy 381.850581 -393.431407) (xy 381.889367 -393.459461)
			(xy 381.923303 -393.493221) (xy 381.951559 -393.53186) (xy 381.962914 -393.552934) (xy 381.963422 -393.55395)
			(xy 382.043728 -393.692888) (xy 382.585976 -393.692888) (xy 382.585976 -393.69238) (xy 382.586444 -393.668389)
			(xy 382.593953 -393.620998) (xy 382.608782 -393.575365) (xy 382.630567 -393.532614) (xy 382.65877 -393.493796)
			(xy 382.692699 -393.459868) (xy 382.731517 -393.431664) (xy 382.774269 -393.40988) (xy 382.819902 -393.395052)
			(xy 382.867293 -393.387544) (xy 382.891284 -393.387072) (xy 382.91522 -393.387511) (xy 382.962506 -393.394974)
			(xy 383.008049 -393.40972) (xy 383.050736 -393.431388) (xy 383.089521 -393.459448) (xy 383.123456 -393.493214)
			(xy 383.15171 -393.531858) (xy 383.163064 -393.552934) (xy 383.163572 -393.55395) (xy 383.243878 -393.692888)
			(xy 383.785872 -393.692888) (xy 383.785872 -393.69238) (xy 383.786344 -393.668389) (xy 383.793853 -393.620999)
			(xy 383.808681 -393.575366) (xy 383.830466 -393.532615) (xy 383.858669 -393.493797) (xy 383.892597 -393.459869)
			(xy 383.931415 -393.431666) (xy 383.974166 -393.409881) (xy 384.019799 -393.395053) (xy 384.067189 -393.387544)
			(xy 384.09118 -393.387072) (xy 384.115116 -393.387515) (xy 384.162401 -393.394977) (xy 384.207945 -393.409722)
			(xy 384.250631 -393.43139) (xy 384.289417 -393.459449) (xy 384.323352 -393.493214) (xy 384.351606 -393.531858)
			(xy 384.36296 -393.552934) (xy 384.363468 -393.55395) (xy 384.443774 -393.692888) (xy 384.985768 -393.692888)
			(xy 384.985768 -393.69238) (xy 384.986244 -393.668389) (xy 384.993752 -393.620999) (xy 385.008581 -393.575367)
			(xy 385.030365 -393.532616) (xy 385.058568 -393.493799) (xy 385.092496 -393.459871) (xy 385.131313 -393.431667)
			(xy 385.174063 -393.409883) (xy 385.219695 -393.395053) (xy 385.267085 -393.387544) (xy 385.291076 -393.387072)
			(xy 385.315011 -393.387518) (xy 385.362297 -393.39498) (xy 385.40784 -393.409724) (xy 385.450527 -393.431391)
			(xy 385.489312 -393.45945) (xy 385.523247 -393.493215) (xy 385.551501 -393.531858) (xy 385.562856 -393.552934)
			(xy 385.563364 -393.55395) (xy 385.64367 -393.692888) (xy 386.185664 -393.692888) (xy 386.185664 -393.69238)
			(xy 386.186121 -393.668375) (xy 386.193637 -393.620957) (xy 386.208482 -393.5753) (xy 386.23029 -393.532528)
			(xy 386.258522 -393.493697) (xy 386.292484 -393.459762) (xy 386.331339 -393.431561) (xy 386.374127 -393.409788)
			(xy 386.419797 -393.39498) (xy 386.467221 -393.387501) (xy 386.491226 -393.387072) (xy 386.51516 -393.387558)
			(xy 386.562444 -393.395013) (xy 386.607986 -393.40975) (xy 386.650673 -393.43141) (xy 386.689459 -393.459463)
			(xy 386.723395 -393.493222) (xy 386.751651 -393.53186) (xy 386.763006 -393.552934) (xy 386.763514 -393.55395)
			(xy 386.84382 -393.692888) (xy 387.38556 -393.692888) (xy 387.38556 -393.69238) (xy 387.386021 -393.668375)
			(xy 387.393537 -393.620958) (xy 387.408382 -393.575301) (xy 387.430189 -393.53253) (xy 387.458421 -393.493698)
			(xy 387.492383 -393.459764) (xy 387.531236 -393.431563) (xy 387.574025 -393.409789) (xy 387.619693 -393.394981)
			(xy 387.667117 -393.387502) (xy 387.691122 -393.387072) (xy 387.715056 -393.387562) (xy 387.762339 -393.395015)
			(xy 387.807882 -393.409752) (xy 387.850568 -393.431412) (xy 387.889354 -393.459464) (xy 387.923291 -393.493222)
			(xy 387.951547 -393.531861) (xy 387.962902 -393.552934) (xy 387.96341 -393.55395) (xy 388.043716 -393.692888)
			(xy 388.585964 -393.692888) (xy 388.585964 -393.69238) (xy 388.586444 -393.66839) (xy 388.593952 -393.621)
			(xy 388.608781 -393.575368) (xy 388.630564 -393.532617) (xy 388.658767 -393.4938) (xy 388.692694 -393.459872)
			(xy 388.73151 -393.431668) (xy 388.774261 -393.409884) (xy 388.819892 -393.395054) (xy 388.867282 -393.387545)
			(xy 388.891272 -393.387072) (xy 388.915207 -393.387521) (xy 388.962493 -393.394982) (xy 389.008036 -393.409727)
			(xy 389.050723 -393.431393) (xy 389.089508 -393.459451) (xy 389.123443 -393.493215) (xy 389.151697 -393.531858)
			(xy 389.163052 -393.552934) (xy 389.16356 -393.55395) (xy 389.243866 -393.692888) (xy 403.113748 -393.692888)
			(xy 403.113748 -393.69238) (xy 403.114244 -393.66839) (xy 403.121752 -393.621002) (xy 403.136579 -393.575372)
			(xy 403.158361 -393.532622) (xy 403.186562 -393.493805) (xy 403.220487 -393.459878) (xy 403.259301 -393.431674)
			(xy 403.302049 -393.409888) (xy 403.347679 -393.395057) (xy 403.395066 -393.387546) (xy 403.419056 -393.387072)
			(xy 403.442991 -393.387534) (xy 403.490276 -393.394993) (xy 403.535819 -393.409735) (xy 403.578505 -393.431399)
			(xy 403.617291 -393.459456) (xy 403.651226 -393.493218) (xy 403.679481 -393.531859) (xy 403.690836 -393.552934)
			(xy 403.691344 -393.55395) (xy 403.77165 -393.692888) (xy 404.313644 -393.692888) (xy 404.313644 -393.69238)
			(xy 404.314144 -393.668391) (xy 404.321652 -393.621003) (xy 404.336479 -393.575373) (xy 404.358261 -393.532623)
			(xy 404.386461 -393.493807) (xy 404.420386 -393.459879) (xy 404.459199 -393.431675) (xy 404.501947 -393.40989)
			(xy 404.547576 -393.395058) (xy 404.594963 -393.387546) (xy 404.618952 -393.387072) (xy 404.642887 -393.387537)
			(xy 404.690171 -393.394995) (xy 404.735714 -393.409737) (xy 404.778401 -393.431401) (xy 404.817187 -393.459457)
			(xy 404.851122 -393.493218) (xy 404.879377 -393.531859) (xy 404.890732 -393.552934) (xy 404.89124 -393.55395)
			(xy 404.971546 -393.692888) (xy 405.51354 -393.692888) (xy 405.51354 -393.69238) (xy 405.51392 -393.668384)
			(xy 405.521431 -393.620983) (xy 405.536265 -393.575341) (xy 405.558057 -393.532582) (xy 405.58627 -393.493758)
			(xy 405.62021 -393.459826) (xy 405.65904 -393.431622) (xy 405.701804 -393.409839) (xy 405.747449 -393.395015)
			(xy 405.794852 -393.387515) (xy 405.818848 -393.387072) (xy 405.842783 -393.387541) (xy 405.890067 -393.394998)
			(xy 405.93561 -393.409739) (xy 405.978297 -393.431402) (xy 406.017082 -393.459458) (xy 406.051018 -393.493219)
			(xy 406.079273 -393.531859) (xy 406.090628 -393.552934) (xy 406.091136 -393.55395) (xy 406.171442 -393.692888)
			(xy 406.713436 -393.692888) (xy 406.713436 -393.69238) (xy 406.713821 -393.668371) (xy 406.72134 -393.620947)
			(xy 406.736189 -393.575283) (xy 406.758003 -393.532507) (xy 406.786244 -393.493672) (xy 406.820215 -393.459737)
			(xy 406.859079 -393.431537) (xy 406.901877 -393.409767) (xy 406.947556 -393.394965) (xy 406.994989 -393.387496)
			(xy 407.018998 -393.387072) (xy 407.042934 -393.3875) (xy 407.090221 -393.394965) (xy 407.135764 -393.409713)
			(xy 407.178451 -393.431383) (xy 407.217236 -393.459445) (xy 407.25117 -393.493212) (xy 407.279424 -393.531857)
			(xy 407.290778 -393.552934) (xy 407.291286 -393.55395) (xy 407.371592 -393.692888) (xy 407.913332 -393.692888)
			(xy 407.913332 -393.69238) (xy 407.913721 -393.668372) (xy 407.92124 -393.620947) (xy 407.936089 -393.575284)
			(xy 407.957902 -393.532508) (xy 407.986142 -393.493674) (xy 408.020113 -393.459738) (xy 408.058976 -393.431538)
			(xy 408.101775 -393.409769) (xy 408.147453 -393.394966) (xy 408.194885 -393.387496) (xy 408.218894 -393.387072)
			(xy 408.24283 -393.387503) (xy 408.290116 -393.394968) (xy 408.33566 -393.409715) (xy 408.378347 -393.431385)
			(xy 408.417132 -393.459446) (xy 408.451066 -393.493212) (xy 408.47932 -393.531857) (xy 408.490674 -393.552934)
			(xy 408.491182 -393.55395) (xy 408.571488 -393.692888) (xy 409.113736 -393.692888) (xy 409.113736 -393.69238)
			(xy 409.11412 -393.668384) (xy 409.121631 -393.620984) (xy 409.136465 -393.575342) (xy 409.158257 -393.532583)
			(xy 409.186469 -393.493759) (xy 409.220408 -393.459828) (xy 409.259238 -393.431623) (xy 409.302001 -393.40984)
			(xy 409.347646 -393.395016) (xy 409.395048 -393.387515) (xy 409.419044 -393.387072) (xy 409.442978 -393.387544)
			(xy 409.490263 -393.395001) (xy 409.535806 -393.409741) (xy 409.578492 -393.431404) (xy 409.617278 -393.459459)
			(xy 409.651214 -393.493219) (xy 409.679469 -393.53186) (xy 409.690824 -393.552934) (xy 409.691332 -393.55395)
			(xy 409.771638 -393.692888) (xy 410.313632 -393.692888) (xy 410.313632 -393.69238) (xy 410.31402 -393.668384)
			(xy 410.321531 -393.620984) (xy 410.336365 -393.575343) (xy 410.358156 -393.532584) (xy 410.386368 -393.493761)
			(xy 410.420306 -393.459829) (xy 410.459135 -393.431624) (xy 410.501898 -393.409842) (xy 410.547543 -393.395017)
			(xy 410.594944 -393.387515) (xy 410.61894 -393.387072) (xy 410.642874 -393.387547) (xy 410.690159 -393.395003)
			(xy 410.735701 -393.409743) (xy 410.778388 -393.431405) (xy 410.817174 -393.45946) (xy 410.85111 -393.49322)
			(xy 410.879365 -393.53186) (xy 410.89072 -393.552934) (xy 410.891228 -393.55395) (xy 410.971534 -393.692888)
			(xy 411.513528 -393.692888) (xy 411.513528 -393.69238) (xy 411.51392 -393.668385) (xy 411.521431 -393.620985)
			(xy 411.536264 -393.575344) (xy 411.558055 -393.532585) (xy 411.586267 -393.493762) (xy 411.620205 -393.45983)
			(xy 411.659033 -393.431626) (xy 411.701796 -393.409843) (xy 411.747439 -393.395018) (xy 411.79484 -393.387515)
			(xy 411.818836 -393.387072) (xy 411.84277 -393.38755) (xy 411.890054 -393.395006) (xy 411.935597 -393.409745)
			(xy 411.978284 -393.431407) (xy 412.017069 -393.459461) (xy 412.051005 -393.49322) (xy 412.079261 -393.53186)
			(xy 412.090616 -393.552934) (xy 412.091124 -393.55395) (xy 412.17143 -393.692888) (xy 412.713424 -393.692888)
			(xy 412.713424 -393.69238) (xy 412.713821 -393.668372) (xy 412.721339 -393.620948) (xy 412.736188 -393.575286)
			(xy 412.758001 -393.53251) (xy 412.78624 -393.493676) (xy 412.820209 -393.459741) (xy 412.859072 -393.431541)
			(xy 412.901869 -393.409771) (xy 412.947546 -393.394968) (xy 412.994978 -393.387497) (xy 413.018986 -393.387072)
			(xy 413.042922 -393.38751) (xy 413.090208 -393.394973) (xy 413.135751 -393.409719) (xy 413.178438 -393.431388)
			(xy 413.217223 -393.459448) (xy 413.251158 -393.493213) (xy 413.279412 -393.531858) (xy 413.290766 -393.552934)
			(xy 413.291274 -393.55395) (xy 413.37158 -393.692888) (xy 413.91332 -393.692888) (xy 413.91332 -393.69238)
			(xy 413.913721 -393.668372) (xy 413.921239 -393.620949) (xy 413.936088 -393.575287) (xy 413.9579 -393.532512)
			(xy 413.986139 -393.493678) (xy 414.020108 -393.459742) (xy 414.05897 -393.431542) (xy 414.101766 -393.409772)
			(xy 414.147443 -393.394969) (xy 414.194874 -393.387497) (xy 414.218882 -393.387072) (xy 414.242818 -393.387513)
			(xy 414.290103 -393.394976) (xy 414.335647 -393.409721) (xy 414.378334 -393.431389) (xy 414.417119 -393.459449)
			(xy 414.451054 -393.493214) (xy 414.479308 -393.531858) (xy 414.490662 -393.552934) (xy 414.49117 -393.55395)
			(xy 414.571476 -393.692888) (xy 415.113724 -393.692888) (xy 415.113724 -393.69238) (xy 415.11412 -393.668385)
			(xy 415.121631 -393.620985) (xy 415.136464 -393.575345) (xy 415.158254 -393.532586) (xy 415.186466 -393.493764)
			(xy 415.220403 -393.459832) (xy 415.259231 -393.431627) (xy 415.301993 -393.409844) (xy 415.347636 -393.395018)
			(xy 415.395037 -393.387516) (xy 415.419032 -393.387072) (xy 415.442966 -393.387554) (xy 415.49025 -393.395009)
			(xy 415.535793 -393.409747) (xy 415.578479 -393.431408) (xy 415.617265 -393.459462) (xy 415.651201 -393.493221)
			(xy 415.679457 -393.53186) (xy 415.690812 -393.552934) (xy 415.69132 -393.55395) (xy 415.771626 -393.692888)
			(xy 416.31362 -393.692888) (xy 416.31362 -393.69238) (xy 416.31402 -393.668385) (xy 416.32153 -393.620986)
			(xy 416.336363 -393.575346) (xy 416.358154 -393.532588) (xy 416.386365 -393.493765) (xy 416.420301 -393.459833)
			(xy 416.459129 -393.431629) (xy 416.50189 -393.409845) (xy 416.547533 -393.395019) (xy 416.594933 -393.387516)
			(xy 416.618928 -393.387072) (xy 416.642862 -393.387557) (xy 416.690146 -393.395011) (xy 416.735688 -393.409749)
			(xy 416.778375 -393.43141) (xy 416.817161 -393.459463) (xy 416.851097 -393.493222) (xy 416.879353 -393.53186)
			(xy 416.890708 -393.552934) (xy 416.891216 -393.55395) (xy 416.971522 -393.692888) (xy 417.513516 -393.692888)
			(xy 417.513516 -393.69238) (xy 417.51392 -393.668385) (xy 417.52143 -393.620987) (xy 417.536263 -393.575347)
			(xy 417.558053 -393.532589) (xy 417.586263 -393.493766) (xy 417.6202 -393.459835) (xy 417.659026 -393.43163)
			(xy 417.701787 -393.409846) (xy 417.747429 -393.39502) (xy 417.794829 -393.387516) (xy 417.818824 -393.387072)
			(xy 417.842758 -393.38756) (xy 417.890042 -393.395014) (xy 417.935584 -393.409751) (xy 417.978271 -393.431411)
			(xy 418.017057 -393.459464) (xy 418.050993 -393.493222) (xy 418.079249 -393.53186) (xy 418.090604 -393.552934)
			(xy 418.091112 -393.55395) (xy 418.171418 -393.692888) (xy 418.713412 -393.692888) (xy 418.713412 -393.69238)
			(xy 418.713821 -393.668373) (xy 418.721339 -393.62095) (xy 418.736187 -393.575289) (xy 418.757999 -393.532514)
			(xy 418.786237 -393.493681) (xy 418.820204 -393.459745) (xy 418.859065 -393.431545) (xy 418.901861 -393.409774)
			(xy 418.947536 -393.39497) (xy 418.994966 -393.387498) (xy 419.018974 -393.387072) (xy 419.042909 -393.387519)
			(xy 419.090195 -393.394981) (xy 419.135738 -393.409726) (xy 419.178425 -393.431392) (xy 419.21721 -393.459451)
			(xy 419.251145 -393.493215) (xy 419.279399 -393.531858) (xy 419.290754 -393.552934) (xy 419.291262 -393.55395)
			(xy 419.371568 -393.692888) (xy 419.913308 -393.692888) (xy 419.913308 -393.69238) (xy 419.913721 -393.668373)
			(xy 419.921239 -393.620951) (xy 419.936087 -393.57529) (xy 419.957898 -393.532515) (xy 419.986135 -393.493682)
			(xy 420.020103 -393.459747) (xy 420.058963 -393.431546) (xy 420.101758 -393.409775) (xy 420.147433 -393.394971)
			(xy 420.194862 -393.387498) (xy 420.21887 -393.387072) (xy 420.242805 -393.387523) (xy 420.290091 -393.394984)
			(xy 420.335634 -393.409728) (xy 420.378321 -393.431394) (xy 420.417106 -393.459452) (xy 420.451041 -393.493216)
			(xy 420.479295 -393.531858) (xy 420.49065 -393.552934) (xy 420.491158 -393.55395) (xy 420.571464 -393.692888)
			(xy 421.113712 -393.692888) (xy 421.113712 -393.69238) (xy 421.114144 -393.668387) (xy 421.121654 -393.620993)
			(xy 421.136485 -393.575357) (xy 421.158273 -393.532603) (xy 421.186481 -393.493784) (xy 421.220414 -393.459855)
			(xy 421.259237 -393.431652) (xy 421.301994 -393.40987) (xy 421.347632 -393.395045) (xy 421.395027 -393.387541)
			(xy 421.41902 -393.387072) (xy 421.442954 -393.387563) (xy 421.490237 -393.395017) (xy 421.53578 -393.409753)
			(xy 421.578466 -393.431413) (xy 421.617252 -393.459465) (xy 421.651189 -393.493223) (xy 421.679444 -393.531861)
			(xy 421.6908 -393.552934) (xy 421.691308 -393.55395) (xy 422.083738 -394.232892) (xy 422.096563 -394.256225)
			(xy 422.114783 -394.306247) (xy 422.124043 -394.358673) (xy 422.124632 -394.385292) (xy 422.124154 -394.409296)
			(xy 422.116641 -394.456714) (xy 422.101799 -394.502371) (xy 422.079995 -394.545143) (xy 422.051765 -394.583974)
			(xy 422.017805 -394.617909) (xy 421.978953 -394.646111) (xy 421.936165 -394.667885) (xy 421.890498 -394.682693)
			(xy 421.843075 -394.690171) (xy 421.81907 -394.6906) (xy 421.795495 -394.69023) (xy 421.748906 -394.682984)
			(xy 421.703987 -394.668654) (xy 421.661808 -394.647582) (xy 421.623376 -394.620268) (xy 421.589605 -394.587365)
			(xy 421.5613 -394.549657) (xy 421.54983 -394.529056) (xy 421.549322 -394.528294) (xy 421.151558 -393.839954)
			(xy 421.139699 -393.817269) (xy 421.122842 -393.76894) (xy 421.114262 -393.71848) (xy 421.113712 -393.692888)
			(xy 420.571464 -393.692888) (xy 420.883588 -394.232892) (xy 420.896337 -394.256249) (xy 420.914447 -394.306281)
			(xy 420.92365 -394.358688) (xy 420.924228 -394.385292) (xy 420.92373 -394.409282) (xy 420.916226 -394.456672)
			(xy 420.901401 -394.502304) (xy 420.87962 -394.545055) (xy 420.85142 -394.583873) (xy 420.817494 -394.617801)
			(xy 420.778679 -394.646005) (xy 420.73593 -394.66779) (xy 420.690299 -394.682619) (xy 420.64291 -394.690128)
			(xy 420.61892 -394.6906) (xy 420.595347 -394.69019) (xy 420.548759 -394.682952) (xy 420.503841 -394.668629)
			(xy 420.461662 -394.647563) (xy 420.423229 -394.620256) (xy 420.389457 -394.587358) (xy 420.361151 -394.549655)
			(xy 420.34968 -394.529056) (xy 420.349172 -394.528294) (xy 419.951408 -393.839954) (xy 419.939474 -393.817295)
			(xy 419.922543 -393.768965) (xy 419.913891 -393.718491) (xy 419.913308 -393.692888) (xy 419.371568 -393.692888)
			(xy 419.683692 -394.232892) (xy 419.696442 -394.256249) (xy 419.714551 -394.306281) (xy 419.723754 -394.358688)
			(xy 419.724332 -394.385292) (xy 419.72383 -394.409282) (xy 419.716326 -394.456671) (xy 419.701501 -394.502303)
			(xy 419.679721 -394.545054) (xy 419.651521 -394.583871) (xy 419.617596 -394.6178) (xy 419.578781 -394.646004)
			(xy 419.536032 -394.667789) (xy 419.490402 -394.682618) (xy 419.443014 -394.690128) (xy 419.419024 -394.6906)
			(xy 419.395451 -394.690187) (xy 419.348863 -394.682949) (xy 419.303945 -394.668627) (xy 419.261767 -394.647561)
			(xy 419.223333 -394.620255) (xy 419.189561 -394.587358) (xy 419.161255 -394.549655) (xy 419.149784 -394.529056)
			(xy 419.149276 -394.528294) (xy 418.751512 -393.839954) (xy 418.739579 -393.817295) (xy 418.722647 -393.768965)
			(xy 418.713995 -393.718491) (xy 418.713412 -393.692888) (xy 418.171418 -393.692888) (xy 418.483542 -394.232892)
			(xy 418.496367 -394.256224) (xy 418.514587 -394.306247) (xy 418.523847 -394.358673) (xy 418.524436 -394.385292)
			(xy 418.523954 -394.409296) (xy 418.516441 -394.456713) (xy 418.5016 -394.50237) (xy 418.479796 -394.545141)
			(xy 418.451566 -394.583973) (xy 418.417607 -394.617908) (xy 418.378755 -394.64611) (xy 418.335968 -394.667883)
			(xy 418.290301 -394.682692) (xy 418.242879 -394.690171) (xy 418.218874 -394.6906) (xy 418.195299 -394.690227)
			(xy 418.14871 -394.682982) (xy 418.103791 -394.668652) (xy 418.061613 -394.64758) (xy 418.02318 -394.620267)
			(xy 417.989409 -394.587365) (xy 417.961104 -394.549657) (xy 417.949634 -394.529056) (xy 417.949126 -394.528294)
			(xy 417.551362 -393.839954) (xy 417.539504 -393.817268) (xy 417.522646 -393.76894) (xy 417.514066 -393.71848)
			(xy 417.513516 -393.692888) (xy 416.971522 -393.692888) (xy 417.283646 -394.232892) (xy 417.296471 -394.256224)
			(xy 417.314691 -394.306247) (xy 417.323951 -394.358673) (xy 417.32454 -394.385292) (xy 417.324054 -394.409296)
			(xy 417.316541 -394.456713) (xy 417.3017 -394.502369) (xy 417.279896 -394.54514) (xy 417.251667 -394.583972)
			(xy 417.217709 -394.617907) (xy 417.178857 -394.646108) (xy 417.136071 -394.667882) (xy 417.090404 -394.682691)
			(xy 417.042982 -394.69017) (xy 417.018978 -394.6906) (xy 416.995403 -394.690224) (xy 416.948814 -394.682979)
			(xy 416.903895 -394.66865) (xy 416.861717 -394.647579) (xy 416.823284 -394.620266) (xy 416.789513 -394.587364)
			(xy 416.761208 -394.549657) (xy 416.749738 -394.529056) (xy 416.74923 -394.528294) (xy 416.351466 -393.839954)
			(xy 416.339608 -393.817268) (xy 416.32275 -393.76894) (xy 416.31417 -393.71848) (xy 416.31362 -393.692888)
			(xy 415.771626 -393.692888) (xy 416.08375 -394.232892) (xy 416.096576 -394.256224) (xy 416.114795 -394.306247)
			(xy 416.124055 -394.358673) (xy 416.124644 -394.385292) (xy 416.124154 -394.409296) (xy 416.116641 -394.456712)
			(xy 416.101801 -394.502368) (xy 416.079997 -394.545139) (xy 416.051769 -394.58397) (xy 416.01781 -394.617905)
			(xy 415.97896 -394.646107) (xy 415.936174 -394.667881) (xy 415.890507 -394.68269) (xy 415.843086 -394.69017)
			(xy 415.819082 -394.6906) (xy 415.795507 -394.690221) (xy 415.748919 -394.682977) (xy 415.704 -394.668648)
			(xy 415.661821 -394.647577) (xy 415.623388 -394.620265) (xy 415.589617 -394.587364) (xy 415.561312 -394.549657)
			(xy 415.549842 -394.529056) (xy 415.549334 -394.528294) (xy 415.15157 -393.839954) (xy 415.139712 -393.817268)
			(xy 415.122855 -393.768939) (xy 415.114274 -393.71848) (xy 415.113724 -393.692888) (xy 414.571476 -393.692888)
			(xy 414.8836 -394.232892) (xy 414.89635 -394.256249) (xy 414.91446 -394.306281) (xy 414.923662 -394.358688)
			(xy 414.92424 -394.385292) (xy 414.92373 -394.409281) (xy 414.916226 -394.45667) (xy 414.901402 -394.502301)
			(xy 414.879622 -394.545051) (xy 414.851423 -394.583869) (xy 414.817499 -394.617797) (xy 414.778686 -394.646001)
			(xy 414.735938 -394.667787) (xy 414.690309 -394.682617) (xy 414.642921 -394.690127) (xy 414.618932 -394.6906)
			(xy 414.595359 -394.69018) (xy 414.548772 -394.682944) (xy 414.503854 -394.668623) (xy 414.461675 -394.647558)
			(xy 414.423242 -394.620253) (xy 414.38947 -394.587357) (xy 414.361163 -394.549654) (xy 414.349692 -394.529056)
			(xy 414.349184 -394.528294) (xy 413.95142 -393.839954) (xy 413.939487 -393.817294) (xy 413.922556 -393.768965)
			(xy 413.913903 -393.718491) (xy 413.91332 -393.692888) (xy 413.37158 -393.692888) (xy 413.683704 -394.232892)
			(xy 413.696455 -394.256249) (xy 413.714564 -394.306281) (xy 413.723766 -394.358688) (xy 413.724344 -394.385292)
			(xy 413.72383 -394.409281) (xy 413.716326 -394.456669) (xy 413.701502 -394.5023) (xy 413.679723 -394.54505)
			(xy 413.651524 -394.583867) (xy 413.617601 -394.617796) (xy 413.578788 -394.646) (xy 413.536041 -394.667785)
			(xy 413.490412 -394.682616) (xy 413.443025 -394.690127) (xy 413.419036 -394.6906) (xy 413.395463 -394.690177)
			(xy 413.348876 -394.682941) (xy 413.303958 -394.668621) (xy 413.26178 -394.647557) (xy 413.223346 -394.620252)
			(xy 413.189574 -394.587356) (xy 413.161267 -394.549654) (xy 413.149796 -394.529056) (xy 413.149288 -394.528294)
			(xy 412.751524 -393.839954) (xy 412.739592 -393.817294) (xy 412.72266 -393.768965) (xy 412.714007 -393.718491)
			(xy 412.713424 -393.692888) (xy 412.17143 -393.692888) (xy 412.483554 -394.232892) (xy 412.49638 -394.256224)
			(xy 412.514599 -394.306247) (xy 412.523859 -394.358673) (xy 412.524448 -394.385292) (xy 412.523954 -394.409296)
			(xy 412.516441 -394.456711) (xy 412.501601 -394.502367) (xy 412.479798 -394.545138) (xy 412.45157 -394.583969)
			(xy 412.417612 -394.617904) (xy 412.378762 -394.646106) (xy 412.335977 -394.66788) (xy 412.290311 -394.68269)
			(xy 412.24289 -394.69017) (xy 412.218886 -394.6906) (xy 412.195312 -394.690217) (xy 412.148723 -394.682974)
			(xy 412.103804 -394.668646) (xy 412.061626 -394.647576) (xy 412.023193 -394.620264) (xy 411.989421 -394.587363)
			(xy 411.961116 -394.549656) (xy 411.949646 -394.529056) (xy 411.949138 -394.528294) (xy 411.551374 -393.839954)
			(xy 411.539517 -393.817268) (xy 411.522659 -393.768939) (xy 411.514078 -393.718479) (xy 411.513528 -393.692888)
			(xy 410.971534 -393.692888) (xy 411.283658 -394.232892) (xy 411.296484 -394.256224) (xy 411.314704 -394.306247)
			(xy 411.323963 -394.358673) (xy 411.324552 -394.385292) (xy 411.324054 -394.409295) (xy 411.316542 -394.456711)
			(xy 411.301701 -394.502366) (xy 411.279899 -394.545137) (xy 411.251671 -394.583968) (xy 411.217714 -394.617902)
			(xy 411.178864 -394.646104) (xy 411.136079 -394.667879) (xy 411.090414 -394.682689) (xy 411.042994 -394.690169)
			(xy 411.01899 -394.6906) (xy 410.995416 -394.690214) (xy 410.948827 -394.682971) (xy 410.903908 -394.668644)
			(xy 410.86173 -394.647574) (xy 410.823297 -394.620263) (xy 410.789526 -394.587363) (xy 410.76122 -394.549656)
			(xy 410.74975 -394.529056) (xy 410.749242 -394.528294) (xy 410.351478 -393.839954) (xy 410.339621 -393.817268)
			(xy 410.322763 -393.768939) (xy 410.314182 -393.718479) (xy 410.313632 -393.692888) (xy 409.771638 -393.692888)
			(xy 410.083762 -394.232892) (xy 410.096589 -394.256224) (xy 410.114808 -394.306247) (xy 410.124067 -394.358673)
			(xy 410.124656 -394.385292) (xy 410.124154 -394.409295) (xy 410.116642 -394.45671) (xy 410.101802 -394.502365)
			(xy 410.079999 -394.545135) (xy 410.051772 -394.583966) (xy 410.017815 -394.617901) (xy 409.978966 -394.646103)
			(xy 409.936182 -394.667878) (xy 409.890517 -394.682688) (xy 409.843098 -394.690169) (xy 409.819094 -394.6906)
			(xy 409.79552 -394.690211) (xy 409.748931 -394.682969) (xy 409.704013 -394.668642) (xy 409.661834 -394.647573)
			(xy 409.623401 -394.620262) (xy 409.58963 -394.587362) (xy 409.561324 -394.549656) (xy 409.549854 -394.529056)
			(xy 409.549346 -394.528294) (xy 409.151582 -393.839954) (xy 409.139725 -393.817268) (xy 409.122867 -393.768939)
			(xy 409.114286 -393.718479) (xy 409.113736 -393.692888) (xy 408.571488 -393.692888) (xy 408.883612 -394.232892)
			(xy 408.896363 -394.256248) (xy 408.914472 -394.306281) (xy 408.923674 -394.358688) (xy 408.924252 -394.385292)
			(xy 408.92373 -394.409281) (xy 408.916227 -394.456668) (xy 408.901403 -394.502298) (xy 408.879624 -394.545048)
			(xy 408.851427 -394.583865) (xy 408.817504 -394.617793) (xy 408.778692 -394.645997) (xy 408.735946 -394.667783)
			(xy 408.690319 -394.682614) (xy 408.642933 -394.690126) (xy 408.618944 -394.6906) (xy 408.595371 -394.690171)
			(xy 408.548785 -394.682936) (xy 408.503867 -394.668616) (xy 408.461689 -394.647554) (xy 408.423255 -394.620249)
			(xy 408.389482 -394.587355) (xy 408.361175 -394.549654) (xy 408.349704 -394.529056) (xy 408.349196 -394.528294)
			(xy 407.951432 -393.839954) (xy 407.9395 -393.817294) (xy 407.922568 -393.768965) (xy 407.913915 -393.718491)
			(xy 407.913332 -393.692888) (xy 407.371592 -393.692888) (xy 407.683716 -394.232892) (xy 407.696468 -394.256248)
			(xy 407.714576 -394.306281) (xy 407.723778 -394.358688) (xy 407.724356 -394.385292) (xy 407.72383 -394.409281)
			(xy 407.716327 -394.456667) (xy 407.701503 -394.502297) (xy 407.679725 -394.545047) (xy 407.651528 -394.583863)
			(xy 407.617606 -394.617791) (xy 407.578794 -394.645996) (xy 407.536049 -394.667782) (xy 407.490422 -394.682614)
			(xy 407.443037 -394.690126) (xy 407.419048 -394.6906) (xy 407.395475 -394.690168) (xy 407.348889 -394.682933)
			(xy 407.303971 -394.668614) (xy 407.261793 -394.647552) (xy 407.223359 -394.620248) (xy 407.189586 -394.587354)
			(xy 407.161279 -394.549654) (xy 407.149808 -394.529056) (xy 407.1493 -394.528294) (xy 406.751536 -393.839954)
			(xy 406.739605 -393.817294) (xy 406.722672 -393.768964) (xy 406.714019 -393.718491) (xy 406.713436 -393.692888)
			(xy 406.171442 -393.692888) (xy 406.483566 -394.232892) (xy 406.496393 -394.256223) (xy 406.514612 -394.306247)
			(xy 406.523871 -394.358673) (xy 406.52446 -394.385292) (xy 406.524053 -394.4093) (xy 406.516538 -394.456724)
			(xy 406.501693 -394.502388) (xy 406.479882 -394.545164) (xy 406.451644 -394.583999) (xy 406.417675 -394.617935)
			(xy 406.378813 -394.646136) (xy 406.336016 -394.667905) (xy 406.290338 -394.682707) (xy 406.242906 -394.690176)
			(xy 406.218898 -394.6906) (xy 406.195324 -394.690208) (xy 406.148736 -394.682966) (xy 406.103817 -394.66864)
			(xy 406.061639 -394.647571) (xy 406.023206 -394.620261) (xy 405.989434 -394.587361) (xy 405.961128 -394.549656)
			(xy 405.949658 -394.529056) (xy 405.94915 -394.528294) (xy 405.551386 -393.839954) (xy 405.53953 -393.817267)
			(xy 405.522671 -393.768939) (xy 405.51409 -393.718479) (xy 405.51354 -393.692888) (xy 404.971546 -393.692888)
			(xy 405.28367 -394.232892) (xy 405.296497 -394.256223) (xy 405.314716 -394.306247) (xy 405.323975 -394.358673)
			(xy 405.324564 -394.385292) (xy 405.324153 -394.4093) (xy 405.316639 -394.456724) (xy 405.301793 -394.502387)
			(xy 405.279983 -394.545163) (xy 405.251745 -394.583998) (xy 405.217777 -394.617934) (xy 405.178915 -394.646134)
			(xy 405.136118 -394.667904) (xy 405.090441 -394.682706) (xy 405.04301 -394.690176) (xy 405.019002 -394.6906)
			(xy 404.995428 -394.690205) (xy 404.94884 -394.682963) (xy 404.903921 -394.668638) (xy 404.861743 -394.64757)
			(xy 404.82331 -394.62026) (xy 404.789538 -394.587361) (xy 404.761233 -394.549656) (xy 404.749762 -394.529056)
			(xy 404.749254 -394.528294) (xy 404.35149 -393.839954) (xy 404.339634 -393.817267) (xy 404.322775 -393.768939)
			(xy 404.314194 -393.718479) (xy 404.313644 -393.692888) (xy 403.77165 -393.692888) (xy 404.083774 -394.232892)
			(xy 404.096601 -394.256223) (xy 404.11482 -394.306247) (xy 404.124079 -394.358673) (xy 404.124668 -394.385292)
			(xy 404.124253 -394.4093) (xy 404.116739 -394.456723) (xy 404.101893 -394.502386) (xy 404.080083 -394.545162)
			(xy 404.051846 -394.583996) (xy 404.017879 -394.617932) (xy 403.979017 -394.646133) (xy 403.936221 -394.667903)
			(xy 403.890545 -394.682706) (xy 403.843114 -394.690176) (xy 403.819106 -394.6906) (xy 403.795532 -394.690201)
			(xy 403.748944 -394.682961) (xy 403.704026 -394.668636) (xy 403.661847 -394.647568) (xy 403.623414 -394.620259)
			(xy 403.589642 -394.58736) (xy 403.561337 -394.549655) (xy 403.549866 -394.529056) (xy 403.549358 -394.528294)
			(xy 403.151594 -393.839954) (xy 403.139738 -393.817267) (xy 403.122879 -393.768939) (xy 403.114298 -393.718479)
			(xy 403.113748 -393.692888) (xy 389.243866 -393.692888) (xy 389.55599 -394.232892) (xy 389.568819 -394.256222)
			(xy 389.587037 -394.306246) (xy 389.596295 -394.358673) (xy 389.596884 -394.385292) (xy 389.596453 -394.409299)
			(xy 389.588939 -394.456721) (xy 389.574095 -394.502382) (xy 389.552286 -394.545157) (xy 389.524051 -394.583991)
			(xy 389.490085 -394.617927) (xy 389.451226 -394.646128) (xy 389.408432 -394.667898) (xy 389.362758 -394.682702)
			(xy 389.315329 -394.690175) (xy 389.291322 -394.6906) (xy 389.267749 -394.690188) (xy 389.221161 -394.68295)
			(xy 389.176243 -394.668628) (xy 389.134065 -394.647562) (xy 389.095631 -394.620255) (xy 389.061859 -394.587358)
			(xy 389.033553 -394.549655) (xy 389.022082 -394.529056) (xy 389.021574 -394.528294) (xy 388.62381 -393.839954)
			(xy 388.611948 -393.81727) (xy 388.595093 -393.76894) (xy 388.586513 -393.71848) (xy 388.585964 -393.692888)
			(xy 388.043716 -393.692888) (xy 388.35584 -394.232892) (xy 388.368594 -394.256247) (xy 388.386701 -394.30628)
			(xy 388.395902 -394.358688) (xy 388.39648 -394.385292) (xy 388.396054 -394.409286) (xy 388.388548 -394.456684)
			(xy 388.373719 -394.502324) (xy 388.351932 -394.545082) (xy 388.323724 -394.583905) (xy 388.28979 -394.617837)
			(xy 388.250965 -394.646042) (xy 388.208206 -394.667826) (xy 388.162565 -394.682653) (xy 388.115166 -394.690156)
			(xy 388.091172 -394.6906) (xy 388.067597 -394.690229) (xy 388.021008 -394.682983) (xy 387.976089 -394.668653)
			(xy 387.93391 -394.647581) (xy 387.895478 -394.620268) (xy 387.861707 -394.587365) (xy 387.833402 -394.549657)
			(xy 387.821932 -394.529056) (xy 387.821424 -394.528294) (xy 387.42366 -393.839954) (xy 387.41173 -393.817293)
			(xy 387.394797 -393.768964) (xy 387.386143 -393.718491) (xy 387.38556 -393.692888) (xy 386.84382 -393.692888)
			(xy 387.155944 -394.232892) (xy 387.168698 -394.256247) (xy 387.186805 -394.30628) (xy 387.196006 -394.358688)
			(xy 387.196584 -394.385292) (xy 387.196154 -394.409286) (xy 387.188648 -394.456684) (xy 387.173819 -394.502323)
			(xy 387.152033 -394.545081) (xy 387.123825 -394.583904) (xy 387.089892 -394.617836) (xy 387.051067 -394.646041)
			(xy 387.008308 -394.667825) (xy 386.962668 -394.682652) (xy 386.91527 -394.690156) (xy 386.891276 -394.6906)
			(xy 386.867701 -394.690226) (xy 386.821112 -394.68298) (xy 386.776193 -394.668651) (xy 386.734015 -394.647579)
			(xy 386.695582 -394.620267) (xy 386.661811 -394.587365) (xy 386.633506 -394.549657) (xy 386.622036 -394.529056)
			(xy 386.621528 -394.528294) (xy 386.223764 -393.839954) (xy 386.211835 -393.817292) (xy 386.194901 -393.768964)
			(xy 386.186248 -393.718491) (xy 386.185664 -393.692888) (xy 385.64367 -393.692888) (xy 385.955794 -394.232892)
			(xy 385.968623 -394.256222) (xy 385.986841 -394.306246) (xy 385.996099 -394.358673) (xy 385.996688 -394.385292)
			(xy 385.996253 -394.409299) (xy 385.988739 -394.45672) (xy 385.973895 -394.502381) (xy 385.952087 -394.545156)
			(xy 385.923852 -394.58399) (xy 385.889887 -394.617925) (xy 385.851029 -394.646126) (xy 385.808235 -394.667897)
			(xy 385.762561 -394.682702) (xy 385.715133 -394.690174) (xy 385.691126 -394.6906) (xy 385.667553 -394.690185)
			(xy 385.620965 -394.682948) (xy 385.576047 -394.668626) (xy 385.533869 -394.64756) (xy 385.495436 -394.620254)
			(xy 385.461663 -394.587357) (xy 385.433357 -394.549655) (xy 385.421886 -394.529056) (xy 385.421378 -394.528294)
			(xy 385.023614 -393.839954) (xy 385.011752 -393.81727) (xy 384.994897 -393.76894) (xy 384.986317 -393.71848)
			(xy 384.985768 -393.692888) (xy 384.443774 -393.692888) (xy 384.755898 -394.232892) (xy 384.768719 -394.256226)
			(xy 384.786942 -394.306248) (xy 384.796203 -394.358674) (xy 384.796792 -394.385292) (xy 384.796353 -394.409298)
			(xy 384.78884 -394.45672) (xy 384.773996 -394.50238) (xy 384.752188 -394.545155) (xy 384.723953 -394.583988)
			(xy 384.689989 -394.617924) (xy 384.651131 -394.646125) (xy 384.608338 -394.667896) (xy 384.562664 -394.682701)
			(xy 384.515237 -394.690174) (xy 384.49123 -394.6906) (xy 384.467657 -394.690182) (xy 384.42107 -394.682945)
			(xy 384.376152 -394.668624) (xy 384.333973 -394.647559) (xy 384.29554 -394.620253) (xy 384.261768 -394.587357)
			(xy 384.233461 -394.549654) (xy 384.22199 -394.529056) (xy 384.221482 -394.528294) (xy 383.823718 -393.839954)
			(xy 383.811856 -393.81727) (xy 383.795001 -393.76894) (xy 383.786421 -393.71848) (xy 383.785872 -393.692888)
			(xy 383.243878 -393.692888) (xy 383.556002 -394.232892) (xy 383.568824 -394.256226) (xy 383.587046 -394.306248)
			(xy 383.596307 -394.358674) (xy 383.596896 -394.385292) (xy 383.596453 -394.409298) (xy 383.58894 -394.456719)
			(xy 383.574096 -394.502379) (xy 383.552288 -394.545153) (xy 383.524055 -394.583987) (xy 383.49009 -394.617922)
			(xy 383.451233 -394.646123) (xy 383.408441 -394.667895) (xy 383.362768 -394.6827) (xy 383.315341 -394.690174)
			(xy 383.291334 -394.6906) (xy 383.267761 -394.690179) (xy 383.221174 -394.682942) (xy 383.176256 -394.668622)
			(xy 383.134078 -394.647557) (xy 383.095644 -394.620252) (xy 383.061872 -394.587356) (xy 383.033565 -394.549654)
			(xy 383.022094 -394.529056) (xy 383.021586 -394.528294) (xy 382.623822 -393.839954) (xy 382.611961 -393.81727)
			(xy 382.595105 -393.76894) (xy 382.586526 -393.71848) (xy 382.585976 -393.692888) (xy 382.043728 -393.692888)
			(xy 382.355852 -394.232892) (xy 382.368607 -394.256246) (xy 382.386713 -394.30628) (xy 382.395914 -394.358688)
			(xy 382.396492 -394.385292) (xy 382.396054 -394.409286) (xy 382.388548 -394.456682) (xy 382.37372 -394.502321)
			(xy 382.351934 -394.545079) (xy 382.323728 -394.583901) (xy 382.289795 -394.617833) (xy 382.250972 -394.646038)
			(xy 382.208214 -394.667823) (xy 382.162575 -394.68265) (xy 382.115178 -394.690155) (xy 382.091184 -394.6906)
			(xy 382.06761 -394.690219) (xy 382.021021 -394.682975) (xy 381.976102 -394.668647) (xy 381.933923 -394.647576)
			(xy 381.895491 -394.620265) (xy 381.861719 -394.587363) (xy 381.833414 -394.549656) (xy 381.821944 -394.529056)
			(xy 381.821436 -394.528294) (xy 381.423672 -393.839954) (xy 381.411736 -393.817296) (xy 381.394806 -393.768965)
			(xy 381.386155 -393.718492) (xy 381.385572 -393.692888) (xy 380.843832 -393.692888) (xy 381.155956 -394.232892)
			(xy 381.168711 -394.256246) (xy 381.186817 -394.30628) (xy 381.196018 -394.358688) (xy 381.196596 -394.385292)
			(xy 381.196154 -394.409286) (xy 381.188648 -394.456682) (xy 381.17382 -394.50232) (xy 381.152035 -394.545077)
			(xy 381.123829 -394.5839) (xy 381.089897 -394.617831) (xy 381.051074 -394.646037) (xy 381.008317 -394.667822)
			(xy 380.962678 -394.682649) (xy 380.915282 -394.690155) (xy 380.891288 -394.6906) (xy 380.867714 -394.690216)
			(xy 380.821125 -394.682973) (xy 380.776206 -394.668645) (xy 380.734028 -394.647575) (xy 380.695595 -394.620264)
			(xy 380.661823 -394.587363) (xy 380.633518 -394.549656) (xy 380.622048 -394.529056) (xy 380.62154 -394.528294)
			(xy 380.223776 -393.839954) (xy 380.21184 -393.817296) (xy 380.19491 -393.768965) (xy 380.186259 -393.718492)
			(xy 380.185676 -393.692888) (xy 379.643682 -393.692888) (xy 379.955806 -394.232892) (xy 379.968628 -394.256226)
			(xy 379.98685 -394.306248) (xy 379.996111 -394.358674) (xy 379.9967 -394.385292) (xy 379.996254 -394.409298)
			(xy 379.98874 -394.456718) (xy 379.973896 -394.502378) (xy 379.952089 -394.545152) (xy 379.923856 -394.583985)
			(xy 379.889892 -394.617921) (xy 379.851035 -394.646122) (xy 379.808243 -394.667894) (xy 379.762571 -394.682699)
			(xy 379.715144 -394.690173) (xy 379.691138 -394.6906) (xy 379.667565 -394.690176) (xy 379.620978 -394.68294)
			(xy 379.57606 -394.66862) (xy 379.533882 -394.647556) (xy 379.495448 -394.620251) (xy 379.461676 -394.587356)
			(xy 379.433369 -394.549654) (xy 379.421898 -394.529056) (xy 379.42139 -394.528294) (xy 379.023626 -393.839954)
			(xy 379.011765 -393.81727) (xy 378.994909 -393.76894) (xy 378.98633 -393.71848) (xy 378.98578 -393.692888)
			(xy 378.443786 -393.692888) (xy 378.75591 -394.232892) (xy 378.768732 -394.256226) (xy 378.786954 -394.306248)
			(xy 378.796215 -394.358673) (xy 378.796804 -394.385292) (xy 378.796354 -394.409298) (xy 378.78884 -394.456718)
			(xy 378.773997 -394.502377) (xy 378.75219 -394.545151) (xy 378.723957 -394.583984) (xy 378.689994 -394.61792)
			(xy 378.651137 -394.646121) (xy 378.608346 -394.667893) (xy 378.562674 -394.682698) (xy 378.515248 -394.690173)
			(xy 378.491242 -394.6906) (xy 378.467669 -394.690172) (xy 378.421083 -394.682937) (xy 378.376165 -394.668617)
			(xy 378.333986 -394.647554) (xy 378.295553 -394.62025) (xy 378.26178 -394.587355) (xy 378.233473 -394.549654)
			(xy 378.222002 -394.529056) (xy 378.221494 -394.528294) (xy 377.82373 -393.839954) (xy 377.811869 -393.81727)
			(xy 377.795013 -393.76894) (xy 377.786434 -393.71848) (xy 377.785884 -393.692888) (xy 377.24389 -393.692888)
			(xy 377.556014 -394.232892) (xy 377.568837 -394.256226) (xy 377.587058 -394.306248) (xy 377.596319 -394.358673)
			(xy 377.596908 -394.385292) (xy 377.596454 -394.409298) (xy 377.58894 -394.456717) (xy 377.574097 -394.502377)
			(xy 377.552291 -394.54515) (xy 377.524058 -394.583983) (xy 377.490095 -394.617918) (xy 377.45124 -394.646119)
			(xy 377.408449 -394.667891) (xy 377.362778 -394.682698) (xy 377.315352 -394.690173) (xy 377.291346 -394.6906)
			(xy 377.267773 -394.690169) (xy 377.221187 -394.682935) (xy 377.176269 -394.668615) (xy 377.134091 -394.647553)
			(xy 377.095657 -394.620249) (xy 377.061884 -394.587355) (xy 377.033577 -394.549654) (xy 377.022106 -394.529056)
			(xy 377.021598 -394.528294) (xy 376.623834 -393.839954) (xy 376.611974 -393.81727) (xy 376.595118 -393.76894)
			(xy 376.586538 -393.71848) (xy 376.585988 -393.692888) (xy 376.04374 -393.692888) (xy 376.355864 -394.232892)
			(xy 376.36862 -394.256246) (xy 376.386726 -394.30628) (xy 376.395926 -394.358688) (xy 376.396504 -394.385292)
			(xy 376.396054 -394.409285) (xy 376.388549 -394.456681) (xy 376.373721 -394.502319) (xy 376.351936 -394.545075)
			(xy 376.323731 -394.583897) (xy 376.2898 -394.617829) (xy 376.250978 -394.646034) (xy 376.208222 -394.66782)
			(xy 376.162585 -394.682648) (xy 376.115189 -394.690154) (xy 376.091196 -394.6906) (xy 376.067622 -394.690209)
			(xy 376.021033 -394.682967) (xy 375.976115 -394.668641) (xy 375.933936 -394.647572) (xy 375.895503 -394.620262)
			(xy 375.861732 -394.587362) (xy 375.833426 -394.549656) (xy 375.821956 -394.529056) (xy 375.821448 -394.528294)
			(xy 375.423684 -393.839954) (xy 375.411748 -393.817296) (xy 375.394819 -393.768965) (xy 375.386167 -393.718492)
			(xy 375.385584 -393.692888) (xy 374.843844 -393.692888) (xy 375.155968 -394.232892) (xy 375.168724 -394.256246)
			(xy 375.18683 -394.30628) (xy 375.19603 -394.358688) (xy 375.196608 -394.385292) (xy 375.196154 -394.409285)
			(xy 375.188649 -394.45668) (xy 375.173821 -394.502318) (xy 375.152037 -394.545074) (xy 375.123832 -394.583896)
			(xy 375.089902 -394.617827) (xy 375.051081 -394.646033) (xy 375.008325 -394.667818) (xy 374.962688 -394.682647)
			(xy 374.915293 -394.690154) (xy 374.8913 -394.6906) (xy 374.867726 -394.690206) (xy 374.821138 -394.682965)
			(xy 374.776219 -394.668639) (xy 374.734041 -394.64757) (xy 374.695608 -394.620261) (xy 374.661836 -394.587361)
			(xy 374.63353 -394.549656) (xy 374.62206 -394.529056) (xy 374.621552 -394.528294) (xy 374.223788 -393.839954)
			(xy 374.211853 -393.817296) (xy 374.194923 -393.768965) (xy 374.186271 -393.718491) (xy 374.185688 -393.692888)
			(xy 373.643694 -393.692888) (xy 373.955818 -394.232892) (xy 373.968641 -394.256226) (xy 373.986862 -394.306248)
			(xy 373.996123 -394.358673) (xy 373.996712 -394.385292) (xy 373.996254 -394.409297) (xy 373.98874 -394.456717)
			(xy 373.973898 -394.502376) (xy 373.952091 -394.545149) (xy 373.923859 -394.583981) (xy 373.889897 -394.617917)
			(xy 373.851042 -394.646118) (xy 373.808252 -394.66789) (xy 373.762581 -394.682697) (xy 373.715156 -394.690172)
			(xy 373.69115 -394.6906) (xy 373.667577 -394.690166) (xy 373.620991 -394.682932) (xy 373.576073 -394.668613)
			(xy 373.533895 -394.647551) (xy 373.495461 -394.620248) (xy 373.461688 -394.587354) (xy 373.433381 -394.549653)
			(xy 373.42191 -394.529056) (xy 373.421402 -394.528294) (xy 373.023638 -393.839954) (xy 373.011778 -393.817269)
			(xy 372.994922 -393.76894) (xy 372.986342 -393.71848) (xy 372.985792 -393.692888) (xy 372.443798 -393.692888)
			(xy 372.755922 -394.232892) (xy 372.768745 -394.256225) (xy 372.786966 -394.306248) (xy 372.796227 -394.358673)
			(xy 372.796816 -394.385292) (xy 372.796354 -394.409297) (xy 372.78884 -394.456716) (xy 372.773998 -394.502375)
			(xy 372.752192 -394.545147) (xy 372.72396 -394.58398) (xy 372.689999 -394.617915) (xy 372.651144 -394.646117)
			(xy 372.608354 -394.667889) (xy 372.562684 -394.682696) (xy 372.51526 -394.690172) (xy 372.491254 -394.6906)
			(xy 372.467682 -394.690163) (xy 372.421095 -394.682929) (xy 372.376178 -394.668611) (xy 372.333999 -394.64755)
			(xy 372.295566 -394.620247) (xy 372.261793 -394.587353) (xy 372.233485 -394.549653) (xy 372.222014 -394.529056)
			(xy 372.221506 -394.528294) (xy 371.823742 -393.839954) (xy 371.811882 -393.817269) (xy 371.795026 -393.76894)
			(xy 371.786446 -393.71848) (xy 371.785896 -393.692888) (xy 371.243902 -393.692888) (xy 371.556026 -394.232892)
			(xy 371.56885 -394.256225) (xy 371.587071 -394.306247) (xy 371.596331 -394.358673) (xy 371.59692 -394.385292)
			(xy 371.596454 -394.409297) (xy 371.588941 -394.456716) (xy 371.574098 -394.502374) (xy 371.552293 -394.545146)
			(xy 371.524062 -394.583979) (xy 371.4901 -394.617914) (xy 371.451246 -394.646115) (xy 371.408457 -394.667888)
			(xy 371.362788 -394.682695) (xy 371.315363 -394.690172) (xy 371.291358 -394.6906) (xy 371.267786 -394.690159)
			(xy 371.2212 -394.682927) (xy 371.176282 -394.668609) (xy 371.134104 -394.647548) (xy 371.09567 -394.620246)
			(xy 371.061897 -394.587353) (xy 371.03359 -394.549653) (xy 371.022118 -394.529056) (xy 371.02161 -394.528294)
			(xy 370.623846 -393.839954) (xy 370.611986 -393.817269) (xy 370.59513 -393.76894) (xy 370.58655 -393.71848)
			(xy 370.586 -393.692888) (xy 354.671418 -393.692888) (xy 354.983542 -394.232892) (xy 354.996367 -394.256224)
			(xy 355.014587 -394.306247) (xy 355.023847 -394.358673) (xy 355.024436 -394.385292) (xy 355.023954 -394.409296)
			(xy 355.016441 -394.456713) (xy 355.0016 -394.50237) (xy 354.979796 -394.545141) (xy 354.951566 -394.583973)
			(xy 354.917607 -394.617908) (xy 354.878755 -394.64611) (xy 354.835968 -394.667883) (xy 354.790301 -394.682692)
			(xy 354.742879 -394.690171) (xy 354.718874 -394.6906) (xy 354.695299 -394.690227) (xy 354.64871 -394.682982)
			(xy 354.603791 -394.668652) (xy 354.561613 -394.64758) (xy 354.52318 -394.620267) (xy 354.489409 -394.587365)
			(xy 354.461104 -394.549657) (xy 354.449634 -394.529056) (xy 354.449126 -394.528294) (xy 354.051362 -393.839954)
			(xy 354.039504 -393.817268) (xy 354.022646 -393.76894) (xy 354.014066 -393.71848) (xy 354.013516 -393.692888)
			(xy 353.471522 -393.692888) (xy 353.783646 -394.232892) (xy 353.796471 -394.256224) (xy 353.814691 -394.306247)
			(xy 353.823951 -394.358673) (xy 353.82454 -394.385292) (xy 353.824054 -394.409296) (xy 353.816541 -394.456713)
			(xy 353.8017 -394.502369) (xy 353.779896 -394.54514) (xy 353.751667 -394.583972) (xy 353.717709 -394.617907)
			(xy 353.678857 -394.646108) (xy 353.636071 -394.667882) (xy 353.590404 -394.682691) (xy 353.542982 -394.69017)
			(xy 353.518978 -394.6906) (xy 353.495403 -394.690224) (xy 353.448814 -394.682979) (xy 353.403895 -394.66865)
			(xy 353.361717 -394.647579) (xy 353.323284 -394.620266) (xy 353.289513 -394.587364) (xy 353.261208 -394.549657)
			(xy 353.249738 -394.529056) (xy 353.24923 -394.528294) (xy 352.851466 -393.839954) (xy 352.839608 -393.817268)
			(xy 352.82275 -393.76894) (xy 352.81417 -393.71848) (xy 352.81362 -393.692888) (xy 352.271372 -393.692888)
			(xy 352.583496 -394.232892) (xy 352.596246 -394.256249) (xy 352.614355 -394.306281) (xy 352.623558 -394.358688)
			(xy 352.624136 -394.385292) (xy 352.62363 -394.409282) (xy 352.616126 -394.45667) (xy 352.601301 -394.502302)
			(xy 352.579521 -394.545053) (xy 352.551322 -394.58387) (xy 352.517397 -394.617798) (xy 352.478583 -394.646002)
			(xy 352.435835 -394.667788) (xy 352.390205 -394.682618) (xy 352.342818 -394.690127) (xy 352.318828 -394.6906)
			(xy 352.295255 -394.690184) (xy 352.248668 -394.682946) (xy 352.20375 -394.668625) (xy 352.161571 -394.64756)
			(xy 352.123138 -394.620254) (xy 352.089365 -394.587357) (xy 352.061059 -394.549654) (xy 352.049588 -394.529056)
			(xy 352.04908 -394.528294) (xy 351.651316 -393.839954) (xy 351.639383 -393.817294) (xy 351.622452 -393.768965)
			(xy 351.613799 -393.718491) (xy 351.613216 -393.692888) (xy 351.071476 -393.692888) (xy 351.3836 -394.232892)
			(xy 351.39635 -394.256249) (xy 351.41446 -394.306281) (xy 351.423662 -394.358688) (xy 351.42424 -394.385292)
			(xy 351.42373 -394.409281) (xy 351.416226 -394.45667) (xy 351.401402 -394.502301) (xy 351.379622 -394.545051)
			(xy 351.351423 -394.583869) (xy 351.317499 -394.617797) (xy 351.278686 -394.646001) (xy 351.235938 -394.667787)
			(xy 351.190309 -394.682617) (xy 351.142921 -394.690127) (xy 351.118932 -394.6906) (xy 351.095359 -394.69018)
			(xy 351.048772 -394.682944) (xy 351.003854 -394.668623) (xy 350.961675 -394.647558) (xy 350.923242 -394.620253)
			(xy 350.88947 -394.587357) (xy 350.861163 -394.549654) (xy 350.849692 -394.529056) (xy 350.849184 -394.528294)
			(xy 350.45142 -393.839954) (xy 350.439487 -393.817294) (xy 350.422556 -393.768965) (xy 350.413903 -393.718491)
			(xy 350.41332 -393.692888) (xy 349.871326 -393.692888) (xy 350.18345 -394.232892) (xy 350.196276 -394.256224)
			(xy 350.214495 -394.306247) (xy 350.223755 -394.358673) (xy 350.224344 -394.385292) (xy 350.223854 -394.409296)
			(xy 350.216341 -394.456712) (xy 350.201501 -394.502368) (xy 350.179697 -394.545139) (xy 350.151469 -394.58397)
			(xy 350.11751 -394.617905) (xy 350.07866 -394.646107) (xy 350.035874 -394.667881) (xy 349.990207 -394.68269)
			(xy 349.942786 -394.69017) (xy 349.918782 -394.6906) (xy 349.895207 -394.690221) (xy 349.848619 -394.682977)
			(xy 349.8037 -394.668648) (xy 349.761521 -394.647577) (xy 349.723088 -394.620265) (xy 349.689317 -394.587364)
			(xy 349.661012 -394.549657) (xy 349.649542 -394.529056) (xy 349.649034 -394.528294) (xy 349.25127 -393.839954)
			(xy 349.239412 -393.817268) (xy 349.222555 -393.768939) (xy 349.213974 -393.71848) (xy 349.213424 -393.692888)
			(xy 348.67143 -393.692888) (xy 348.983554 -394.232892) (xy 348.99638 -394.256224) (xy 349.014599 -394.306247)
			(xy 349.023859 -394.358673) (xy 349.024448 -394.385292) (xy 349.023954 -394.409296) (xy 349.016441 -394.456711)
			(xy 349.001601 -394.502367) (xy 348.979798 -394.545138) (xy 348.95157 -394.583969) (xy 348.917612 -394.617904)
			(xy 348.878762 -394.646106) (xy 348.835977 -394.66788) (xy 348.790311 -394.68269) (xy 348.74289 -394.69017)
			(xy 348.718886 -394.6906) (xy 348.695312 -394.690217) (xy 348.648723 -394.682974) (xy 348.603804 -394.668646)
			(xy 348.561626 -394.647576) (xy 348.523193 -394.620264) (xy 348.489421 -394.587363) (xy 348.461116 -394.549656)
			(xy 348.449646 -394.529056) (xy 348.449138 -394.528294) (xy 348.051374 -393.839954) (xy 348.039517 -393.817268)
			(xy 348.022659 -393.768939) (xy 348.014078 -393.718479) (xy 348.013528 -393.692888) (xy 347.47128 -393.692888)
			(xy 347.783404 -394.232892) (xy 347.796155 -394.256249) (xy 347.814264 -394.306281) (xy 347.823466 -394.358688)
			(xy 347.824044 -394.385292) (xy 347.82353 -394.409281) (xy 347.816026 -394.456669) (xy 347.801202 -394.5023)
			(xy 347.779423 -394.54505) (xy 347.751224 -394.583867) (xy 347.717301 -394.617796) (xy 347.678488 -394.646)
			(xy 347.635741 -394.667785) (xy 347.590112 -394.682616) (xy 347.542725 -394.690127) (xy 347.518736 -394.6906)
			(xy 347.495163 -394.690177) (xy 347.448576 -394.682941) (xy 347.403658 -394.668621) (xy 347.36148 -394.647557)
			(xy 347.323046 -394.620252) (xy 347.289274 -394.587356) (xy 347.260967 -394.549654) (xy 347.249496 -394.529056)
			(xy 347.248988 -394.528294) (xy 346.851224 -393.839954) (xy 346.839292 -393.817294) (xy 346.82236 -393.768965)
			(xy 346.813707 -393.718491) (xy 346.813124 -393.692888) (xy 346.271384 -393.692888) (xy 346.583508 -394.232892)
			(xy 346.596259 -394.256248) (xy 346.614368 -394.306281) (xy 346.62357 -394.358688) (xy 346.624148 -394.385292)
			(xy 346.62363 -394.409281) (xy 346.616126 -394.456669) (xy 346.601303 -394.502299) (xy 346.579524 -394.545049)
			(xy 346.551325 -394.583866) (xy 346.517403 -394.617794) (xy 346.47859 -394.645998) (xy 346.435843 -394.667784)
			(xy 346.390215 -394.682615) (xy 346.342829 -394.690126) (xy 346.31884 -394.6906) (xy 346.295267 -394.690174)
			(xy 346.24868 -394.682939) (xy 346.203763 -394.668618) (xy 346.161584 -394.647555) (xy 346.123151 -394.620251)
			(xy 346.089378 -394.587355) (xy 346.061071 -394.549654) (xy 346.0496 -394.529056) (xy 346.049092 -394.528294)
			(xy 345.651328 -393.839954) (xy 345.639396 -393.817294) (xy 345.622464 -393.768965) (xy 345.613811 -393.718491)
			(xy 345.613228 -393.692888) (xy 345.071488 -393.692888) (xy 345.383612 -394.232892) (xy 345.396363 -394.256248)
			(xy 345.414472 -394.306281) (xy 345.423674 -394.358688) (xy 345.424252 -394.385292) (xy 345.42373 -394.409281)
			(xy 345.416227 -394.456668) (xy 345.401403 -394.502298) (xy 345.379624 -394.545048) (xy 345.351427 -394.583865)
			(xy 345.317504 -394.617793) (xy 345.278692 -394.645997) (xy 345.235946 -394.667783) (xy 345.190319 -394.682614)
			(xy 345.142933 -394.690126) (xy 345.118944 -394.6906) (xy 345.095371 -394.690171) (xy 345.048785 -394.682936)
			(xy 345.003867 -394.668616) (xy 344.961689 -394.647554) (xy 344.923255 -394.620249) (xy 344.889482 -394.587355)
			(xy 344.861175 -394.549654) (xy 344.849704 -394.529056) (xy 344.849196 -394.528294) (xy 344.451432 -393.839954)
			(xy 344.4395 -393.817294) (xy 344.422568 -393.768965) (xy 344.413915 -393.718491) (xy 344.413332 -393.692888)
			(xy 343.871338 -393.692888) (xy 344.183462 -394.232892) (xy 344.196289 -394.256224) (xy 344.214508 -394.306247)
			(xy 344.223767 -394.358673) (xy 344.224356 -394.385292) (xy 344.223854 -394.409295) (xy 344.216342 -394.45671)
			(xy 344.201502 -394.502365) (xy 344.179699 -394.545135) (xy 344.151472 -394.583966) (xy 344.117515 -394.617901)
			(xy 344.078666 -394.646103) (xy 344.035882 -394.667878) (xy 343.990217 -394.682688) (xy 343.942798 -394.690169)
			(xy 343.918794 -394.6906) (xy 343.89522 -394.690211) (xy 343.848631 -394.682969) (xy 343.803713 -394.668642)
			(xy 343.761534 -394.647573) (xy 343.723101 -394.620262) (xy 343.68933 -394.587362) (xy 343.661024 -394.549656)
			(xy 343.649554 -394.529056) (xy 343.649046 -394.528294) (xy 343.251282 -393.839954) (xy 343.239425 -393.817268)
			(xy 343.222567 -393.768939) (xy 343.213986 -393.718479) (xy 343.213436 -393.692888) (xy 342.671442 -393.692888)
			(xy 342.983566 -394.232892) (xy 342.996393 -394.256223) (xy 343.014612 -394.306247) (xy 343.023871 -394.358673)
			(xy 343.02446 -394.385292) (xy 343.024053 -394.4093) (xy 343.016538 -394.456724) (xy 343.001693 -394.502388)
			(xy 342.979882 -394.545164) (xy 342.951644 -394.583999) (xy 342.917675 -394.617935) (xy 342.878813 -394.646136)
			(xy 342.836016 -394.667905) (xy 342.790338 -394.682707) (xy 342.742906 -394.690176) (xy 342.718898 -394.6906)
			(xy 342.695324 -394.690208) (xy 342.648736 -394.682966) (xy 342.603817 -394.66864) (xy 342.561639 -394.647571)
			(xy 342.523206 -394.620261) (xy 342.489434 -394.587361) (xy 342.461128 -394.549656) (xy 342.449658 -394.529056)
			(xy 342.44915 -394.528294) (xy 342.051386 -393.839954) (xy 342.03953 -393.817267) (xy 342.022671 -393.768939)
			(xy 342.01409 -393.718479) (xy 342.01354 -393.692888) (xy 341.471292 -393.692888) (xy 341.783416 -394.232892)
			(xy 341.796168 -394.256248) (xy 341.814276 -394.306281) (xy 341.823478 -394.358688) (xy 341.824056 -394.385292)
			(xy 341.82353 -394.409281) (xy 341.816027 -394.456667) (xy 341.801203 -394.502297) (xy 341.779425 -394.545047)
			(xy 341.751228 -394.583863) (xy 341.717306 -394.617791) (xy 341.678494 -394.645996) (xy 341.635749 -394.667782)
			(xy 341.590122 -394.682614) (xy 341.542737 -394.690126) (xy 341.518748 -394.6906) (xy 341.495175 -394.690168)
			(xy 341.448589 -394.682933) (xy 341.403671 -394.668614) (xy 341.361493 -394.647552) (xy 341.323059 -394.620248)
			(xy 341.289286 -394.587354) (xy 341.260979 -394.549654) (xy 341.249508 -394.529056) (xy 341.249 -394.528294)
			(xy 340.851236 -393.839954) (xy 340.839305 -393.817294) (xy 340.822372 -393.768964) (xy 340.813719 -393.718491)
			(xy 340.813136 -393.692888) (xy 340.271396 -393.692888) (xy 340.58352 -394.232892) (xy 340.596272 -394.256248)
			(xy 340.61438 -394.306281) (xy 340.623582 -394.358688) (xy 340.62416 -394.385292) (xy 340.623754 -394.409287)
			(xy 340.616247 -394.456687) (xy 340.601417 -394.502329) (xy 340.579628 -394.545088) (xy 340.551418 -394.583912)
			(xy 340.517482 -394.617844) (xy 340.478654 -394.646049) (xy 340.435892 -394.667832) (xy 340.390248 -394.682657)
			(xy 340.342847 -394.690157) (xy 340.318852 -394.6906) (xy 340.295279 -394.690164) (xy 340.248693 -394.682931)
			(xy 340.203776 -394.668612) (xy 340.161597 -394.647551) (xy 340.123164 -394.620247) (xy 340.089391 -394.587354)
			(xy 340.061083 -394.549653) (xy 340.049612 -394.529056) (xy 340.049104 -394.528294) (xy 339.65134 -393.839954)
			(xy 339.639409 -393.817293) (xy 339.622476 -393.768964) (xy 339.613823 -393.718491) (xy 339.61324 -393.692888)
			(xy 339.0715 -393.692888) (xy 339.383624 -394.232892) (xy 339.396376 -394.256248) (xy 339.414484 -394.30628)
			(xy 339.423686 -394.358688) (xy 339.424264 -394.385292) (xy 339.423854 -394.409287) (xy 339.416347 -394.456687)
			(xy 339.401517 -394.502328) (xy 339.379729 -394.545087) (xy 339.351519 -394.583911) (xy 339.317583 -394.617843)
			(xy 339.278756 -394.646048) (xy 339.235995 -394.667831) (xy 339.190352 -394.682656) (xy 339.142951 -394.690157)
			(xy 339.118956 -394.6906) (xy 339.095384 -394.690161) (xy 339.048797 -394.682928) (xy 339.00388 -394.66861)
			(xy 338.961702 -394.647549) (xy 338.923268 -394.620246) (xy 338.889495 -394.587353) (xy 338.861187 -394.549653)
			(xy 338.849716 -394.529056) (xy 338.849208 -394.528294) (xy 338.451444 -393.839954) (xy 338.439513 -393.817293)
			(xy 338.42258 -393.768964) (xy 338.413927 -393.718491) (xy 338.413344 -393.692888) (xy 337.87135 -393.692888)
			(xy 338.183474 -394.232892) (xy 338.196301 -394.256223) (xy 338.21452 -394.306247) (xy 338.223779 -394.358673)
			(xy 338.224368 -394.385292) (xy 338.223953 -394.4093) (xy 338.216439 -394.456723) (xy 338.201593 -394.502386)
			(xy 338.179783 -394.545162) (xy 338.151546 -394.583996) (xy 338.117579 -394.617932) (xy 338.078717 -394.646133)
			(xy 338.035921 -394.667903) (xy 337.990245 -394.682706) (xy 337.942814 -394.690176) (xy 337.918806 -394.6906)
			(xy 337.895232 -394.690201) (xy 337.848644 -394.682961) (xy 337.803726 -394.668636) (xy 337.761547 -394.647568)
			(xy 337.723114 -394.620259) (xy 337.689342 -394.58736) (xy 337.661037 -394.549655) (xy 337.649566 -394.529056)
			(xy 337.649058 -394.528294) (xy 337.251294 -393.839954) (xy 337.239438 -393.817267) (xy 337.222579 -393.768939)
			(xy 337.213998 -393.718479) (xy 337.213448 -393.692888) (xy 336.671454 -393.692888) (xy 336.983578 -394.232892)
			(xy 336.996406 -394.256223) (xy 337.014624 -394.306247) (xy 337.023883 -394.358673) (xy 337.024472 -394.385292)
			(xy 337.024053 -394.409299) (xy 337.016539 -394.456723) (xy 337.001694 -394.502385) (xy 336.979884 -394.545161)
			(xy 336.951648 -394.583995) (xy 336.91768 -394.617931) (xy 336.87882 -394.646132) (xy 336.836024 -394.667902)
			(xy 336.790348 -394.682705) (xy 336.742918 -394.690175) (xy 336.71891 -394.6906) (xy 336.695336 -394.690198)
			(xy 336.648748 -394.682958) (xy 336.60383 -394.668634) (xy 336.561652 -394.647566) (xy 336.523218 -394.620258)
			(xy 336.489447 -394.58736) (xy 336.461141 -394.549655) (xy 336.44967 -394.529056) (xy 336.449162 -394.528294)
			(xy 336.051398 -393.839954) (xy 336.039542 -393.817267) (xy 336.022683 -393.768939) (xy 336.014102 -393.718479)
			(xy 336.013552 -393.692888) (xy 322.143924 -393.692888) (xy 322.456048 -394.232892) (xy 322.468802 -394.256247)
			(xy 322.486909 -394.30628) (xy 322.49611 -394.358688) (xy 322.496688 -394.385292) (xy 322.496254 -394.409286)
			(xy 322.488748 -394.456683) (xy 322.47392 -394.502322) (xy 322.452133 -394.54508) (xy 322.423926 -394.583902)
			(xy 322.389993 -394.617834) (xy 322.35117 -394.64604) (xy 322.308411 -394.667824) (xy 322.262771 -394.682651)
			(xy 322.215374 -394.690155) (xy 322.19138 -394.6906) (xy 322.191126 -394.6906) (xy 322.167553 -394.690185)
			(xy 322.120965 -394.682948) (xy 322.076047 -394.668626) (xy 322.033869 -394.64756) (xy 321.995436 -394.620254)
			(xy 321.961663 -394.587357) (xy 321.933357 -394.549655) (xy 321.921886 -394.529056) (xy 321.921378 -394.528294)
			(xy 321.523614 -393.839954) (xy 321.511752 -393.81727) (xy 321.494897 -393.76894) (xy 321.486317 -393.71848)
			(xy 321.485768 -393.692888) (xy 320.943774 -393.692888) (xy 321.255898 -394.232892) (xy 321.268719 -394.256226)
			(xy 321.286942 -394.306248) (xy 321.296203 -394.358674) (xy 321.296792 -394.385292) (xy 321.296353 -394.409298)
			(xy 321.28884 -394.45672) (xy 321.273996 -394.50238) (xy 321.252188 -394.545155) (xy 321.223953 -394.583988)
			(xy 321.189989 -394.617924) (xy 321.151131 -394.646125) (xy 321.108338 -394.667896) (xy 321.062664 -394.682701)
			(xy 321.015237 -394.690174) (xy 320.99123 -394.6906) (xy 320.967657 -394.690182) (xy 320.92107 -394.682945)
			(xy 320.876152 -394.668624) (xy 320.833973 -394.647559) (xy 320.79554 -394.620253) (xy 320.761768 -394.587357)
			(xy 320.733461 -394.549654) (xy 320.72199 -394.529056) (xy 320.721482 -394.528294) (xy 320.323718 -393.839954)
			(xy 320.311856 -393.81727) (xy 320.295001 -393.76894) (xy 320.286421 -393.71848) (xy 320.285872 -393.692888)
			(xy 319.743878 -393.692888) (xy 320.056002 -394.232892) (xy 320.068824 -394.256226) (xy 320.087046 -394.306248)
			(xy 320.096307 -394.358674) (xy 320.096896 -394.385292) (xy 320.096453 -394.409298) (xy 320.08894 -394.456719)
			(xy 320.074096 -394.502379) (xy 320.052288 -394.545153) (xy 320.024055 -394.583987) (xy 319.99009 -394.617922)
			(xy 319.951233 -394.646123) (xy 319.908441 -394.667895) (xy 319.862768 -394.6827) (xy 319.815341 -394.690174)
			(xy 319.791334 -394.6906) (xy 319.79108 -394.6906) (xy 319.767505 -394.690222) (xy 319.720916 -394.682978)
			(xy 319.675997 -394.668649) (xy 319.633819 -394.647578) (xy 319.595386 -394.620266) (xy 319.561615 -394.587364)
			(xy 319.53331 -394.549657) (xy 319.52184 -394.529056) (xy 319.521332 -394.528294) (xy 319.123568 -393.839954)
			(xy 319.111639 -393.817292) (xy 319.094706 -393.768964) (xy 319.086052 -393.718491) (xy 319.085468 -393.692888)
			(xy 318.543728 -393.692888) (xy 318.855852 -394.232892) (xy 318.868607 -394.256246) (xy 318.886713 -394.30628)
			(xy 318.895914 -394.358688) (xy 318.896492 -394.385292) (xy 318.896054 -394.409286) (xy 318.888548 -394.456682)
			(xy 318.87372 -394.502321) (xy 318.851934 -394.545079) (xy 318.823728 -394.583901) (xy 318.789795 -394.617833)
			(xy 318.750972 -394.646038) (xy 318.708214 -394.667823) (xy 318.662575 -394.68265) (xy 318.615178 -394.690155)
			(xy 318.591184 -394.6906) (xy 318.56761 -394.690219) (xy 318.521021 -394.682975) (xy 318.476102 -394.668647)
			(xy 318.433923 -394.647576) (xy 318.395491 -394.620265) (xy 318.361719 -394.587363) (xy 318.333414 -394.549656)
			(xy 318.321944 -394.529056) (xy 318.321436 -394.528294) (xy 317.923672 -393.839954) (xy 317.911736 -393.817296)
			(xy 317.894806 -393.768965) (xy 317.886155 -393.718492) (xy 317.885572 -393.692888) (xy 317.343832 -393.692888)
			(xy 317.655956 -394.232892) (xy 317.668711 -394.256246) (xy 317.686817 -394.30628) (xy 317.696018 -394.358688)
			(xy 317.696596 -394.385292) (xy 317.696154 -394.409286) (xy 317.688648 -394.456682) (xy 317.67382 -394.50232)
			(xy 317.652035 -394.545077) (xy 317.623829 -394.5839) (xy 317.589897 -394.617831) (xy 317.551074 -394.646037)
			(xy 317.508317 -394.667822) (xy 317.462678 -394.682649) (xy 317.415282 -394.690155) (xy 317.391288 -394.6906)
			(xy 317.391034 -394.6906) (xy 317.367461 -394.690179) (xy 317.320874 -394.682942) (xy 317.275956 -394.668622)
			(xy 317.233778 -394.647557) (xy 317.195344 -394.620252) (xy 317.161572 -394.587356) (xy 317.133265 -394.549654)
			(xy 317.121794 -394.529056) (xy 317.121286 -394.528294) (xy 316.723522 -393.839954) (xy 316.711661 -393.81727)
			(xy 316.694805 -393.76894) (xy 316.686226 -393.71848) (xy 316.685676 -393.692888) (xy 316.143936 -393.692888)
			(xy 316.45606 -394.232892) (xy 316.468815 -394.256246) (xy 316.486921 -394.30628) (xy 316.496122 -394.358688)
			(xy 316.4967 -394.385292) (xy 316.496254 -394.409285) (xy 316.488749 -394.456681) (xy 316.473921 -394.50232)
			(xy 316.452136 -394.545076) (xy 316.42393 -394.583898) (xy 316.389998 -394.61783) (xy 316.351176 -394.646036)
			(xy 316.30842 -394.667821) (xy 316.262781 -394.682649) (xy 316.215385 -394.690154) (xy 316.191392 -394.6906)
			(xy 316.191138 -394.6906) (xy 316.167565 -394.690176) (xy 316.120978 -394.68294) (xy 316.07606 -394.66862)
			(xy 316.033882 -394.647556) (xy 315.995448 -394.620251) (xy 315.961676 -394.587356) (xy 315.933369 -394.549654)
			(xy 315.921898 -394.529056) (xy 315.92139 -394.528294) (xy 315.523626 -393.839954) (xy 315.511765 -393.81727)
			(xy 315.494909 -393.76894) (xy 315.48633 -393.71848) (xy 315.48578 -393.692888) (xy 314.943786 -393.692888)
			(xy 315.25591 -394.232892) (xy 315.268732 -394.256226) (xy 315.286954 -394.306248) (xy 315.296215 -394.358673)
			(xy 315.296804 -394.385292) (xy 315.296354 -394.409298) (xy 315.28884 -394.456718) (xy 315.273997 -394.502377)
			(xy 315.25219 -394.545151) (xy 315.223957 -394.583984) (xy 315.189994 -394.61792) (xy 315.151137 -394.646121)
			(xy 315.108346 -394.667893) (xy 315.062674 -394.682698) (xy 315.015248 -394.690173) (xy 314.991242 -394.6906)
			(xy 314.990988 -394.6906) (xy 314.967414 -394.690216) (xy 314.920825 -394.682973) (xy 314.875906 -394.668645)
			(xy 314.833728 -394.647575) (xy 314.795295 -394.620264) (xy 314.761523 -394.587363) (xy 314.733218 -394.549656)
			(xy 314.721748 -394.529056) (xy 314.72124 -394.528294) (xy 314.323476 -393.839954) (xy 314.31154 -393.817296)
			(xy 314.29461 -393.768965) (xy 314.285959 -393.718492) (xy 314.285376 -393.692888) (xy 313.74389 -393.692888)
			(xy 314.056014 -394.232892) (xy 314.068837 -394.256226) (xy 314.087058 -394.306248) (xy 314.096319 -394.358673)
			(xy 314.096908 -394.385292) (xy 314.096454 -394.409298) (xy 314.08894 -394.456717) (xy 314.074097 -394.502377)
			(xy 314.052291 -394.54515) (xy 314.024058 -394.583983) (xy 313.990095 -394.617918) (xy 313.95124 -394.646119)
			(xy 313.908449 -394.667891) (xy 313.862778 -394.682698) (xy 313.815352 -394.690173) (xy 313.791346 -394.6906)
			(xy 313.791092 -394.6906) (xy 313.767518 -394.690213) (xy 313.720929 -394.68297) (xy 313.67601 -394.668643)
			(xy 313.633832 -394.647573) (xy 313.595399 -394.620263) (xy 313.561628 -394.587362) (xy 313.533322 -394.549656)
			(xy 313.521852 -394.529056) (xy 313.521344 -394.528294) (xy 313.12358 -393.839954) (xy 313.111644 -393.817296)
			(xy 313.094715 -393.768965) (xy 313.086063 -393.718492) (xy 313.08548 -393.692888) (xy 312.54374 -393.692888)
			(xy 312.855864 -394.232892) (xy 312.86862 -394.256246) (xy 312.886726 -394.30628) (xy 312.895926 -394.358688)
			(xy 312.896504 -394.385292) (xy 312.896054 -394.409285) (xy 312.888549 -394.456681) (xy 312.873721 -394.502319)
			(xy 312.851936 -394.545075) (xy 312.823731 -394.583897) (xy 312.7898 -394.617829) (xy 312.750978 -394.646034)
			(xy 312.708222 -394.66782) (xy 312.662585 -394.682648) (xy 312.615189 -394.690154) (xy 312.591196 -394.6906)
			(xy 312.567622 -394.690209) (xy 312.521033 -394.682967) (xy 312.476115 -394.668641) (xy 312.433936 -394.647572)
			(xy 312.395503 -394.620262) (xy 312.361732 -394.587362) (xy 312.333426 -394.549656) (xy 312.321956 -394.529056)
			(xy 312.321448 -394.528294) (xy 311.923684 -393.839954) (xy 311.911748 -393.817296) (xy 311.894819 -393.768965)
			(xy 311.886167 -393.718492) (xy 311.885584 -393.692888) (xy 311.34359 -393.692888) (xy 311.655714 -394.232892)
			(xy 311.668537 -394.256226) (xy 311.686758 -394.306248) (xy 311.696019 -394.358673) (xy 311.696608 -394.385292)
			(xy 311.696154 -394.409298) (xy 311.68864 -394.456717) (xy 311.673797 -394.502377) (xy 311.651991 -394.54515)
			(xy 311.623758 -394.583983) (xy 311.589795 -394.617918) (xy 311.55094 -394.646119) (xy 311.508149 -394.667891)
			(xy 311.462478 -394.682698) (xy 311.415052 -394.690173) (xy 311.391046 -394.6906) (xy 311.367473 -394.690169)
			(xy 311.320887 -394.682935) (xy 311.275969 -394.668615) (xy 311.233791 -394.647553) (xy 311.195357 -394.620249)
			(xy 311.161584 -394.587355) (xy 311.133277 -394.549654) (xy 311.121806 -394.529056) (xy 311.121298 -394.528294)
			(xy 310.723534 -393.839954) (xy 310.711674 -393.81727) (xy 310.694818 -393.76894) (xy 310.686238 -393.71848)
			(xy 310.685688 -393.692888) (xy 310.143694 -393.692888) (xy 310.455818 -394.232892) (xy 310.468641 -394.256226)
			(xy 310.486862 -394.306248) (xy 310.496123 -394.358673) (xy 310.496712 -394.385292) (xy 310.496254 -394.409297)
			(xy 310.48874 -394.456717) (xy 310.473898 -394.502376) (xy 310.452091 -394.545149) (xy 310.423859 -394.583981)
			(xy 310.389897 -394.617917) (xy 310.351042 -394.646118) (xy 310.308252 -394.66789) (xy 310.262581 -394.682697)
			(xy 310.215156 -394.690172) (xy 310.19115 -394.6906) (xy 310.167577 -394.690166) (xy 310.120991 -394.682932)
			(xy 310.076073 -394.668613) (xy 310.033895 -394.647551) (xy 309.995461 -394.620248) (xy 309.961688 -394.587354)
			(xy 309.933381 -394.549653) (xy 309.92191 -394.529056) (xy 309.921402 -394.528294) (xy 309.523638 -393.839954)
			(xy 309.511778 -393.817269) (xy 309.494922 -393.76894) (xy 309.486342 -393.71848) (xy 309.485792 -393.692888)
			(xy 308.943544 -393.692888) (xy 309.255668 -394.232892) (xy 309.268424 -394.256246) (xy 309.28653 -394.30628)
			(xy 309.29573 -394.358688) (xy 309.296308 -394.385292) (xy 309.295854 -394.409285) (xy 309.288349 -394.45668)
			(xy 309.273521 -394.502318) (xy 309.251737 -394.545074) (xy 309.223532 -394.583896) (xy 309.189602 -394.617827)
			(xy 309.150781 -394.646033) (xy 309.108025 -394.667818) (xy 309.062388 -394.682647) (xy 309.014993 -394.690154)
			(xy 308.991 -394.6906) (xy 308.967426 -394.690206) (xy 308.920838 -394.682965) (xy 308.875919 -394.668639)
			(xy 308.833741 -394.64757) (xy 308.795308 -394.620261) (xy 308.761536 -394.587361) (xy 308.73323 -394.549656)
			(xy 308.72176 -394.529056) (xy 308.721252 -394.528294) (xy 308.323488 -393.839954) (xy 308.311553 -393.817296)
			(xy 308.294623 -393.768965) (xy 308.285971 -393.718491) (xy 308.285388 -393.692888) (xy 307.743648 -393.692888)
			(xy 308.055772 -394.232892) (xy 308.068528 -394.256246) (xy 308.086634 -394.30628) (xy 308.095834 -394.358688)
			(xy 308.096412 -394.385292) (xy 308.095954 -394.409285) (xy 308.088449 -394.45668) (xy 308.073622 -394.502317)
			(xy 308.051838 -394.545073) (xy 308.023634 -394.583894) (xy 307.989703 -394.617826) (xy 307.950883 -394.646032)
			(xy 307.908128 -394.667817) (xy 307.862491 -394.682646) (xy 307.815097 -394.690154) (xy 307.791104 -394.6906)
			(xy 307.76753 -394.690203) (xy 307.720942 -394.682962) (xy 307.676023 -394.668637) (xy 307.633845 -394.647569)
			(xy 307.595412 -394.62026) (xy 307.56164 -394.587361) (xy 307.533335 -394.549656) (xy 307.521864 -394.529056)
			(xy 307.521356 -394.528294) (xy 307.123592 -393.839954) (xy 307.111657 -393.817295) (xy 307.094727 -393.768965)
			(xy 307.086075 -393.718491) (xy 307.085492 -393.692888) (xy 306.543752 -393.692888) (xy 306.855876 -394.232892)
			(xy 306.868624 -394.25625) (xy 306.886735 -394.306281) (xy 306.895938 -394.358688) (xy 306.896516 -394.385292)
			(xy 306.89603 -394.409283) (xy 306.888525 -394.456673) (xy 306.8737 -394.502306) (xy 306.851918 -394.545059)
			(xy 306.823716 -394.583877) (xy 306.789789 -394.617806) (xy 306.750972 -394.646009) (xy 306.708221 -394.667793)
			(xy 306.662589 -394.682622) (xy 306.615199 -394.690129) (xy 306.591208 -394.6906) (xy 306.567634 -394.6902)
			(xy 306.521046 -394.68296) (xy 306.476128 -394.668635) (xy 306.433949 -394.647567) (xy 306.395516 -394.620259)
			(xy 306.361744 -394.58736) (xy 306.333439 -394.549655) (xy 306.321968 -394.529056) (xy 306.32146 -394.528294)
			(xy 305.923696 -393.839954) (xy 305.911761 -393.817295) (xy 305.894831 -393.768965) (xy 305.886179 -393.718491)
			(xy 305.885596 -393.692888) (xy 305.343602 -393.692888) (xy 305.655726 -394.232892) (xy 305.66855 -394.256225)
			(xy 305.686771 -394.306247) (xy 305.696031 -394.358673) (xy 305.69662 -394.385292) (xy 305.696154 -394.409297)
			(xy 305.688641 -394.456716) (xy 305.673798 -394.502374) (xy 305.651993 -394.545146) (xy 305.623762 -394.583979)
			(xy 305.5898 -394.617914) (xy 305.550946 -394.646115) (xy 305.508157 -394.667888) (xy 305.462488 -394.682695)
			(xy 305.415063 -394.690172) (xy 305.391058 -394.6906) (xy 305.367486 -394.690159) (xy 305.3209 -394.682927)
			(xy 305.275982 -394.668609) (xy 305.233804 -394.647548) (xy 305.19537 -394.620246) (xy 305.161597 -394.587353)
			(xy 305.13329 -394.549653) (xy 305.121818 -394.529056) (xy 305.12131 -394.528294) (xy 304.723546 -393.839954)
			(xy 304.711686 -393.817269) (xy 304.69483 -393.76894) (xy 304.68625 -393.71848) (xy 304.6857 -393.692888)
			(xy 304.143706 -393.692888) (xy 304.45583 -394.232892) (xy 304.468654 -394.256225) (xy 304.486875 -394.306247)
			(xy 304.496135 -394.358673) (xy 304.496724 -394.385292) (xy 304.496254 -394.409297) (xy 304.488741 -394.456715)
			(xy 304.473899 -394.502373) (xy 304.452094 -394.545145) (xy 304.423863 -394.583977) (xy 304.389902 -394.617912)
			(xy 304.351049 -394.646114) (xy 304.30826 -394.667887) (xy 304.262591 -394.682694) (xy 304.215167 -394.690172)
			(xy 304.191162 -394.6906) (xy 304.16759 -394.690156) (xy 304.121004 -394.682924) (xy 304.076086 -394.668607)
			(xy 304.033908 -394.647547) (xy 303.995474 -394.620245) (xy 303.961701 -394.587352) (xy 303.933394 -394.549653)
			(xy 303.921922 -394.529056) (xy 303.921414 -394.528294) (xy 303.52365 -393.839954) (xy 303.511791 -393.817269)
			(xy 303.494934 -393.76894) (xy 303.486354 -393.71848) (xy 303.485804 -393.692888) (xy 280.345134 -393.692888)
			(xy 280.093674 -393.944348) (xy 280.08686 -393.951769) (xy 280.079126 -393.970352) (xy 280.078688 -393.980416)
			(xy 280.079196 -394.062966) (xy 280.08707 -394.081508) (xy 280.094436 -394.08862) (xy 280.100532 -394.094716)
			(xy 280.483818 -394.478002) (xy 280.510712 -394.505555) (xy 280.558798 -394.565692) (xy 280.599841 -394.630839)
			(xy 280.633323 -394.700176) (xy 280.658823 -394.772829) (xy 280.67602 -394.847882) (xy 280.684696 -394.924389)
			(xy 280.68524 -394.962888) (xy 280.68524 -396.171674) (xy 296.901108 -396.171674) (xy 296.901108 -395.308074)
			(xy 296.901594 -395.280823) (xy 296.90935 -395.226875) (xy 296.924705 -395.17458) (xy 296.947347 -395.125003)
			(xy 296.976813 -395.079153) (xy 297.012504 -395.037962) (xy 297.053695 -395.002271) (xy 297.099545 -394.972805)
			(xy 297.149122 -394.950163) (xy 297.201417 -394.934808) (xy 297.255365 -394.927052) (xy 297.309867 -394.927052)
			(xy 297.363815 -394.934808) (xy 297.41611 -394.950163) (xy 297.465687 -394.972805) (xy 297.511537 -395.002271)
			(xy 297.552728 -395.037962) (xy 297.588419 -395.079153) (xy 297.617885 -395.125003) (xy 297.640527 -395.17458)
			(xy 297.655882 -395.226875) (xy 297.663638 -395.280823) (xy 297.664124 -395.308074) (xy 297.664124 -396.171674)
			(xy 329.428856 -396.171674) (xy 329.428856 -395.308074) (xy 329.429342 -395.280823) (xy 329.437098 -395.226875)
			(xy 329.452453 -395.17458) (xy 329.475095 -395.125003) (xy 329.504561 -395.079153) (xy 329.540252 -395.037962)
			(xy 329.581443 -395.002271) (xy 329.627293 -394.972805) (xy 329.67687 -394.950163) (xy 329.729165 -394.934808)
			(xy 329.783113 -394.927052) (xy 329.837615 -394.927052) (xy 329.891563 -394.934808) (xy 329.943858 -394.950163)
			(xy 329.993435 -394.972805) (xy 330.039285 -395.002271) (xy 330.080476 -395.037962) (xy 330.116167 -395.079153)
			(xy 330.145633 -395.125003) (xy 330.168275 -395.17458) (xy 330.18363 -395.226875) (xy 330.191386 -395.280823)
			(xy 330.191872 -395.308074) (xy 330.191872 -396.171674) (xy 364.001304 -396.171674) (xy 364.001304 -395.308074)
			(xy 364.00179 -395.280823) (xy 364.009546 -395.226875) (xy 364.024901 -395.17458) (xy 364.047543 -395.125003)
			(xy 364.077009 -395.079153) (xy 364.1127 -395.037962) (xy 364.153891 -395.002271) (xy 364.199741 -394.972805)
			(xy 364.249318 -394.950163) (xy 364.301613 -394.934808) (xy 364.355561 -394.927052) (xy 364.410063 -394.927052)
			(xy 364.464011 -394.934808) (xy 364.516306 -394.950163) (xy 364.565883 -394.972805) (xy 364.611733 -395.002271)
			(xy 364.652924 -395.037962) (xy 364.688615 -395.079153) (xy 364.718081 -395.125003) (xy 364.740723 -395.17458)
			(xy 364.756078 -395.226875) (xy 364.763834 -395.280823) (xy 364.76432 -395.308074) (xy 364.76432 -396.171674)
			(xy 396.529052 -396.171674) (xy 396.529052 -395.308074) (xy 396.529538 -395.280823) (xy 396.537294 -395.226875)
			(xy 396.552649 -395.17458) (xy 396.575291 -395.125003) (xy 396.604757 -395.079153) (xy 396.640448 -395.037962)
			(xy 396.681639 -395.002271) (xy 396.727489 -394.972805) (xy 396.777066 -394.950163) (xy 396.829361 -394.934808)
			(xy 396.883309 -394.927052) (xy 396.937811 -394.927052) (xy 396.991759 -394.934808) (xy 397.044054 -394.950163)
			(xy 397.093631 -394.972805) (xy 397.139481 -395.002271) (xy 397.180672 -395.037962) (xy 397.216363 -395.079153)
			(xy 397.245829 -395.125003) (xy 397.268471 -395.17458) (xy 397.283826 -395.226875) (xy 397.291582 -395.280823)
			(xy 397.292068 -395.308074) (xy 397.292068 -396.171674) (xy 397.291582 -396.198925) (xy 397.283826 -396.252873)
			(xy 397.268471 -396.305168) (xy 397.245829 -396.354745) (xy 397.216363 -396.400595) (xy 397.180672 -396.441786)
			(xy 397.139481 -396.477477) (xy 397.093631 -396.506943) (xy 397.044054 -396.529585) (xy 396.991759 -396.54494)
			(xy 396.937811 -396.552696) (xy 396.883309 -396.552696) (xy 396.829361 -396.54494) (xy 396.777066 -396.529585)
			(xy 396.727489 -396.506943) (xy 396.681639 -396.477477) (xy 396.640448 -396.441786) (xy 396.604757 -396.400595)
			(xy 396.575291 -396.354745) (xy 396.552649 -396.305168) (xy 396.537294 -396.252873) (xy 396.529538 -396.198925)
			(xy 396.529052 -396.171674) (xy 364.76432 -396.171674) (xy 364.763834 -396.198925) (xy 364.756078 -396.252873)
			(xy 364.740723 -396.305168) (xy 364.718081 -396.354745) (xy 364.688615 -396.400595) (xy 364.652924 -396.441786)
			(xy 364.611733 -396.477477) (xy 364.565883 -396.506943) (xy 364.516306 -396.529585) (xy 364.464011 -396.54494)
			(xy 364.410063 -396.552696) (xy 364.355561 -396.552696) (xy 364.301613 -396.54494) (xy 364.249318 -396.529585)
			(xy 364.199741 -396.506943) (xy 364.153891 -396.477477) (xy 364.1127 -396.441786) (xy 364.077009 -396.400595)
			(xy 364.047543 -396.354745) (xy 364.024901 -396.305168) (xy 364.009546 -396.252873) (xy 364.00179 -396.198925)
			(xy 364.001304 -396.171674) (xy 330.191872 -396.171674) (xy 330.191386 -396.198925) (xy 330.18363 -396.252873)
			(xy 330.168275 -396.305168) (xy 330.145633 -396.354745) (xy 330.116167 -396.400595) (xy 330.080476 -396.441786)
			(xy 330.039285 -396.477477) (xy 329.993435 -396.506943) (xy 329.943858 -396.529585) (xy 329.891563 -396.54494)
			(xy 329.837615 -396.552696) (xy 329.783113 -396.552696) (xy 329.729165 -396.54494) (xy 329.67687 -396.529585)
			(xy 329.627293 -396.506943) (xy 329.581443 -396.477477) (xy 329.540252 -396.441786) (xy 329.504561 -396.400595)
			(xy 329.475095 -396.354745) (xy 329.452453 -396.305168) (xy 329.437098 -396.252873) (xy 329.429342 -396.198925)
			(xy 329.428856 -396.171674) (xy 297.664124 -396.171674) (xy 297.663638 -396.198925) (xy 297.655882 -396.252873)
			(xy 297.640527 -396.305168) (xy 297.617885 -396.354745) (xy 297.588419 -396.400595) (xy 297.552728 -396.441786)
			(xy 297.511537 -396.477477) (xy 297.465687 -396.506943) (xy 297.41611 -396.529585) (xy 297.363815 -396.54494)
			(xy 297.309867 -396.552696) (xy 297.255365 -396.552696) (xy 297.201417 -396.54494) (xy 297.149122 -396.529585)
			(xy 297.099545 -396.506943) (xy 297.053695 -396.477477) (xy 297.012504 -396.441786) (xy 296.976813 -396.400595)
			(xy 296.947347 -396.354745) (xy 296.924705 -396.305168) (xy 296.90935 -396.252873) (xy 296.901594 -396.198925)
			(xy 296.901108 -396.171674) (xy 280.68524 -396.171674) (xy 280.68524 -397.15694) (xy 303.485804 -397.15694)
			(xy 303.485804 -397.156432) (xy 303.486268 -397.132439) (xy 303.49377 -397.085044) (xy 303.508595 -397.039405)
			(xy 303.530377 -396.996648) (xy 303.558581 -396.957826) (xy 303.592511 -396.923894) (xy 303.631331 -396.895688)
			(xy 303.674087 -396.873903) (xy 303.719724 -396.859075) (xy 303.767119 -396.851569) (xy 303.791112 -396.851124)
			(xy 303.815047 -396.851594) (xy 303.862333 -396.859047) (xy 303.907877 -396.873786) (xy 303.950565 -396.895448)
			(xy 303.989351 -396.923504) (xy 304.023286 -396.957267) (xy 304.051539 -396.99591) (xy 304.062892 -397.016986)
			(xy 304.0634 -397.018002) (xy 304.143706 -397.15694) (xy 304.6857 -397.15694) (xy 304.6857 -397.156432)
			(xy 304.686168 -397.132439) (xy 304.69367 -397.085044) (xy 304.708495 -397.039406) (xy 304.730277 -396.99665)
			(xy 304.75848 -396.957827) (xy 304.792409 -396.923895) (xy 304.831229 -396.895689) (xy 304.873984 -396.873904)
			(xy 304.919621 -396.859076) (xy 304.967015 -396.85157) (xy 304.991008 -396.851124) (xy 305.014943 -396.851597)
			(xy 305.062229 -396.85905) (xy 305.107773 -396.873788) (xy 305.150461 -396.89545) (xy 305.189247 -396.923505)
			(xy 305.223182 -396.957268) (xy 305.251435 -396.99591) (xy 305.262788 -397.016986) (xy 305.263296 -397.018002)
			(xy 305.343602 -397.15694) (xy 305.885596 -397.15694) (xy 305.885596 -397.156432) (xy 305.886068 -397.13244)
			(xy 305.89357 -397.085045) (xy 305.908394 -397.039407) (xy 305.930176 -396.996651) (xy 305.958378 -396.957829)
			(xy 305.992307 -396.923897) (xy 306.031127 -396.895691) (xy 306.073881 -396.873905) (xy 306.119517 -396.859076)
			(xy 306.166912 -396.85157) (xy 306.190904 -396.851124) (xy 306.214839 -396.8516) (xy 306.262124 -396.859053)
			(xy 306.307668 -396.87379) (xy 306.350356 -396.895451) (xy 306.389142 -396.923506) (xy 306.423077 -396.957268)
			(xy 306.451331 -396.99591) (xy 306.462684 -397.016986) (xy 306.463192 -397.018002) (xy 306.543498 -397.15694)
			(xy 307.085492 -397.15694) (xy 307.085492 -397.156432) (xy 307.085969 -397.132427) (xy 307.093478 -397.085008)
			(xy 307.108318 -397.039349) (xy 307.130122 -396.996576) (xy 307.158352 -396.957743) (xy 307.192312 -396.923807)
			(xy 307.231166 -396.895605) (xy 307.273955 -396.873833) (xy 307.319624 -396.859027) (xy 307.367049 -396.851551)
			(xy 307.391054 -396.851124) (xy 307.41499 -396.85156) (xy 307.462278 -396.85902) (xy 307.507823 -396.873764)
			(xy 307.550511 -396.895432) (xy 307.589296 -396.923493) (xy 307.62323 -396.957261) (xy 307.651481 -396.995908)
			(xy 307.662834 -397.016986) (xy 307.663342 -397.018002) (xy 307.743648 -397.15694) (xy 308.285388 -397.15694)
			(xy 308.285388 -397.156432) (xy 308.285869 -397.132427) (xy 308.293378 -397.085009) (xy 308.308218 -397.03935)
			(xy 308.330021 -396.996577) (xy 308.35825 -396.957744) (xy 308.39221 -396.923809) (xy 308.431063 -396.895607)
			(xy 308.473852 -396.873834) (xy 308.519521 -396.859027) (xy 308.566945 -396.851552) (xy 308.59095 -396.851124)
			(xy 308.614886 -396.851563) (xy 308.662173 -396.859022) (xy 308.707718 -396.873766) (xy 308.750406 -396.895434)
			(xy 308.789192 -396.923494) (xy 308.823126 -396.957262) (xy 308.851377 -396.995908) (xy 308.86273 -397.016986)
			(xy 308.863238 -397.018002) (xy 308.943544 -397.15694) (xy 309.485792 -397.15694) (xy 309.485792 -397.156432)
			(xy 309.486268 -397.13244) (xy 309.49377 -397.085045) (xy 309.508594 -397.039408) (xy 309.530375 -396.996652)
			(xy 309.558577 -396.95783) (xy 309.592506 -396.923898) (xy 309.631325 -396.895692) (xy 309.674079 -396.873906)
			(xy 309.719714 -396.859077) (xy 309.767108 -396.85157) (xy 309.7911 -396.851124) (xy 309.815035 -396.851603)
			(xy 309.86232 -396.859055) (xy 309.907864 -396.873792) (xy 309.950552 -396.895453) (xy 309.989338 -396.923507)
			(xy 310.023273 -396.957269) (xy 310.051526 -396.995911) (xy 310.06288 -397.016986) (xy 310.063388 -397.018002)
			(xy 310.143694 -397.15694) (xy 310.685688 -397.15694) (xy 310.685688 -397.156432) (xy 310.686168 -397.13244)
			(xy 310.69367 -397.085046) (xy 310.708493 -397.039409) (xy 310.730274 -396.996653) (xy 310.758476 -396.957831)
			(xy 310.792404 -396.9239) (xy 310.831223 -396.895693) (xy 310.873976 -396.873907) (xy 310.919611 -396.859078)
			(xy 310.967004 -396.851571) (xy 310.990996 -396.851124) (xy 311.014933 -396.851526) (xy 311.062223 -396.858992)
			(xy 311.107768 -396.873742) (xy 311.150456 -396.895416) (xy 311.189241 -396.923483) (xy 311.223174 -396.957255)
			(xy 311.251424 -396.995906) (xy 311.262776 -397.016986) (xy 311.263284 -397.018002) (xy 311.34359 -397.15694)
			(xy 311.885584 -397.15694) (xy 311.885584 -397.156432) (xy 311.886068 -397.13244) (xy 311.893569 -397.085046)
			(xy 311.908393 -397.03941) (xy 311.930174 -396.996654) (xy 311.958375 -396.957833) (xy 311.992302 -396.923901)
			(xy 312.03112 -396.895695) (xy 312.073873 -396.873908) (xy 312.119508 -396.859079) (xy 312.1669 -396.851571)
			(xy 312.190892 -396.851124) (xy 312.214829 -396.851529) (xy 312.262118 -396.858995) (xy 312.307664 -396.873745)
			(xy 312.350352 -396.895418) (xy 312.389137 -396.923484) (xy 312.42307 -396.957256) (xy 312.45132 -396.995906)
			(xy 312.462672 -397.016986) (xy 312.46318 -397.018002) (xy 312.543486 -397.15694) (xy 313.08548 -397.15694)
			(xy 313.08548 -397.156432) (xy 313.085969 -397.132428) (xy 313.093478 -397.08501) (xy 313.108317 -397.039352)
			(xy 313.130119 -396.99658) (xy 313.158348 -396.957747) (xy 313.192307 -396.923811) (xy 313.231159 -396.89561)
			(xy 313.273946 -396.873836) (xy 313.319614 -396.859029) (xy 313.367037 -396.851552) (xy 313.391042 -396.851124)
			(xy 313.414978 -396.851569) (xy 313.462265 -396.859028) (xy 313.50781 -396.87377) (xy 313.550497 -396.895437)
			(xy 313.589283 -396.923496) (xy 313.623217 -396.957263) (xy 313.651469 -396.995909) (xy 313.662822 -397.016986)
			(xy 313.66333 -397.018002) (xy 313.743636 -397.15694) (xy 314.285376 -397.15694) (xy 314.285376 -397.156432)
			(xy 314.285869 -397.132428) (xy 314.293378 -397.085011) (xy 314.308217 -397.039353) (xy 314.330019 -396.996581)
			(xy 314.358247 -396.957748) (xy 314.392205 -396.923813) (xy 314.431057 -396.895611) (xy 314.473844 -396.873838)
			(xy 314.519511 -396.85903) (xy 314.566934 -396.851552) (xy 314.590938 -396.851124) (xy 314.614874 -396.851573)
			(xy 314.662161 -396.85903) (xy 314.707705 -396.873772) (xy 314.750393 -396.895438) (xy 314.789179 -396.923498)
			(xy 314.823113 -396.957263) (xy 314.851365 -396.995909) (xy 314.862718 -397.016986) (xy 314.863226 -397.018002)
			(xy 314.943532 -397.15694) (xy 315.48578 -397.15694) (xy 315.48578 -397.156432) (xy 315.486268 -397.13244)
			(xy 315.493769 -397.085047) (xy 315.508593 -397.039411) (xy 315.530373 -396.996656) (xy 315.558574 -396.957834)
			(xy 315.592501 -396.923902) (xy 315.631318 -396.895696) (xy 315.67407 -396.87391) (xy 315.719704 -396.85908)
			(xy 315.767096 -396.851571) (xy 315.791088 -396.851124) (xy 315.815025 -396.851532) (xy 315.862314 -396.858997)
			(xy 315.90786 -396.873747) (xy 315.950547 -396.895419) (xy 315.989333 -396.923485) (xy 316.023266 -396.957256)
			(xy 316.051516 -396.995907) (xy 316.062868 -397.016986) (xy 316.063376 -397.018002) (xy 316.143682 -397.15694)
			(xy 316.685676 -397.15694) (xy 316.685676 -397.156432) (xy 316.686168 -397.132441) (xy 316.693669 -397.085048)
			(xy 316.708492 -397.039412) (xy 316.730272 -396.996657) (xy 316.758473 -396.957836) (xy 316.792399 -396.923904)
			(xy 316.831216 -396.895697) (xy 316.873967 -396.873911) (xy 316.919601 -396.85908) (xy 316.966993 -396.851571)
			(xy 316.990984 -396.851124) (xy 317.014921 -396.851535) (xy 317.06221 -396.859) (xy 317.107755 -396.873749)
			(xy 317.150443 -396.895421) (xy 317.189228 -396.923486) (xy 317.223161 -396.957257) (xy 317.251412 -396.995907)
			(xy 317.262764 -397.016986) (xy 317.263272 -397.018002) (xy 317.343578 -397.15694) (xy 317.885572 -397.15694)
			(xy 317.885572 -397.156432) (xy 317.886068 -397.132441) (xy 317.893569 -397.085048) (xy 317.908392 -397.039413)
			(xy 317.930172 -396.996658) (xy 317.958371 -396.957837) (xy 317.992297 -396.923905) (xy 318.031114 -396.895699)
			(xy 318.073865 -396.873912) (xy 318.119498 -396.859081) (xy 318.166889 -396.851572) (xy 318.19088 -396.851124)
			(xy 318.214817 -396.851539) (xy 318.262105 -396.859002) (xy 318.307651 -396.873751) (xy 318.350339 -396.895422)
			(xy 318.389124 -396.923487) (xy 318.423057 -396.957257) (xy 318.451308 -396.995907) (xy 318.46266 -397.016986)
			(xy 318.463168 -397.018002) (xy 318.543474 -397.15694) (xy 319.085468 -397.15694) (xy 319.085468 -397.156432)
			(xy 319.085969 -397.132428) (xy 319.093478 -397.085012) (xy 319.108316 -397.039355) (xy 319.130117 -396.996583)
			(xy 319.158345 -396.957751) (xy 319.192302 -396.923816) (xy 319.231152 -396.895614) (xy 319.273938 -396.87384)
			(xy 319.319605 -396.859031) (xy 319.367026 -396.851553) (xy 319.39103 -396.851124) (xy 319.414965 -396.851579)
			(xy 319.462252 -396.859035) (xy 319.507797 -396.873776) (xy 319.550484 -396.895441) (xy 319.58927 -396.9235)
			(xy 319.623205 -396.957264) (xy 319.651457 -396.995909) (xy 319.66281 -397.016986) (xy 319.663318 -397.018002)
			(xy 319.743624 -397.15694) (xy 320.285364 -397.15694) (xy 320.285364 -397.156432) (xy 320.285869 -397.132428)
			(xy 320.293378 -397.085012) (xy 320.308215 -397.039356) (xy 320.330017 -396.996584) (xy 320.358243 -396.957753)
			(xy 320.3922 -396.923817) (xy 320.43105 -396.895615) (xy 320.473835 -396.873841) (xy 320.519501 -396.859032)
			(xy 320.566922 -396.851553) (xy 320.590926 -396.851124) (xy 320.614861 -396.851582) (xy 320.662148 -396.859038)
			(xy 320.707692 -396.873778) (xy 320.75038 -396.895443) (xy 320.789166 -396.923501) (xy 320.823101 -396.957265)
			(xy 320.851353 -396.995909) (xy 320.862706 -397.016986) (xy 320.863214 -397.018002) (xy 320.94352 -397.15694)
			(xy 321.485768 -397.15694) (xy 321.485768 -397.156432) (xy 321.486268 -397.132441) (xy 321.493769 -397.085049)
			(xy 321.508592 -397.039414) (xy 321.530371 -396.996659) (xy 321.55857 -396.957838) (xy 321.592496 -396.923907)
			(xy 321.631311 -396.8957) (xy 321.674062 -396.873913) (xy 321.719694 -396.859082) (xy 321.767085 -396.851572)
			(xy 321.791076 -396.851124) (xy 321.815013 -396.851542) (xy 321.862301 -396.859005) (xy 321.907847 -396.873753)
			(xy 321.950534 -396.895424) (xy 321.98932 -396.923488) (xy 322.023253 -396.957258) (xy 322.051504 -396.995907)
			(xy 322.062856 -397.016986) (xy 322.063364 -397.018002) (xy 322.14367 -397.15694) (xy 336.013552 -397.15694)
			(xy 336.013552 -397.156432) (xy 336.014092 -397.132444) (xy 336.021592 -397.085057) (xy 336.036413 -397.039427)
			(xy 336.058189 -396.996677) (xy 336.086384 -396.95786) (xy 336.120305 -396.923931) (xy 336.159115 -396.895726)
			(xy 336.20186 -396.87394) (xy 336.247487 -396.859109) (xy 336.294872 -396.851598) (xy 336.31886 -396.851124)
			(xy 336.342796 -396.851555) (xy 336.390084 -396.859016) (xy 336.435629 -396.873761) (xy 336.478317 -396.89543)
			(xy 336.517103 -396.923492) (xy 336.551036 -396.95726) (xy 336.579288 -396.995908) (xy 336.59064 -397.016986)
			(xy 336.591148 -397.018002) (xy 336.671454 -397.15694) (xy 337.213448 -397.15694) (xy 337.213448 -397.156432)
			(xy 337.213992 -397.132444) (xy 337.221492 -397.085057) (xy 337.236312 -397.039428) (xy 337.258088 -396.996678)
			(xy 337.286283 -396.957861) (xy 337.320203 -396.923933) (xy 337.359013 -396.895728) (xy 337.401757 -396.873941)
			(xy 337.447383 -396.85911) (xy 337.494768 -396.851598) (xy 337.518756 -396.851124) (xy 337.542692 -396.851558)
			(xy 337.58998 -396.859018) (xy 337.635525 -396.873763) (xy 337.678213 -396.895431) (xy 337.716998 -396.923493)
			(xy 337.750932 -396.957261) (xy 337.779183 -396.995908) (xy 337.790536 -397.016986) (xy 337.791044 -397.018002)
			(xy 337.87135 -397.15694) (xy 338.413344 -397.15694) (xy 338.413344 -397.156432) (xy 338.413892 -397.132444)
			(xy 338.421392 -397.085058) (xy 338.436212 -397.039429) (xy 338.457987 -396.996679) (xy 338.486182 -396.957862)
			(xy 338.520101 -396.923934) (xy 338.558911 -396.895729) (xy 338.601655 -396.873943) (xy 338.64728 -396.859111)
			(xy 338.694664 -396.851598) (xy 338.718652 -396.851124) (xy 338.742588 -396.851561) (xy 338.789876 -396.859021)
			(xy 338.835421 -396.873765) (xy 338.878108 -396.895433) (xy 338.916894 -396.923494) (xy 338.950828 -396.957261)
			(xy 338.979079 -396.995908) (xy 338.990432 -397.016986) (xy 338.99094 -397.018002) (xy 339.071246 -397.15694)
			(xy 339.61324 -397.15694) (xy 339.61324 -397.156432) (xy 339.613669 -397.132425) (xy 339.62118 -397.085001)
			(xy 339.636023 -397.039338) (xy 339.65783 -396.996562) (xy 339.686066 -396.957726) (xy 339.720032 -396.92379)
			(xy 339.758892 -396.895589) (xy 339.801688 -396.873819) (xy 339.847364 -396.859017) (xy 339.894794 -396.851548)
			(xy 339.918802 -396.851124) (xy 339.942737 -396.851602) (xy 339.990022 -396.859054) (xy 340.035566 -396.873791)
			(xy 340.078254 -396.895452) (xy 340.11704 -396.923507) (xy 340.150975 -396.957268) (xy 340.179229 -396.99591)
			(xy 340.190582 -397.016986) (xy 340.19109 -397.018002) (xy 340.271396 -397.15694) (xy 340.813136 -397.15694)
			(xy 340.813136 -397.156432) (xy 340.813569 -397.132425) (xy 340.82108 -397.085002) (xy 340.835922 -397.039339)
			(xy 340.85773 -396.996563) (xy 340.885964 -396.957728) (xy 340.91993 -396.923791) (xy 340.95879 -396.89559)
			(xy 341.001585 -396.87382) (xy 341.047261 -396.859018) (xy 341.09469 -396.851548) (xy 341.118698 -396.851124)
			(xy 341.142635 -396.851524) (xy 341.189925 -396.858991) (xy 341.235471 -396.873741) (xy 341.278158 -396.895415)
			(xy 341.316943 -396.923482) (xy 341.350876 -396.957255) (xy 341.379126 -396.995906) (xy 341.390478 -397.016986)
			(xy 341.390986 -397.018002) (xy 341.471292 -397.15694) (xy 342.01354 -397.15694) (xy 342.01354 -397.156432)
			(xy 342.013968 -397.132437) (xy 342.021471 -397.085038) (xy 342.036298 -397.039397) (xy 342.058084 -396.996638)
			(xy 342.086291 -396.957814) (xy 342.120226 -396.923881) (xy 342.159051 -396.895676) (xy 342.201812 -396.873892)
			(xy 342.247454 -396.859068) (xy 342.294853 -396.851567) (xy 342.318848 -396.851124) (xy 342.342784 -396.851565)
			(xy 342.390071 -396.859024) (xy 342.435616 -396.873767) (xy 342.478304 -396.895434) (xy 342.51709 -396.923495)
			(xy 342.551024 -396.957262) (xy 342.579275 -396.995908) (xy 342.590628 -397.016986) (xy 342.591136 -397.018002)
			(xy 342.671442 -397.15694) (xy 343.213436 -397.15694) (xy 343.213436 -397.156432) (xy 343.213868 -397.132438)
			(xy 343.221371 -397.085039) (xy 343.236198 -397.039398) (xy 343.257983 -396.996639) (xy 343.28619 -396.957815)
			(xy 343.320124 -396.923882) (xy 343.358949 -396.895677) (xy 343.401709 -396.873893) (xy 343.447351 -396.859068)
			(xy 343.49475 -396.851567) (xy 343.518744 -396.851124) (xy 343.54268 -396.851568) (xy 343.589967 -396.859026)
			(xy 343.635512 -396.873769) (xy 343.6782 -396.895436) (xy 343.716985 -396.923496) (xy 343.750919 -396.957262)
			(xy 343.779171 -396.995909) (xy 343.790524 -397.016986) (xy 343.791032 -397.018002) (xy 343.871338 -397.15694)
			(xy 344.413332 -397.15694) (xy 344.413332 -397.156432) (xy 344.413768 -397.132438) (xy 344.421271 -397.085039)
			(xy 344.436098 -397.039399) (xy 344.457883 -396.99664) (xy 344.486089 -396.957816) (xy 344.520022 -396.923884)
			(xy 344.558847 -396.895678) (xy 344.601606 -396.873895) (xy 344.647247 -396.859069) (xy 344.694646 -396.851567)
			(xy 344.71864 -396.851124) (xy 344.742576 -396.851571) (xy 344.789863 -396.859029) (xy 344.835408 -396.873771)
			(xy 344.878095 -396.895437) (xy 344.916881 -396.923497) (xy 344.950815 -396.957263) (xy 344.979067 -396.995909)
			(xy 344.99042 -397.016986) (xy 344.990928 -397.018002) (xy 345.071234 -397.15694) (xy 345.613228 -397.15694)
			(xy 345.613228 -397.156432) (xy 345.613669 -397.132425) (xy 345.62118 -397.085003) (xy 345.636022 -397.039341)
			(xy 345.657828 -396.996565) (xy 345.686062 -396.957731) (xy 345.720027 -396.923794) (xy 345.758886 -396.895593)
			(xy 345.80168 -396.873823) (xy 345.847354 -396.859019) (xy 345.894783 -396.851549) (xy 345.91879 -396.851124)
			(xy 345.942727 -396.85153) (xy 345.990016 -396.858996) (xy 346.035562 -396.873746) (xy 346.07825 -396.895419)
			(xy 346.117035 -396.923484) (xy 346.150968 -396.957256) (xy 346.179218 -396.995907) (xy 346.19057 -397.016986)
			(xy 346.191078 -397.018002) (xy 346.271384 -397.15694) (xy 346.813124 -397.15694) (xy 346.813124 -397.156432)
			(xy 346.813569 -397.132425) (xy 346.82108 -397.085004) (xy 346.835921 -397.039342) (xy 346.857727 -396.996567)
			(xy 346.885961 -396.957732) (xy 346.919925 -396.923796) (xy 346.958783 -396.895595) (xy 347.001577 -396.873824)
			(xy 347.047251 -396.85902) (xy 347.094679 -396.851549) (xy 347.118686 -396.851124) (xy 347.142623 -396.851534)
			(xy 347.189912 -396.858998) (xy 347.235457 -396.873748) (xy 347.278145 -396.89542) (xy 347.31693 -396.923485)
			(xy 347.350864 -396.957256) (xy 347.379114 -396.995907) (xy 347.390466 -397.016986) (xy 347.390974 -397.018002)
			(xy 347.47128 -397.15694) (xy 348.013528 -397.15694) (xy 348.013528 -397.156432) (xy 348.013968 -397.132438)
			(xy 348.021471 -397.08504) (xy 348.036297 -397.0394) (xy 348.058082 -396.996641) (xy 348.086288 -396.957818)
			(xy 348.120221 -396.923885) (xy 348.159045 -396.89568) (xy 348.201804 -396.873896) (xy 348.247444 -396.85907)
			(xy 348.294842 -396.851568) (xy 348.318836 -396.851124) (xy 348.342772 -396.851574) (xy 348.390058 -396.859031)
			(xy 348.435603 -396.873773) (xy 348.478291 -396.895439) (xy 348.517077 -396.923498) (xy 348.551011 -396.957264)
			(xy 348.579263 -396.995909) (xy 348.590616 -397.016986) (xy 348.591124 -397.018002) (xy 348.67143 -397.15694)
			(xy 349.213424 -397.15694) (xy 349.213424 -397.156432) (xy 349.213868 -397.132438) (xy 349.221371 -397.085041)
			(xy 349.236197 -397.039401) (xy 349.257981 -396.996643) (xy 349.286187 -396.957819) (xy 349.320119 -396.923887)
			(xy 349.358943 -396.895681) (xy 349.401701 -396.873897) (xy 349.447341 -396.859071) (xy 349.494738 -396.851568)
			(xy 349.518732 -396.851124) (xy 349.542668 -396.851578) (xy 349.589954 -396.859034) (xy 349.635499 -396.873775)
			(xy 349.678187 -396.89544) (xy 349.716972 -396.923499) (xy 349.750907 -396.957264) (xy 349.779159 -396.995909)
			(xy 349.790512 -397.016986) (xy 349.79102 -397.018002) (xy 349.871326 -397.15694) (xy 350.41332 -397.15694)
			(xy 350.41332 -397.156432) (xy 350.413768 -397.132438) (xy 350.421271 -397.085041) (xy 350.436097 -397.039402)
			(xy 350.45788 -396.996644) (xy 350.486086 -396.95782) (xy 350.520017 -396.923888) (xy 350.55884 -396.895682)
			(xy 350.601598 -396.873898) (xy 350.647237 -396.859072) (xy 350.694634 -396.851568) (xy 350.718628 -396.851124)
			(xy 350.742563 -396.851581) (xy 350.78985 -396.859037) (xy 350.835395 -396.873777) (xy 350.878082 -396.895442)
			(xy 350.916868 -396.9235) (xy 350.950803 -396.957265) (xy 350.979055 -396.995909) (xy 350.990408 -397.016986)
			(xy 350.990916 -397.018002) (xy 351.071222 -397.15694) (xy 351.613216 -397.15694) (xy 351.613216 -397.156432)
			(xy 351.613669 -397.132426) (xy 351.621179 -397.085005) (xy 351.63602 -397.039344) (xy 351.657826 -396.996569)
			(xy 351.686059 -396.957735) (xy 351.720022 -396.923799) (xy 351.758879 -396.895597) (xy 351.801671 -396.873826)
			(xy 351.847344 -396.859022) (xy 351.894771 -396.851549) (xy 351.918778 -396.851124) (xy 351.942715 -396.85154)
			(xy 351.990003 -396.859004) (xy 352.035549 -396.873752) (xy 352.078237 -396.895423) (xy 352.117022 -396.923487)
			(xy 352.150955 -396.957258) (xy 352.179206 -396.995907) (xy 352.190558 -397.016986) (xy 352.191066 -397.018002)
			(xy 352.271372 -397.15694) (xy 352.813112 -397.15694) (xy 352.813112 -397.156432) (xy 352.813569 -397.132426)
			(xy 352.821079 -397.085005) (xy 352.83592 -397.039345) (xy 352.857725 -396.99657) (xy 352.885957 -396.957736)
			(xy 352.91992 -396.9238) (xy 352.958777 -396.895599) (xy 353.001569 -396.873827) (xy 353.047241 -396.859023)
			(xy 353.094668 -396.85155) (xy 353.118674 -396.851124) (xy 353.142611 -396.851543) (xy 353.189899 -396.859006)
			(xy 353.235444 -396.873754) (xy 353.278132 -396.895425) (xy 353.316918 -396.923488) (xy 353.350851 -396.957258)
			(xy 353.379102 -396.995907) (xy 353.390454 -397.016986) (xy 353.390962 -397.018002) (xy 353.471268 -397.15694)
			(xy 354.013516 -397.15694) (xy 354.013516 -397.156432) (xy 354.013968 -397.132439) (xy 354.021471 -397.085042)
			(xy 354.036296 -397.039403) (xy 354.05808 -396.996645) (xy 354.086284 -396.957822) (xy 354.120216 -396.92389)
			(xy 354.159038 -396.895684) (xy 354.201795 -396.873899) (xy 354.247434 -396.859072) (xy 354.294831 -396.851568)
			(xy 354.318824 -396.851124) (xy 354.342759 -396.851584) (xy 354.390046 -396.859039) (xy 354.43559 -396.873779)
			(xy 354.478278 -396.895444) (xy 354.517064 -396.923501) (xy 354.550998 -396.957265) (xy 354.579251 -396.99591)
			(xy 354.590604 -397.016986) (xy 354.591112 -397.018002) (xy 354.671418 -397.15694) (xy 370.586 -397.15694)
			(xy 370.586 -397.156432) (xy 370.586468 -397.132439) (xy 370.59397 -397.085044) (xy 370.608795 -397.039406)
			(xy 370.630577 -396.99665) (xy 370.65878 -396.957827) (xy 370.692709 -396.923895) (xy 370.731529 -396.895689)
			(xy 370.774284 -396.873904) (xy 370.819921 -396.859076) (xy 370.867315 -396.85157) (xy 370.891308 -396.851124)
			(xy 370.915243 -396.851597) (xy 370.962529 -396.85905) (xy 371.008073 -396.873788) (xy 371.050761 -396.89545)
			(xy 371.089547 -396.923505) (xy 371.123482 -396.957268) (xy 371.151735 -396.99591) (xy 371.163088 -397.016986)
			(xy 371.163596 -397.018002) (xy 371.243902 -397.15694) (xy 371.785896 -397.15694) (xy 371.785896 -397.156432)
			(xy 371.786368 -397.13244) (xy 371.79387 -397.085045) (xy 371.808694 -397.039407) (xy 371.830476 -396.996651)
			(xy 371.858678 -396.957829) (xy 371.892607 -396.923897) (xy 371.931427 -396.895691) (xy 371.974181 -396.873905)
			(xy 372.019817 -396.859076) (xy 372.067212 -396.85157) (xy 372.091204 -396.851124) (xy 372.115139 -396.8516)
			(xy 372.162424 -396.859053) (xy 372.207968 -396.87379) (xy 372.250656 -396.895451) (xy 372.289442 -396.923506)
			(xy 372.323377 -396.957268) (xy 372.351631 -396.99591) (xy 372.362984 -397.016986) (xy 372.363492 -397.018002)
			(xy 372.443798 -397.15694) (xy 372.985792 -397.15694) (xy 372.985792 -397.156432) (xy 372.986268 -397.13244)
			(xy 372.99377 -397.085045) (xy 373.008594 -397.039408) (xy 373.030375 -396.996652) (xy 373.058577 -396.95783)
			(xy 373.092506 -396.923898) (xy 373.131325 -396.895692) (xy 373.174079 -396.873906) (xy 373.219714 -396.859077)
			(xy 373.267108 -396.85157) (xy 373.2911 -396.851124) (xy 373.315035 -396.851603) (xy 373.36232 -396.859055)
			(xy 373.407864 -396.873792) (xy 373.450552 -396.895453) (xy 373.489338 -396.923507) (xy 373.523273 -396.957269)
			(xy 373.551526 -396.995911) (xy 373.56288 -397.016986) (xy 373.563388 -397.018002) (xy 373.643694 -397.15694)
			(xy 374.185688 -397.15694) (xy 374.185688 -397.156432) (xy 374.186169 -397.132427) (xy 374.193678 -397.085009)
			(xy 374.208518 -397.03935) (xy 374.230321 -396.996577) (xy 374.25855 -396.957744) (xy 374.29251 -396.923809)
			(xy 374.331363 -396.895607) (xy 374.374152 -396.873834) (xy 374.419821 -396.859027) (xy 374.467245 -396.851552)
			(xy 374.49125 -396.851124) (xy 374.515186 -396.851563) (xy 374.562473 -396.859022) (xy 374.608018 -396.873766)
			(xy 374.650706 -396.895434) (xy 374.689492 -396.923494) (xy 374.723426 -396.957262) (xy 374.751677 -396.995908)
			(xy 374.76303 -397.016986) (xy 374.763538 -397.018002) (xy 374.843844 -397.15694) (xy 375.385584 -397.15694)
			(xy 375.385584 -397.156432) (xy 375.386069 -397.132427) (xy 375.393578 -397.085009) (xy 375.408417 -397.039351)
			(xy 375.43022 -396.996578) (xy 375.458449 -396.957746) (xy 375.492409 -396.92381) (xy 375.531261 -396.895608)
			(xy 375.574049 -396.873835) (xy 375.619718 -396.859028) (xy 375.667141 -396.851552) (xy 375.691146 -396.851124)
			(xy 375.715082 -396.851566) (xy 375.762369 -396.859025) (xy 375.807914 -396.873768) (xy 375.850602 -396.895435)
			(xy 375.889387 -396.923495) (xy 375.923322 -396.957262) (xy 375.951573 -396.995909) (xy 375.962926 -397.016986)
			(xy 375.963434 -397.018002) (xy 376.04374 -397.15694) (xy 376.585988 -397.15694) (xy 376.585988 -397.156432)
			(xy 376.586468 -397.13244) (xy 376.59397 -397.085046) (xy 376.608793 -397.039409) (xy 376.630574 -396.996653)
			(xy 376.658776 -396.957831) (xy 376.692704 -396.9239) (xy 376.731523 -396.895693) (xy 376.774276 -396.873907)
			(xy 376.819911 -396.859078) (xy 376.867304 -396.851571) (xy 376.891296 -396.851124) (xy 376.915233 -396.851526)
			(xy 376.962523 -396.858992) (xy 377.008068 -396.873742) (xy 377.050756 -396.895416) (xy 377.089541 -396.923483)
			(xy 377.123474 -396.957255) (xy 377.151724 -396.995906) (xy 377.163076 -397.016986) (xy 377.163584 -397.018002)
			(xy 377.24389 -397.15694) (xy 377.785884 -397.15694) (xy 377.785884 -397.156432) (xy 377.786368 -397.13244)
			(xy 377.793869 -397.085046) (xy 377.808693 -397.03941) (xy 377.830474 -396.996654) (xy 377.858675 -396.957833)
			(xy 377.892602 -396.923901) (xy 377.93142 -396.895695) (xy 377.974173 -396.873908) (xy 378.019808 -396.859079)
			(xy 378.0672 -396.851571) (xy 378.091192 -396.851124) (xy 378.115129 -396.851529) (xy 378.162418 -396.858995)
			(xy 378.207964 -396.873745) (xy 378.250652 -396.895418) (xy 378.289437 -396.923484) (xy 378.32337 -396.957256)
			(xy 378.35162 -396.995906) (xy 378.362972 -397.016986) (xy 378.36348 -397.018002) (xy 378.443786 -397.15694)
			(xy 378.98578 -397.15694) (xy 378.98578 -397.156432) (xy 378.986268 -397.13244) (xy 378.993769 -397.085047)
			(xy 379.008593 -397.039411) (xy 379.030373 -396.996656) (xy 379.058574 -396.957834) (xy 379.092501 -396.923902)
			(xy 379.131318 -396.895696) (xy 379.17407 -396.87391) (xy 379.219704 -396.85908) (xy 379.267096 -396.851571)
			(xy 379.291088 -396.851124) (xy 379.315025 -396.851532) (xy 379.362314 -396.858997) (xy 379.40786 -396.873747)
			(xy 379.450547 -396.895419) (xy 379.489333 -396.923485) (xy 379.523266 -396.957256) (xy 379.551516 -396.995907)
			(xy 379.562868 -397.016986) (xy 379.563376 -397.018002) (xy 379.643682 -397.15694) (xy 380.185676 -397.15694)
			(xy 380.185676 -397.156432) (xy 380.186169 -397.132428) (xy 380.193678 -397.085011) (xy 380.208517 -397.039353)
			(xy 380.230319 -396.996581) (xy 380.258547 -396.957748) (xy 380.292505 -396.923813) (xy 380.331357 -396.895611)
			(xy 380.374144 -396.873838) (xy 380.419811 -396.85903) (xy 380.467234 -396.851552) (xy 380.491238 -396.851124)
			(xy 380.515174 -396.851573) (xy 380.562461 -396.85903) (xy 380.608005 -396.873772) (xy 380.650693 -396.895438)
			(xy 380.689479 -396.923498) (xy 380.723413 -396.957263) (xy 380.751665 -396.995909) (xy 380.763018 -397.016986)
			(xy 380.763526 -397.018002) (xy 380.843832 -397.15694) (xy 381.385572 -397.15694) (xy 381.385572 -397.156432)
			(xy 381.386069 -397.132428) (xy 381.393578 -397.085011) (xy 381.408416 -397.039354) (xy 381.430218 -396.996582)
			(xy 381.458446 -396.95775) (xy 381.492404 -396.923814) (xy 381.531255 -396.895612) (xy 381.574041 -396.873839)
			(xy 381.619708 -396.859031) (xy 381.66713 -396.851553) (xy 381.691134 -396.851124) (xy 381.71507 -396.851576)
			(xy 381.762356 -396.859033) (xy 381.807901 -396.873774) (xy 381.850589 -396.89544) (xy 381.889375 -396.923499)
			(xy 381.923309 -396.957264) (xy 381.951561 -396.995909) (xy 381.962914 -397.016986) (xy 381.963422 -397.018002)
			(xy 382.043728 -397.15694) (xy 382.585976 -397.15694) (xy 382.585976 -397.156432) (xy 382.586468 -397.132441)
			(xy 382.593969 -397.085048) (xy 382.608792 -397.039412) (xy 382.630572 -396.996657) (xy 382.658773 -396.957836)
			(xy 382.692699 -396.923904) (xy 382.731516 -396.895697) (xy 382.774267 -396.873911) (xy 382.819901 -396.85908)
			(xy 382.867293 -396.851571) (xy 382.891284 -396.851124) (xy 382.915221 -396.851535) (xy 382.96251 -396.859)
			(xy 383.008055 -396.873749) (xy 383.050743 -396.895421) (xy 383.089528 -396.923486) (xy 383.123461 -396.957257)
			(xy 383.151712 -396.995907) (xy 383.163064 -397.016986) (xy 383.163572 -397.018002) (xy 383.243878 -397.15694)
			(xy 383.785872 -397.15694) (xy 383.785872 -397.156432) (xy 383.786368 -397.132441) (xy 383.793869 -397.085048)
			(xy 383.808692 -397.039413) (xy 383.830472 -396.996658) (xy 383.858671 -396.957837) (xy 383.892597 -396.923905)
			(xy 383.931414 -396.895699) (xy 383.974165 -396.873912) (xy 384.019798 -396.859081) (xy 384.067189 -396.851572)
			(xy 384.09118 -396.851124) (xy 384.115117 -396.851539) (xy 384.162405 -396.859002) (xy 384.207951 -396.873751)
			(xy 384.250639 -396.895422) (xy 384.289424 -396.923487) (xy 384.323357 -396.957257) (xy 384.351608 -396.995907)
			(xy 384.36296 -397.016986) (xy 384.363468 -397.018002) (xy 384.443774 -397.15694) (xy 384.985768 -397.15694)
			(xy 384.985768 -397.156432) (xy 384.986268 -397.132441) (xy 384.993769 -397.085049) (xy 385.008592 -397.039414)
			(xy 385.030371 -396.996659) (xy 385.05857 -396.957838) (xy 385.092496 -396.923907) (xy 385.131311 -396.8957)
			(xy 385.174062 -396.873913) (xy 385.219694 -396.859082) (xy 385.267085 -396.851572) (xy 385.291076 -396.851124)
			(xy 385.315013 -396.851542) (xy 385.362301 -396.859005) (xy 385.407847 -396.873753) (xy 385.450534 -396.895424)
			(xy 385.48932 -396.923488) (xy 385.523253 -396.957258) (xy 385.551504 -396.995907) (xy 385.562856 -397.016986)
			(xy 385.563364 -397.018002) (xy 385.64367 -397.15694) (xy 386.185664 -397.15694) (xy 386.185664 -397.156432)
			(xy 386.186169 -397.132428) (xy 386.193678 -397.085012) (xy 386.208515 -397.039356) (xy 386.230317 -396.996584)
			(xy 386.258543 -396.957753) (xy 386.2925 -396.923817) (xy 386.33135 -396.895615) (xy 386.374135 -396.873841)
			(xy 386.419801 -396.859032) (xy 386.467222 -396.851553) (xy 386.491226 -396.851124) (xy 386.515161 -396.851582)
			(xy 386.562448 -396.859038) (xy 386.607992 -396.873778) (xy 386.65068 -396.895443) (xy 386.689466 -396.923501)
			(xy 386.723401 -396.957265) (xy 386.751653 -396.995909) (xy 386.763006 -397.016986) (xy 386.763514 -397.018002)
			(xy 386.84382 -397.15694) (xy 387.38556 -397.15694) (xy 387.38556 -397.156432) (xy 387.386068 -397.132429)
			(xy 387.393577 -397.085013) (xy 387.408415 -397.039357) (xy 387.430216 -396.996586) (xy 387.458442 -396.957754)
			(xy 387.492399 -396.923819) (xy 387.531248 -396.895616) (xy 387.574033 -396.873842) (xy 387.619698 -396.859033)
			(xy 387.667118 -396.851554) (xy 387.691122 -396.851124) (xy 387.715057 -396.851586) (xy 387.762343 -396.859041)
			(xy 387.807888 -396.873781) (xy 387.850576 -396.895444) (xy 387.889362 -396.923502) (xy 387.923296 -396.957266)
			(xy 387.951549 -396.99591) (xy 387.962902 -397.016986) (xy 387.96341 -397.018002) (xy 388.043716 -397.15694)
			(xy 388.585964 -397.15694) (xy 388.585964 -397.156432) (xy 388.586468 -397.132441) (xy 388.593969 -397.085049)
			(xy 388.608791 -397.039415) (xy 388.63057 -396.99666) (xy 388.658769 -396.95784) (xy 388.692694 -396.923908)
			(xy 388.731509 -396.895701) (xy 388.774259 -396.873914) (xy 388.819891 -396.859083) (xy 388.867281 -396.851572)
			(xy 388.891272 -396.851124) (xy 388.915209 -396.851545) (xy 388.962497 -396.859008) (xy 389.008042 -396.873755)
			(xy 389.05073 -396.895425) (xy 389.089515 -396.923489) (xy 389.123449 -396.957258) (xy 389.1517 -396.995907)
			(xy 389.163052 -397.016986) (xy 389.16356 -397.018002) (xy 389.243866 -397.15694) (xy 403.113748 -397.15694)
			(xy 403.113748 -397.156432) (xy 403.114292 -397.132444) (xy 403.121792 -397.085057) (xy 403.136612 -397.039428)
			(xy 403.158388 -396.996678) (xy 403.186583 -396.957861) (xy 403.220503 -396.923933) (xy 403.259313 -396.895728)
			(xy 403.302057 -396.873941) (xy 403.347683 -396.85911) (xy 403.395068 -396.851598) (xy 403.419056 -396.851124)
			(xy 403.442992 -396.851558) (xy 403.49028 -396.859018) (xy 403.535825 -396.873763) (xy 403.578513 -396.895431)
			(xy 403.617298 -396.923493) (xy 403.651232 -396.957261) (xy 403.679483 -396.995908) (xy 403.690836 -397.016986)
			(xy 403.691344 -397.018002) (xy 403.77165 -397.15694) (xy 404.313644 -397.15694) (xy 404.313644 -397.156432)
			(xy 404.314192 -397.132444) (xy 404.321692 -397.085058) (xy 404.336512 -397.039429) (xy 404.358287 -396.996679)
			(xy 404.386482 -396.957862) (xy 404.420401 -396.923934) (xy 404.459211 -396.895729) (xy 404.501955 -396.873943)
			(xy 404.54758 -396.859111) (xy 404.594964 -396.851598) (xy 404.618952 -396.851124) (xy 404.642888 -396.851561)
			(xy 404.690176 -396.859021) (xy 404.735721 -396.873765) (xy 404.778408 -396.895433) (xy 404.817194 -396.923494)
			(xy 404.851128 -396.957261) (xy 404.879379 -396.995908) (xy 404.890732 -397.016986) (xy 404.89124 -397.018002)
			(xy 404.971546 -397.15694) (xy 405.51354 -397.15694) (xy 405.51354 -397.156432) (xy 405.513968 -397.132437)
			(xy 405.521471 -397.085038) (xy 405.536298 -397.039397) (xy 405.558084 -396.996638) (xy 405.586291 -396.957814)
			(xy 405.620226 -396.923881) (xy 405.659051 -396.895676) (xy 405.701812 -396.873892) (xy 405.747454 -396.859068)
			(xy 405.794853 -396.851567) (xy 405.818848 -396.851124) (xy 405.842784 -396.851565) (xy 405.890071 -396.859024)
			(xy 405.935616 -396.873767) (xy 405.978304 -396.895434) (xy 406.01709 -396.923495) (xy 406.051024 -396.957262)
			(xy 406.079275 -396.995908) (xy 406.090628 -397.016986) (xy 406.091136 -397.018002) (xy 406.171442 -397.15694)
			(xy 406.713436 -397.15694) (xy 406.713436 -397.156432) (xy 406.713869 -397.132425) (xy 406.72138 -397.085002)
			(xy 406.736222 -397.039339) (xy 406.75803 -396.996563) (xy 406.786264 -396.957728) (xy 406.82023 -396.923791)
			(xy 406.85909 -396.89559) (xy 406.901885 -396.87382) (xy 406.947561 -396.859018) (xy 406.99499 -396.851548)
			(xy 407.018998 -396.851124) (xy 407.042935 -396.851524) (xy 407.090225 -396.858991) (xy 407.135771 -396.873741)
			(xy 407.178458 -396.895415) (xy 407.217243 -396.923482) (xy 407.251176 -396.957255) (xy 407.279426 -396.995906)
			(xy 407.290778 -397.016986) (xy 407.291286 -397.018002) (xy 407.371592 -397.15694) (xy 407.913332 -397.15694)
			(xy 407.913332 -397.156432) (xy 407.913769 -397.132425) (xy 407.92128 -397.085002) (xy 407.936122 -397.03934)
			(xy 407.957929 -396.996564) (xy 407.986163 -396.957729) (xy 408.020129 -396.923793) (xy 408.058988 -396.895592)
			(xy 408.101783 -396.873822) (xy 408.147458 -396.859019) (xy 408.194887 -396.851548) (xy 408.218894 -396.851124)
			(xy 408.242831 -396.851527) (xy 408.29012 -396.858993) (xy 408.335666 -396.873744) (xy 408.378354 -396.895417)
			(xy 408.417139 -396.923483) (xy 408.451072 -396.957255) (xy 408.479322 -396.995906) (xy 408.490674 -397.016986)
			(xy 408.491182 -397.018002) (xy 408.571488 -397.15694) (xy 409.113736 -397.15694) (xy 409.113736 -397.156432)
			(xy 409.114168 -397.132438) (xy 409.121671 -397.085039) (xy 409.136498 -397.039398) (xy 409.158283 -396.996639)
			(xy 409.18649 -396.957815) (xy 409.220424 -396.923882) (xy 409.259249 -396.895677) (xy 409.302009 -396.873893)
			(xy 409.347651 -396.859068) (xy 409.39505 -396.851567) (xy 409.419044 -396.851124) (xy 409.44298 -396.851568)
			(xy 409.490267 -396.859026) (xy 409.535812 -396.873769) (xy 409.5785 -396.895436) (xy 409.617285 -396.923496)
			(xy 409.651219 -396.957262) (xy 409.679471 -396.995909) (xy 409.690824 -397.016986) (xy 409.691332 -397.018002)
			(xy 409.771638 -397.15694) (xy 410.313632 -397.15694) (xy 410.313632 -397.156432) (xy 410.314068 -397.132438)
			(xy 410.321571 -397.085039) (xy 410.336398 -397.039399) (xy 410.358183 -396.99664) (xy 410.386389 -396.957816)
			(xy 410.420322 -396.923884) (xy 410.459147 -396.895678) (xy 410.501906 -396.873895) (xy 410.547547 -396.859069)
			(xy 410.594946 -396.851567) (xy 410.61894 -396.851124) (xy 410.642876 -396.851571) (xy 410.690163 -396.859029)
			(xy 410.735708 -396.873771) (xy 410.778395 -396.895437) (xy 410.817181 -396.923497) (xy 410.851115 -396.957263)
			(xy 410.879367 -396.995909) (xy 410.89072 -397.016986) (xy 410.891228 -397.018002) (xy 410.971534 -397.15694)
			(xy 411.513528 -397.15694) (xy 411.513528 -397.156432) (xy 411.513968 -397.132438) (xy 411.521471 -397.08504)
			(xy 411.536297 -397.0394) (xy 411.558082 -396.996641) (xy 411.586288 -396.957818) (xy 411.620221 -396.923885)
			(xy 411.659045 -396.89568) (xy 411.701804 -396.873896) (xy 411.747444 -396.85907) (xy 411.794842 -396.851568)
			(xy 411.818836 -396.851124) (xy 411.842772 -396.851574) (xy 411.890058 -396.859031) (xy 411.935603 -396.873773)
			(xy 411.978291 -396.895439) (xy 412.017077 -396.923498) (xy 412.051011 -396.957264) (xy 412.079263 -396.995909)
			(xy 412.090616 -397.016986) (xy 412.091124 -397.018002) (xy 412.17143 -397.15694) (xy 412.713424 -397.15694)
			(xy 412.713424 -397.156432) (xy 412.713869 -397.132425) (xy 412.72138 -397.085004) (xy 412.736221 -397.039342)
			(xy 412.758027 -396.996567) (xy 412.786261 -396.957732) (xy 412.820225 -396.923796) (xy 412.859083 -396.895595)
			(xy 412.901877 -396.873824) (xy 412.947551 -396.85902) (xy 412.994979 -396.851549) (xy 413.018986 -396.851124)
			(xy 413.042923 -396.851534) (xy 413.090212 -396.858998) (xy 413.135757 -396.873748) (xy 413.178445 -396.89542)
			(xy 413.21723 -396.923485) (xy 413.251164 -396.957256) (xy 413.279414 -396.995907) (xy 413.290766 -397.016986)
			(xy 413.291274 -397.018002) (xy 413.37158 -397.15694) (xy 413.91332 -397.15694) (xy 413.91332 -397.156432)
			(xy 413.913769 -397.132426) (xy 413.921279 -397.085004) (xy 413.936121 -397.039343) (xy 413.957927 -396.996568)
			(xy 413.98616 -396.957733) (xy 414.020124 -396.923797) (xy 414.058981 -396.895596) (xy 414.101774 -396.873825)
			(xy 414.147448 -396.859021) (xy 414.194875 -396.851549) (xy 414.218882 -396.851124) (xy 414.242819 -396.851537)
			(xy 414.290108 -396.859001) (xy 414.335653 -396.87375) (xy 414.378341 -396.895422) (xy 414.417126 -396.923486)
			(xy 414.451059 -396.957257) (xy 414.47931 -396.995907) (xy 414.490662 -397.016986) (xy 414.49117 -397.018002)
			(xy 414.571476 -397.15694) (xy 415.113724 -397.15694) (xy 415.113724 -397.156432) (xy 415.114168 -397.132438)
			(xy 415.121671 -397.085041) (xy 415.136497 -397.039401) (xy 415.158281 -396.996643) (xy 415.186487 -396.957819)
			(xy 415.220419 -396.923887) (xy 415.259243 -396.895681) (xy 415.302001 -396.873897) (xy 415.347641 -396.859071)
			(xy 415.395038 -396.851568) (xy 415.419032 -396.851124) (xy 415.442968 -396.851578) (xy 415.490254 -396.859034)
			(xy 415.535799 -396.873775) (xy 415.578487 -396.89544) (xy 415.617272 -396.923499) (xy 415.651207 -396.957264)
			(xy 415.679459 -396.995909) (xy 415.690812 -397.016986) (xy 415.69132 -397.018002) (xy 415.771626 -397.15694)
			(xy 416.31362 -397.15694) (xy 416.31362 -397.156432) (xy 416.314068 -397.132438) (xy 416.321571 -397.085041)
			(xy 416.336397 -397.039402) (xy 416.35818 -396.996644) (xy 416.386386 -396.95782) (xy 416.420317 -396.923888)
			(xy 416.45914 -396.895682) (xy 416.501898 -396.873898) (xy 416.547537 -396.859072) (xy 416.594934 -396.851568)
			(xy 416.618928 -396.851124) (xy 416.642863 -396.851581) (xy 416.69015 -396.859037) (xy 416.735695 -396.873777)
			(xy 416.778382 -396.895442) (xy 416.817168 -396.9235) (xy 416.851103 -396.957265) (xy 416.879355 -396.995909)
			(xy 416.890708 -397.016986) (xy 416.891216 -397.018002) (xy 416.971522 -397.15694) (xy 417.513516 -397.15694)
			(xy 417.513516 -397.156432) (xy 417.513968 -397.132439) (xy 417.521471 -397.085042) (xy 417.536296 -397.039403)
			(xy 417.55808 -396.996645) (xy 417.586284 -396.957822) (xy 417.620216 -396.92389) (xy 417.659038 -396.895684)
			(xy 417.701795 -396.873899) (xy 417.747434 -396.859072) (xy 417.794831 -396.851568) (xy 417.818824 -396.851124)
			(xy 417.842759 -396.851584) (xy 417.890046 -396.859039) (xy 417.93559 -396.873779) (xy 417.978278 -396.895444)
			(xy 418.017064 -396.923501) (xy 418.050998 -396.957265) (xy 418.079251 -396.99591) (xy 418.090604 -397.016986)
			(xy 418.091112 -397.018002) (xy 418.171418 -397.15694) (xy 418.713412 -397.15694) (xy 418.713412 -397.156432)
			(xy 418.713869 -397.132426) (xy 418.721379 -397.085005) (xy 418.73622 -397.039345) (xy 418.758025 -396.99657)
			(xy 418.786257 -396.957736) (xy 418.82022 -396.9238) (xy 418.859077 -396.895599) (xy 418.901869 -396.873827)
			(xy 418.947541 -396.859023) (xy 418.994968 -396.85155) (xy 419.018974 -396.851124) (xy 419.042911 -396.851543)
			(xy 419.090199 -396.859006) (xy 419.135744 -396.873754) (xy 419.178432 -396.895425) (xy 419.217218 -396.923488)
			(xy 419.251151 -396.957258) (xy 419.279402 -396.995907) (xy 419.290754 -397.016986) (xy 419.291262 -397.018002)
			(xy 419.371568 -397.15694) (xy 419.913308 -397.15694) (xy 419.913308 -397.156432) (xy 419.913769 -397.132426)
			(xy 419.921279 -397.085006) (xy 419.93612 -397.039346) (xy 419.957925 -396.996571) (xy 419.986156 -396.957737)
			(xy 420.020119 -396.923801) (xy 420.058975 -396.8956) (xy 420.101766 -396.873828) (xy 420.147438 -396.859023)
			(xy 420.194864 -396.85155) (xy 420.21887 -396.851124) (xy 420.242807 -396.851547) (xy 420.290095 -396.859009)
			(xy 420.33564 -396.873756) (xy 420.378328 -396.895426) (xy 420.417113 -396.923489) (xy 420.451047 -396.957259)
			(xy 420.479298 -396.995907) (xy 420.49065 -397.016986) (xy 420.491158 -397.018002) (xy 420.571464 -397.15694)
			(xy 421.113712 -397.15694) (xy 421.113712 -397.156432) (xy 421.114168 -397.132439) (xy 421.12167 -397.085042)
			(xy 421.136496 -397.039404) (xy 421.158279 -396.996646) (xy 421.186483 -396.957823) (xy 421.220414 -396.923891)
			(xy 421.259236 -396.895685) (xy 421.301992 -396.8739) (xy 421.347631 -396.859073) (xy 421.395027 -396.851569)
			(xy 421.41902 -396.851124) (xy 421.442955 -396.851587) (xy 421.490241 -396.859042) (xy 421.535786 -396.873782)
			(xy 421.578474 -396.895445) (xy 421.61726 -396.923502) (xy 421.651194 -396.957266) (xy 421.679447 -396.99591)
			(xy 421.6908 -397.016986) (xy 421.691308 -397.018002) (xy 422.083738 -397.696944) (xy 422.096544 -397.720286)
			(xy 422.114771 -397.770304) (xy 422.124039 -397.822727) (xy 422.124632 -397.849344) (xy 422.124202 -397.87335)
			(xy 422.116681 -397.920769) (xy 422.101833 -397.966427) (xy 422.080022 -398.009199) (xy 422.051786 -398.04803)
			(xy 422.017821 -398.081964) (xy 421.978965 -398.110165) (xy 421.936173 -398.131938) (xy 421.890502 -398.146745)
			(xy 421.843076 -398.154223) (xy 421.81907 -398.154652) (xy 421.795497 -398.154255) (xy 421.74891 -398.14701)
			(xy 421.703993 -398.132683) (xy 421.661815 -398.111614) (xy 421.623383 -398.084306) (xy 421.58961 -398.051409)
			(xy 421.561302 -398.013706) (xy 421.54983 -397.993108) (xy 421.549322 -397.992346) (xy 421.151558 -397.304006)
			(xy 421.139682 -397.281329) (xy 421.122831 -397.232996) (xy 421.114258 -397.182533) (xy 421.113712 -397.15694)
			(xy 420.571464 -397.15694) (xy 420.883588 -397.696944) (xy 420.896319 -397.72031) (xy 420.914436 -397.770338)
			(xy 420.923646 -397.822741) (xy 420.924228 -397.849344) (xy 420.923778 -397.873335) (xy 420.916266 -397.920727)
			(xy 420.901434 -397.96636) (xy 420.879647 -398.009111) (xy 420.851441 -398.047928) (xy 420.81751 -398.081856)
			(xy 420.778691 -398.110059) (xy 420.735937 -398.131843) (xy 420.690303 -398.146672) (xy 420.642911 -398.15418)
			(xy 420.61892 -398.154652) (xy 420.595348 -398.154215) (xy 420.548763 -398.146978) (xy 420.503847 -398.132658)
			(xy 420.46167 -398.111595) (xy 420.423236 -398.084293) (xy 420.389462 -398.051402) (xy 420.361153 -398.013704)
			(xy 420.34968 -397.993108) (xy 420.349172 -397.992346) (xy 419.951408 -397.304006) (xy 419.939493 -397.281337)
			(xy 419.922555 -397.233012) (xy 419.913896 -397.182542) (xy 419.913308 -397.15694) (xy 419.371568 -397.15694)
			(xy 419.683692 -397.696944) (xy 419.696424 -397.72031) (xy 419.71454 -397.770338) (xy 419.72375 -397.822741)
			(xy 419.724332 -397.849344) (xy 419.723878 -397.873335) (xy 419.716366 -397.920726) (xy 419.701534 -397.966359)
			(xy 419.679747 -398.00911) (xy 419.651542 -398.047927) (xy 419.617612 -398.081855) (xy 419.578793 -398.110058)
			(xy 419.53604 -398.131842) (xy 419.490407 -398.146671) (xy 419.443015 -398.15418) (xy 419.419024 -398.154652)
			(xy 419.395452 -398.154211) (xy 419.348867 -398.146975) (xy 419.303951 -398.132656) (xy 419.261774 -398.111594)
			(xy 419.223341 -398.084292) (xy 419.189567 -398.051401) (xy 419.161257 -398.013704) (xy 419.149784 -397.993108)
			(xy 419.149276 -397.992346) (xy 418.751512 -397.304006) (xy 418.739598 -397.281337) (xy 418.72266 -397.233012)
			(xy 418.714 -397.182542) (xy 418.713412 -397.15694) (xy 418.171418 -397.15694) (xy 418.483542 -397.696944)
			(xy 418.496349 -397.720286) (xy 418.514576 -397.770304) (xy 418.523843 -397.822727) (xy 418.524436 -397.849344)
			(xy 418.524002 -397.87335) (xy 418.516481 -397.920768) (xy 418.501633 -397.966426) (xy 418.479822 -398.009197)
			(xy 418.451587 -398.048029) (xy 418.417623 -398.081963) (xy 418.378767 -398.110164) (xy 418.335976 -398.131936)
			(xy 418.290305 -398.146744) (xy 418.24288 -398.154223) (xy 418.218874 -398.154652) (xy 418.195301 -398.154252)
			(xy 418.148714 -398.147008) (xy 418.103797 -398.132681) (xy 418.06162 -398.111613) (xy 418.023187 -398.084305)
			(xy 417.989414 -398.051408) (xy 417.961106 -398.013706) (xy 417.949634 -397.993108) (xy 417.949126 -397.992346)
			(xy 417.551362 -397.304006) (xy 417.539486 -397.281329) (xy 417.522635 -397.232996) (xy 417.514062 -397.182533)
			(xy 417.513516 -397.15694) (xy 416.971522 -397.15694) (xy 417.283646 -397.696944) (xy 417.296453 -397.720286)
			(xy 417.31468 -397.770304) (xy 417.323947 -397.822727) (xy 417.32454 -397.849344) (xy 417.324102 -397.873349)
			(xy 417.316581 -397.920768) (xy 417.301733 -397.966425) (xy 417.279923 -398.009196) (xy 417.251688 -398.048027)
			(xy 417.217725 -398.081961) (xy 417.178869 -398.110162) (xy 417.136079 -398.131935) (xy 417.090409 -398.146744)
			(xy 417.042984 -398.154222) (xy 417.018978 -398.154652) (xy 416.995405 -398.154249) (xy 416.948818 -398.147005)
			(xy 416.903901 -398.132679) (xy 416.861724 -398.111611) (xy 416.823291 -398.084304) (xy 416.789518 -398.051408)
			(xy 416.76121 -398.013706) (xy 416.749738 -397.993108) (xy 416.74923 -397.992346) (xy 416.351466 -397.304006)
			(xy 416.339591 -397.281329) (xy 416.322739 -397.232996) (xy 416.314166 -397.182533) (xy 416.31362 -397.15694)
			(xy 415.771626 -397.15694) (xy 416.08375 -397.696944) (xy 416.096557 -397.720285) (xy 416.114784 -397.770304)
			(xy 416.124051 -397.822726) (xy 416.124644 -397.849344) (xy 416.124202 -397.873349) (xy 416.116682 -397.920767)
			(xy 416.101834 -397.966424) (xy 416.080024 -398.009195) (xy 416.05179 -398.048026) (xy 416.017826 -398.08196)
			(xy 415.978971 -398.110161) (xy 415.936182 -398.131934) (xy 415.890512 -398.146743) (xy 415.843088 -398.154222)
			(xy 415.819082 -398.154652) (xy 415.795509 -398.154245) (xy 415.748922 -398.147003) (xy 415.704006 -398.132677)
			(xy 415.661828 -398.11161) (xy 415.623395 -398.084303) (xy 415.589623 -398.051407) (xy 415.561314 -398.013706)
			(xy 415.549842 -397.993108) (xy 415.549334 -397.992346) (xy 415.15157 -397.304006) (xy 415.139695 -397.281329)
			(xy 415.122843 -397.232996) (xy 415.11427 -397.182533) (xy 415.113724 -397.15694) (xy 414.571476 -397.15694)
			(xy 414.8836 -397.696944) (xy 414.896332 -397.72031) (xy 414.914448 -397.770338) (xy 414.923658 -397.822741)
			(xy 414.92424 -397.849344) (xy 414.923778 -397.873335) (xy 414.916266 -397.920725) (xy 414.901435 -397.966357)
			(xy 414.879649 -398.009107) (xy 414.851444 -398.047924) (xy 414.817515 -398.081852) (xy 414.778697 -398.110055)
			(xy 414.735946 -398.13184) (xy 414.690313 -398.146669) (xy 414.642923 -398.154179) (xy 414.618932 -398.154652)
			(xy 414.59536 -398.154205) (xy 414.548776 -398.14697) (xy 414.50386 -398.132651) (xy 414.461683 -398.111591)
			(xy 414.423249 -398.08429) (xy 414.389475 -398.0514) (xy 414.361165 -398.013703) (xy 414.349692 -397.993108)
			(xy 414.349184 -397.992346) (xy 413.95142 -397.304006) (xy 413.939506 -397.281337) (xy 413.922568 -397.233012)
			(xy 413.913908 -397.182542) (xy 413.91332 -397.15694) (xy 413.37158 -397.15694) (xy 413.683704 -397.696944)
			(xy 413.696437 -397.72031) (xy 413.714552 -397.770337) (xy 413.723762 -397.822741) (xy 413.724344 -397.849344)
			(xy 413.723878 -397.873335) (xy 413.716367 -397.920724) (xy 413.701535 -397.966356) (xy 413.679749 -398.009106)
			(xy 413.651545 -398.047923) (xy 413.617617 -398.08185) (xy 413.578799 -398.110054) (xy 413.536049 -398.131838)
			(xy 413.490417 -398.146668) (xy 413.443027 -398.154179) (xy 413.419036 -398.154652) (xy 413.395464 -398.154202)
			(xy 413.34888 -398.146967) (xy 413.303964 -398.132649) (xy 413.261787 -398.111589) (xy 413.223353 -398.084289)
			(xy 413.189579 -398.051399) (xy 413.161269 -398.013703) (xy 413.149796 -397.993108) (xy 413.149288 -397.992346)
			(xy 412.751524 -397.304006) (xy 412.739611 -397.281337) (xy 412.722672 -397.233012) (xy 412.714012 -397.182542)
			(xy 412.713424 -397.15694) (xy 412.17143 -397.15694) (xy 412.483554 -397.696944) (xy 412.496362 -397.720285)
			(xy 412.514588 -397.770304) (xy 412.523855 -397.822726) (xy 412.524448 -397.849344) (xy 412.524002 -397.873349)
			(xy 412.516482 -397.920767) (xy 412.501634 -397.966423) (xy 412.479825 -398.009194) (xy 412.451591 -398.048025)
			(xy 412.417628 -398.081959) (xy 412.378773 -398.11016) (xy 412.335984 -398.131933) (xy 412.290315 -398.146742)
			(xy 412.242891 -398.154222) (xy 412.218886 -398.154652) (xy 412.195313 -398.154242) (xy 412.148727 -398.147)
			(xy 412.10381 -398.132675) (xy 412.061633 -398.111608) (xy 412.0232 -398.084302) (xy 411.989427 -398.051406)
			(xy 411.961119 -398.013705) (xy 411.949646 -397.993108) (xy 411.949138 -397.992346) (xy 411.551374 -397.304006)
			(xy 411.539499 -397.281329) (xy 411.522648 -397.232996) (xy 411.514074 -397.182533) (xy 411.513528 -397.15694)
			(xy 410.971534 -397.15694) (xy 411.283658 -397.696944) (xy 411.296466 -397.720285) (xy 411.314692 -397.770304)
			(xy 411.323959 -397.822726) (xy 411.324552 -397.849344) (xy 411.324102 -397.873349) (xy 411.316582 -397.920766)
			(xy 411.301734 -397.966422) (xy 411.279925 -398.009193) (xy 411.251692 -398.048023) (xy 411.21773 -398.081957)
			(xy 411.178876 -398.110158) (xy 411.136087 -398.131932) (xy 411.090419 -398.146741) (xy 411.042995 -398.154222)
			(xy 411.01899 -398.154652) (xy 410.995417 -398.154239) (xy 410.948831 -398.146997) (xy 410.903914 -398.132673)
			(xy 410.861737 -398.111607) (xy 410.823304 -398.084301) (xy 410.789531 -398.051406) (xy 410.761223 -398.013705)
			(xy 410.74975 -397.993108) (xy 410.749242 -397.992346) (xy 410.351478 -397.304006) (xy 410.339603 -397.281328)
			(xy 410.322752 -397.232996) (xy 410.314178 -397.182533) (xy 410.313632 -397.15694) (xy 409.771638 -397.15694)
			(xy 410.083762 -397.696944) (xy 410.09657 -397.720285) (xy 410.114796 -397.770304) (xy 410.124063 -397.822726)
			(xy 410.124656 -397.849344) (xy 410.124202 -397.873349) (xy 410.116682 -397.920765) (xy 410.101835 -397.966421)
			(xy 410.080026 -398.009191) (xy 410.051793 -398.048022) (xy 410.017831 -398.081956) (xy 409.978978 -398.110157)
			(xy 409.93619 -398.131931) (xy 409.890522 -398.14674) (xy 409.843099 -398.154221) (xy 409.819094 -398.154652)
			(xy 409.795521 -398.154236) (xy 409.748935 -398.146995) (xy 409.704019 -398.132671) (xy 409.661841 -398.111605)
			(xy 409.623408 -398.0843) (xy 409.589635 -398.051405) (xy 409.561327 -398.013705) (xy 409.549854 -397.993108)
			(xy 409.549346 -397.992346) (xy 409.151582 -397.304006) (xy 409.139708 -397.281328) (xy 409.122856 -397.232996)
			(xy 409.114282 -397.182533) (xy 409.113736 -397.15694) (xy 408.571488 -397.15694) (xy 408.883612 -397.696944)
			(xy 408.896345 -397.720309) (xy 408.91446 -397.770337) (xy 408.92367 -397.822741) (xy 408.924252 -397.849344)
			(xy 408.923778 -397.873334) (xy 408.916267 -397.920723) (xy 408.901436 -397.966354) (xy 408.879651 -398.009104)
			(xy 408.851448 -398.04792) (xy 408.81752 -398.081848) (xy 408.778704 -398.110051) (xy 408.735954 -398.131836)
			(xy 408.690323 -398.146667) (xy 408.642934 -398.154178) (xy 408.618944 -398.154652) (xy 408.595373 -398.154195)
			(xy 408.548789 -398.146962) (xy 408.503873 -398.132645) (xy 408.461696 -398.111586) (xy 408.423262 -398.084287)
			(xy 408.389488 -398.051398) (xy 408.361178 -398.013703) (xy 408.349704 -397.993108) (xy 408.349196 -397.992346)
			(xy 407.951432 -397.304006) (xy 407.939519 -397.281336) (xy 407.92258 -397.233012) (xy 407.91392 -397.182542)
			(xy 407.913332 -397.15694) (xy 407.371592 -397.15694) (xy 407.683716 -397.696944) (xy 407.69645 -397.720309)
			(xy 407.714565 -397.770337) (xy 407.723774 -397.822741) (xy 407.724356 -397.849344) (xy 407.723878 -397.873334)
			(xy 407.716367 -397.920723) (xy 407.701536 -397.966353) (xy 407.679752 -398.009103) (xy 407.651549 -398.047919)
			(xy 407.617622 -398.081846) (xy 407.578806 -398.11005) (xy 407.536057 -398.131835) (xy 407.490427 -398.146666)
			(xy 407.443038 -398.154178) (xy 407.419048 -398.154652) (xy 407.395477 -398.154192) (xy 407.348893 -398.146959)
			(xy 407.303977 -398.132643) (xy 407.2618 -398.111585) (xy 407.223366 -398.084286) (xy 407.189592 -398.051398)
			(xy 407.161282 -398.013703) (xy 407.149808 -397.993108) (xy 407.1493 -397.992346) (xy 406.751536 -397.304006)
			(xy 406.739623 -397.281336) (xy 406.722684 -397.233012) (xy 406.714024 -397.182542) (xy 406.713436 -397.15694)
			(xy 406.171442 -397.15694) (xy 406.483566 -397.696944) (xy 406.496375 -397.720285) (xy 406.5146 -397.770303)
			(xy 406.523867 -397.822726) (xy 406.52446 -397.849344) (xy 406.524101 -397.873353) (xy 406.516579 -397.92078)
			(xy 406.501726 -397.966444) (xy 406.479909 -398.00922) (xy 406.451665 -398.048055) (xy 406.417691 -398.08199)
			(xy 406.378825 -398.11019) (xy 406.336023 -398.131958) (xy 406.290342 -398.146759) (xy 406.242908 -398.154228)
			(xy 406.218898 -398.154652) (xy 406.195325 -398.154232) (xy 406.14874 -398.146992) (xy 406.103823 -398.132669)
			(xy 406.061646 -398.111604) (xy 406.023213 -398.084299) (xy 405.989439 -398.051405) (xy 405.961131 -398.013705)
			(xy 405.949658 -397.993108) (xy 405.94915 -397.992346) (xy 405.551386 -397.304006) (xy 405.539512 -397.281328)
			(xy 405.52266 -397.232996) (xy 405.514086 -397.182533) (xy 405.51354 -397.15694) (xy 404.971546 -397.15694)
			(xy 405.28367 -397.696944) (xy 405.296479 -397.720285) (xy 405.314704 -397.770303) (xy 405.323971 -397.822726)
			(xy 405.324564 -397.849344) (xy 405.324201 -397.873353) (xy 405.316679 -397.920779) (xy 405.301826 -397.966443)
			(xy 405.280009 -398.009219) (xy 405.251766 -398.048053) (xy 405.217793 -398.081989) (xy 405.178927 -398.110188)
			(xy 405.136126 -398.131957) (xy 405.090446 -398.146759) (xy 405.043012 -398.154228) (xy 405.019002 -398.154652)
			(xy 404.995429 -398.154229) (xy 404.948844 -398.14699) (xy 404.903927 -398.132667) (xy 404.86175 -398.111602)
			(xy 404.823317 -398.084298) (xy 404.789544 -398.051404) (xy 404.761235 -398.013705) (xy 404.749762 -397.993108)
			(xy 404.749254 -397.992346) (xy 404.35149 -397.304006) (xy 404.339616 -397.281328) (xy 404.322764 -397.232995)
			(xy 404.31419 -397.182533) (xy 404.313644 -397.15694) (xy 403.77165 -397.15694) (xy 404.083774 -397.696944)
			(xy 404.096583 -397.720284) (xy 404.114808 -397.770303) (xy 404.124075 -397.822726) (xy 404.124668 -397.849344)
			(xy 404.124301 -397.873353) (xy 404.116779 -397.920778) (xy 404.101926 -397.966442) (xy 404.08011 -398.009218)
			(xy 404.051867 -398.048052) (xy 404.017895 -398.081987) (xy 403.979029 -398.110187) (xy 403.936229 -398.131956)
			(xy 403.890549 -398.146758) (xy 403.843116 -398.154228) (xy 403.819106 -398.154652) (xy 403.795534 -398.154226)
			(xy 403.748948 -398.146987) (xy 403.704032 -398.132665) (xy 403.661854 -398.111601) (xy 403.623421 -398.084297)
			(xy 403.589648 -398.051404) (xy 403.561339 -398.013705) (xy 403.549866 -397.993108) (xy 403.549358 -397.992346)
			(xy 403.151594 -397.304006) (xy 403.139721 -397.281328) (xy 403.122868 -397.232995) (xy 403.114294 -397.182532)
			(xy 403.113748 -397.15694) (xy 389.243866 -397.15694) (xy 389.55599 -397.696944) (xy 389.568801 -397.720284)
			(xy 389.587025 -397.770303) (xy 389.596291 -397.822726) (xy 389.596884 -397.849344) (xy 389.596501 -397.873352)
			(xy 389.588979 -397.920776) (xy 389.574128 -397.966438) (xy 389.552313 -398.009213) (xy 389.524072 -398.048046)
			(xy 389.490101 -398.081981) (xy 389.451238 -398.110181) (xy 389.40844 -398.131951) (xy 389.362762 -398.146755)
			(xy 389.315331 -398.154227) (xy 389.291322 -398.154652) (xy 389.26775 -398.154213) (xy 389.221165 -398.146976)
			(xy 389.176249 -398.132657) (xy 389.134072 -398.111595) (xy 389.095638 -398.084293) (xy 389.061865 -398.051401)
			(xy 389.033555 -398.013704) (xy 389.022082 -397.993108) (xy 389.021574 -397.992346) (xy 388.62381 -397.304006)
			(xy 388.61193 -397.281331) (xy 388.595082 -397.232997) (xy 388.58651 -397.182533) (xy 388.585964 -397.15694)
			(xy 388.043716 -397.15694) (xy 388.35584 -397.696944) (xy 388.368576 -397.720308) (xy 388.386689 -397.770337)
			(xy 388.395898 -397.822741) (xy 388.39648 -397.849344) (xy 388.396078 -397.873338) (xy 388.388564 -397.920734)
			(xy 388.373729 -397.966371) (xy 388.351938 -398.009125) (xy 388.323726 -398.047945) (xy 388.28979 -398.081873)
			(xy 388.250964 -398.110075) (xy 388.208204 -398.131857) (xy 388.162564 -398.146681) (xy 388.115166 -398.154184)
			(xy 388.091172 -398.154652) (xy 388.067599 -398.154253) (xy 388.021012 -398.147009) (xy 387.976095 -398.132682)
			(xy 387.933917 -398.111614) (xy 387.895485 -398.084306) (xy 387.861712 -398.051408) (xy 387.833404 -398.013706)
			(xy 387.821932 -397.993108) (xy 387.821424 -397.992346) (xy 387.42366 -397.304006) (xy 387.411749 -397.281335)
			(xy 387.394809 -397.233011) (xy 387.386148 -397.182542) (xy 387.38556 -397.15694) (xy 386.84382 -397.15694)
			(xy 387.155944 -397.696944) (xy 387.16868 -397.720308) (xy 387.186793 -397.770337) (xy 387.196002 -397.822741)
			(xy 387.196584 -397.849344) (xy 387.196178 -397.873338) (xy 387.188664 -397.920733) (xy 387.17383 -397.96637)
			(xy 387.152038 -398.009124) (xy 387.123828 -398.047943) (xy 387.089892 -398.081872) (xy 387.051066 -398.110074)
			(xy 387.008307 -398.131856) (xy 386.962667 -398.14668) (xy 386.91527 -398.154183) (xy 386.891276 -398.154652)
			(xy 386.867703 -398.15425) (xy 386.821116 -398.147007) (xy 386.776199 -398.13268) (xy 386.734022 -398.111612)
			(xy 386.695589 -398.084305) (xy 386.661816 -398.051408) (xy 386.633508 -398.013706) (xy 386.622036 -397.993108)
			(xy 386.621528 -397.992346) (xy 386.223764 -397.304006) (xy 386.211854 -397.281335) (xy 386.194914 -397.233011)
			(xy 386.186252 -397.182542) (xy 386.185664 -397.15694) (xy 385.64367 -397.15694) (xy 385.955794 -397.696944)
			(xy 385.968605 -397.720283) (xy 385.986829 -397.770303) (xy 385.996095 -397.822726) (xy 385.996688 -397.849344)
			(xy 385.996301 -397.873352) (xy 385.98878 -397.920775) (xy 385.973928 -397.966437) (xy 385.952114 -398.009212)
			(xy 385.923873 -398.048045) (xy 385.889903 -398.08198) (xy 385.85104 -398.11018) (xy 385.808243 -398.13195)
			(xy 385.762566 -398.146754) (xy 385.715134 -398.154226) (xy 385.691126 -398.154652) (xy 385.667554 -398.15421)
			(xy 385.620969 -398.146974) (xy 385.576053 -398.132654) (xy 385.533876 -398.111593) (xy 385.495443 -398.084292)
			(xy 385.461669 -398.051401) (xy 385.433359 -398.013704) (xy 385.421886 -397.993108) (xy 385.421378 -397.992346)
			(xy 385.023614 -397.304006) (xy 385.011735 -397.281331) (xy 384.994886 -397.232997) (xy 384.986314 -397.182533)
			(xy 384.985768 -397.15694) (xy 384.443774 -397.15694) (xy 384.755898 -397.696944) (xy 384.768701 -397.720288)
			(xy 384.78693 -397.770305) (xy 384.796199 -397.822727) (xy 384.796792 -397.849344) (xy 384.796401 -397.873352)
			(xy 384.78888 -397.920775) (xy 384.774029 -397.966436) (xy 384.752214 -398.009211) (xy 384.723974 -398.048044)
			(xy 384.690005 -398.081979) (xy 384.651142 -398.110179) (xy 384.608346 -398.131949) (xy 384.562669 -398.146753)
			(xy 384.515238 -398.154226) (xy 384.49123 -398.154652) (xy 384.467658 -398.154207) (xy 384.421074 -398.146971)
			(xy 384.376158 -398.132652) (xy 384.33398 -398.111592) (xy 384.295547 -398.084291) (xy 384.261773 -398.0514)
			(xy 384.233463 -398.013704) (xy 384.22199 -397.993108) (xy 384.221482 -397.992346) (xy 383.823718 -397.304006)
			(xy 383.811839 -397.281331) (xy 383.79499 -397.232997) (xy 383.786418 -397.182533) (xy 383.785872 -397.15694)
			(xy 383.243878 -397.15694) (xy 383.556002 -397.696944) (xy 383.568805 -397.720288) (xy 383.587034 -397.770305)
			(xy 383.596303 -397.822727) (xy 383.596896 -397.849344) (xy 383.596501 -397.873352) (xy 383.58898 -397.920774)
			(xy 383.574129 -397.966435) (xy 383.552315 -398.009209) (xy 383.524075 -398.048042) (xy 383.490106 -398.081977)
			(xy 383.451245 -398.110177) (xy 383.408448 -398.131948) (xy 383.362772 -398.146752) (xy 383.315342 -398.154226)
			(xy 383.291334 -398.154652) (xy 383.267762 -398.154203) (xy 383.221178 -398.146969) (xy 383.176262 -398.13265)
			(xy 383.134085 -398.11159) (xy 383.095651 -398.08429) (xy 383.061877 -398.0514) (xy 383.033567 -398.013703)
			(xy 383.022094 -397.993108) (xy 383.021586 -397.992346) (xy 382.623822 -397.304006) (xy 382.611943 -397.281331)
			(xy 382.595094 -397.232996) (xy 382.586522 -397.182533) (xy 382.585976 -397.15694) (xy 382.043728 -397.15694)
			(xy 382.355852 -397.696944) (xy 382.368589 -397.720308) (xy 382.386702 -397.770337) (xy 382.39591 -397.822741)
			(xy 382.396492 -397.849344) (xy 382.396078 -397.873337) (xy 382.388565 -397.920732) (xy 382.37373 -397.966368)
			(xy 382.35194 -398.009122) (xy 382.32373 -398.047941) (xy 382.289795 -398.081869) (xy 382.250971 -398.110071)
			(xy 382.208212 -398.131853) (xy 382.162574 -398.146679) (xy 382.115177 -398.154183) (xy 382.091184 -398.154652)
			(xy 382.067611 -398.154244) (xy 382.021025 -398.147001) (xy 381.976108 -398.132676) (xy 381.933931 -398.111609)
			(xy 381.895498 -398.084302) (xy 381.861725 -398.051407) (xy 381.833416 -398.013706) (xy 381.821944 -397.993108)
			(xy 381.821436 -397.992346) (xy 381.423672 -397.304006) (xy 381.411754 -397.281339) (xy 381.394818 -397.233013)
			(xy 381.386159 -397.182542) (xy 381.385572 -397.15694) (xy 380.843832 -397.15694) (xy 381.155956 -397.696944)
			(xy 381.168693 -397.720307) (xy 381.186806 -397.770337) (xy 381.196014 -397.822741) (xy 381.196596 -397.849344)
			(xy 381.196178 -397.873337) (xy 381.188665 -397.920731) (xy 381.173831 -397.966367) (xy 381.152041 -398.009121)
			(xy 381.123831 -398.047939) (xy 381.089897 -398.081868) (xy 381.051073 -398.11007) (xy 381.008315 -398.131852)
			(xy 380.962677 -398.146678) (xy 380.915281 -398.154182) (xy 380.891288 -398.154652) (xy 380.867715 -398.154241)
			(xy 380.821129 -398.146999) (xy 380.776212 -398.132674) (xy 380.734035 -398.111608) (xy 380.695602 -398.084301)
			(xy 380.661829 -398.051406) (xy 380.633521 -398.013705) (xy 380.622048 -397.993108) (xy 380.62154 -397.992346)
			(xy 380.223776 -397.304006) (xy 380.211859 -397.281339) (xy 380.194923 -397.233013) (xy 380.186263 -397.182542)
			(xy 380.185676 -397.15694) (xy 379.643682 -397.15694) (xy 379.955806 -397.696944) (xy 379.96861 -397.720287)
			(xy 379.986838 -397.770304) (xy 379.996107 -397.822727) (xy 379.9967 -397.849344) (xy 379.996301 -397.873351)
			(xy 379.98878 -397.920774) (xy 379.97393 -397.966434) (xy 379.952116 -398.009208) (xy 379.923877 -398.048041)
			(xy 379.889908 -398.081976) (xy 379.851047 -398.110176) (xy 379.808251 -398.131947) (xy 379.762576 -398.146752)
			(xy 379.715146 -398.154225) (xy 379.691138 -398.154652) (xy 379.667566 -398.1542) (xy 379.620982 -398.146966)
			(xy 379.576066 -398.132648) (xy 379.533889 -398.111589) (xy 379.495456 -398.084289) (xy 379.461681 -398.051399)
			(xy 379.433371 -398.013703) (xy 379.421898 -397.993108) (xy 379.42139 -397.992346) (xy 379.023626 -397.304006)
			(xy 379.011747 -397.28133) (xy 378.994898 -397.232996) (xy 378.986326 -397.182533) (xy 378.98578 -397.15694)
			(xy 378.443786 -397.15694) (xy 378.75591 -397.696944) (xy 378.768714 -397.720287) (xy 378.786943 -397.770304)
			(xy 378.796211 -397.822727) (xy 378.796804 -397.849344) (xy 378.796401 -397.873351) (xy 378.78888 -397.920773)
			(xy 378.77403 -397.966433) (xy 378.752217 -398.009207) (xy 378.723978 -398.04804) (xy 378.69001 -398.081974)
			(xy 378.651149 -398.110175) (xy 378.608354 -398.131946) (xy 378.562679 -398.146751) (xy 378.51525 -398.154225)
			(xy 378.491242 -398.154652) (xy 378.467671 -398.154197) (xy 378.421086 -398.146963) (xy 378.376171 -398.132646)
			(xy 378.333993 -398.111587) (xy 378.29556 -398.084288) (xy 378.261786 -398.051398) (xy 378.233476 -398.013703)
			(xy 378.222002 -397.993108) (xy 378.221494 -397.992346) (xy 377.82373 -397.304006) (xy 377.811852 -397.28133)
			(xy 377.795002 -397.232996) (xy 377.78643 -397.182533) (xy 377.785884 -397.15694) (xy 377.24389 -397.15694)
			(xy 377.556014 -397.696944) (xy 377.568818 -397.720287) (xy 377.587047 -397.770304) (xy 377.596315 -397.822727)
			(xy 377.596908 -397.849344) (xy 377.596501 -397.873351) (xy 377.58898 -397.920772) (xy 377.57413 -397.966432)
			(xy 377.552317 -398.009206) (xy 377.524079 -398.048038) (xy 377.490111 -398.081973) (xy 377.451251 -398.110173)
			(xy 377.408457 -398.131944) (xy 377.362782 -398.14675) (xy 377.315353 -398.154225) (xy 377.291346 -398.154652)
			(xy 377.267775 -398.154194) (xy 377.221191 -398.146961) (xy 377.176275 -398.132644) (xy 377.134098 -398.111586)
			(xy 377.095664 -398.084287) (xy 377.06189 -398.051398) (xy 377.03358 -398.013703) (xy 377.022106 -397.993108)
			(xy 377.021598 -397.992346) (xy 376.623834 -397.304006) (xy 376.611956 -397.28133) (xy 376.595106 -397.232996)
			(xy 376.586534 -397.182533) (xy 376.585988 -397.15694) (xy 376.04374 -397.15694) (xy 376.355864 -397.696944)
			(xy 376.368602 -397.720307) (xy 376.386714 -397.770336) (xy 376.395922 -397.822741) (xy 376.396504 -397.849344)
			(xy 376.396078 -397.873337) (xy 376.388565 -397.92073) (xy 376.373731 -397.966365) (xy 376.351942 -398.009118)
			(xy 376.323733 -398.047937) (xy 376.2898 -398.081865) (xy 376.250977 -398.110067) (xy 376.208221 -398.13185)
			(xy 376.162583 -398.146676) (xy 376.115189 -398.154182) (xy 376.091196 -398.154652) (xy 376.067623 -398.154234)
			(xy 376.021037 -398.146993) (xy 375.976121 -398.13267) (xy 375.933944 -398.111605) (xy 375.89551 -398.084299)
			(xy 375.861737 -398.051405) (xy 375.833429 -398.013705) (xy 375.821956 -397.993108) (xy 375.821448 -397.992346)
			(xy 375.423684 -397.304006) (xy 375.411767 -397.281338) (xy 375.394831 -397.233013) (xy 375.386171 -397.182542)
			(xy 375.385584 -397.15694) (xy 374.843844 -397.15694) (xy 375.155968 -397.696944) (xy 375.168706 -397.720307)
			(xy 375.186818 -397.770336) (xy 375.196026 -397.822741) (xy 375.196608 -397.849344) (xy 375.196178 -397.873336)
			(xy 375.188665 -397.92073) (xy 375.173832 -397.966364) (xy 375.152043 -398.009117) (xy 375.123835 -398.047935)
			(xy 375.089902 -398.081863) (xy 375.051079 -398.110066) (xy 375.008324 -398.131849) (xy 374.962687 -398.146676)
			(xy 374.915292 -398.154181) (xy 374.8913 -398.154652) (xy 374.867727 -398.154231) (xy 374.821142 -398.146991)
			(xy 374.776225 -398.132668) (xy 374.734048 -398.111603) (xy 374.695615 -398.084298) (xy 374.661842 -398.051404)
			(xy 374.633533 -398.013705) (xy 374.62206 -397.993108) (xy 374.621552 -397.992346) (xy 374.223788 -397.304006)
			(xy 374.211872 -397.281338) (xy 374.194935 -397.233013) (xy 374.186275 -397.182542) (xy 374.185688 -397.15694)
			(xy 373.643694 -397.15694) (xy 373.955818 -397.696944) (xy 373.968623 -397.720287) (xy 373.986851 -397.770304)
			(xy 373.996119 -397.822727) (xy 373.996712 -397.849344) (xy 373.996302 -397.873351) (xy 373.98878 -397.920772)
			(xy 373.973931 -397.966432) (xy 373.952118 -398.009205) (xy 373.92388 -398.048037) (xy 373.889913 -398.081971)
			(xy 373.851053 -398.110172) (xy 373.808259 -398.131943) (xy 373.762586 -398.146749) (xy 373.715157 -398.154225)
			(xy 373.69115 -398.154652) (xy 373.667579 -398.154191) (xy 373.620995 -398.146958) (xy 373.576079 -398.132642)
			(xy 373.533902 -398.111584) (xy 373.495468 -398.084286) (xy 373.461694 -398.051397) (xy 373.433384 -398.013703)
			(xy 373.42191 -397.993108) (xy 373.421402 -397.992346) (xy 373.023638 -397.304006) (xy 373.01176 -397.28133)
			(xy 372.994911 -397.232996) (xy 372.986338 -397.182533) (xy 372.985792 -397.15694) (xy 372.443798 -397.15694)
			(xy 372.755922 -397.696944) (xy 372.768727 -397.720287) (xy 372.786955 -397.770304) (xy 372.796223 -397.822727)
			(xy 372.796816 -397.849344) (xy 372.796402 -397.873351) (xy 372.788881 -397.920771) (xy 372.774031 -397.966431)
			(xy 372.752219 -398.009203) (xy 372.723981 -398.048036) (xy 372.690015 -398.08197) (xy 372.651156 -398.110171)
			(xy 372.608362 -398.131942) (xy 372.562689 -398.146748) (xy 372.515261 -398.154224) (xy 372.491254 -398.154652)
			(xy 372.467683 -398.154187) (xy 372.421099 -398.146955) (xy 372.376184 -398.13264) (xy 372.334006 -398.111583)
			(xy 372.295573 -398.084285) (xy 372.261798 -398.051397) (xy 372.233488 -398.013702) (xy 372.222014 -397.993108)
			(xy 372.221506 -397.992346) (xy 371.823742 -397.304006) (xy 371.811865 -397.28133) (xy 371.795015 -397.232996)
			(xy 371.786442 -397.182533) (xy 371.785896 -397.15694) (xy 371.243902 -397.15694) (xy 371.556026 -397.696944)
			(xy 371.568831 -397.720286) (xy 371.587059 -397.770304) (xy 371.596327 -397.822727) (xy 371.59692 -397.849344)
			(xy 371.596502 -397.87335) (xy 371.588981 -397.920771) (xy 371.574131 -397.96643) (xy 371.552319 -398.009202)
			(xy 371.524082 -398.048034) (xy 371.490116 -398.081969) (xy 371.451258 -398.110169) (xy 371.408465 -398.131941)
			(xy 371.362792 -398.146748) (xy 371.315365 -398.154224) (xy 371.291358 -398.154652) (xy 371.267787 -398.154184)
			(xy 371.221204 -398.146953) (xy 371.176288 -398.132638) (xy 371.134111 -398.111581) (xy 371.095677 -398.084284)
			(xy 371.061902 -398.051396) (xy 371.033592 -398.013702) (xy 371.022118 -397.993108) (xy 371.02161 -397.992346)
			(xy 370.623846 -397.304006) (xy 370.611969 -397.28133) (xy 370.595119 -397.232996) (xy 370.586546 -397.182533)
			(xy 370.586 -397.15694) (xy 354.671418 -397.15694) (xy 354.983542 -397.696944) (xy 354.996349 -397.720286)
			(xy 355.014576 -397.770304) (xy 355.023843 -397.822727) (xy 355.024436 -397.849344) (xy 355.024002 -397.87335)
			(xy 355.016481 -397.920768) (xy 355.001633 -397.966426) (xy 354.979822 -398.009197) (xy 354.951587 -398.048029)
			(xy 354.917623 -398.081963) (xy 354.878767 -398.110164) (xy 354.835976 -398.131936) (xy 354.790305 -398.146744)
			(xy 354.74288 -398.154223) (xy 354.718874 -398.154652) (xy 354.695301 -398.154252) (xy 354.648714 -398.147008)
			(xy 354.603797 -398.132681) (xy 354.56162 -398.111613) (xy 354.523187 -398.084305) (xy 354.489414 -398.051408)
			(xy 354.461106 -398.013706) (xy 354.449634 -397.993108) (xy 354.449126 -397.992346) (xy 354.051362 -397.304006)
			(xy 354.039486 -397.281329) (xy 354.022635 -397.232996) (xy 354.014062 -397.182533) (xy 354.013516 -397.15694)
			(xy 353.471268 -397.15694) (xy 353.783392 -397.696944) (xy 353.796124 -397.72031) (xy 353.81424 -397.770338)
			(xy 353.82345 -397.822741) (xy 353.824032 -397.849344) (xy 353.823578 -397.873335) (xy 353.816066 -397.920726)
			(xy 353.801234 -397.966359) (xy 353.779447 -398.00911) (xy 353.751242 -398.047927) (xy 353.717312 -398.081855)
			(xy 353.678493 -398.110058) (xy 353.63574 -398.131842) (xy 353.590107 -398.146671) (xy 353.542715 -398.15418)
			(xy 353.518724 -398.154652) (xy 353.495152 -398.154211) (xy 353.448567 -398.146975) (xy 353.403651 -398.132656)
			(xy 353.361474 -398.111594) (xy 353.323041 -398.084292) (xy 353.289267 -398.051401) (xy 353.260957 -398.013704)
			(xy 353.249484 -397.993108) (xy 353.248976 -397.992346) (xy 352.851212 -397.304006) (xy 352.839298 -397.281337)
			(xy 352.82236 -397.233012) (xy 352.8137 -397.182542) (xy 352.813112 -397.15694) (xy 352.271372 -397.15694)
			(xy 352.583496 -397.696944) (xy 352.596228 -397.72031) (xy 352.614344 -397.770338) (xy 352.623554 -397.822741)
			(xy 352.624136 -397.849344) (xy 352.623678 -397.873335) (xy 352.616166 -397.920726) (xy 352.601335 -397.966358)
			(xy 352.579548 -398.009109) (xy 352.551343 -398.047926) (xy 352.517413 -398.081853) (xy 352.478595 -398.110056)
			(xy 352.435843 -398.131841) (xy 352.39021 -398.14667) (xy 352.342819 -398.154179) (xy 352.318828 -398.154652)
			(xy 352.295256 -398.154208) (xy 352.248672 -398.146972) (xy 352.203756 -398.132653) (xy 352.161578 -398.111592)
			(xy 352.123145 -398.084291) (xy 352.089371 -398.0514) (xy 352.061061 -398.013704) (xy 352.049588 -397.993108)
			(xy 352.04908 -397.992346) (xy 351.651316 -397.304006) (xy 351.639402 -397.281337) (xy 351.622464 -397.233012)
			(xy 351.613804 -397.182542) (xy 351.613216 -397.15694) (xy 351.071222 -397.15694) (xy 351.383346 -397.696944)
			(xy 351.396153 -397.720286) (xy 351.41438 -397.770304) (xy 351.423647 -397.822727) (xy 351.42424 -397.849344)
			(xy 351.423802 -397.873349) (xy 351.416281 -397.920768) (xy 351.401433 -397.966425) (xy 351.379623 -398.009196)
			(xy 351.351388 -398.048027) (xy 351.317425 -398.081961) (xy 351.278569 -398.110162) (xy 351.235779 -398.131935)
			(xy 351.190109 -398.146744) (xy 351.142684 -398.154222) (xy 351.118678 -398.154652) (xy 351.095105 -398.154249)
			(xy 351.048518 -398.147005) (xy 351.003601 -398.132679) (xy 350.961424 -398.111611) (xy 350.922991 -398.084304)
			(xy 350.889218 -398.051408) (xy 350.86091 -398.013706) (xy 350.849438 -397.993108) (xy 350.84893 -397.992346)
			(xy 350.451166 -397.304006) (xy 350.439291 -397.281329) (xy 350.422439 -397.232996) (xy 350.413866 -397.182533)
			(xy 350.41332 -397.15694) (xy 349.871326 -397.15694) (xy 350.18345 -397.696944) (xy 350.196257 -397.720285)
			(xy 350.214484 -397.770304) (xy 350.223751 -397.822726) (xy 350.224344 -397.849344) (xy 350.223902 -397.873349)
			(xy 350.216382 -397.920767) (xy 350.201534 -397.966424) (xy 350.179724 -398.009195) (xy 350.15149 -398.048026)
			(xy 350.117526 -398.08196) (xy 350.078671 -398.110161) (xy 350.035882 -398.131934) (xy 349.990212 -398.146743)
			(xy 349.942788 -398.154222) (xy 349.918782 -398.154652) (xy 349.895209 -398.154245) (xy 349.848622 -398.147003)
			(xy 349.803706 -398.132677) (xy 349.761528 -398.11161) (xy 349.723095 -398.084303) (xy 349.689323 -398.051407)
			(xy 349.661014 -398.013706) (xy 349.649542 -397.993108) (xy 349.649034 -397.992346) (xy 349.25127 -397.304006)
			(xy 349.239395 -397.281329) (xy 349.222543 -397.232996) (xy 349.21397 -397.182533) (xy 349.213424 -397.15694)
			(xy 348.67143 -397.15694) (xy 348.983554 -397.696944) (xy 348.996362 -397.720285) (xy 349.014588 -397.770304)
			(xy 349.023855 -397.822726) (xy 349.024448 -397.849344) (xy 349.024002 -397.873349) (xy 349.016482 -397.920767)
			(xy 349.001634 -397.966423) (xy 348.979825 -398.009194) (xy 348.951591 -398.048025) (xy 348.917628 -398.081959)
			(xy 348.878773 -398.11016) (xy 348.835984 -398.131933) (xy 348.790315 -398.146742) (xy 348.742891 -398.154222)
			(xy 348.718886 -398.154652) (xy 348.695313 -398.154242) (xy 348.648727 -398.147) (xy 348.60381 -398.132675)
			(xy 348.561633 -398.111608) (xy 348.5232 -398.084302) (xy 348.489427 -398.051406) (xy 348.461119 -398.013705)
			(xy 348.449646 -397.993108) (xy 348.449138 -397.992346) (xy 348.051374 -397.304006) (xy 348.039499 -397.281329)
			(xy 348.022648 -397.232996) (xy 348.014074 -397.182533) (xy 348.013528 -397.15694) (xy 347.47128 -397.15694)
			(xy 347.783404 -397.696944) (xy 347.796137 -397.72031) (xy 347.814252 -397.770337) (xy 347.823462 -397.822741)
			(xy 347.824044 -397.849344) (xy 347.823578 -397.873335) (xy 347.816067 -397.920724) (xy 347.801235 -397.966356)
			(xy 347.779449 -398.009106) (xy 347.751245 -398.047923) (xy 347.717317 -398.08185) (xy 347.678499 -398.110054)
			(xy 347.635749 -398.131838) (xy 347.590117 -398.146668) (xy 347.542727 -398.154179) (xy 347.518736 -398.154652)
			(xy 347.495164 -398.154202) (xy 347.44858 -398.146967) (xy 347.403664 -398.132649) (xy 347.361487 -398.111589)
			(xy 347.323053 -398.084289) (xy 347.289279 -398.051399) (xy 347.260969 -398.013703) (xy 347.249496 -397.993108)
			(xy 347.248988 -397.992346) (xy 346.851224 -397.304006) (xy 346.839311 -397.281337) (xy 346.822372 -397.233012)
			(xy 346.813712 -397.182542) (xy 346.813124 -397.15694) (xy 346.271384 -397.15694) (xy 346.583508 -397.696944)
			(xy 346.596241 -397.72031) (xy 346.614356 -397.770337) (xy 346.623566 -397.822741) (xy 346.624148 -397.849344)
			(xy 346.623678 -397.873334) (xy 346.616167 -397.920724) (xy 346.601336 -397.966355) (xy 346.57955 -398.009105)
			(xy 346.551346 -398.047922) (xy 346.517418 -398.081849) (xy 346.478602 -398.110052) (xy 346.435851 -398.131837)
			(xy 346.39022 -398.146668) (xy 346.34283 -398.154178) (xy 346.31884 -398.154652) (xy 346.295269 -398.154199)
			(xy 346.248684 -398.146965) (xy 346.203769 -398.132647) (xy 346.161591 -398.111588) (xy 346.123158 -398.084288)
			(xy 346.089383 -398.051399) (xy 346.061073 -398.013703) (xy 346.0496 -397.993108) (xy 346.049092 -397.992346)
			(xy 345.651328 -397.304006) (xy 345.639415 -397.281337) (xy 345.622476 -397.233012) (xy 345.613816 -397.182542)
			(xy 345.613228 -397.15694) (xy 345.071234 -397.15694) (xy 345.383358 -397.696944) (xy 345.396166 -397.720285)
			(xy 345.414392 -397.770304) (xy 345.423659 -397.822726) (xy 345.424252 -397.849344) (xy 345.423802 -397.873349)
			(xy 345.416282 -397.920766) (xy 345.401434 -397.966422) (xy 345.379625 -398.009193) (xy 345.351392 -398.048023)
			(xy 345.31743 -398.081957) (xy 345.278576 -398.110158) (xy 345.235787 -398.131932) (xy 345.190119 -398.146741)
			(xy 345.142695 -398.154222) (xy 345.11869 -398.154652) (xy 345.095117 -398.154239) (xy 345.048531 -398.146997)
			(xy 345.003614 -398.132673) (xy 344.961437 -398.111607) (xy 344.923004 -398.084301) (xy 344.889231 -398.051406)
			(xy 344.860923 -398.013705) (xy 344.84945 -397.993108) (xy 344.848942 -397.992346) (xy 344.451178 -397.304006)
			(xy 344.439303 -397.281328) (xy 344.422452 -397.232996) (xy 344.413878 -397.182533) (xy 344.413332 -397.15694)
			(xy 343.871338 -397.15694) (xy 344.183462 -397.696944) (xy 344.19627 -397.720285) (xy 344.214496 -397.770304)
			(xy 344.223763 -397.822726) (xy 344.224356 -397.849344) (xy 344.223902 -397.873349) (xy 344.216382 -397.920765)
			(xy 344.201535 -397.966421) (xy 344.179726 -398.009191) (xy 344.151493 -398.048022) (xy 344.117531 -398.081956)
			(xy 344.078678 -398.110157) (xy 344.03589 -398.131931) (xy 343.990222 -398.14674) (xy 343.942799 -398.154221)
			(xy 343.918794 -398.154652) (xy 343.895221 -398.154236) (xy 343.848635 -398.146995) (xy 343.803719 -398.132671)
			(xy 343.761541 -398.111605) (xy 343.723108 -398.0843) (xy 343.689335 -398.051405) (xy 343.661027 -398.013705)
			(xy 343.649554 -397.993108) (xy 343.649046 -397.992346) (xy 343.251282 -397.304006) (xy 343.239408 -397.281328)
			(xy 343.222556 -397.232996) (xy 343.213982 -397.182533) (xy 343.213436 -397.15694) (xy 342.671442 -397.15694)
			(xy 342.983566 -397.696944) (xy 342.996375 -397.720285) (xy 343.0146 -397.770303) (xy 343.023867 -397.822726)
			(xy 343.02446 -397.849344) (xy 343.024101 -397.873353) (xy 343.016579 -397.92078) (xy 343.001726 -397.966444)
			(xy 342.979909 -398.00922) (xy 342.951665 -398.048055) (xy 342.917691 -398.08199) (xy 342.878825 -398.11019)
			(xy 342.836023 -398.131958) (xy 342.790342 -398.146759) (xy 342.742908 -398.154228) (xy 342.718898 -398.154652)
			(xy 342.695325 -398.154232) (xy 342.64874 -398.146992) (xy 342.603823 -398.132669) (xy 342.561646 -398.111604)
			(xy 342.523213 -398.084299) (xy 342.489439 -398.051405) (xy 342.461131 -398.013705) (xy 342.449658 -397.993108)
			(xy 342.44915 -397.992346) (xy 342.051386 -397.304006) (xy 342.039512 -397.281328) (xy 342.02266 -397.232996)
			(xy 342.014086 -397.182533) (xy 342.01354 -397.15694) (xy 341.471292 -397.15694) (xy 341.783416 -397.696944)
			(xy 341.79615 -397.720309) (xy 341.814265 -397.770337) (xy 341.823474 -397.822741) (xy 341.824056 -397.849344)
			(xy 341.823578 -397.873334) (xy 341.816067 -397.920723) (xy 341.801236 -397.966353) (xy 341.779452 -398.009103)
			(xy 341.751249 -398.047919) (xy 341.717322 -398.081846) (xy 341.678506 -398.11005) (xy 341.635757 -398.131835)
			(xy 341.590127 -398.146666) (xy 341.542738 -398.154178) (xy 341.518748 -398.154652) (xy 341.495177 -398.154192)
			(xy 341.448593 -398.146959) (xy 341.403677 -398.132643) (xy 341.3615 -398.111585) (xy 341.323066 -398.084286)
			(xy 341.289292 -398.051398) (xy 341.260982 -398.013703) (xy 341.249508 -397.993108) (xy 341.249 -397.992346)
			(xy 340.851236 -397.304006) (xy 340.839323 -397.281336) (xy 340.822384 -397.233012) (xy 340.813724 -397.182542)
			(xy 340.813136 -397.15694) (xy 340.271396 -397.15694) (xy 340.58352 -397.696944) (xy 340.596254 -397.720309)
			(xy 340.614369 -397.770337) (xy 340.623578 -397.822741) (xy 340.62416 -397.849344) (xy 340.623802 -397.873341)
			(xy 340.616287 -397.920742) (xy 340.60145 -397.966385) (xy 340.579655 -398.009144) (xy 340.551439 -398.047968)
			(xy 340.517498 -398.081899) (xy 340.478666 -398.110103) (xy 340.4359 -398.131885) (xy 340.390253 -398.146709)
			(xy 340.342849 -398.154209) (xy 340.318852 -398.154652) (xy 340.295281 -398.154189) (xy 340.248697 -398.146957)
			(xy 340.203782 -398.132641) (xy 340.161604 -398.111583) (xy 340.123171 -398.084285) (xy 340.089396 -398.051397)
			(xy 340.061086 -398.013703) (xy 340.049612 -397.993108) (xy 340.049104 -397.992346) (xy 339.65134 -397.304006)
			(xy 339.639428 -397.281336) (xy 339.622488 -397.233012) (xy 339.613828 -397.182542) (xy 339.61324 -397.15694)
			(xy 339.071246 -397.15694) (xy 339.38337 -397.696944) (xy 339.396179 -397.720285) (xy 339.414404 -397.770303)
			(xy 339.423671 -397.822726) (xy 339.424264 -397.849344) (xy 339.423901 -397.873353) (xy 339.416379 -397.920779)
			(xy 339.401526 -397.966443) (xy 339.379709 -398.009219) (xy 339.351466 -398.048053) (xy 339.317493 -398.081989)
			(xy 339.278627 -398.110188) (xy 339.235826 -398.131957) (xy 339.190146 -398.146759) (xy 339.142712 -398.154228)
			(xy 339.118702 -398.154652) (xy 339.095129 -398.154229) (xy 339.048544 -398.14699) (xy 339.003627 -398.132667)
			(xy 338.96145 -398.111602) (xy 338.923017 -398.084298) (xy 338.889244 -398.051404) (xy 338.860935 -398.013705)
			(xy 338.849462 -397.993108) (xy 338.848954 -397.992346) (xy 338.45119 -397.304006) (xy 338.439316 -397.281328)
			(xy 338.422464 -397.232995) (xy 338.41389 -397.182533) (xy 338.413344 -397.15694) (xy 337.87135 -397.15694)
			(xy 338.183474 -397.696944) (xy 338.196283 -397.720284) (xy 338.214508 -397.770303) (xy 338.223775 -397.822726)
			(xy 338.224368 -397.849344) (xy 338.224001 -397.873353) (xy 338.216479 -397.920778) (xy 338.201626 -397.966442)
			(xy 338.17981 -398.009218) (xy 338.151567 -398.048052) (xy 338.117595 -398.081987) (xy 338.078729 -398.110187)
			(xy 338.035929 -398.131956) (xy 337.990249 -398.146758) (xy 337.942816 -398.154228) (xy 337.918806 -398.154652)
			(xy 337.895234 -398.154226) (xy 337.848648 -398.146987) (xy 337.803732 -398.132665) (xy 337.761554 -398.111601)
			(xy 337.723121 -398.084297) (xy 337.689348 -398.051404) (xy 337.661039 -398.013705) (xy 337.649566 -397.993108)
			(xy 337.649058 -397.992346) (xy 337.251294 -397.304006) (xy 337.239421 -397.281328) (xy 337.222568 -397.232995)
			(xy 337.213994 -397.182532) (xy 337.213448 -397.15694) (xy 336.671454 -397.15694) (xy 336.983578 -397.696944)
			(xy 336.996388 -397.720284) (xy 337.014613 -397.770303) (xy 337.023879 -397.822726) (xy 337.024472 -397.849344)
			(xy 337.024101 -397.873353) (xy 337.016579 -397.920778) (xy 337.001727 -397.966441) (xy 336.979911 -398.009217)
			(xy 336.951668 -398.048051) (xy 336.917696 -398.081986) (xy 336.878831 -398.110185) (xy 336.836032 -398.131955)
			(xy 336.790352 -398.146757) (xy 336.742919 -398.154228) (xy 336.71891 -398.154652) (xy 336.695338 -398.154223)
			(xy 336.648752 -398.146984) (xy 336.603836 -398.132663) (xy 336.561659 -398.111599) (xy 336.523225 -398.084296)
			(xy 336.489452 -398.051403) (xy 336.461143 -398.013704) (xy 336.44967 -397.993108) (xy 336.449162 -397.992346)
			(xy 336.051398 -397.304006) (xy 336.039525 -397.281328) (xy 336.022672 -397.232995) (xy 336.014098 -397.182532)
			(xy 336.013552 -397.15694) (xy 322.14367 -397.15694) (xy 322.455794 -397.696944) (xy 322.468605 -397.720283)
			(xy 322.486829 -397.770303) (xy 322.496095 -397.822726) (xy 322.496688 -397.849344) (xy 322.496301 -397.873352)
			(xy 322.48878 -397.920775) (xy 322.473928 -397.966437) (xy 322.452114 -398.009212) (xy 322.423873 -398.048045)
			(xy 322.389903 -398.08198) (xy 322.35104 -398.11018) (xy 322.308243 -398.13195) (xy 322.262566 -398.146754)
			(xy 322.215134 -398.154226) (xy 322.191126 -398.154652) (xy 322.167554 -398.15421) (xy 322.120969 -398.146974)
			(xy 322.076053 -398.132654) (xy 322.033876 -398.111593) (xy 321.995443 -398.084292) (xy 321.961669 -398.051401)
			(xy 321.933359 -398.013704) (xy 321.921886 -397.993108) (xy 321.921378 -397.992346) (xy 321.523614 -397.304006)
			(xy 321.511735 -397.281331) (xy 321.494886 -397.232997) (xy 321.486314 -397.182533) (xy 321.485768 -397.15694)
			(xy 320.94352 -397.15694) (xy 321.255644 -397.696944) (xy 321.26838 -397.720308) (xy 321.286493 -397.770337)
			(xy 321.295702 -397.822741) (xy 321.296284 -397.849344) (xy 321.295878 -397.873338) (xy 321.288364 -397.920733)
			(xy 321.27353 -397.96637) (xy 321.251738 -398.009124) (xy 321.223528 -398.047943) (xy 321.189592 -398.081872)
			(xy 321.150766 -398.110074) (xy 321.108007 -398.131856) (xy 321.062367 -398.14668) (xy 321.01497 -398.154183)
			(xy 320.990976 -398.154652) (xy 320.967403 -398.15425) (xy 320.920816 -398.147007) (xy 320.875899 -398.13268)
			(xy 320.833722 -398.111612) (xy 320.795289 -398.084305) (xy 320.761516 -398.051408) (xy 320.733208 -398.013706)
			(xy 320.721736 -397.993108) (xy 320.721228 -397.992346) (xy 320.323464 -397.304006) (xy 320.311554 -397.281335)
			(xy 320.294614 -397.233011) (xy 320.285952 -397.182542) (xy 320.285364 -397.15694) (xy 319.743624 -397.15694)
			(xy 320.055748 -397.696944) (xy 320.068484 -397.720308) (xy 320.086597 -397.770337) (xy 320.095806 -397.822741)
			(xy 320.096388 -397.849344) (xy 320.095978 -397.873337) (xy 320.088465 -397.920733) (xy 320.07363 -397.966369)
			(xy 320.051839 -398.009123) (xy 320.023629 -398.047942) (xy 319.989693 -398.08187) (xy 319.950868 -398.110073)
			(xy 319.90811 -398.131854) (xy 319.86247 -398.14668) (xy 319.815074 -398.154183) (xy 319.79108 -398.154652)
			(xy 319.767507 -398.154247) (xy 319.72092 -398.147004) (xy 319.676003 -398.132678) (xy 319.633826 -398.111611)
			(xy 319.595393 -398.084304) (xy 319.561621 -398.051407) (xy 319.533312 -398.013706) (xy 319.52184 -397.993108)
			(xy 319.521332 -397.992346) (xy 319.123568 -397.304006) (xy 319.111658 -397.281335) (xy 319.094718 -397.233011)
			(xy 319.086056 -397.182542) (xy 319.085468 -397.15694) (xy 318.543474 -397.15694) (xy 318.855598 -397.696944)
			(xy 318.868401 -397.720288) (xy 318.88663 -397.770305) (xy 318.895899 -397.822727) (xy 318.896492 -397.849344)
			(xy 318.896101 -397.873352) (xy 318.88858 -397.920775) (xy 318.873729 -397.966436) (xy 318.851914 -398.009211)
			(xy 318.823674 -398.048044) (xy 318.789705 -398.081979) (xy 318.750842 -398.110179) (xy 318.708046 -398.131949)
			(xy 318.662369 -398.146753) (xy 318.614938 -398.154226) (xy 318.59093 -398.154652) (xy 318.567358 -398.154207)
			(xy 318.520774 -398.146971) (xy 318.475858 -398.132652) (xy 318.43368 -398.111592) (xy 318.395247 -398.084291)
			(xy 318.361473 -398.0514) (xy 318.333163 -398.013704) (xy 318.32169 -397.993108) (xy 318.321182 -397.992346)
			(xy 317.923418 -397.304006) (xy 317.911539 -397.281331) (xy 317.89469 -397.232997) (xy 317.886118 -397.182533)
			(xy 317.885572 -397.15694) (xy 317.343578 -397.15694) (xy 317.655702 -397.696944) (xy 317.668505 -397.720288)
			(xy 317.686734 -397.770305) (xy 317.696003 -397.822727) (xy 317.696596 -397.849344) (xy 317.696201 -397.873352)
			(xy 317.68868 -397.920774) (xy 317.673829 -397.966435) (xy 317.652015 -398.009209) (xy 317.623775 -398.048042)
			(xy 317.589806 -398.081977) (xy 317.550945 -398.110177) (xy 317.508148 -398.131948) (xy 317.462472 -398.146752)
			(xy 317.415042 -398.154226) (xy 317.391034 -398.154652) (xy 317.367462 -398.154203) (xy 317.320878 -398.146969)
			(xy 317.275962 -398.13265) (xy 317.233785 -398.11159) (xy 317.195351 -398.08429) (xy 317.161577 -398.0514)
			(xy 317.133267 -398.013703) (xy 317.121794 -397.993108) (xy 317.121286 -397.992346) (xy 316.723522 -397.304006)
			(xy 316.711643 -397.281331) (xy 316.694794 -397.232996) (xy 316.686222 -397.182533) (xy 316.685676 -397.15694)
			(xy 316.143682 -397.15694) (xy 316.455806 -397.696944) (xy 316.46861 -397.720287) (xy 316.486838 -397.770304)
			(xy 316.496107 -397.822727) (xy 316.4967 -397.849344) (xy 316.496301 -397.873351) (xy 316.48878 -397.920774)
			(xy 316.47393 -397.966434) (xy 316.452116 -398.009208) (xy 316.423877 -398.048041) (xy 316.389908 -398.081976)
			(xy 316.351047 -398.110176) (xy 316.308251 -398.131947) (xy 316.262576 -398.146752) (xy 316.215146 -398.154225)
			(xy 316.191138 -398.154652) (xy 316.167566 -398.1542) (xy 316.120982 -398.146966) (xy 316.076066 -398.132648)
			(xy 316.033889 -398.111589) (xy 315.995456 -398.084289) (xy 315.961681 -398.051399) (xy 315.933371 -398.013703)
			(xy 315.921898 -397.993108) (xy 315.92139 -397.992346) (xy 315.523626 -397.304006) (xy 315.511747 -397.28133)
			(xy 315.494898 -397.232996) (xy 315.486326 -397.182533) (xy 315.48578 -397.15694) (xy 314.943532 -397.15694)
			(xy 315.255656 -397.696944) (xy 315.268393 -397.720307) (xy 315.286506 -397.770337) (xy 315.295714 -397.822741)
			(xy 315.296296 -397.849344) (xy 315.295878 -397.873337) (xy 315.288365 -397.920731) (xy 315.273531 -397.966367)
			(xy 315.251741 -398.009121) (xy 315.223531 -398.047939) (xy 315.189597 -398.081868) (xy 315.150773 -398.11007)
			(xy 315.108015 -398.131852) (xy 315.062377 -398.146678) (xy 315.014981 -398.154182) (xy 314.990988 -398.154652)
			(xy 314.967415 -398.154241) (xy 314.920829 -398.146999) (xy 314.875912 -398.132674) (xy 314.833735 -398.111608)
			(xy 314.795302 -398.084301) (xy 314.761529 -398.051406) (xy 314.733221 -398.013705) (xy 314.721748 -397.993108)
			(xy 314.72124 -397.992346) (xy 314.323476 -397.304006) (xy 314.311559 -397.281339) (xy 314.294623 -397.233013)
			(xy 314.285963 -397.182542) (xy 314.285376 -397.15694) (xy 313.743636 -397.15694) (xy 314.05576 -397.696944)
			(xy 314.068497 -397.720307) (xy 314.08661 -397.770337) (xy 314.095818 -397.822741) (xy 314.0964 -397.849344)
			(xy 314.095978 -397.873337) (xy 314.088465 -397.920731) (xy 314.073631 -397.966366) (xy 314.051841 -398.009119)
			(xy 314.023632 -398.047938) (xy 313.989698 -398.081866) (xy 313.950875 -398.110069) (xy 313.908118 -398.131851)
			(xy 313.86248 -398.146677) (xy 313.815085 -398.154182) (xy 313.791092 -398.154652) (xy 313.767519 -398.154237)
			(xy 313.720933 -398.146996) (xy 313.676016 -398.132672) (xy 313.633839 -398.111606) (xy 313.595406 -398.0843)
			(xy 313.561633 -398.051406) (xy 313.533325 -398.013705) (xy 313.521852 -397.993108) (xy 313.521344 -397.992346)
			(xy 313.12358 -397.304006) (xy 313.111663 -397.281339) (xy 313.094727 -397.233013) (xy 313.086067 -397.182542)
			(xy 313.08548 -397.15694) (xy 312.543486 -397.15694) (xy 312.85561 -397.696944) (xy 312.868414 -397.720287)
			(xy 312.886643 -397.770304) (xy 312.895911 -397.822727) (xy 312.896504 -397.849344) (xy 312.896101 -397.873351)
			(xy 312.88858 -397.920773) (xy 312.87373 -397.966433) (xy 312.851917 -398.009207) (xy 312.823678 -398.04804)
			(xy 312.78971 -398.081974) (xy 312.750849 -398.110175) (xy 312.708054 -398.131946) (xy 312.662379 -398.146751)
			(xy 312.61495 -398.154225) (xy 312.590942 -398.154652) (xy 312.567371 -398.154197) (xy 312.520786 -398.146963)
			(xy 312.475871 -398.132646) (xy 312.433693 -398.111587) (xy 312.39526 -398.084288) (xy 312.361486 -398.051398)
			(xy 312.333176 -398.013703) (xy 312.321702 -397.993108) (xy 312.321194 -397.992346) (xy 311.92343 -397.304006)
			(xy 311.911552 -397.28133) (xy 311.894702 -397.232996) (xy 311.88613 -397.182533) (xy 311.885584 -397.15694)
			(xy 311.34359 -397.15694) (xy 311.655714 -397.696944) (xy 311.668518 -397.720287) (xy 311.686747 -397.770304)
			(xy 311.696015 -397.822727) (xy 311.696608 -397.849344) (xy 311.696201 -397.873351) (xy 311.68868 -397.920772)
			(xy 311.67383 -397.966432) (xy 311.652017 -398.009206) (xy 311.623779 -398.048038) (xy 311.589811 -398.081973)
			(xy 311.550951 -398.110173) (xy 311.508157 -398.131944) (xy 311.462482 -398.14675) (xy 311.415053 -398.154225)
			(xy 311.391046 -398.154652) (xy 311.367475 -398.154194) (xy 311.320891 -398.146961) (xy 311.275975 -398.132644)
			(xy 311.233798 -398.111586) (xy 311.195364 -398.084287) (xy 311.16159 -398.051398) (xy 311.13328 -398.013703)
			(xy 311.121806 -397.993108) (xy 311.121298 -397.992346) (xy 310.723534 -397.304006) (xy 310.711656 -397.28133)
			(xy 310.694806 -397.232996) (xy 310.686234 -397.182533) (xy 310.685688 -397.15694) (xy 310.143694 -397.15694)
			(xy 310.455818 -397.696944) (xy 310.468623 -397.720287) (xy 310.486851 -397.770304) (xy 310.496119 -397.822727)
			(xy 310.496712 -397.849344) (xy 310.496302 -397.873351) (xy 310.48878 -397.920772) (xy 310.473931 -397.966432)
			(xy 310.452118 -398.009205) (xy 310.42388 -398.048037) (xy 310.389913 -398.081971) (xy 310.351053 -398.110172)
			(xy 310.308259 -398.131943) (xy 310.262586 -398.146749) (xy 310.215157 -398.154225) (xy 310.19115 -398.154652)
			(xy 310.167579 -398.154191) (xy 310.120995 -398.146958) (xy 310.076079 -398.132642) (xy 310.033902 -398.111584)
			(xy 309.995468 -398.084286) (xy 309.961694 -398.051397) (xy 309.933384 -398.013703) (xy 309.92191 -397.993108)
			(xy 309.921402 -397.992346) (xy 309.523638 -397.304006) (xy 309.51176 -397.28133) (xy 309.494911 -397.232996)
			(xy 309.486338 -397.182533) (xy 309.485792 -397.15694) (xy 308.943544 -397.15694) (xy 309.255668 -397.696944)
			(xy 309.268406 -397.720307) (xy 309.286518 -397.770336) (xy 309.295726 -397.822741) (xy 309.296308 -397.849344)
			(xy 309.295878 -397.873336) (xy 309.288365 -397.92073) (xy 309.273532 -397.966364) (xy 309.251743 -398.009117)
			(xy 309.223535 -398.047935) (xy 309.189602 -398.081863) (xy 309.150779 -398.110066) (xy 309.108024 -398.131849)
			(xy 309.062387 -398.146676) (xy 309.014992 -398.154181) (xy 308.991 -398.154652) (xy 308.967427 -398.154231)
			(xy 308.920842 -398.146991) (xy 308.875925 -398.132668) (xy 308.833748 -398.111603) (xy 308.795315 -398.084298)
			(xy 308.761542 -398.051404) (xy 308.733233 -398.013705) (xy 308.72176 -397.993108) (xy 308.721252 -397.992346)
			(xy 308.323488 -397.304006) (xy 308.311572 -397.281338) (xy 308.294635 -397.233013) (xy 308.285975 -397.182542)
			(xy 308.285388 -397.15694) (xy 307.743648 -397.15694) (xy 308.055772 -397.696944) (xy 308.06851 -397.720307)
			(xy 308.086622 -397.770336) (xy 308.09583 -397.822741) (xy 308.096412 -397.849344) (xy 308.095978 -397.873336)
			(xy 308.088465 -397.920729) (xy 308.073632 -397.966363) (xy 308.051844 -398.009116) (xy 308.023636 -398.047934)
			(xy 307.989703 -398.081862) (xy 307.950882 -398.110065) (xy 307.908126 -398.131848) (xy 307.86249 -398.146675)
			(xy 307.815096 -398.154181) (xy 307.791104 -398.154652) (xy 307.767532 -398.154228) (xy 307.720946 -398.146988)
			(xy 307.676029 -398.132666) (xy 307.633852 -398.111602) (xy 307.595419 -398.084297) (xy 307.561646 -398.051404)
			(xy 307.533337 -398.013705) (xy 307.521864 -397.993108) (xy 307.521356 -397.992346) (xy 307.123592 -397.304006)
			(xy 307.111676 -397.281338) (xy 307.094739 -397.233012) (xy 307.086079 -397.182542) (xy 307.085492 -397.15694)
			(xy 306.543498 -397.15694) (xy 306.855622 -397.696944) (xy 306.868427 -397.720287) (xy 306.886655 -397.770304)
			(xy 306.895923 -397.822727) (xy 306.896516 -397.849344) (xy 306.896102 -397.873351) (xy 306.888581 -397.920771)
			(xy 306.873731 -397.966431) (xy 306.851919 -398.009203) (xy 306.823681 -398.048036) (xy 306.789715 -398.08197)
			(xy 306.750856 -398.110171) (xy 306.708062 -398.131942) (xy 306.662389 -398.146748) (xy 306.614961 -398.154224)
			(xy 306.590954 -398.154652) (xy 306.567383 -398.154187) (xy 306.520799 -398.146955) (xy 306.475884 -398.13264)
			(xy 306.433706 -398.111583) (xy 306.395273 -398.084285) (xy 306.361498 -398.051397) (xy 306.333188 -398.013702)
			(xy 306.321714 -397.993108) (xy 306.321206 -397.992346) (xy 305.923442 -397.304006) (xy 305.911565 -397.28133)
			(xy 305.894715 -397.232996) (xy 305.886142 -397.182533) (xy 305.885596 -397.15694) (xy 305.343602 -397.15694)
			(xy 305.655726 -397.696944) (xy 305.668531 -397.720286) (xy 305.686759 -397.770304) (xy 305.696027 -397.822727)
			(xy 305.69662 -397.849344) (xy 305.696202 -397.87335) (xy 305.688681 -397.920771) (xy 305.673831 -397.96643)
			(xy 305.652019 -398.009202) (xy 305.623782 -398.048034) (xy 305.589816 -398.081969) (xy 305.550958 -398.110169)
			(xy 305.508165 -398.131941) (xy 305.462492 -398.146748) (xy 305.415065 -398.154224) (xy 305.391058 -398.154652)
			(xy 305.367487 -398.154184) (xy 305.320904 -398.146953) (xy 305.275988 -398.132638) (xy 305.233811 -398.111581)
			(xy 305.195377 -398.084284) (xy 305.161602 -398.051396) (xy 305.133292 -398.013702) (xy 305.121818 -397.993108)
			(xy 305.12131 -397.992346) (xy 304.723546 -397.304006) (xy 304.711669 -397.28133) (xy 304.694819 -397.232996)
			(xy 304.686246 -397.182533) (xy 304.6857 -397.15694) (xy 304.143706 -397.15694) (xy 304.45583 -397.696944)
			(xy 304.468636 -397.720286) (xy 304.486863 -397.770304) (xy 304.496131 -397.822727) (xy 304.496724 -397.849344)
			(xy 304.496302 -397.87335) (xy 304.488781 -397.92077) (xy 304.473932 -397.966429) (xy 304.45212 -398.009201)
			(xy 304.423884 -398.048033) (xy 304.389918 -398.081967) (xy 304.35106 -398.110168) (xy 304.308268 -398.13194)
			(xy 304.262595 -398.146747) (xy 304.215169 -398.154224) (xy 304.191162 -398.154652) (xy 304.167591 -398.154181)
			(xy 304.121008 -398.14695) (xy 304.076092 -398.132636) (xy 304.033915 -398.11158) (xy 303.995481 -398.084283)
			(xy 303.961707 -398.051396) (xy 303.933396 -398.013702) (xy 303.921922 -397.993108) (xy 303.921414 -397.992346)
			(xy 303.52365 -397.304006) (xy 303.511773 -397.281329) (xy 303.494923 -397.232996) (xy 303.48635 -397.182533)
			(xy 303.485804 -397.15694) (xy 280.68524 -397.15694) (xy 280.68524 -401.674838) (xy 303.434496 -401.674838)
			(xy 303.434496 -400.811238) (xy 303.434982 -400.783969) (xy 303.442744 -400.729985) (xy 303.458109 -400.677655)
			(xy 303.480766 -400.628045) (xy 303.510252 -400.582164) (xy 303.545967 -400.540947) (xy 303.587184 -400.505232)
			(xy 303.633065 -400.475746) (xy 303.682675 -400.453089) (xy 303.735005 -400.437724) (xy 303.788989 -400.429962)
			(xy 303.843527 -400.429962) (xy 303.897511 -400.437724) (xy 303.949841 -400.453089) (xy 303.999451 -400.475746)
			(xy 304.045332 -400.505232) (xy 304.086549 -400.540947) (xy 304.122264 -400.582164) (xy 304.15175 -400.628045)
			(xy 304.174407 -400.677655) (xy 304.189772 -400.729985) (xy 304.197534 -400.783969) (xy 304.19802 -400.811238)
			(xy 304.19802 -401.674838) (xy 304.634392 -401.674838) (xy 304.634392 -400.811238) (xy 304.634878 -400.783969)
			(xy 304.64264 -400.729985) (xy 304.658005 -400.677655) (xy 304.680662 -400.628045) (xy 304.710148 -400.582164)
			(xy 304.745863 -400.540947) (xy 304.78708 -400.505232) (xy 304.832961 -400.475746) (xy 304.882571 -400.453089)
			(xy 304.934901 -400.437724) (xy 304.988885 -400.429962) (xy 305.043423 -400.429962) (xy 305.097407 -400.437724)
			(xy 305.149737 -400.453089) (xy 305.199347 -400.475746) (xy 305.245228 -400.505232) (xy 305.286445 -400.540947)
			(xy 305.32216 -400.582164) (xy 305.351646 -400.628045) (xy 305.374303 -400.677655) (xy 305.389668 -400.729985)
			(xy 305.39743 -400.783969) (xy 305.397916 -400.811238) (xy 305.397916 -401.674838) (xy 305.834796 -401.674838)
			(xy 305.834796 -400.811238) (xy 305.835282 -400.783987) (xy 305.843038 -400.730039) (xy 305.858393 -400.677744)
			(xy 305.881035 -400.628167) (xy 305.910501 -400.582317) (xy 305.946192 -400.541126) (xy 305.987383 -400.505435)
			(xy 306.033233 -400.475969) (xy 306.08281 -400.453327) (xy 306.135105 -400.437972) (xy 306.189053 -400.430216)
			(xy 306.243555 -400.430216) (xy 306.297503 -400.437972) (xy 306.349798 -400.453327) (xy 306.399375 -400.475969)
			(xy 306.445225 -400.505435) (xy 306.486416 -400.541126) (xy 306.522107 -400.582317) (xy 306.551573 -400.628167)
			(xy 306.574215 -400.677744) (xy 306.58957 -400.730039) (xy 306.597326 -400.783987) (xy 306.597812 -400.811238)
			(xy 306.597812 -401.674838) (xy 307.034692 -401.674838) (xy 307.034692 -400.811238) (xy 307.035178 -400.783987)
			(xy 307.042934 -400.730039) (xy 307.058289 -400.677744) (xy 307.080931 -400.628167) (xy 307.110397 -400.582317)
			(xy 307.146088 -400.541126) (xy 307.187279 -400.505435) (xy 307.233129 -400.475969) (xy 307.282706 -400.453327)
			(xy 307.335001 -400.437972) (xy 307.388949 -400.430216) (xy 307.443451 -400.430216) (xy 307.497399 -400.437972)
			(xy 307.549694 -400.453327) (xy 307.599271 -400.475969) (xy 307.645121 -400.505435) (xy 307.686312 -400.541126)
			(xy 307.722003 -400.582317) (xy 307.751469 -400.628167) (xy 307.774111 -400.677744) (xy 307.789466 -400.730039)
			(xy 307.797222 -400.783987) (xy 307.797708 -400.811238) (xy 307.797708 -401.674838) (xy 308.234588 -401.674838)
			(xy 308.234588 -400.811238) (xy 308.235074 -400.783969) (xy 308.242836 -400.729985) (xy 308.258201 -400.677655)
			(xy 308.280858 -400.628045) (xy 308.310344 -400.582164) (xy 308.346059 -400.540947) (xy 308.387276 -400.505232)
			(xy 308.433157 -400.475746) (xy 308.482767 -400.453089) (xy 308.535097 -400.437724) (xy 308.589081 -400.429962)
			(xy 308.643619 -400.429962) (xy 308.697603 -400.437724) (xy 308.749933 -400.453089) (xy 308.799543 -400.475746)
			(xy 308.845424 -400.505232) (xy 308.886641 -400.540947) (xy 308.922356 -400.582164) (xy 308.951842 -400.628045)
			(xy 308.974499 -400.677655) (xy 308.989864 -400.729985) (xy 308.997626 -400.783969) (xy 308.998112 -400.811238)
			(xy 308.998112 -401.674838) (xy 309.434484 -401.674838) (xy 309.434484 -400.811238) (xy 309.43497 -400.783969)
			(xy 309.442732 -400.729985) (xy 309.458097 -400.677655) (xy 309.480754 -400.628045) (xy 309.51024 -400.582164)
			(xy 309.545955 -400.540947) (xy 309.587172 -400.505232) (xy 309.633053 -400.475746) (xy 309.682663 -400.453089)
			(xy 309.734993 -400.437724) (xy 309.788977 -400.429962) (xy 309.843515 -400.429962) (xy 309.897499 -400.437724)
			(xy 309.949829 -400.453089) (xy 309.999439 -400.475746) (xy 310.04532 -400.505232) (xy 310.086537 -400.540947)
			(xy 310.122252 -400.582164) (xy 310.151738 -400.628045) (xy 310.174395 -400.677655) (xy 310.18976 -400.729985)
			(xy 310.197522 -400.783969) (xy 310.198008 -400.811238) (xy 310.198008 -401.674838) (xy 310.634888 -401.674838)
			(xy 310.634888 -400.811238) (xy 310.635374 -400.783987) (xy 310.64313 -400.730039) (xy 310.658485 -400.677744)
			(xy 310.681127 -400.628167) (xy 310.710593 -400.582317) (xy 310.746284 -400.541126) (xy 310.787475 -400.505435)
			(xy 310.833325 -400.475969) (xy 310.882902 -400.453327) (xy 310.935197 -400.437972) (xy 310.989145 -400.430216)
			(xy 311.043647 -400.430216) (xy 311.097595 -400.437972) (xy 311.14989 -400.453327) (xy 311.199467 -400.475969)
			(xy 311.245317 -400.505435) (xy 311.286508 -400.541126) (xy 311.322199 -400.582317) (xy 311.351665 -400.628167)
			(xy 311.374307 -400.677744) (xy 311.389662 -400.730039) (xy 311.397418 -400.783987) (xy 311.397904 -400.811238)
			(xy 311.397904 -401.674838) (xy 311.834784 -401.674838) (xy 311.834784 -400.811238) (xy 311.83527 -400.783987)
			(xy 311.843026 -400.730039) (xy 311.858381 -400.677744) (xy 311.881023 -400.628167) (xy 311.910489 -400.582317)
			(xy 311.94618 -400.541126) (xy 311.987371 -400.505435) (xy 312.033221 -400.475969) (xy 312.082798 -400.453327)
			(xy 312.135093 -400.437972) (xy 312.189041 -400.430216) (xy 312.243543 -400.430216) (xy 312.297491 -400.437972)
			(xy 312.349786 -400.453327) (xy 312.399363 -400.475969) (xy 312.445213 -400.505435) (xy 312.486404 -400.541126)
			(xy 312.522095 -400.582317) (xy 312.551561 -400.628167) (xy 312.574203 -400.677744) (xy 312.589558 -400.730039)
			(xy 312.597314 -400.783987) (xy 312.5978 -400.811238) (xy 312.5978 -401.674838) (xy 313.03468 -401.674838)
			(xy 313.03468 -400.811238) (xy 313.035166 -400.783969) (xy 313.042928 -400.729985) (xy 313.058293 -400.677655)
			(xy 313.08095 -400.628045) (xy 313.110436 -400.582164) (xy 313.146151 -400.540947) (xy 313.187368 -400.505232)
			(xy 313.233249 -400.475746) (xy 313.282859 -400.453089) (xy 313.335189 -400.437724) (xy 313.389173 -400.429962)
			(xy 313.443711 -400.429962) (xy 313.497695 -400.437724) (xy 313.550025 -400.453089) (xy 313.599635 -400.475746)
			(xy 313.645516 -400.505232) (xy 313.686733 -400.540947) (xy 313.722448 -400.582164) (xy 313.751934 -400.628045)
			(xy 313.774591 -400.677655) (xy 313.789956 -400.729985) (xy 313.797718 -400.783969) (xy 313.798204 -400.811238)
			(xy 313.798204 -401.674838) (xy 314.234576 -401.674838) (xy 314.234576 -400.811238) (xy 314.235062 -400.783969)
			(xy 314.242824 -400.729985) (xy 314.258189 -400.677655) (xy 314.280846 -400.628045) (xy 314.310332 -400.582164)
			(xy 314.346047 -400.540947) (xy 314.387264 -400.505232) (xy 314.433145 -400.475746) (xy 314.482755 -400.453089)
			(xy 314.535085 -400.437724) (xy 314.589069 -400.429962) (xy 314.643607 -400.429962) (xy 314.697591 -400.437724)
			(xy 314.749921 -400.453089) (xy 314.799531 -400.475746) (xy 314.845412 -400.505232) (xy 314.886629 -400.540947)
			(xy 314.922344 -400.582164) (xy 314.95183 -400.628045) (xy 314.974487 -400.677655) (xy 314.989852 -400.729985)
			(xy 314.997614 -400.783969) (xy 314.9981 -400.811238) (xy 314.9981 -401.674838) (xy 315.43498 -401.674838)
			(xy 315.43498 -400.811238) (xy 315.435466 -400.783987) (xy 315.443222 -400.730039) (xy 315.458577 -400.677744)
			(xy 315.481219 -400.628167) (xy 315.510685 -400.582317) (xy 315.546376 -400.541126) (xy 315.587567 -400.505435)
			(xy 315.633417 -400.475969) (xy 315.682994 -400.453327) (xy 315.735289 -400.437972) (xy 315.789237 -400.430216)
			(xy 315.843739 -400.430216) (xy 315.897687 -400.437972) (xy 315.949982 -400.453327) (xy 315.999559 -400.475969)
			(xy 316.045409 -400.505435) (xy 316.0866 -400.541126) (xy 316.122291 -400.582317) (xy 316.151757 -400.628167)
			(xy 316.174399 -400.677744) (xy 316.189754 -400.730039) (xy 316.19751 -400.783987) (xy 316.197996 -400.811238)
			(xy 316.197996 -401.674838) (xy 316.634876 -401.674838) (xy 316.634876 -400.811238) (xy 316.635362 -400.783987)
			(xy 316.643118 -400.730039) (xy 316.658473 -400.677744) (xy 316.681115 -400.628167) (xy 316.710581 -400.582317)
			(xy 316.746272 -400.541126) (xy 316.787463 -400.505435) (xy 316.833313 -400.475969) (xy 316.88289 -400.453327)
			(xy 316.935185 -400.437972) (xy 316.989133 -400.430216) (xy 317.043635 -400.430216) (xy 317.097583 -400.437972)
			(xy 317.149878 -400.453327) (xy 317.199455 -400.475969) (xy 317.245305 -400.505435) (xy 317.286496 -400.541126)
			(xy 317.322187 -400.582317) (xy 317.351653 -400.628167) (xy 317.374295 -400.677744) (xy 317.38965 -400.730039)
			(xy 317.397406 -400.783987) (xy 317.397892 -400.811238) (xy 317.397892 -401.674838) (xy 317.834772 -401.674838)
			(xy 317.834772 -400.811238) (xy 317.835258 -400.783987) (xy 317.843014 -400.730039) (xy 317.858369 -400.677744)
			(xy 317.881011 -400.628167) (xy 317.910477 -400.582317) (xy 317.946168 -400.541126) (xy 317.987359 -400.505435)
			(xy 318.033209 -400.475969) (xy 318.082786 -400.453327) (xy 318.135081 -400.437972) (xy 318.189029 -400.430216)
			(xy 318.243531 -400.430216) (xy 318.297479 -400.437972) (xy 318.349774 -400.453327) (xy 318.399351 -400.475969)
			(xy 318.445201 -400.505435) (xy 318.486392 -400.541126) (xy 318.522083 -400.582317) (xy 318.551549 -400.628167)
			(xy 318.574191 -400.677744) (xy 318.589546 -400.730039) (xy 318.597302 -400.783987) (xy 318.597788 -400.811238)
			(xy 318.597788 -401.674838) (xy 319.034668 -401.674838) (xy 319.034668 -400.811238) (xy 319.035154 -400.783987)
			(xy 319.04291 -400.730039) (xy 319.058265 -400.677744) (xy 319.080907 -400.628167) (xy 319.110373 -400.582317)
			(xy 319.146064 -400.541126) (xy 319.187255 -400.505435) (xy 319.233105 -400.475969) (xy 319.282682 -400.453327)
			(xy 319.334977 -400.437972) (xy 319.388925 -400.430216) (xy 319.443427 -400.430216) (xy 319.497375 -400.437972)
			(xy 319.54967 -400.453327) (xy 319.599247 -400.475969) (xy 319.645097 -400.505435) (xy 319.686288 -400.541126)
			(xy 319.721979 -400.582317) (xy 319.751445 -400.628167) (xy 319.774087 -400.677744) (xy 319.789442 -400.730039)
			(xy 319.797198 -400.783987) (xy 319.797684 -400.811238) (xy 319.797684 -401.674838) (xy 320.234564 -401.674838)
			(xy 320.234564 -400.811238) (xy 320.23505 -400.783969) (xy 320.242812 -400.729985) (xy 320.258177 -400.677655)
			(xy 320.280834 -400.628045) (xy 320.31032 -400.582164) (xy 320.346035 -400.540947) (xy 320.387252 -400.505232)
			(xy 320.433133 -400.475746) (xy 320.482743 -400.453089) (xy 320.535073 -400.437724) (xy 320.589057 -400.429962)
			(xy 320.643595 -400.429962) (xy 320.697579 -400.437724) (xy 320.749909 -400.453089) (xy 320.799519 -400.475746)
			(xy 320.8454 -400.505232) (xy 320.886617 -400.540947) (xy 320.922332 -400.582164) (xy 320.951818 -400.628045)
			(xy 320.974475 -400.677655) (xy 320.98984 -400.729985) (xy 320.997602 -400.783969) (xy 320.998088 -400.811238)
			(xy 320.998088 -401.674838) (xy 321.43446 -401.674838) (xy 321.43446 -400.811238) (xy 321.434946 -400.783969)
			(xy 321.442708 -400.729985) (xy 321.458073 -400.677655) (xy 321.48073 -400.628045) (xy 321.510216 -400.582164)
			(xy 321.545931 -400.540947) (xy 321.587148 -400.505232) (xy 321.633029 -400.475746) (xy 321.682639 -400.453089)
			(xy 321.734969 -400.437724) (xy 321.788953 -400.429962) (xy 321.843491 -400.429962) (xy 321.897475 -400.437724)
			(xy 321.949805 -400.453089) (xy 321.999415 -400.475746) (xy 322.045296 -400.505232) (xy 322.086513 -400.540947)
			(xy 322.122228 -400.582164) (xy 322.151714 -400.628045) (xy 322.174371 -400.677655) (xy 322.189736 -400.729985)
			(xy 322.197498 -400.783969) (xy 322.197984 -400.811238) (xy 322.197984 -401.674838) (xy 335.962244 -401.674838)
			(xy 335.962244 -400.811238) (xy 335.96273 -400.783969) (xy 335.970492 -400.729985) (xy 335.985857 -400.677655)
			(xy 336.008514 -400.628045) (xy 336.038 -400.582164) (xy 336.073715 -400.540947) (xy 336.114932 -400.505232)
			(xy 336.160813 -400.475746) (xy 336.210423 -400.453089) (xy 336.262753 -400.437724) (xy 336.316737 -400.429962)
			(xy 336.371275 -400.429962) (xy 336.425259 -400.437724) (xy 336.477589 -400.453089) (xy 336.527199 -400.475746)
			(xy 336.57308 -400.505232) (xy 336.614297 -400.540947) (xy 336.650012 -400.582164) (xy 336.679498 -400.628045)
			(xy 336.702155 -400.677655) (xy 336.71752 -400.729985) (xy 336.725282 -400.783969) (xy 336.725768 -400.811238)
			(xy 336.725768 -401.674838) (xy 337.16214 -401.674838) (xy 337.16214 -400.811238) (xy 337.162626 -400.783969)
			(xy 337.170388 -400.729985) (xy 337.185753 -400.677655) (xy 337.20841 -400.628045) (xy 337.237896 -400.582164)
			(xy 337.273611 -400.540947) (xy 337.314828 -400.505232) (xy 337.360709 -400.475746) (xy 337.410319 -400.453089)
			(xy 337.462649 -400.437724) (xy 337.516633 -400.429962) (xy 337.571171 -400.429962) (xy 337.625155 -400.437724)
			(xy 337.677485 -400.453089) (xy 337.727095 -400.475746) (xy 337.772976 -400.505232) (xy 337.814193 -400.540947)
			(xy 337.849908 -400.582164) (xy 337.879394 -400.628045) (xy 337.902051 -400.677655) (xy 337.917416 -400.729985)
			(xy 337.925178 -400.783969) (xy 337.925664 -400.811238) (xy 337.925664 -401.674838) (xy 338.362544 -401.674838)
			(xy 338.362544 -400.811238) (xy 338.36303 -400.783987) (xy 338.370786 -400.730039) (xy 338.386141 -400.677744)
			(xy 338.408783 -400.628167) (xy 338.438249 -400.582317) (xy 338.47394 -400.541126) (xy 338.515131 -400.505435)
			(xy 338.560981 -400.475969) (xy 338.610558 -400.453327) (xy 338.662853 -400.437972) (xy 338.716801 -400.430216)
			(xy 338.771303 -400.430216) (xy 338.825251 -400.437972) (xy 338.877546 -400.453327) (xy 338.927123 -400.475969)
			(xy 338.972973 -400.505435) (xy 339.014164 -400.541126) (xy 339.049855 -400.582317) (xy 339.079321 -400.628167)
			(xy 339.101963 -400.677744) (xy 339.117318 -400.730039) (xy 339.125074 -400.783987) (xy 339.12556 -400.811238)
			(xy 339.12556 -401.674838) (xy 339.56244 -401.674838) (xy 339.56244 -400.811238) (xy 339.562926 -400.783987)
			(xy 339.570682 -400.730039) (xy 339.586037 -400.677744) (xy 339.608679 -400.628167) (xy 339.638145 -400.582317)
			(xy 339.673836 -400.541126) (xy 339.715027 -400.505435) (xy 339.760877 -400.475969) (xy 339.810454 -400.453327)
			(xy 339.862749 -400.437972) (xy 339.916697 -400.430216) (xy 339.971199 -400.430216) (xy 340.025147 -400.437972)
			(xy 340.077442 -400.453327) (xy 340.127019 -400.475969) (xy 340.172869 -400.505435) (xy 340.21406 -400.541126)
			(xy 340.249751 -400.582317) (xy 340.279217 -400.628167) (xy 340.301859 -400.677744) (xy 340.317214 -400.730039)
			(xy 340.32497 -400.783987) (xy 340.325456 -400.811238) (xy 340.325456 -401.674838) (xy 340.762336 -401.674838)
			(xy 340.762336 -400.811238) (xy 340.762822 -400.783969) (xy 340.770584 -400.729985) (xy 340.785949 -400.677655)
			(xy 340.808606 -400.628045) (xy 340.838092 -400.582164) (xy 340.873807 -400.540947) (xy 340.915024 -400.505232)
			(xy 340.960905 -400.475746) (xy 341.010515 -400.453089) (xy 341.062845 -400.437724) (xy 341.116829 -400.429962)
			(xy 341.171367 -400.429962) (xy 341.225351 -400.437724) (xy 341.277681 -400.453089) (xy 341.327291 -400.475746)
			(xy 341.373172 -400.505232) (xy 341.414389 -400.540947) (xy 341.450104 -400.582164) (xy 341.47959 -400.628045)
			(xy 341.502247 -400.677655) (xy 341.517612 -400.729985) (xy 341.525374 -400.783969) (xy 341.52586 -400.811238)
			(xy 341.52586 -401.674838) (xy 341.962232 -401.674838) (xy 341.962232 -400.811238) (xy 341.962718 -400.783969)
			(xy 341.97048 -400.729985) (xy 341.985845 -400.677655) (xy 342.008502 -400.628045) (xy 342.037988 -400.582164)
			(xy 342.073703 -400.540947) (xy 342.11492 -400.505232) (xy 342.160801 -400.475746) (xy 342.210411 -400.453089)
			(xy 342.262741 -400.437724) (xy 342.316725 -400.429962) (xy 342.371263 -400.429962) (xy 342.425247 -400.437724)
			(xy 342.477577 -400.453089) (xy 342.527187 -400.475746) (xy 342.573068 -400.505232) (xy 342.614285 -400.540947)
			(xy 342.65 -400.582164) (xy 342.679486 -400.628045) (xy 342.702143 -400.677655) (xy 342.717508 -400.729985)
			(xy 342.72527 -400.783969) (xy 342.725756 -400.811238) (xy 342.725756 -401.674838) (xy 343.162636 -401.674838)
			(xy 343.162636 -400.811238) (xy 343.163122 -400.783987) (xy 343.170878 -400.730039) (xy 343.186233 -400.677744)
			(xy 343.208875 -400.628167) (xy 343.238341 -400.582317) (xy 343.274032 -400.541126) (xy 343.315223 -400.505435)
			(xy 343.361073 -400.475969) (xy 343.41065 -400.453327) (xy 343.462945 -400.437972) (xy 343.516893 -400.430216)
			(xy 343.571395 -400.430216) (xy 343.625343 -400.437972) (xy 343.677638 -400.453327) (xy 343.727215 -400.475969)
			(xy 343.773065 -400.505435) (xy 343.814256 -400.541126) (xy 343.849947 -400.582317) (xy 343.879413 -400.628167)
			(xy 343.902055 -400.677744) (xy 343.91741 -400.730039) (xy 343.925166 -400.783987) (xy 343.925652 -400.811238)
			(xy 343.925652 -401.674838) (xy 344.362532 -401.674838) (xy 344.362532 -400.811238) (xy 344.363018 -400.783987)
			(xy 344.370774 -400.730039) (xy 344.386129 -400.677744) (xy 344.408771 -400.628167) (xy 344.438237 -400.582317)
			(xy 344.473928 -400.541126) (xy 344.515119 -400.505435) (xy 344.560969 -400.475969) (xy 344.610546 -400.453327)
			(xy 344.662841 -400.437972) (xy 344.716789 -400.430216) (xy 344.771291 -400.430216) (xy 344.825239 -400.437972)
			(xy 344.877534 -400.453327) (xy 344.927111 -400.475969) (xy 344.972961 -400.505435) (xy 345.014152 -400.541126)
			(xy 345.049843 -400.582317) (xy 345.079309 -400.628167) (xy 345.101951 -400.677744) (xy 345.117306 -400.730039)
			(xy 345.125062 -400.783987) (xy 345.125548 -400.811238) (xy 345.125548 -401.674838) (xy 345.562428 -401.674838)
			(xy 345.562428 -400.811238) (xy 345.562914 -400.783969) (xy 345.570676 -400.729985) (xy 345.586041 -400.677655)
			(xy 345.608698 -400.628045) (xy 345.638184 -400.582164) (xy 345.673899 -400.540947) (xy 345.715116 -400.505232)
			(xy 345.760997 -400.475746) (xy 345.810607 -400.453089) (xy 345.862937 -400.437724) (xy 345.916921 -400.429962)
			(xy 345.971459 -400.429962) (xy 346.025443 -400.437724) (xy 346.077773 -400.453089) (xy 346.127383 -400.475746)
			(xy 346.173264 -400.505232) (xy 346.214481 -400.540947) (xy 346.250196 -400.582164) (xy 346.279682 -400.628045)
			(xy 346.302339 -400.677655) (xy 346.317704 -400.729985) (xy 346.325466 -400.783969) (xy 346.325952 -400.811238)
			(xy 346.325952 -401.674838) (xy 346.762324 -401.674838) (xy 346.762324 -400.811238) (xy 346.76281 -400.783969)
			(xy 346.770572 -400.729985) (xy 346.785937 -400.677655) (xy 346.808594 -400.628045) (xy 346.83808 -400.582164)
			(xy 346.873795 -400.540947) (xy 346.915012 -400.505232) (xy 346.960893 -400.475746) (xy 347.010503 -400.453089)
			(xy 347.062833 -400.437724) (xy 347.116817 -400.429962) (xy 347.171355 -400.429962) (xy 347.225339 -400.437724)
			(xy 347.277669 -400.453089) (xy 347.327279 -400.475746) (xy 347.37316 -400.505232) (xy 347.414377 -400.540947)
			(xy 347.450092 -400.582164) (xy 347.479578 -400.628045) (xy 347.502235 -400.677655) (xy 347.5176 -400.729985)
			(xy 347.525362 -400.783969) (xy 347.525848 -400.811238) (xy 347.525848 -401.674838) (xy 347.962728 -401.674838)
			(xy 347.962728 -400.811238) (xy 347.963214 -400.783987) (xy 347.97097 -400.730039) (xy 347.986325 -400.677744)
			(xy 348.008967 -400.628167) (xy 348.038433 -400.582317) (xy 348.074124 -400.541126) (xy 348.115315 -400.505435)
			(xy 348.161165 -400.475969) (xy 348.210742 -400.453327) (xy 348.263037 -400.437972) (xy 348.316985 -400.430216)
			(xy 348.371487 -400.430216) (xy 348.425435 -400.437972) (xy 348.47773 -400.453327) (xy 348.527307 -400.475969)
			(xy 348.573157 -400.505435) (xy 348.614348 -400.541126) (xy 348.650039 -400.582317) (xy 348.679505 -400.628167)
			(xy 348.702147 -400.677744) (xy 348.717502 -400.730039) (xy 348.725258 -400.783987) (xy 348.725744 -400.811238)
			(xy 348.725744 -401.674838) (xy 349.162624 -401.674838) (xy 349.162624 -400.811238) (xy 349.16311 -400.783987)
			(xy 349.170866 -400.730039) (xy 349.186221 -400.677744) (xy 349.208863 -400.628167) (xy 349.238329 -400.582317)
			(xy 349.27402 -400.541126) (xy 349.315211 -400.505435) (xy 349.361061 -400.475969) (xy 349.410638 -400.453327)
			(xy 349.462933 -400.437972) (xy 349.516881 -400.430216) (xy 349.571383 -400.430216) (xy 349.625331 -400.437972)
			(xy 349.677626 -400.453327) (xy 349.727203 -400.475969) (xy 349.773053 -400.505435) (xy 349.814244 -400.541126)
			(xy 349.849935 -400.582317) (xy 349.879401 -400.628167) (xy 349.902043 -400.677744) (xy 349.917398 -400.730039)
			(xy 349.925154 -400.783987) (xy 349.92564 -400.811238) (xy 349.92564 -401.674838) (xy 350.36252 -401.674838)
			(xy 350.36252 -400.811238) (xy 350.363006 -400.783987) (xy 350.370762 -400.730039) (xy 350.386117 -400.677744)
			(xy 350.408759 -400.628167) (xy 350.438225 -400.582317) (xy 350.473916 -400.541126) (xy 350.515107 -400.505435)
			(xy 350.560957 -400.475969) (xy 350.610534 -400.453327) (xy 350.662829 -400.437972) (xy 350.716777 -400.430216)
			(xy 350.771279 -400.430216) (xy 350.825227 -400.437972) (xy 350.877522 -400.453327) (xy 350.927099 -400.475969)
			(xy 350.972949 -400.505435) (xy 351.01414 -400.541126) (xy 351.049831 -400.582317) (xy 351.079297 -400.628167)
			(xy 351.101939 -400.677744) (xy 351.117294 -400.730039) (xy 351.12505 -400.783987) (xy 351.125536 -400.811238)
			(xy 351.125536 -401.674838) (xy 351.562416 -401.674838) (xy 351.562416 -400.811238) (xy 351.562902 -400.783987)
			(xy 351.570658 -400.730039) (xy 351.586013 -400.677744) (xy 351.608655 -400.628167) (xy 351.638121 -400.582317)
			(xy 351.673812 -400.541126) (xy 351.715003 -400.505435) (xy 351.760853 -400.475969) (xy 351.81043 -400.453327)
			(xy 351.862725 -400.437972) (xy 351.916673 -400.430216) (xy 351.971175 -400.430216) (xy 352.025123 -400.437972)
			(xy 352.077418 -400.453327) (xy 352.126995 -400.475969) (xy 352.172845 -400.505435) (xy 352.214036 -400.541126)
			(xy 352.249727 -400.582317) (xy 352.279193 -400.628167) (xy 352.301835 -400.677744) (xy 352.31719 -400.730039)
			(xy 352.324946 -400.783987) (xy 352.325432 -400.811238) (xy 352.325432 -401.674838) (xy 352.762312 -401.674838)
			(xy 352.762312 -400.811238) (xy 352.762798 -400.783969) (xy 352.77056 -400.729985) (xy 352.785925 -400.677655)
			(xy 352.808582 -400.628045) (xy 352.838068 -400.582164) (xy 352.873783 -400.540947) (xy 352.915 -400.505232)
			(xy 352.960881 -400.475746) (xy 353.010491 -400.453089) (xy 353.062821 -400.437724) (xy 353.116805 -400.429962)
			(xy 353.171343 -400.429962) (xy 353.225327 -400.437724) (xy 353.277657 -400.453089) (xy 353.327267 -400.475746)
			(xy 353.373148 -400.505232) (xy 353.414365 -400.540947) (xy 353.45008 -400.582164) (xy 353.479566 -400.628045)
			(xy 353.502223 -400.677655) (xy 353.517588 -400.729985) (xy 353.52535 -400.783969) (xy 353.525836 -400.811238)
			(xy 353.525836 -401.674838) (xy 353.962208 -401.674838) (xy 353.962208 -400.811238) (xy 353.962694 -400.783969)
			(xy 353.970456 -400.729985) (xy 353.985821 -400.677655) (xy 354.008478 -400.628045) (xy 354.037964 -400.582164)
			(xy 354.073679 -400.540947) (xy 354.114896 -400.505232) (xy 354.160777 -400.475746) (xy 354.210387 -400.453089)
			(xy 354.262717 -400.437724) (xy 354.316701 -400.429962) (xy 354.371239 -400.429962) (xy 354.425223 -400.437724)
			(xy 354.477553 -400.453089) (xy 354.527163 -400.475746) (xy 354.573044 -400.505232) (xy 354.614261 -400.540947)
			(xy 354.649976 -400.582164) (xy 354.679462 -400.628045) (xy 354.702119 -400.677655) (xy 354.717484 -400.729985)
			(xy 354.725246 -400.783969) (xy 354.725732 -400.811238) (xy 354.725732 -401.674838) (xy 370.534692 -401.674838)
			(xy 370.534692 -400.811238) (xy 370.535178 -400.783969) (xy 370.54294 -400.729985) (xy 370.558305 -400.677655)
			(xy 370.580962 -400.628045) (xy 370.610448 -400.582164) (xy 370.646163 -400.540947) (xy 370.68738 -400.505232)
			(xy 370.733261 -400.475746) (xy 370.782871 -400.453089) (xy 370.835201 -400.437724) (xy 370.889185 -400.429962)
			(xy 370.943723 -400.429962) (xy 370.997707 -400.437724) (xy 371.050037 -400.453089) (xy 371.099647 -400.475746)
			(xy 371.145528 -400.505232) (xy 371.186745 -400.540947) (xy 371.22246 -400.582164) (xy 371.251946 -400.628045)
			(xy 371.274603 -400.677655) (xy 371.289968 -400.729985) (xy 371.29773 -400.783969) (xy 371.298216 -400.811238)
			(xy 371.298216 -401.674838) (xy 371.734588 -401.674838) (xy 371.734588 -400.811238) (xy 371.735074 -400.783969)
			(xy 371.742836 -400.729985) (xy 371.758201 -400.677655) (xy 371.780858 -400.628045) (xy 371.810344 -400.582164)
			(xy 371.846059 -400.540947) (xy 371.887276 -400.505232) (xy 371.933157 -400.475746) (xy 371.982767 -400.453089)
			(xy 372.035097 -400.437724) (xy 372.089081 -400.429962) (xy 372.143619 -400.429962) (xy 372.197603 -400.437724)
			(xy 372.249933 -400.453089) (xy 372.299543 -400.475746) (xy 372.345424 -400.505232) (xy 372.386641 -400.540947)
			(xy 372.422356 -400.582164) (xy 372.451842 -400.628045) (xy 372.474499 -400.677655) (xy 372.489864 -400.729985)
			(xy 372.497626 -400.783969) (xy 372.498112 -400.811238) (xy 372.498112 -401.674838) (xy 372.934992 -401.674838)
			(xy 372.934992 -400.811238) (xy 372.935478 -400.783987) (xy 372.943234 -400.730039) (xy 372.958589 -400.677744)
			(xy 372.981231 -400.628167) (xy 373.010697 -400.582317) (xy 373.046388 -400.541126) (xy 373.087579 -400.505435)
			(xy 373.133429 -400.475969) (xy 373.183006 -400.453327) (xy 373.235301 -400.437972) (xy 373.289249 -400.430216)
			(xy 373.343751 -400.430216) (xy 373.397699 -400.437972) (xy 373.449994 -400.453327) (xy 373.499571 -400.475969)
			(xy 373.545421 -400.505435) (xy 373.586612 -400.541126) (xy 373.622303 -400.582317) (xy 373.651769 -400.628167)
			(xy 373.674411 -400.677744) (xy 373.689766 -400.730039) (xy 373.697522 -400.783987) (xy 373.698008 -400.811238)
			(xy 373.698008 -401.674838) (xy 374.134888 -401.674838) (xy 374.134888 -400.811238) (xy 374.135374 -400.783987)
			(xy 374.14313 -400.730039) (xy 374.158485 -400.677744) (xy 374.181127 -400.628167) (xy 374.210593 -400.582317)
			(xy 374.246284 -400.541126) (xy 374.287475 -400.505435) (xy 374.333325 -400.475969) (xy 374.382902 -400.453327)
			(xy 374.435197 -400.437972) (xy 374.489145 -400.430216) (xy 374.543647 -400.430216) (xy 374.597595 -400.437972)
			(xy 374.64989 -400.453327) (xy 374.699467 -400.475969) (xy 374.745317 -400.505435) (xy 374.786508 -400.541126)
			(xy 374.822199 -400.582317) (xy 374.851665 -400.628167) (xy 374.874307 -400.677744) (xy 374.889662 -400.730039)
			(xy 374.897418 -400.783987) (xy 374.897904 -400.811238) (xy 374.897904 -401.674838) (xy 375.334784 -401.674838)
			(xy 375.334784 -400.811238) (xy 375.33527 -400.783969) (xy 375.343032 -400.729985) (xy 375.358397 -400.677655)
			(xy 375.381054 -400.628045) (xy 375.41054 -400.582164) (xy 375.446255 -400.540947) (xy 375.487472 -400.505232)
			(xy 375.533353 -400.475746) (xy 375.582963 -400.453089) (xy 375.635293 -400.437724) (xy 375.689277 -400.429962)
			(xy 375.743815 -400.429962) (xy 375.797799 -400.437724) (xy 375.850129 -400.453089) (xy 375.899739 -400.475746)
			(xy 375.94562 -400.505232) (xy 375.986837 -400.540947) (xy 376.022552 -400.582164) (xy 376.052038 -400.628045)
			(xy 376.074695 -400.677655) (xy 376.09006 -400.729985) (xy 376.097822 -400.783969) (xy 376.098308 -400.811238)
			(xy 376.098308 -401.674838) (xy 376.53468 -401.674838) (xy 376.53468 -400.811238) (xy 376.535166 -400.783969)
			(xy 376.542928 -400.729985) (xy 376.558293 -400.677655) (xy 376.58095 -400.628045) (xy 376.610436 -400.582164)
			(xy 376.646151 -400.540947) (xy 376.687368 -400.505232) (xy 376.733249 -400.475746) (xy 376.782859 -400.453089)
			(xy 376.835189 -400.437724) (xy 376.889173 -400.429962) (xy 376.943711 -400.429962) (xy 376.997695 -400.437724)
			(xy 377.050025 -400.453089) (xy 377.099635 -400.475746) (xy 377.145516 -400.505232) (xy 377.186733 -400.540947)
			(xy 377.222448 -400.582164) (xy 377.251934 -400.628045) (xy 377.274591 -400.677655) (xy 377.289956 -400.729985)
			(xy 377.297718 -400.783969) (xy 377.298204 -400.811238) (xy 377.298204 -401.674838) (xy 377.735084 -401.674838)
			(xy 377.735084 -400.811238) (xy 377.73557 -400.783987) (xy 377.743326 -400.730039) (xy 377.758681 -400.677744)
			(xy 377.781323 -400.628167) (xy 377.810789 -400.582317) (xy 377.84648 -400.541126) (xy 377.887671 -400.505435)
			(xy 377.933521 -400.475969) (xy 377.983098 -400.453327) (xy 378.035393 -400.437972) (xy 378.089341 -400.430216)
			(xy 378.143843 -400.430216) (xy 378.197791 -400.437972) (xy 378.250086 -400.453327) (xy 378.299663 -400.475969)
			(xy 378.345513 -400.505435) (xy 378.386704 -400.541126) (xy 378.422395 -400.582317) (xy 378.451861 -400.628167)
			(xy 378.474503 -400.677744) (xy 378.489858 -400.730039) (xy 378.497614 -400.783987) (xy 378.4981 -400.811238)
			(xy 378.4981 -401.674838) (xy 378.93498 -401.674838) (xy 378.93498 -400.811238) (xy 378.935466 -400.783987)
			(xy 378.943222 -400.730039) (xy 378.958577 -400.677744) (xy 378.981219 -400.628167) (xy 379.010685 -400.582317)
			(xy 379.046376 -400.541126) (xy 379.087567 -400.505435) (xy 379.133417 -400.475969) (xy 379.182994 -400.453327)
			(xy 379.235289 -400.437972) (xy 379.289237 -400.430216) (xy 379.343739 -400.430216) (xy 379.397687 -400.437972)
			(xy 379.449982 -400.453327) (xy 379.499559 -400.475969) (xy 379.545409 -400.505435) (xy 379.5866 -400.541126)
			(xy 379.622291 -400.582317) (xy 379.651757 -400.628167) (xy 379.674399 -400.677744) (xy 379.689754 -400.730039)
			(xy 379.69751 -400.783987) (xy 379.697996 -400.811238) (xy 379.697996 -401.674838) (xy 380.134876 -401.674838)
			(xy 380.134876 -400.811238) (xy 380.135362 -400.783969) (xy 380.143124 -400.729985) (xy 380.158489 -400.677655)
			(xy 380.181146 -400.628045) (xy 380.210632 -400.582164) (xy 380.246347 -400.540947) (xy 380.287564 -400.505232)
			(xy 380.333445 -400.475746) (xy 380.383055 -400.453089) (xy 380.435385 -400.437724) (xy 380.489369 -400.429962)
			(xy 380.543907 -400.429962) (xy 380.597891 -400.437724) (xy 380.650221 -400.453089) (xy 380.699831 -400.475746)
			(xy 380.745712 -400.505232) (xy 380.786929 -400.540947) (xy 380.822644 -400.582164) (xy 380.85213 -400.628045)
			(xy 380.874787 -400.677655) (xy 380.890152 -400.729985) (xy 380.897914 -400.783969) (xy 380.8984 -400.811238)
			(xy 380.8984 -401.674838) (xy 381.334772 -401.674838) (xy 381.334772 -400.811238) (xy 381.335258 -400.783969)
			(xy 381.34302 -400.729985) (xy 381.358385 -400.677655) (xy 381.381042 -400.628045) (xy 381.410528 -400.582164)
			(xy 381.446243 -400.540947) (xy 381.48746 -400.505232) (xy 381.533341 -400.475746) (xy 381.582951 -400.453089)
			(xy 381.635281 -400.437724) (xy 381.689265 -400.429962) (xy 381.743803 -400.429962) (xy 381.797787 -400.437724)
			(xy 381.850117 -400.453089) (xy 381.899727 -400.475746) (xy 381.945608 -400.505232) (xy 381.986825 -400.540947)
			(xy 382.02254 -400.582164) (xy 382.052026 -400.628045) (xy 382.074683 -400.677655) (xy 382.090048 -400.729985)
			(xy 382.09781 -400.783969) (xy 382.098296 -400.811238) (xy 382.098296 -401.674838) (xy 382.535176 -401.674838)
			(xy 382.535176 -400.811238) (xy 382.535662 -400.783987) (xy 382.543418 -400.730039) (xy 382.558773 -400.677744)
			(xy 382.581415 -400.628167) (xy 382.610881 -400.582317) (xy 382.646572 -400.541126) (xy 382.687763 -400.505435)
			(xy 382.733613 -400.475969) (xy 382.78319 -400.453327) (xy 382.835485 -400.437972) (xy 382.889433 -400.430216)
			(xy 382.943935 -400.430216) (xy 382.997883 -400.437972) (xy 383.050178 -400.453327) (xy 383.099755 -400.475969)
			(xy 383.145605 -400.505435) (xy 383.186796 -400.541126) (xy 383.222487 -400.582317) (xy 383.251953 -400.628167)
			(xy 383.274595 -400.677744) (xy 383.28995 -400.730039) (xy 383.297706 -400.783987) (xy 383.298192 -400.811238)
			(xy 383.298192 -401.674838) (xy 383.735072 -401.674838) (xy 383.735072 -400.811238) (xy 383.735558 -400.783987)
			(xy 383.743314 -400.730039) (xy 383.758669 -400.677744) (xy 383.781311 -400.628167) (xy 383.810777 -400.582317)
			(xy 383.846468 -400.541126) (xy 383.887659 -400.505435) (xy 383.933509 -400.475969) (xy 383.983086 -400.453327)
			(xy 384.035381 -400.437972) (xy 384.089329 -400.430216) (xy 384.143831 -400.430216) (xy 384.197779 -400.437972)
			(xy 384.250074 -400.453327) (xy 384.299651 -400.475969) (xy 384.345501 -400.505435) (xy 384.386692 -400.541126)
			(xy 384.422383 -400.582317) (xy 384.451849 -400.628167) (xy 384.474491 -400.677744) (xy 384.489846 -400.730039)
			(xy 384.497602 -400.783987) (xy 384.498088 -400.811238) (xy 384.498088 -401.674838) (xy 384.934968 -401.674838)
			(xy 384.934968 -400.811238) (xy 384.935454 -400.783987) (xy 384.94321 -400.730039) (xy 384.958565 -400.677744)
			(xy 384.981207 -400.628167) (xy 385.010673 -400.582317) (xy 385.046364 -400.541126) (xy 385.087555 -400.505435)
			(xy 385.133405 -400.475969) (xy 385.182982 -400.453327) (xy 385.235277 -400.437972) (xy 385.289225 -400.430216)
			(xy 385.343727 -400.430216) (xy 385.397675 -400.437972) (xy 385.44997 -400.453327) (xy 385.499547 -400.475969)
			(xy 385.545397 -400.505435) (xy 385.586588 -400.541126) (xy 385.622279 -400.582317) (xy 385.651745 -400.628167)
			(xy 385.674387 -400.677744) (xy 385.689742 -400.730039) (xy 385.697498 -400.783987) (xy 385.697984 -400.811238)
			(xy 385.697984 -401.674838) (xy 386.134864 -401.674838) (xy 386.134864 -400.811238) (xy 386.13535 -400.783987)
			(xy 386.143106 -400.730039) (xy 386.158461 -400.677744) (xy 386.181103 -400.628167) (xy 386.210569 -400.582317)
			(xy 386.24626 -400.541126) (xy 386.287451 -400.505435) (xy 386.333301 -400.475969) (xy 386.382878 -400.453327)
			(xy 386.435173 -400.437972) (xy 386.489121 -400.430216) (xy 386.543623 -400.430216) (xy 386.597571 -400.437972)
			(xy 386.649866 -400.453327) (xy 386.699443 -400.475969) (xy 386.745293 -400.505435) (xy 386.786484 -400.541126)
			(xy 386.822175 -400.582317) (xy 386.851641 -400.628167) (xy 386.874283 -400.677744) (xy 386.889638 -400.730039)
			(xy 386.897394 -400.783987) (xy 386.89788 -400.811238) (xy 386.89788 -401.674838) (xy 387.33476 -401.674838)
			(xy 387.33476 -400.811238) (xy 387.335246 -400.783969) (xy 387.343008 -400.729985) (xy 387.358373 -400.677655)
			(xy 387.38103 -400.628045) (xy 387.410516 -400.582164) (xy 387.446231 -400.540947) (xy 387.487448 -400.505232)
			(xy 387.533329 -400.475746) (xy 387.582939 -400.453089) (xy 387.635269 -400.437724) (xy 387.689253 -400.429962)
			(xy 387.743791 -400.429962) (xy 387.797775 -400.437724) (xy 387.850105 -400.453089) (xy 387.899715 -400.475746)
			(xy 387.945596 -400.505232) (xy 387.986813 -400.540947) (xy 388.022528 -400.582164) (xy 388.052014 -400.628045)
			(xy 388.074671 -400.677655) (xy 388.090036 -400.729985) (xy 388.097798 -400.783969) (xy 388.098284 -400.811238)
			(xy 388.098284 -401.674838) (xy 388.534656 -401.674838) (xy 388.534656 -400.811238) (xy 388.535142 -400.783969)
			(xy 388.542904 -400.729985) (xy 388.558269 -400.677655) (xy 388.580926 -400.628045) (xy 388.610412 -400.582164)
			(xy 388.646127 -400.540947) (xy 388.687344 -400.505232) (xy 388.733225 -400.475746) (xy 388.782835 -400.453089)
			(xy 388.835165 -400.437724) (xy 388.889149 -400.429962) (xy 388.943687 -400.429962) (xy 388.997671 -400.437724)
			(xy 389.050001 -400.453089) (xy 389.099611 -400.475746) (xy 389.145492 -400.505232) (xy 389.186709 -400.540947)
			(xy 389.222424 -400.582164) (xy 389.25191 -400.628045) (xy 389.274567 -400.677655) (xy 389.289932 -400.729985)
			(xy 389.297694 -400.783969) (xy 389.29818 -400.811238) (xy 389.29818 -401.674838) (xy 403.06244 -401.674838)
			(xy 403.06244 -400.811238) (xy 403.062926 -400.783969) (xy 403.070688 -400.729985) (xy 403.086053 -400.677655)
			(xy 403.10871 -400.628045) (xy 403.138196 -400.582164) (xy 403.173911 -400.540947) (xy 403.215128 -400.505232)
			(xy 403.261009 -400.475746) (xy 403.310619 -400.453089) (xy 403.362949 -400.437724) (xy 403.416933 -400.429962)
			(xy 403.471471 -400.429962) (xy 403.525455 -400.437724) (xy 403.577785 -400.453089) (xy 403.627395 -400.475746)
			(xy 403.673276 -400.505232) (xy 403.714493 -400.540947) (xy 403.750208 -400.582164) (xy 403.779694 -400.628045)
			(xy 403.802351 -400.677655) (xy 403.817716 -400.729985) (xy 403.825478 -400.783969) (xy 403.825964 -400.811238)
			(xy 403.825964 -401.674838) (xy 404.262336 -401.674838) (xy 404.262336 -400.811238) (xy 404.262822 -400.783969)
			(xy 404.270584 -400.729985) (xy 404.285949 -400.677655) (xy 404.308606 -400.628045) (xy 404.338092 -400.582164)
			(xy 404.373807 -400.540947) (xy 404.415024 -400.505232) (xy 404.460905 -400.475746) (xy 404.510515 -400.453089)
			(xy 404.562845 -400.437724) (xy 404.616829 -400.429962) (xy 404.671367 -400.429962) (xy 404.725351 -400.437724)
			(xy 404.777681 -400.453089) (xy 404.827291 -400.475746) (xy 404.873172 -400.505232) (xy 404.914389 -400.540947)
			(xy 404.950104 -400.582164) (xy 404.97959 -400.628045) (xy 405.002247 -400.677655) (xy 405.017612 -400.729985)
			(xy 405.025374 -400.783969) (xy 405.02586 -400.811238) (xy 405.02586 -401.674838) (xy 405.46274 -401.674838)
			(xy 405.46274 -400.811238) (xy 405.463226 -400.783987) (xy 405.470982 -400.730039) (xy 405.486337 -400.677744)
			(xy 405.508979 -400.628167) (xy 405.538445 -400.582317) (xy 405.574136 -400.541126) (xy 405.615327 -400.505435)
			(xy 405.661177 -400.475969) (xy 405.710754 -400.453327) (xy 405.763049 -400.437972) (xy 405.816997 -400.430216)
			(xy 405.871499 -400.430216) (xy 405.925447 -400.437972) (xy 405.977742 -400.453327) (xy 406.027319 -400.475969)
			(xy 406.073169 -400.505435) (xy 406.11436 -400.541126) (xy 406.150051 -400.582317) (xy 406.179517 -400.628167)
			(xy 406.202159 -400.677744) (xy 406.217514 -400.730039) (xy 406.22527 -400.783987) (xy 406.225756 -400.811238)
			(xy 406.225756 -401.674838) (xy 406.662636 -401.674838) (xy 406.662636 -400.811238) (xy 406.663122 -400.783987)
			(xy 406.670878 -400.730039) (xy 406.686233 -400.677744) (xy 406.708875 -400.628167) (xy 406.738341 -400.582317)
			(xy 406.774032 -400.541126) (xy 406.815223 -400.505435) (xy 406.861073 -400.475969) (xy 406.91065 -400.453327)
			(xy 406.962945 -400.437972) (xy 407.016893 -400.430216) (xy 407.071395 -400.430216) (xy 407.125343 -400.437972)
			(xy 407.177638 -400.453327) (xy 407.227215 -400.475969) (xy 407.273065 -400.505435) (xy 407.314256 -400.541126)
			(xy 407.349947 -400.582317) (xy 407.379413 -400.628167) (xy 407.402055 -400.677744) (xy 407.41741 -400.730039)
			(xy 407.425166 -400.783987) (xy 407.425652 -400.811238) (xy 407.425652 -401.674838) (xy 407.862532 -401.674838)
			(xy 407.862532 -400.811238) (xy 407.863018 -400.783969) (xy 407.87078 -400.729985) (xy 407.886145 -400.677655)
			(xy 407.908802 -400.628045) (xy 407.938288 -400.582164) (xy 407.974003 -400.540947) (xy 408.01522 -400.505232)
			(xy 408.061101 -400.475746) (xy 408.110711 -400.453089) (xy 408.163041 -400.437724) (xy 408.217025 -400.429962)
			(xy 408.271563 -400.429962) (xy 408.325547 -400.437724) (xy 408.377877 -400.453089) (xy 408.427487 -400.475746)
			(xy 408.473368 -400.505232) (xy 408.514585 -400.540947) (xy 408.5503 -400.582164) (xy 408.579786 -400.628045)
			(xy 408.602443 -400.677655) (xy 408.617808 -400.729985) (xy 408.62557 -400.783969) (xy 408.626056 -400.811238)
			(xy 408.626056 -401.674838) (xy 409.062428 -401.674838) (xy 409.062428 -400.811238) (xy 409.062914 -400.783969)
			(xy 409.070676 -400.729985) (xy 409.086041 -400.677655) (xy 409.108698 -400.628045) (xy 409.138184 -400.582164)
			(xy 409.173899 -400.540947) (xy 409.215116 -400.505232) (xy 409.260997 -400.475746) (xy 409.310607 -400.453089)
			(xy 409.362937 -400.437724) (xy 409.416921 -400.429962) (xy 409.471459 -400.429962) (xy 409.525443 -400.437724)
			(xy 409.577773 -400.453089) (xy 409.627383 -400.475746) (xy 409.673264 -400.505232) (xy 409.714481 -400.540947)
			(xy 409.750196 -400.582164) (xy 409.779682 -400.628045) (xy 409.802339 -400.677655) (xy 409.817704 -400.729985)
			(xy 409.825466 -400.783969) (xy 409.825952 -400.811238) (xy 409.825952 -401.674838) (xy 410.262832 -401.674838)
			(xy 410.262832 -400.811238) (xy 410.263318 -400.783987) (xy 410.271074 -400.730039) (xy 410.286429 -400.677744)
			(xy 410.309071 -400.628167) (xy 410.338537 -400.582317) (xy 410.374228 -400.541126) (xy 410.415419 -400.505435)
			(xy 410.461269 -400.475969) (xy 410.510846 -400.453327) (xy 410.563141 -400.437972) (xy 410.617089 -400.430216)
			(xy 410.671591 -400.430216) (xy 410.725539 -400.437972) (xy 410.777834 -400.453327) (xy 410.827411 -400.475969)
			(xy 410.873261 -400.505435) (xy 410.914452 -400.541126) (xy 410.950143 -400.582317) (xy 410.979609 -400.628167)
			(xy 411.002251 -400.677744) (xy 411.017606 -400.730039) (xy 411.025362 -400.783987) (xy 411.025848 -400.811238)
			(xy 411.025848 -401.674838) (xy 411.462728 -401.674838) (xy 411.462728 -400.811238) (xy 411.463214 -400.783987)
			(xy 411.47097 -400.730039) (xy 411.486325 -400.677744) (xy 411.508967 -400.628167) (xy 411.538433 -400.582317)
			(xy 411.574124 -400.541126) (xy 411.615315 -400.505435) (xy 411.661165 -400.475969) (xy 411.710742 -400.453327)
			(xy 411.763037 -400.437972) (xy 411.816985 -400.430216) (xy 411.871487 -400.430216) (xy 411.925435 -400.437972)
			(xy 411.97773 -400.453327) (xy 412.027307 -400.475969) (xy 412.073157 -400.505435) (xy 412.114348 -400.541126)
			(xy 412.150039 -400.582317) (xy 412.179505 -400.628167) (xy 412.202147 -400.677744) (xy 412.217502 -400.730039)
			(xy 412.225258 -400.783987) (xy 412.225744 -400.811238) (xy 412.225744 -401.674838) (xy 412.662624 -401.674838)
			(xy 412.662624 -400.811238) (xy 412.66311 -400.783969) (xy 412.670872 -400.729985) (xy 412.686237 -400.677655)
			(xy 412.708894 -400.628045) (xy 412.73838 -400.582164) (xy 412.774095 -400.540947) (xy 412.815312 -400.505232)
			(xy 412.861193 -400.475746) (xy 412.910803 -400.453089) (xy 412.963133 -400.437724) (xy 413.017117 -400.429962)
			(xy 413.071655 -400.429962) (xy 413.125639 -400.437724) (xy 413.177969 -400.453089) (xy 413.227579 -400.475746)
			(xy 413.27346 -400.505232) (xy 413.314677 -400.540947) (xy 413.350392 -400.582164) (xy 413.379878 -400.628045)
			(xy 413.402535 -400.677655) (xy 413.4179 -400.729985) (xy 413.425662 -400.783969) (xy 413.426148 -400.811238)
			(xy 413.426148 -401.674838) (xy 413.86252 -401.674838) (xy 413.86252 -400.811238) (xy 413.863006 -400.783969)
			(xy 413.870768 -400.729985) (xy 413.886133 -400.677655) (xy 413.90879 -400.628045) (xy 413.938276 -400.582164)
			(xy 413.973991 -400.540947) (xy 414.015208 -400.505232) (xy 414.061089 -400.475746) (xy 414.110699 -400.453089)
			(xy 414.163029 -400.437724) (xy 414.217013 -400.429962) (xy 414.271551 -400.429962) (xy 414.325535 -400.437724)
			(xy 414.377865 -400.453089) (xy 414.427475 -400.475746) (xy 414.473356 -400.505232) (xy 414.514573 -400.540947)
			(xy 414.550288 -400.582164) (xy 414.579774 -400.628045) (xy 414.602431 -400.677655) (xy 414.617796 -400.729985)
			(xy 414.625558 -400.783969) (xy 414.626044 -400.811238) (xy 414.626044 -401.674838) (xy 415.062924 -401.674838)
			(xy 415.062924 -400.811238) (xy 415.06341 -400.783987) (xy 415.071166 -400.730039) (xy 415.086521 -400.677744)
			(xy 415.109163 -400.628167) (xy 415.138629 -400.582317) (xy 415.17432 -400.541126) (xy 415.215511 -400.505435)
			(xy 415.261361 -400.475969) (xy 415.310938 -400.453327) (xy 415.363233 -400.437972) (xy 415.417181 -400.430216)
			(xy 415.471683 -400.430216) (xy 415.525631 -400.437972) (xy 415.577926 -400.453327) (xy 415.627503 -400.475969)
			(xy 415.673353 -400.505435) (xy 415.714544 -400.541126) (xy 415.750235 -400.582317) (xy 415.779701 -400.628167)
			(xy 415.802343 -400.677744) (xy 415.817698 -400.730039) (xy 415.825454 -400.783987) (xy 415.82594 -400.811238)
			(xy 415.82594 -401.674838) (xy 416.26282 -401.674838) (xy 416.26282 -400.811238) (xy 416.263306 -400.783987)
			(xy 416.271062 -400.730039) (xy 416.286417 -400.677744) (xy 416.309059 -400.628167) (xy 416.338525 -400.582317)
			(xy 416.374216 -400.541126) (xy 416.415407 -400.505435) (xy 416.461257 -400.475969) (xy 416.510834 -400.453327)
			(xy 416.563129 -400.437972) (xy 416.617077 -400.430216) (xy 416.671579 -400.430216) (xy 416.725527 -400.437972)
			(xy 416.777822 -400.453327) (xy 416.827399 -400.475969) (xy 416.873249 -400.505435) (xy 416.91444 -400.541126)
			(xy 416.950131 -400.582317) (xy 416.979597 -400.628167) (xy 417.002239 -400.677744) (xy 417.017594 -400.730039)
			(xy 417.02535 -400.783987) (xy 417.025836 -400.811238) (xy 417.025836 -401.674838) (xy 417.462716 -401.674838)
			(xy 417.462716 -400.811238) (xy 417.463202 -400.783987) (xy 417.470958 -400.730039) (xy 417.486313 -400.677744)
			(xy 417.508955 -400.628167) (xy 417.538421 -400.582317) (xy 417.574112 -400.541126) (xy 417.615303 -400.505435)
			(xy 417.661153 -400.475969) (xy 417.71073 -400.453327) (xy 417.763025 -400.437972) (xy 417.816973 -400.430216)
			(xy 417.871475 -400.430216) (xy 417.925423 -400.437972) (xy 417.977718 -400.453327) (xy 418.027295 -400.475969)
			(xy 418.073145 -400.505435) (xy 418.114336 -400.541126) (xy 418.150027 -400.582317) (xy 418.179493 -400.628167)
			(xy 418.202135 -400.677744) (xy 418.21749 -400.730039) (xy 418.225246 -400.783987) (xy 418.225732 -400.811238)
			(xy 418.225732 -401.674838) (xy 418.662612 -401.674838) (xy 418.662612 -400.811238) (xy 418.663098 -400.783987)
			(xy 418.670854 -400.730039) (xy 418.686209 -400.677744) (xy 418.708851 -400.628167) (xy 418.738317 -400.582317)
			(xy 418.774008 -400.541126) (xy 418.815199 -400.505435) (xy 418.861049 -400.475969) (xy 418.910626 -400.453327)
			(xy 418.962921 -400.437972) (xy 419.016869 -400.430216) (xy 419.071371 -400.430216) (xy 419.125319 -400.437972)
			(xy 419.177614 -400.453327) (xy 419.227191 -400.475969) (xy 419.273041 -400.505435) (xy 419.314232 -400.541126)
			(xy 419.349923 -400.582317) (xy 419.379389 -400.628167) (xy 419.402031 -400.677744) (xy 419.417386 -400.730039)
			(xy 419.425142 -400.783987) (xy 419.425628 -400.811238) (xy 419.425628 -401.674838) (xy 419.862508 -401.674838)
			(xy 419.862508 -400.811238) (xy 419.862994 -400.783969) (xy 419.870756 -400.729985) (xy 419.886121 -400.677655)
			(xy 419.908778 -400.628045) (xy 419.938264 -400.582164) (xy 419.973979 -400.540947) (xy 420.015196 -400.505232)
			(xy 420.061077 -400.475746) (xy 420.110687 -400.453089) (xy 420.163017 -400.437724) (xy 420.217001 -400.429962)
			(xy 420.271539 -400.429962) (xy 420.325523 -400.437724) (xy 420.377853 -400.453089) (xy 420.427463 -400.475746)
			(xy 420.473344 -400.505232) (xy 420.514561 -400.540947) (xy 420.550276 -400.582164) (xy 420.579762 -400.628045)
			(xy 420.602419 -400.677655) (xy 420.617784 -400.729985) (xy 420.625546 -400.783969) (xy 420.626032 -400.811238)
			(xy 420.626032 -401.674838) (xy 421.062404 -401.674838) (xy 421.062404 -400.811238) (xy 421.06289 -400.783969)
			(xy 421.070652 -400.729985) (xy 421.086017 -400.677655) (xy 421.108674 -400.628045) (xy 421.13816 -400.582164)
			(xy 421.173875 -400.540947) (xy 421.215092 -400.505232) (xy 421.260973 -400.475746) (xy 421.310583 -400.453089)
			(xy 421.362913 -400.437724) (xy 421.416897 -400.429962) (xy 421.471435 -400.429962) (xy 421.525419 -400.437724)
			(xy 421.577749 -400.453089) (xy 421.627359 -400.475746) (xy 421.67324 -400.505232) (xy 421.714457 -400.540947)
			(xy 421.750172 -400.582164) (xy 421.779658 -400.628045) (xy 421.802315 -400.677655) (xy 421.81768 -400.729985)
			(xy 421.825442 -400.783969) (xy 421.825928 -400.811238) (xy 421.825928 -401.674838) (xy 421.825442 -401.702107)
			(xy 421.81768 -401.756091) (xy 421.802315 -401.808421) (xy 421.779658 -401.858031) (xy 421.750172 -401.903912)
			(xy 421.714457 -401.945129) (xy 421.67324 -401.980844) (xy 421.627359 -402.01033) (xy 421.577749 -402.032987)
			(xy 421.525419 -402.048352) (xy 421.471435 -402.056114) (xy 421.416897 -402.056114) (xy 421.362913 -402.048352)
			(xy 421.310583 -402.032987) (xy 421.260973 -402.01033) (xy 421.215092 -401.980844) (xy 421.173875 -401.945129)
			(xy 421.13816 -401.903912) (xy 421.108674 -401.858031) (xy 421.086017 -401.808421) (xy 421.070652 -401.756091)
			(xy 421.06289 -401.702107) (xy 421.062404 -401.674838) (xy 420.626032 -401.674838) (xy 420.625546 -401.702107)
			(xy 420.617784 -401.756091) (xy 420.602419 -401.808421) (xy 420.579762 -401.858031) (xy 420.550276 -401.903912)
			(xy 420.514561 -401.945129) (xy 420.473344 -401.980844) (xy 420.427463 -402.01033) (xy 420.377853 -402.032987)
			(xy 420.325523 -402.048352) (xy 420.271539 -402.056114) (xy 420.217001 -402.056114) (xy 420.163017 -402.048352)
			(xy 420.110687 -402.032987) (xy 420.061077 -402.01033) (xy 420.015196 -401.980844) (xy 419.973979 -401.945129)
			(xy 419.938264 -401.903912) (xy 419.908778 -401.858031) (xy 419.886121 -401.808421) (xy 419.870756 -401.756091)
			(xy 419.862994 -401.702107) (xy 419.862508 -401.674838) (xy 419.425628 -401.674838) (xy 419.425142 -401.702089)
			(xy 419.417386 -401.756037) (xy 419.402031 -401.808332) (xy 419.379389 -401.857909) (xy 419.349923 -401.903759)
			(xy 419.314232 -401.94495) (xy 419.273041 -401.980641) (xy 419.227191 -402.010107) (xy 419.177614 -402.032749)
			(xy 419.125319 -402.048104) (xy 419.071371 -402.05586) (xy 419.016869 -402.05586) (xy 418.962921 -402.048104)
			(xy 418.910626 -402.032749) (xy 418.861049 -402.010107) (xy 418.815199 -401.980641) (xy 418.774008 -401.94495)
			(xy 418.738317 -401.903759) (xy 418.708851 -401.857909) (xy 418.686209 -401.808332) (xy 418.670854 -401.756037)
			(xy 418.663098 -401.702089) (xy 418.662612 -401.674838) (xy 418.225732 -401.674838) (xy 418.225246 -401.702089)
			(xy 418.21749 -401.756037) (xy 418.202135 -401.808332) (xy 418.179493 -401.857909) (xy 418.150027 -401.903759)
			(xy 418.114336 -401.94495) (xy 418.073145 -401.980641) (xy 418.027295 -402.010107) (xy 417.977718 -402.032749)
			(xy 417.925423 -402.048104) (xy 417.871475 -402.05586) (xy 417.816973 -402.05586) (xy 417.763025 -402.048104)
			(xy 417.71073 -402.032749) (xy 417.661153 -402.010107) (xy 417.615303 -401.980641) (xy 417.574112 -401.94495)
			(xy 417.538421 -401.903759) (xy 417.508955 -401.857909) (xy 417.486313 -401.808332) (xy 417.470958 -401.756037)
			(xy 417.463202 -401.702089) (xy 417.462716 -401.674838) (xy 417.025836 -401.674838) (xy 417.02535 -401.702089)
			(xy 417.017594 -401.756037) (xy 417.002239 -401.808332) (xy 416.979597 -401.857909) (xy 416.950131 -401.903759)
			(xy 416.91444 -401.94495) (xy 416.873249 -401.980641) (xy 416.827399 -402.010107) (xy 416.777822 -402.032749)
			(xy 416.725527 -402.048104) (xy 416.671579 -402.05586) (xy 416.617077 -402.05586) (xy 416.563129 -402.048104)
			(xy 416.510834 -402.032749) (xy 416.461257 -402.010107) (xy 416.415407 -401.980641) (xy 416.374216 -401.94495)
			(xy 416.338525 -401.903759) (xy 416.309059 -401.857909) (xy 416.286417 -401.808332) (xy 416.271062 -401.756037)
			(xy 416.263306 -401.702089) (xy 416.26282 -401.674838) (xy 415.82594 -401.674838) (xy 415.825454 -401.702089)
			(xy 415.817698 -401.756037) (xy 415.802343 -401.808332) (xy 415.779701 -401.857909) (xy 415.750235 -401.903759)
			(xy 415.714544 -401.94495) (xy 415.673353 -401.980641) (xy 415.627503 -402.010107) (xy 415.577926 -402.032749)
			(xy 415.525631 -402.048104) (xy 415.471683 -402.05586) (xy 415.417181 -402.05586) (xy 415.363233 -402.048104)
			(xy 415.310938 -402.032749) (xy 415.261361 -402.010107) (xy 415.215511 -401.980641) (xy 415.17432 -401.94495)
			(xy 415.138629 -401.903759) (xy 415.109163 -401.857909) (xy 415.086521 -401.808332) (xy 415.071166 -401.756037)
			(xy 415.06341 -401.702089) (xy 415.062924 -401.674838) (xy 414.626044 -401.674838) (xy 414.625558 -401.702107)
			(xy 414.617796 -401.756091) (xy 414.602431 -401.808421) (xy 414.579774 -401.858031) (xy 414.550288 -401.903912)
			(xy 414.514573 -401.945129) (xy 414.473356 -401.980844) (xy 414.427475 -402.01033) (xy 414.377865 -402.032987)
			(xy 414.325535 -402.048352) (xy 414.271551 -402.056114) (xy 414.217013 -402.056114) (xy 414.163029 -402.048352)
			(xy 414.110699 -402.032987) (xy 414.061089 -402.01033) (xy 414.015208 -401.980844) (xy 413.973991 -401.945129)
			(xy 413.938276 -401.903912) (xy 413.90879 -401.858031) (xy 413.886133 -401.808421) (xy 413.870768 -401.756091)
			(xy 413.863006 -401.702107) (xy 413.86252 -401.674838) (xy 413.426148 -401.674838) (xy 413.425662 -401.702107)
			(xy 413.4179 -401.756091) (xy 413.402535 -401.808421) (xy 413.379878 -401.858031) (xy 413.350392 -401.903912)
			(xy 413.314677 -401.945129) (xy 413.27346 -401.980844) (xy 413.227579 -402.01033) (xy 413.177969 -402.032987)
			(xy 413.125639 -402.048352) (xy 413.071655 -402.056114) (xy 413.017117 -402.056114) (xy 412.963133 -402.048352)
			(xy 412.910803 -402.032987) (xy 412.861193 -402.01033) (xy 412.815312 -401.980844) (xy 412.774095 -401.945129)
			(xy 412.73838 -401.903912) (xy 412.708894 -401.858031) (xy 412.686237 -401.808421) (xy 412.670872 -401.756091)
			(xy 412.66311 -401.702107) (xy 412.662624 -401.674838) (xy 412.225744 -401.674838) (xy 412.225258 -401.702089)
			(xy 412.217502 -401.756037) (xy 412.202147 -401.808332) (xy 412.179505 -401.857909) (xy 412.150039 -401.903759)
			(xy 412.114348 -401.94495) (xy 412.073157 -401.980641) (xy 412.027307 -402.010107) (xy 411.97773 -402.032749)
			(xy 411.925435 -402.048104) (xy 411.871487 -402.05586) (xy 411.816985 -402.05586) (xy 411.763037 -402.048104)
			(xy 411.710742 -402.032749) (xy 411.661165 -402.010107) (xy 411.615315 -401.980641) (xy 411.574124 -401.94495)
			(xy 411.538433 -401.903759) (xy 411.508967 -401.857909) (xy 411.486325 -401.808332) (xy 411.47097 -401.756037)
			(xy 411.463214 -401.702089) (xy 411.462728 -401.674838) (xy 411.025848 -401.674838) (xy 411.025362 -401.702089)
			(xy 411.017606 -401.756037) (xy 411.002251 -401.808332) (xy 410.979609 -401.857909) (xy 410.950143 -401.903759)
			(xy 410.914452 -401.94495) (xy 410.873261 -401.980641) (xy 410.827411 -402.010107) (xy 410.777834 -402.032749)
			(xy 410.725539 -402.048104) (xy 410.671591 -402.05586) (xy 410.617089 -402.05586) (xy 410.563141 -402.048104)
			(xy 410.510846 -402.032749) (xy 410.461269 -402.010107) (xy 410.415419 -401.980641) (xy 410.374228 -401.94495)
			(xy 410.338537 -401.903759) (xy 410.309071 -401.857909) (xy 410.286429 -401.808332) (xy 410.271074 -401.756037)
			(xy 410.263318 -401.702089) (xy 410.262832 -401.674838) (xy 409.825952 -401.674838) (xy 409.825466 -401.702107)
			(xy 409.817704 -401.756091) (xy 409.802339 -401.808421) (xy 409.779682 -401.858031) (xy 409.750196 -401.903912)
			(xy 409.714481 -401.945129) (xy 409.673264 -401.980844) (xy 409.627383 -402.01033) (xy 409.577773 -402.032987)
			(xy 409.525443 -402.048352) (xy 409.471459 -402.056114) (xy 409.416921 -402.056114) (xy 409.362937 -402.048352)
			(xy 409.310607 -402.032987) (xy 409.260997 -402.01033) (xy 409.215116 -401.980844) (xy 409.173899 -401.945129)
			(xy 409.138184 -401.903912) (xy 409.108698 -401.858031) (xy 409.086041 -401.808421) (xy 409.070676 -401.756091)
			(xy 409.062914 -401.702107) (xy 409.062428 -401.674838) (xy 408.626056 -401.674838) (xy 408.62557 -401.702107)
			(xy 408.617808 -401.756091) (xy 408.602443 -401.808421) (xy 408.579786 -401.858031) (xy 408.5503 -401.903912)
			(xy 408.514585 -401.945129) (xy 408.473368 -401.980844) (xy 408.427487 -402.01033) (xy 408.377877 -402.032987)
			(xy 408.325547 -402.048352) (xy 408.271563 -402.056114) (xy 408.217025 -402.056114) (xy 408.163041 -402.048352)
			(xy 408.110711 -402.032987) (xy 408.061101 -402.01033) (xy 408.01522 -401.980844) (xy 407.974003 -401.945129)
			(xy 407.938288 -401.903912) (xy 407.908802 -401.858031) (xy 407.886145 -401.808421) (xy 407.87078 -401.756091)
			(xy 407.863018 -401.702107) (xy 407.862532 -401.674838) (xy 407.425652 -401.674838) (xy 407.425166 -401.702089)
			(xy 407.41741 -401.756037) (xy 407.402055 -401.808332) (xy 407.379413 -401.857909) (xy 407.349947 -401.903759)
			(xy 407.314256 -401.94495) (xy 407.273065 -401.980641) (xy 407.227215 -402.010107) (xy 407.177638 -402.032749)
			(xy 407.125343 -402.048104) (xy 407.071395 -402.05586) (xy 407.016893 -402.05586) (xy 406.962945 -402.048104)
			(xy 406.91065 -402.032749) (xy 406.861073 -402.010107) (xy 406.815223 -401.980641) (xy 406.774032 -401.94495)
			(xy 406.738341 -401.903759) (xy 406.708875 -401.857909) (xy 406.686233 -401.808332) (xy 406.670878 -401.756037)
			(xy 406.663122 -401.702089) (xy 406.662636 -401.674838) (xy 406.225756 -401.674838) (xy 406.22527 -401.702089)
			(xy 406.217514 -401.756037) (xy 406.202159 -401.808332) (xy 406.179517 -401.857909) (xy 406.150051 -401.903759)
			(xy 406.11436 -401.94495) (xy 406.073169 -401.980641) (xy 406.027319 -402.010107) (xy 405.977742 -402.032749)
			(xy 405.925447 -402.048104) (xy 405.871499 -402.05586) (xy 405.816997 -402.05586) (xy 405.763049 -402.048104)
			(xy 405.710754 -402.032749) (xy 405.661177 -402.010107) (xy 405.615327 -401.980641) (xy 405.574136 -401.94495)
			(xy 405.538445 -401.903759) (xy 405.508979 -401.857909) (xy 405.486337 -401.808332) (xy 405.470982 -401.756037)
			(xy 405.463226 -401.702089) (xy 405.46274 -401.674838) (xy 405.02586 -401.674838) (xy 405.025374 -401.702107)
			(xy 405.017612 -401.756091) (xy 405.002247 -401.808421) (xy 404.97959 -401.858031) (xy 404.950104 -401.903912)
			(xy 404.914389 -401.945129) (xy 404.873172 -401.980844) (xy 404.827291 -402.01033) (xy 404.777681 -402.032987)
			(xy 404.725351 -402.048352) (xy 404.671367 -402.056114) (xy 404.616829 -402.056114) (xy 404.562845 -402.048352)
			(xy 404.510515 -402.032987) (xy 404.460905 -402.01033) (xy 404.415024 -401.980844) (xy 404.373807 -401.945129)
			(xy 404.338092 -401.903912) (xy 404.308606 -401.858031) (xy 404.285949 -401.808421) (xy 404.270584 -401.756091)
			(xy 404.262822 -401.702107) (xy 404.262336 -401.674838) (xy 403.825964 -401.674838) (xy 403.825478 -401.702107)
			(xy 403.817716 -401.756091) (xy 403.802351 -401.808421) (xy 403.779694 -401.858031) (xy 403.750208 -401.903912)
			(xy 403.714493 -401.945129) (xy 403.673276 -401.980844) (xy 403.627395 -402.01033) (xy 403.577785 -402.032987)
			(xy 403.525455 -402.048352) (xy 403.471471 -402.056114) (xy 403.416933 -402.056114) (xy 403.362949 -402.048352)
			(xy 403.310619 -402.032987) (xy 403.261009 -402.01033) (xy 403.215128 -401.980844) (xy 403.173911 -401.945129)
			(xy 403.138196 -401.903912) (xy 403.10871 -401.858031) (xy 403.086053 -401.808421) (xy 403.070688 -401.756091)
			(xy 403.062926 -401.702107) (xy 403.06244 -401.674838) (xy 389.29818 -401.674838) (xy 389.297694 -401.702107)
			(xy 389.289932 -401.756091) (xy 389.274567 -401.808421) (xy 389.25191 -401.858031) (xy 389.222424 -401.903912)
			(xy 389.186709 -401.945129) (xy 389.145492 -401.980844) (xy 389.099611 -402.01033) (xy 389.050001 -402.032987)
			(xy 388.997671 -402.048352) (xy 388.943687 -402.056114) (xy 388.889149 -402.056114) (xy 388.835165 -402.048352)
			(xy 388.782835 -402.032987) (xy 388.733225 -402.01033) (xy 388.687344 -401.980844) (xy 388.646127 -401.945129)
			(xy 388.610412 -401.903912) (xy 388.580926 -401.858031) (xy 388.558269 -401.808421) (xy 388.542904 -401.756091)
			(xy 388.535142 -401.702107) (xy 388.534656 -401.674838) (xy 388.098284 -401.674838) (xy 388.097798 -401.702107)
			(xy 388.090036 -401.756091) (xy 388.074671 -401.808421) (xy 388.052014 -401.858031) (xy 388.022528 -401.903912)
			(xy 387.986813 -401.945129) (xy 387.945596 -401.980844) (xy 387.899715 -402.01033) (xy 387.850105 -402.032987)
			(xy 387.797775 -402.048352) (xy 387.743791 -402.056114) (xy 387.689253 -402.056114) (xy 387.635269 -402.048352)
			(xy 387.582939 -402.032987) (xy 387.533329 -402.01033) (xy 387.487448 -401.980844) (xy 387.446231 -401.945129)
			(xy 387.410516 -401.903912) (xy 387.38103 -401.858031) (xy 387.358373 -401.808421) (xy 387.343008 -401.756091)
			(xy 387.335246 -401.702107) (xy 387.33476 -401.674838) (xy 386.89788 -401.674838) (xy 386.897394 -401.702089)
			(xy 386.889638 -401.756037) (xy 386.874283 -401.808332) (xy 386.851641 -401.857909) (xy 386.822175 -401.903759)
			(xy 386.786484 -401.94495) (xy 386.745293 -401.980641) (xy 386.699443 -402.010107) (xy 386.649866 -402.032749)
			(xy 386.597571 -402.048104) (xy 386.543623 -402.05586) (xy 386.489121 -402.05586) (xy 386.435173 -402.048104)
			(xy 386.382878 -402.032749) (xy 386.333301 -402.010107) (xy 386.287451 -401.980641) (xy 386.24626 -401.94495)
			(xy 386.210569 -401.903759) (xy 386.181103 -401.857909) (xy 386.158461 -401.808332) (xy 386.143106 -401.756037)
			(xy 386.13535 -401.702089) (xy 386.134864 -401.674838) (xy 385.697984 -401.674838) (xy 385.697498 -401.702089)
			(xy 385.689742 -401.756037) (xy 385.674387 -401.808332) (xy 385.651745 -401.857909) (xy 385.622279 -401.903759)
			(xy 385.586588 -401.94495) (xy 385.545397 -401.980641) (xy 385.499547 -402.010107) (xy 385.44997 -402.032749)
			(xy 385.397675 -402.048104) (xy 385.343727 -402.05586) (xy 385.289225 -402.05586) (xy 385.235277 -402.048104)
			(xy 385.182982 -402.032749) (xy 385.133405 -402.010107) (xy 385.087555 -401.980641) (xy 385.046364 -401.94495)
			(xy 385.010673 -401.903759) (xy 384.981207 -401.857909) (xy 384.958565 -401.808332) (xy 384.94321 -401.756037)
			(xy 384.935454 -401.702089) (xy 384.934968 -401.674838) (xy 384.498088 -401.674838) (xy 384.497602 -401.702089)
			(xy 384.489846 -401.756037) (xy 384.474491 -401.808332) (xy 384.451849 -401.857909) (xy 384.422383 -401.903759)
			(xy 384.386692 -401.94495) (xy 384.345501 -401.980641) (xy 384.299651 -402.010107) (xy 384.250074 -402.032749)
			(xy 384.197779 -402.048104) (xy 384.143831 -402.05586) (xy 384.089329 -402.05586) (xy 384.035381 -402.048104)
			(xy 383.983086 -402.032749) (xy 383.933509 -402.010107) (xy 383.887659 -401.980641) (xy 383.846468 -401.94495)
			(xy 383.810777 -401.903759) (xy 383.781311 -401.857909) (xy 383.758669 -401.808332) (xy 383.743314 -401.756037)
			(xy 383.735558 -401.702089) (xy 383.735072 -401.674838) (xy 383.298192 -401.674838) (xy 383.297706 -401.702089)
			(xy 383.28995 -401.756037) (xy 383.274595 -401.808332) (xy 383.251953 -401.857909) (xy 383.222487 -401.903759)
			(xy 383.186796 -401.94495) (xy 383.145605 -401.980641) (xy 383.099755 -402.010107) (xy 383.050178 -402.032749)
			(xy 382.997883 -402.048104) (xy 382.943935 -402.05586) (xy 382.889433 -402.05586) (xy 382.835485 -402.048104)
			(xy 382.78319 -402.032749) (xy 382.733613 -402.010107) (xy 382.687763 -401.980641) (xy 382.646572 -401.94495)
			(xy 382.610881 -401.903759) (xy 382.581415 -401.857909) (xy 382.558773 -401.808332) (xy 382.543418 -401.756037)
			(xy 382.535662 -401.702089) (xy 382.535176 -401.674838) (xy 382.098296 -401.674838) (xy 382.09781 -401.702107)
			(xy 382.090048 -401.756091) (xy 382.074683 -401.808421) (xy 382.052026 -401.858031) (xy 382.02254 -401.903912)
			(xy 381.986825 -401.945129) (xy 381.945608 -401.980844) (xy 381.899727 -402.01033) (xy 381.850117 -402.032987)
			(xy 381.797787 -402.048352) (xy 381.743803 -402.056114) (xy 381.689265 -402.056114) (xy 381.635281 -402.048352)
			(xy 381.582951 -402.032987) (xy 381.533341 -402.01033) (xy 381.48746 -401.980844) (xy 381.446243 -401.945129)
			(xy 381.410528 -401.903912) (xy 381.381042 -401.858031) (xy 381.358385 -401.808421) (xy 381.34302 -401.756091)
			(xy 381.335258 -401.702107) (xy 381.334772 -401.674838) (xy 380.8984 -401.674838) (xy 380.897914 -401.702107)
			(xy 380.890152 -401.756091) (xy 380.874787 -401.808421) (xy 380.85213 -401.858031) (xy 380.822644 -401.903912)
			(xy 380.786929 -401.945129) (xy 380.745712 -401.980844) (xy 380.699831 -402.01033) (xy 380.650221 -402.032987)
			(xy 380.597891 -402.048352) (xy 380.543907 -402.056114) (xy 380.489369 -402.056114) (xy 380.435385 -402.048352)
			(xy 380.383055 -402.032987) (xy 380.333445 -402.01033) (xy 380.287564 -401.980844) (xy 380.246347 -401.945129)
			(xy 380.210632 -401.903912) (xy 380.181146 -401.858031) (xy 380.158489 -401.808421) (xy 380.143124 -401.756091)
			(xy 380.135362 -401.702107) (xy 380.134876 -401.674838) (xy 379.697996 -401.674838) (xy 379.69751 -401.702089)
			(xy 379.689754 -401.756037) (xy 379.674399 -401.808332) (xy 379.651757 -401.857909) (xy 379.622291 -401.903759)
			(xy 379.5866 -401.94495) (xy 379.545409 -401.980641) (xy 379.499559 -402.010107) (xy 379.449982 -402.032749)
			(xy 379.397687 -402.048104) (xy 379.343739 -402.05586) (xy 379.289237 -402.05586) (xy 379.235289 -402.048104)
			(xy 379.182994 -402.032749) (xy 379.133417 -402.010107) (xy 379.087567 -401.980641) (xy 379.046376 -401.94495)
			(xy 379.010685 -401.903759) (xy 378.981219 -401.857909) (xy 378.958577 -401.808332) (xy 378.943222 -401.756037)
			(xy 378.935466 -401.702089) (xy 378.93498 -401.674838) (xy 378.4981 -401.674838) (xy 378.497614 -401.702089)
			(xy 378.489858 -401.756037) (xy 378.474503 -401.808332) (xy 378.451861 -401.857909) (xy 378.422395 -401.903759)
			(xy 378.386704 -401.94495) (xy 378.345513 -401.980641) (xy 378.299663 -402.010107) (xy 378.250086 -402.032749)
			(xy 378.197791 -402.048104) (xy 378.143843 -402.05586) (xy 378.089341 -402.05586) (xy 378.035393 -402.048104)
			(xy 377.983098 -402.032749) (xy 377.933521 -402.010107) (xy 377.887671 -401.980641) (xy 377.84648 -401.94495)
			(xy 377.810789 -401.903759) (xy 377.781323 -401.857909) (xy 377.758681 -401.808332) (xy 377.743326 -401.756037)
			(xy 377.73557 -401.702089) (xy 377.735084 -401.674838) (xy 377.298204 -401.674838) (xy 377.297718 -401.702107)
			(xy 377.289956 -401.756091) (xy 377.274591 -401.808421) (xy 377.251934 -401.858031) (xy 377.222448 -401.903912)
			(xy 377.186733 -401.945129) (xy 377.145516 -401.980844) (xy 377.099635 -402.01033) (xy 377.050025 -402.032987)
			(xy 376.997695 -402.048352) (xy 376.943711 -402.056114) (xy 376.889173 -402.056114) (xy 376.835189 -402.048352)
			(xy 376.782859 -402.032987) (xy 376.733249 -402.01033) (xy 376.687368 -401.980844) (xy 376.646151 -401.945129)
			(xy 376.610436 -401.903912) (xy 376.58095 -401.858031) (xy 376.558293 -401.808421) (xy 376.542928 -401.756091)
			(xy 376.535166 -401.702107) (xy 376.53468 -401.674838) (xy 376.098308 -401.674838) (xy 376.097822 -401.702107)
			(xy 376.09006 -401.756091) (xy 376.074695 -401.808421) (xy 376.052038 -401.858031) (xy 376.022552 -401.903912)
			(xy 375.986837 -401.945129) (xy 375.94562 -401.980844) (xy 375.899739 -402.01033) (xy 375.850129 -402.032987)
			(xy 375.797799 -402.048352) (xy 375.743815 -402.056114) (xy 375.689277 -402.056114) (xy 375.635293 -402.048352)
			(xy 375.582963 -402.032987) (xy 375.533353 -402.01033) (xy 375.487472 -401.980844) (xy 375.446255 -401.945129)
			(xy 375.41054 -401.903912) (xy 375.381054 -401.858031) (xy 375.358397 -401.808421) (xy 375.343032 -401.756091)
			(xy 375.33527 -401.702107) (xy 375.334784 -401.674838) (xy 374.897904 -401.674838) (xy 374.897418 -401.702089)
			(xy 374.889662 -401.756037) (xy 374.874307 -401.808332) (xy 374.851665 -401.857909) (xy 374.822199 -401.903759)
			(xy 374.786508 -401.94495) (xy 374.745317 -401.980641) (xy 374.699467 -402.010107) (xy 374.64989 -402.032749)
			(xy 374.597595 -402.048104) (xy 374.543647 -402.05586) (xy 374.489145 -402.05586) (xy 374.435197 -402.048104)
			(xy 374.382902 -402.032749) (xy 374.333325 -402.010107) (xy 374.287475 -401.980641) (xy 374.246284 -401.94495)
			(xy 374.210593 -401.903759) (xy 374.181127 -401.857909) (xy 374.158485 -401.808332) (xy 374.14313 -401.756037)
			(xy 374.135374 -401.702089) (xy 374.134888 -401.674838) (xy 373.698008 -401.674838) (xy 373.697522 -401.702089)
			(xy 373.689766 -401.756037) (xy 373.674411 -401.808332) (xy 373.651769 -401.857909) (xy 373.622303 -401.903759)
			(xy 373.586612 -401.94495) (xy 373.545421 -401.980641) (xy 373.499571 -402.010107) (xy 373.449994 -402.032749)
			(xy 373.397699 -402.048104) (xy 373.343751 -402.05586) (xy 373.289249 -402.05586) (xy 373.235301 -402.048104)
			(xy 373.183006 -402.032749) (xy 373.133429 -402.010107) (xy 373.087579 -401.980641) (xy 373.046388 -401.94495)
			(xy 373.010697 -401.903759) (xy 372.981231 -401.857909) (xy 372.958589 -401.808332) (xy 372.943234 -401.756037)
			(xy 372.935478 -401.702089) (xy 372.934992 -401.674838) (xy 372.498112 -401.674838) (xy 372.497626 -401.702107)
			(xy 372.489864 -401.756091) (xy 372.474499 -401.808421) (xy 372.451842 -401.858031) (xy 372.422356 -401.903912)
			(xy 372.386641 -401.945129) (xy 372.345424 -401.980844) (xy 372.299543 -402.01033) (xy 372.249933 -402.032987)
			(xy 372.197603 -402.048352) (xy 372.143619 -402.056114) (xy 372.089081 -402.056114) (xy 372.035097 -402.048352)
			(xy 371.982767 -402.032987) (xy 371.933157 -402.01033) (xy 371.887276 -401.980844) (xy 371.846059 -401.945129)
			(xy 371.810344 -401.903912) (xy 371.780858 -401.858031) (xy 371.758201 -401.808421) (xy 371.742836 -401.756091)
			(xy 371.735074 -401.702107) (xy 371.734588 -401.674838) (xy 371.298216 -401.674838) (xy 371.29773 -401.702107)
			(xy 371.289968 -401.756091) (xy 371.274603 -401.808421) (xy 371.251946 -401.858031) (xy 371.22246 -401.903912)
			(xy 371.186745 -401.945129) (xy 371.145528 -401.980844) (xy 371.099647 -402.01033) (xy 371.050037 -402.032987)
			(xy 370.997707 -402.048352) (xy 370.943723 -402.056114) (xy 370.889185 -402.056114) (xy 370.835201 -402.048352)
			(xy 370.782871 -402.032987) (xy 370.733261 -402.01033) (xy 370.68738 -401.980844) (xy 370.646163 -401.945129)
			(xy 370.610448 -401.903912) (xy 370.580962 -401.858031) (xy 370.558305 -401.808421) (xy 370.54294 -401.756091)
			(xy 370.535178 -401.702107) (xy 370.534692 -401.674838) (xy 354.725732 -401.674838) (xy 354.725246 -401.702107)
			(xy 354.717484 -401.756091) (xy 354.702119 -401.808421) (xy 354.679462 -401.858031) (xy 354.649976 -401.903912)
			(xy 354.614261 -401.945129) (xy 354.573044 -401.980844) (xy 354.527163 -402.01033) (xy 354.477553 -402.032987)
			(xy 354.425223 -402.048352) (xy 354.371239 -402.056114) (xy 354.316701 -402.056114) (xy 354.262717 -402.048352)
			(xy 354.210387 -402.032987) (xy 354.160777 -402.01033) (xy 354.114896 -401.980844) (xy 354.073679 -401.945129)
			(xy 354.037964 -401.903912) (xy 354.008478 -401.858031) (xy 353.985821 -401.808421) (xy 353.970456 -401.756091)
			(xy 353.962694 -401.702107) (xy 353.962208 -401.674838) (xy 353.525836 -401.674838) (xy 353.52535 -401.702107)
			(xy 353.517588 -401.756091) (xy 353.502223 -401.808421) (xy 353.479566 -401.858031) (xy 353.45008 -401.903912)
			(xy 353.414365 -401.945129) (xy 353.373148 -401.980844) (xy 353.327267 -402.01033) (xy 353.277657 -402.032987)
			(xy 353.225327 -402.048352) (xy 353.171343 -402.056114) (xy 353.116805 -402.056114) (xy 353.062821 -402.048352)
			(xy 353.010491 -402.032987) (xy 352.960881 -402.01033) (xy 352.915 -401.980844) (xy 352.873783 -401.945129)
			(xy 352.838068 -401.903912) (xy 352.808582 -401.858031) (xy 352.785925 -401.808421) (xy 352.77056 -401.756091)
			(xy 352.762798 -401.702107) (xy 352.762312 -401.674838) (xy 352.325432 -401.674838) (xy 352.324946 -401.702089)
			(xy 352.31719 -401.756037) (xy 352.301835 -401.808332) (xy 352.279193 -401.857909) (xy 352.249727 -401.903759)
			(xy 352.214036 -401.94495) (xy 352.172845 -401.980641) (xy 352.126995 -402.010107) (xy 352.077418 -402.032749)
			(xy 352.025123 -402.048104) (xy 351.971175 -402.05586) (xy 351.916673 -402.05586) (xy 351.862725 -402.048104)
			(xy 351.81043 -402.032749) (xy 351.760853 -402.010107) (xy 351.715003 -401.980641) (xy 351.673812 -401.94495)
			(xy 351.638121 -401.903759) (xy 351.608655 -401.857909) (xy 351.586013 -401.808332) (xy 351.570658 -401.756037)
			(xy 351.562902 -401.702089) (xy 351.562416 -401.674838) (xy 351.125536 -401.674838) (xy 351.12505 -401.702089)
			(xy 351.117294 -401.756037) (xy 351.101939 -401.808332) (xy 351.079297 -401.857909) (xy 351.049831 -401.903759)
			(xy 351.01414 -401.94495) (xy 350.972949 -401.980641) (xy 350.927099 -402.010107) (xy 350.877522 -402.032749)
			(xy 350.825227 -402.048104) (xy 350.771279 -402.05586) (xy 350.716777 -402.05586) (xy 350.662829 -402.048104)
			(xy 350.610534 -402.032749) (xy 350.560957 -402.010107) (xy 350.515107 -401.980641) (xy 350.473916 -401.94495)
			(xy 350.438225 -401.903759) (xy 350.408759 -401.857909) (xy 350.386117 -401.808332) (xy 350.370762 -401.756037)
			(xy 350.363006 -401.702089) (xy 350.36252 -401.674838) (xy 349.92564 -401.674838) (xy 349.925154 -401.702089)
			(xy 349.917398 -401.756037) (xy 349.902043 -401.808332) (xy 349.879401 -401.857909) (xy 349.849935 -401.903759)
			(xy 349.814244 -401.94495) (xy 349.773053 -401.980641) (xy 349.727203 -402.010107) (xy 349.677626 -402.032749)
			(xy 349.625331 -402.048104) (xy 349.571383 -402.05586) (xy 349.516881 -402.05586) (xy 349.462933 -402.048104)
			(xy 349.410638 -402.032749) (xy 349.361061 -402.010107) (xy 349.315211 -401.980641) (xy 349.27402 -401.94495)
			(xy 349.238329 -401.903759) (xy 349.208863 -401.857909) (xy 349.186221 -401.808332) (xy 349.170866 -401.756037)
			(xy 349.16311 -401.702089) (xy 349.162624 -401.674838) (xy 348.725744 -401.674838) (xy 348.725258 -401.702089)
			(xy 348.717502 -401.756037) (xy 348.702147 -401.808332) (xy 348.679505 -401.857909) (xy 348.650039 -401.903759)
			(xy 348.614348 -401.94495) (xy 348.573157 -401.980641) (xy 348.527307 -402.010107) (xy 348.47773 -402.032749)
			(xy 348.425435 -402.048104) (xy 348.371487 -402.05586) (xy 348.316985 -402.05586) (xy 348.263037 -402.048104)
			(xy 348.210742 -402.032749) (xy 348.161165 -402.010107) (xy 348.115315 -401.980641) (xy 348.074124 -401.94495)
			(xy 348.038433 -401.903759) (xy 348.008967 -401.857909) (xy 347.986325 -401.808332) (xy 347.97097 -401.756037)
			(xy 347.963214 -401.702089) (xy 347.962728 -401.674838) (xy 347.525848 -401.674838) (xy 347.525362 -401.702107)
			(xy 347.5176 -401.756091) (xy 347.502235 -401.808421) (xy 347.479578 -401.858031) (xy 347.450092 -401.903912)
			(xy 347.414377 -401.945129) (xy 347.37316 -401.980844) (xy 347.327279 -402.01033) (xy 347.277669 -402.032987)
			(xy 347.225339 -402.048352) (xy 347.171355 -402.056114) (xy 347.116817 -402.056114) (xy 347.062833 -402.048352)
			(xy 347.010503 -402.032987) (xy 346.960893 -402.01033) (xy 346.915012 -401.980844) (xy 346.873795 -401.945129)
			(xy 346.83808 -401.903912) (xy 346.808594 -401.858031) (xy 346.785937 -401.808421) (xy 346.770572 -401.756091)
			(xy 346.76281 -401.702107) (xy 346.762324 -401.674838) (xy 346.325952 -401.674838) (xy 346.325466 -401.702107)
			(xy 346.317704 -401.756091) (xy 346.302339 -401.808421) (xy 346.279682 -401.858031) (xy 346.250196 -401.903912)
			(xy 346.214481 -401.945129) (xy 346.173264 -401.980844) (xy 346.127383 -402.01033) (xy 346.077773 -402.032987)
			(xy 346.025443 -402.048352) (xy 345.971459 -402.056114) (xy 345.916921 -402.056114) (xy 345.862937 -402.048352)
			(xy 345.810607 -402.032987) (xy 345.760997 -402.01033) (xy 345.715116 -401.980844) (xy 345.673899 -401.945129)
			(xy 345.638184 -401.903912) (xy 345.608698 -401.858031) (xy 345.586041 -401.808421) (xy 345.570676 -401.756091)
			(xy 345.562914 -401.702107) (xy 345.562428 -401.674838) (xy 345.125548 -401.674838) (xy 345.125062 -401.702089)
			(xy 345.117306 -401.756037) (xy 345.101951 -401.808332) (xy 345.079309 -401.857909) (xy 345.049843 -401.903759)
			(xy 345.014152 -401.94495) (xy 344.972961 -401.980641) (xy 344.927111 -402.010107) (xy 344.877534 -402.032749)
			(xy 344.825239 -402.048104) (xy 344.771291 -402.05586) (xy 344.716789 -402.05586) (xy 344.662841 -402.048104)
			(xy 344.610546 -402.032749) (xy 344.560969 -402.010107) (xy 344.515119 -401.980641) (xy 344.473928 -401.94495)
			(xy 344.438237 -401.903759) (xy 344.408771 -401.857909) (xy 344.386129 -401.808332) (xy 344.370774 -401.756037)
			(xy 344.363018 -401.702089) (xy 344.362532 -401.674838) (xy 343.925652 -401.674838) (xy 343.925166 -401.702089)
			(xy 343.91741 -401.756037) (xy 343.902055 -401.808332) (xy 343.879413 -401.857909) (xy 343.849947 -401.903759)
			(xy 343.814256 -401.94495) (xy 343.773065 -401.980641) (xy 343.727215 -402.010107) (xy 343.677638 -402.032749)
			(xy 343.625343 -402.048104) (xy 343.571395 -402.05586) (xy 343.516893 -402.05586) (xy 343.462945 -402.048104)
			(xy 343.41065 -402.032749) (xy 343.361073 -402.010107) (xy 343.315223 -401.980641) (xy 343.274032 -401.94495)
			(xy 343.238341 -401.903759) (xy 343.208875 -401.857909) (xy 343.186233 -401.808332) (xy 343.170878 -401.756037)
			(xy 343.163122 -401.702089) (xy 343.162636 -401.674838) (xy 342.725756 -401.674838) (xy 342.72527 -401.702107)
			(xy 342.717508 -401.756091) (xy 342.702143 -401.808421) (xy 342.679486 -401.858031) (xy 342.65 -401.903912)
			(xy 342.614285 -401.945129) (xy 342.573068 -401.980844) (xy 342.527187 -402.01033) (xy 342.477577 -402.032987)
			(xy 342.425247 -402.048352) (xy 342.371263 -402.056114) (xy 342.316725 -402.056114) (xy 342.262741 -402.048352)
			(xy 342.210411 -402.032987) (xy 342.160801 -402.01033) (xy 342.11492 -401.980844) (xy 342.073703 -401.945129)
			(xy 342.037988 -401.903912) (xy 342.008502 -401.858031) (xy 341.985845 -401.808421) (xy 341.97048 -401.756091)
			(xy 341.962718 -401.702107) (xy 341.962232 -401.674838) (xy 341.52586 -401.674838) (xy 341.525374 -401.702107)
			(xy 341.517612 -401.756091) (xy 341.502247 -401.808421) (xy 341.47959 -401.858031) (xy 341.450104 -401.903912)
			(xy 341.414389 -401.945129) (xy 341.373172 -401.980844) (xy 341.327291 -402.01033) (xy 341.277681 -402.032987)
			(xy 341.225351 -402.048352) (xy 341.171367 -402.056114) (xy 341.116829 -402.056114) (xy 341.062845 -402.048352)
			(xy 341.010515 -402.032987) (xy 340.960905 -402.01033) (xy 340.915024 -401.980844) (xy 340.873807 -401.945129)
			(xy 340.838092 -401.903912) (xy 340.808606 -401.858031) (xy 340.785949 -401.808421) (xy 340.770584 -401.756091)
			(xy 340.762822 -401.702107) (xy 340.762336 -401.674838) (xy 340.325456 -401.674838) (xy 340.32497 -401.702089)
			(xy 340.317214 -401.756037) (xy 340.301859 -401.808332) (xy 340.279217 -401.857909) (xy 340.249751 -401.903759)
			(xy 340.21406 -401.94495) (xy 340.172869 -401.980641) (xy 340.127019 -402.010107) (xy 340.077442 -402.032749)
			(xy 340.025147 -402.048104) (xy 339.971199 -402.05586) (xy 339.916697 -402.05586) (xy 339.862749 -402.048104)
			(xy 339.810454 -402.032749) (xy 339.760877 -402.010107) (xy 339.715027 -401.980641) (xy 339.673836 -401.94495)
			(xy 339.638145 -401.903759) (xy 339.608679 -401.857909) (xy 339.586037 -401.808332) (xy 339.570682 -401.756037)
			(xy 339.562926 -401.702089) (xy 339.56244 -401.674838) (xy 339.12556 -401.674838) (xy 339.125074 -401.702089)
			(xy 339.117318 -401.756037) (xy 339.101963 -401.808332) (xy 339.079321 -401.857909) (xy 339.049855 -401.903759)
			(xy 339.014164 -401.94495) (xy 338.972973 -401.980641) (xy 338.927123 -402.010107) (xy 338.877546 -402.032749)
			(xy 338.825251 -402.048104) (xy 338.771303 -402.05586) (xy 338.716801 -402.05586) (xy 338.662853 -402.048104)
			(xy 338.610558 -402.032749) (xy 338.560981 -402.010107) (xy 338.515131 -401.980641) (xy 338.47394 -401.94495)
			(xy 338.438249 -401.903759) (xy 338.408783 -401.857909) (xy 338.386141 -401.808332) (xy 338.370786 -401.756037)
			(xy 338.36303 -401.702089) (xy 338.362544 -401.674838) (xy 337.925664 -401.674838) (xy 337.925178 -401.702107)
			(xy 337.917416 -401.756091) (xy 337.902051 -401.808421) (xy 337.879394 -401.858031) (xy 337.849908 -401.903912)
			(xy 337.814193 -401.945129) (xy 337.772976 -401.980844) (xy 337.727095 -402.01033) (xy 337.677485 -402.032987)
			(xy 337.625155 -402.048352) (xy 337.571171 -402.056114) (xy 337.516633 -402.056114) (xy 337.462649 -402.048352)
			(xy 337.410319 -402.032987) (xy 337.360709 -402.01033) (xy 337.314828 -401.980844) (xy 337.273611 -401.945129)
			(xy 337.237896 -401.903912) (xy 337.20841 -401.858031) (xy 337.185753 -401.808421) (xy 337.170388 -401.756091)
			(xy 337.162626 -401.702107) (xy 337.16214 -401.674838) (xy 336.725768 -401.674838) (xy 336.725282 -401.702107)
			(xy 336.71752 -401.756091) (xy 336.702155 -401.808421) (xy 336.679498 -401.858031) (xy 336.650012 -401.903912)
			(xy 336.614297 -401.945129) (xy 336.57308 -401.980844) (xy 336.527199 -402.01033) (xy 336.477589 -402.032987)
			(xy 336.425259 -402.048352) (xy 336.371275 -402.056114) (xy 336.316737 -402.056114) (xy 336.262753 -402.048352)
			(xy 336.210423 -402.032987) (xy 336.160813 -402.01033) (xy 336.114932 -401.980844) (xy 336.073715 -401.945129)
			(xy 336.038 -401.903912) (xy 336.008514 -401.858031) (xy 335.985857 -401.808421) (xy 335.970492 -401.756091)
			(xy 335.96273 -401.702107) (xy 335.962244 -401.674838) (xy 322.197984 -401.674838) (xy 322.197498 -401.702107)
			(xy 322.189736 -401.756091) (xy 322.174371 -401.808421) (xy 322.151714 -401.858031) (xy 322.122228 -401.903912)
			(xy 322.086513 -401.945129) (xy 322.045296 -401.980844) (xy 321.999415 -402.01033) (xy 321.949805 -402.032987)
			(xy 321.897475 -402.048352) (xy 321.843491 -402.056114) (xy 321.788953 -402.056114) (xy 321.734969 -402.048352)
			(xy 321.682639 -402.032987) (xy 321.633029 -402.01033) (xy 321.587148 -401.980844) (xy 321.545931 -401.945129)
			(xy 321.510216 -401.903912) (xy 321.48073 -401.858031) (xy 321.458073 -401.808421) (xy 321.442708 -401.756091)
			(xy 321.434946 -401.702107) (xy 321.43446 -401.674838) (xy 320.998088 -401.674838) (xy 320.997602 -401.702107)
			(xy 320.98984 -401.756091) (xy 320.974475 -401.808421) (xy 320.951818 -401.858031) (xy 320.922332 -401.903912)
			(xy 320.886617 -401.945129) (xy 320.8454 -401.980844) (xy 320.799519 -402.01033) (xy 320.749909 -402.032987)
			(xy 320.697579 -402.048352) (xy 320.643595 -402.056114) (xy 320.589057 -402.056114) (xy 320.535073 -402.048352)
			(xy 320.482743 -402.032987) (xy 320.433133 -402.01033) (xy 320.387252 -401.980844) (xy 320.346035 -401.945129)
			(xy 320.31032 -401.903912) (xy 320.280834 -401.858031) (xy 320.258177 -401.808421) (xy 320.242812 -401.756091)
			(xy 320.23505 -401.702107) (xy 320.234564 -401.674838) (xy 319.797684 -401.674838) (xy 319.797198 -401.702089)
			(xy 319.789442 -401.756037) (xy 319.774087 -401.808332) (xy 319.751445 -401.857909) (xy 319.721979 -401.903759)
			(xy 319.686288 -401.94495) (xy 319.645097 -401.980641) (xy 319.599247 -402.010107) (xy 319.54967 -402.032749)
			(xy 319.497375 -402.048104) (xy 319.443427 -402.05586) (xy 319.388925 -402.05586) (xy 319.334977 -402.048104)
			(xy 319.282682 -402.032749) (xy 319.233105 -402.010107) (xy 319.187255 -401.980641) (xy 319.146064 -401.94495)
			(xy 319.110373 -401.903759) (xy 319.080907 -401.857909) (xy 319.058265 -401.808332) (xy 319.04291 -401.756037)
			(xy 319.035154 -401.702089) (xy 319.034668 -401.674838) (xy 318.597788 -401.674838) (xy 318.597302 -401.702089)
			(xy 318.589546 -401.756037) (xy 318.574191 -401.808332) (xy 318.551549 -401.857909) (xy 318.522083 -401.903759)
			(xy 318.486392 -401.94495) (xy 318.445201 -401.980641) (xy 318.399351 -402.010107) (xy 318.349774 -402.032749)
			(xy 318.297479 -402.048104) (xy 318.243531 -402.05586) (xy 318.189029 -402.05586) (xy 318.135081 -402.048104)
			(xy 318.082786 -402.032749) (xy 318.033209 -402.010107) (xy 317.987359 -401.980641) (xy 317.946168 -401.94495)
			(xy 317.910477 -401.903759) (xy 317.881011 -401.857909) (xy 317.858369 -401.808332) (xy 317.843014 -401.756037)
			(xy 317.835258 -401.702089) (xy 317.834772 -401.674838) (xy 317.397892 -401.674838) (xy 317.397406 -401.702089)
			(xy 317.38965 -401.756037) (xy 317.374295 -401.808332) (xy 317.351653 -401.857909) (xy 317.322187 -401.903759)
			(xy 317.286496 -401.94495) (xy 317.245305 -401.980641) (xy 317.199455 -402.010107) (xy 317.149878 -402.032749)
			(xy 317.097583 -402.048104) (xy 317.043635 -402.05586) (xy 316.989133 -402.05586) (xy 316.935185 -402.048104)
			(xy 316.88289 -402.032749) (xy 316.833313 -402.010107) (xy 316.787463 -401.980641) (xy 316.746272 -401.94495)
			(xy 316.710581 -401.903759) (xy 316.681115 -401.857909) (xy 316.658473 -401.808332) (xy 316.643118 -401.756037)
			(xy 316.635362 -401.702089) (xy 316.634876 -401.674838) (xy 316.197996 -401.674838) (xy 316.19751 -401.702089)
			(xy 316.189754 -401.756037) (xy 316.174399 -401.808332) (xy 316.151757 -401.857909) (xy 316.122291 -401.903759)
			(xy 316.0866 -401.94495) (xy 316.045409 -401.980641) (xy 315.999559 -402.010107) (xy 315.949982 -402.032749)
			(xy 315.897687 -402.048104) (xy 315.843739 -402.05586) (xy 315.789237 -402.05586) (xy 315.735289 -402.048104)
			(xy 315.682994 -402.032749) (xy 315.633417 -402.010107) (xy 315.587567 -401.980641) (xy 315.546376 -401.94495)
			(xy 315.510685 -401.903759) (xy 315.481219 -401.857909) (xy 315.458577 -401.808332) (xy 315.443222 -401.756037)
			(xy 315.435466 -401.702089) (xy 315.43498 -401.674838) (xy 314.9981 -401.674838) (xy 314.997614 -401.702107)
			(xy 314.989852 -401.756091) (xy 314.974487 -401.808421) (xy 314.95183 -401.858031) (xy 314.922344 -401.903912)
			(xy 314.886629 -401.945129) (xy 314.845412 -401.980844) (xy 314.799531 -402.01033) (xy 314.749921 -402.032987)
			(xy 314.697591 -402.048352) (xy 314.643607 -402.056114) (xy 314.589069 -402.056114) (xy 314.535085 -402.048352)
			(xy 314.482755 -402.032987) (xy 314.433145 -402.01033) (xy 314.387264 -401.980844) (xy 314.346047 -401.945129)
			(xy 314.310332 -401.903912) (xy 314.280846 -401.858031) (xy 314.258189 -401.808421) (xy 314.242824 -401.756091)
			(xy 314.235062 -401.702107) (xy 314.234576 -401.674838) (xy 313.798204 -401.674838) (xy 313.797718 -401.702107)
			(xy 313.789956 -401.756091) (xy 313.774591 -401.808421) (xy 313.751934 -401.858031) (xy 313.722448 -401.903912)
			(xy 313.686733 -401.945129) (xy 313.645516 -401.980844) (xy 313.599635 -402.01033) (xy 313.550025 -402.032987)
			(xy 313.497695 -402.048352) (xy 313.443711 -402.056114) (xy 313.389173 -402.056114) (xy 313.335189 -402.048352)
			(xy 313.282859 -402.032987) (xy 313.233249 -402.01033) (xy 313.187368 -401.980844) (xy 313.146151 -401.945129)
			(xy 313.110436 -401.903912) (xy 313.08095 -401.858031) (xy 313.058293 -401.808421) (xy 313.042928 -401.756091)
			(xy 313.035166 -401.702107) (xy 313.03468 -401.674838) (xy 312.5978 -401.674838) (xy 312.597314 -401.702089)
			(xy 312.589558 -401.756037) (xy 312.574203 -401.808332) (xy 312.551561 -401.857909) (xy 312.522095 -401.903759)
			(xy 312.486404 -401.94495) (xy 312.445213 -401.980641) (xy 312.399363 -402.010107) (xy 312.349786 -402.032749)
			(xy 312.297491 -402.048104) (xy 312.243543 -402.05586) (xy 312.189041 -402.05586) (xy 312.135093 -402.048104)
			(xy 312.082798 -402.032749) (xy 312.033221 -402.010107) (xy 311.987371 -401.980641) (xy 311.94618 -401.94495)
			(xy 311.910489 -401.903759) (xy 311.881023 -401.857909) (xy 311.858381 -401.808332) (xy 311.843026 -401.756037)
			(xy 311.83527 -401.702089) (xy 311.834784 -401.674838) (xy 311.397904 -401.674838) (xy 311.397418 -401.702089)
			(xy 311.389662 -401.756037) (xy 311.374307 -401.808332) (xy 311.351665 -401.857909) (xy 311.322199 -401.903759)
			(xy 311.286508 -401.94495) (xy 311.245317 -401.980641) (xy 311.199467 -402.010107) (xy 311.14989 -402.032749)
			(xy 311.097595 -402.048104) (xy 311.043647 -402.05586) (xy 310.989145 -402.05586) (xy 310.935197 -402.048104)
			(xy 310.882902 -402.032749) (xy 310.833325 -402.010107) (xy 310.787475 -401.980641) (xy 310.746284 -401.94495)
			(xy 310.710593 -401.903759) (xy 310.681127 -401.857909) (xy 310.658485 -401.808332) (xy 310.64313 -401.756037)
			(xy 310.635374 -401.702089) (xy 310.634888 -401.674838) (xy 310.198008 -401.674838) (xy 310.197522 -401.702107)
			(xy 310.18976 -401.756091) (xy 310.174395 -401.808421) (xy 310.151738 -401.858031) (xy 310.122252 -401.903912)
			(xy 310.086537 -401.945129) (xy 310.04532 -401.980844) (xy 309.999439 -402.01033) (xy 309.949829 -402.032987)
			(xy 309.897499 -402.048352) (xy 309.843515 -402.056114) (xy 309.788977 -402.056114) (xy 309.734993 -402.048352)
			(xy 309.682663 -402.032987) (xy 309.633053 -402.01033) (xy 309.587172 -401.980844) (xy 309.545955 -401.945129)
			(xy 309.51024 -401.903912) (xy 309.480754 -401.858031) (xy 309.458097 -401.808421) (xy 309.442732 -401.756091)
			(xy 309.43497 -401.702107) (xy 309.434484 -401.674838) (xy 308.998112 -401.674838) (xy 308.997626 -401.702107)
			(xy 308.989864 -401.756091) (xy 308.974499 -401.808421) (xy 308.951842 -401.858031) (xy 308.922356 -401.903912)
			(xy 308.886641 -401.945129) (xy 308.845424 -401.980844) (xy 308.799543 -402.01033) (xy 308.749933 -402.032987)
			(xy 308.697603 -402.048352) (xy 308.643619 -402.056114) (xy 308.589081 -402.056114) (xy 308.535097 -402.048352)
			(xy 308.482767 -402.032987) (xy 308.433157 -402.01033) (xy 308.387276 -401.980844) (xy 308.346059 -401.945129)
			(xy 308.310344 -401.903912) (xy 308.280858 -401.858031) (xy 308.258201 -401.808421) (xy 308.242836 -401.756091)
			(xy 308.235074 -401.702107) (xy 308.234588 -401.674838) (xy 307.797708 -401.674838) (xy 307.797222 -401.702089)
			(xy 307.789466 -401.756037) (xy 307.774111 -401.808332) (xy 307.751469 -401.857909) (xy 307.722003 -401.903759)
			(xy 307.686312 -401.94495) (xy 307.645121 -401.980641) (xy 307.599271 -402.010107) (xy 307.549694 -402.032749)
			(xy 307.497399 -402.048104) (xy 307.443451 -402.05586) (xy 307.388949 -402.05586) (xy 307.335001 -402.048104)
			(xy 307.282706 -402.032749) (xy 307.233129 -402.010107) (xy 307.187279 -401.980641) (xy 307.146088 -401.94495)
			(xy 307.110397 -401.903759) (xy 307.080931 -401.857909) (xy 307.058289 -401.808332) (xy 307.042934 -401.756037)
			(xy 307.035178 -401.702089) (xy 307.034692 -401.674838) (xy 306.597812 -401.674838) (xy 306.597326 -401.702089)
			(xy 306.58957 -401.756037) (xy 306.574215 -401.808332) (xy 306.551573 -401.857909) (xy 306.522107 -401.903759)
			(xy 306.486416 -401.94495) (xy 306.445225 -401.980641) (xy 306.399375 -402.010107) (xy 306.349798 -402.032749)
			(xy 306.297503 -402.048104) (xy 306.243555 -402.05586) (xy 306.189053 -402.05586) (xy 306.135105 -402.048104)
			(xy 306.08281 -402.032749) (xy 306.033233 -402.010107) (xy 305.987383 -401.980641) (xy 305.946192 -401.94495)
			(xy 305.910501 -401.903759) (xy 305.881035 -401.857909) (xy 305.858393 -401.808332) (xy 305.843038 -401.756037)
			(xy 305.835282 -401.702089) (xy 305.834796 -401.674838) (xy 305.397916 -401.674838) (xy 305.39743 -401.702107)
			(xy 305.389668 -401.756091) (xy 305.374303 -401.808421) (xy 305.351646 -401.858031) (xy 305.32216 -401.903912)
			(xy 305.286445 -401.945129) (xy 305.245228 -401.980844) (xy 305.199347 -402.01033) (xy 305.149737 -402.032987)
			(xy 305.097407 -402.048352) (xy 305.043423 -402.056114) (xy 304.988885 -402.056114) (xy 304.934901 -402.048352)
			(xy 304.882571 -402.032987) (xy 304.832961 -402.01033) (xy 304.78708 -401.980844) (xy 304.745863 -401.945129)
			(xy 304.710148 -401.903912) (xy 304.680662 -401.858031) (xy 304.658005 -401.808421) (xy 304.64264 -401.756091)
			(xy 304.634878 -401.702107) (xy 304.634392 -401.674838) (xy 304.19802 -401.674838) (xy 304.197534 -401.702107)
			(xy 304.189772 -401.756091) (xy 304.174407 -401.808421) (xy 304.15175 -401.858031) (xy 304.122264 -401.903912)
			(xy 304.086549 -401.945129) (xy 304.045332 -401.980844) (xy 303.999451 -402.01033) (xy 303.949841 -402.032987)
			(xy 303.897511 -402.048352) (xy 303.843527 -402.056114) (xy 303.788989 -402.056114) (xy 303.735005 -402.048352)
			(xy 303.682675 -402.032987) (xy 303.633065 -402.01033) (xy 303.587184 -401.980844) (xy 303.545967 -401.945129)
			(xy 303.510252 -401.903912) (xy 303.480766 -401.858031) (xy 303.458109 -401.808421) (xy 303.442744 -401.756091)
			(xy 303.434982 -401.702107) (xy 303.434496 -401.674838) (xy 280.68524 -401.674838) (xy 280.68524 -404.215092)
			(xy 283.62402 -404.215092) (xy 283.62402 -403.351492) (xy 283.624506 -403.324223) (xy 283.632268 -403.270239)
			(xy 283.647633 -403.217909) (xy 283.67029 -403.168299) (xy 283.699776 -403.122418) (xy 283.735491 -403.081201)
			(xy 283.776708 -403.045486) (xy 283.822589 -403.016) (xy 283.872199 -402.993343) (xy 283.924529 -402.977978)
			(xy 283.978513 -402.970216) (xy 284.033051 -402.970216) (xy 284.087035 -402.977978) (xy 284.139365 -402.993343)
			(xy 284.188975 -403.016) (xy 284.203533 -403.025356) (xy 289.919156 -403.025356) (xy 289.919156 -402.161756)
			(xy 289.919642 -402.134487) (xy 289.927404 -402.080503) (xy 289.942769 -402.028173) (xy 289.965426 -401.978563)
			(xy 289.994912 -401.932682) (xy 290.030627 -401.891465) (xy 290.071844 -401.85575) (xy 290.117725 -401.826264)
			(xy 290.167335 -401.803607) (xy 290.219665 -401.788242) (xy 290.273649 -401.78048) (xy 290.328187 -401.78048)
			(xy 290.382171 -401.788242) (xy 290.434501 -401.803607) (xy 290.484111 -401.826264) (xy 290.529992 -401.85575)
			(xy 290.571209 -401.891465) (xy 290.606924 -401.932682) (xy 290.63641 -401.978563) (xy 290.659067 -402.028173)
			(xy 290.674432 -402.080503) (xy 290.682194 -402.134487) (xy 290.68268 -402.161756) (xy 290.68268 -403.025356)
			(xy 290.682194 -403.052625) (xy 290.674432 -403.106609) (xy 290.659067 -403.158939) (xy 290.63641 -403.208549)
			(xy 290.606924 -403.25443) (xy 290.571209 -403.295647) (xy 290.529992 -403.331362) (xy 290.484111 -403.360848)
			(xy 290.434501 -403.383505) (xy 290.382171 -403.39887) (xy 290.328187 -403.406632) (xy 290.273649 -403.406632)
			(xy 290.219665 -403.39887) (xy 290.167335 -403.383505) (xy 290.117725 -403.360848) (xy 290.071844 -403.331362)
			(xy 290.030627 -403.295647) (xy 289.994912 -403.25443) (xy 289.965426 -403.208549) (xy 289.942769 -403.158939)
			(xy 289.927404 -403.106609) (xy 289.919642 -403.052625) (xy 289.919156 -403.025356) (xy 284.203533 -403.025356)
			(xy 284.234856 -403.045486) (xy 284.276073 -403.081201) (xy 284.311788 -403.122418) (xy 284.341274 -403.168299)
			(xy 284.363931 -403.217909) (xy 284.379296 -403.270239) (xy 284.387058 -403.324223) (xy 284.387544 -403.351492)
			(xy 284.387544 -404.215092) (xy 284.387058 -404.242361) (xy 284.379296 -404.296345) (xy 284.363931 -404.348675)
			(xy 284.341274 -404.398285) (xy 284.311788 -404.444166) (xy 284.276073 -404.485383) (xy 284.234856 -404.521098)
			(xy 284.188975 -404.550584) (xy 284.139365 -404.573241) (xy 284.087035 -404.588606) (xy 284.033051 -404.596368)
			(xy 283.978513 -404.596368) (xy 283.924529 -404.588606) (xy 283.872199 -404.573241) (xy 283.822589 -404.550584)
			(xy 283.776708 -404.521098) (xy 283.735491 -404.485383) (xy 283.699776 -404.444166) (xy 283.67029 -404.398285)
			(xy 283.647633 -404.348675) (xy 283.632268 -404.296345) (xy 283.624506 -404.242361) (xy 283.62402 -404.215092)
			(xy 280.68524 -404.215092) (xy 280.68524 -407.583953) (xy 282.536071 -407.583953) (xy 282.536071 -407.529447)
			(xy 282.543829 -407.475495) (xy 282.559186 -407.423196) (xy 282.581831 -407.373615) (xy 282.611301 -407.327762)
			(xy 282.646997 -407.28657) (xy 282.688193 -407.250878) (xy 282.734049 -407.221412) (xy 282.783632 -407.198773)
			(xy 282.835932 -407.183421) (xy 282.889885 -407.175669) (xy 282.917138 -407.175208) (xy 283.780738 -407.175208)
			(xy 283.807989 -407.175664) (xy 283.861934 -407.183426) (xy 283.914227 -407.198785) (xy 283.963801 -407.221429)
			(xy 284.009649 -407.250898) (xy 284.050836 -407.286591) (xy 284.086525 -407.327782) (xy 284.115989 -407.373632)
			(xy 284.134525 -407.414222) (xy 287.101788 -407.414222) (xy 287.101788 -406.550622) (xy 287.102274 -406.523371)
			(xy 287.11003 -406.469423) (xy 287.125385 -406.417128) (xy 287.148027 -406.367551) (xy 287.177493 -406.321701)
			(xy 287.213184 -406.28051) (xy 287.254375 -406.244819) (xy 287.300225 -406.215353) (xy 287.349802 -406.192711)
			(xy 287.402097 -406.177356) (xy 287.456045 -406.1696) (xy 287.510547 -406.1696) (xy 287.564495 -406.177356)
			(xy 287.61679 -406.192711) (xy 287.666367 -406.215353) (xy 287.712217 -406.244819) (xy 287.753408 -406.28051)
			(xy 287.789099 -406.321701) (xy 287.818565 -406.367551) (xy 287.841207 -406.417128) (xy 287.856562 -406.469423)
			(xy 287.864318 -406.523371) (xy 287.864804 -406.550622) (xy 287.864804 -407.414222) (xy 287.864318 -407.441473)
			(xy 287.856562 -407.495421) (xy 287.841207 -407.547716) (xy 287.818565 -407.597293) (xy 287.789099 -407.643143)
			(xy 287.753408 -407.684334) (xy 287.712217 -407.720025) (xy 287.666367 -407.749491) (xy 287.61679 -407.772133)
			(xy 287.564495 -407.787488) (xy 287.510547 -407.795244) (xy 287.456045 -407.795244) (xy 287.402097 -407.787488)
			(xy 287.349802 -407.772133) (xy 287.300225 -407.749491) (xy 287.254375 -407.720025) (xy 287.213184 -407.684334)
			(xy 287.177493 -407.643143) (xy 287.148027 -407.597293) (xy 287.125385 -407.547716) (xy 287.11003 -407.495421)
			(xy 287.102274 -407.441473) (xy 287.101788 -407.414222) (xy 284.134525 -407.414222) (xy 284.138629 -407.423209)
			(xy 284.153982 -407.475503) (xy 284.161738 -407.529449) (xy 284.161738 -407.583951) (xy 284.153982 -407.637897)
			(xy 284.138629 -407.690191) (xy 284.115989 -407.739768) (xy 284.086525 -407.785619) (xy 284.050836 -407.826809)
			(xy 284.009649 -407.862502) (xy 283.963801 -407.891971) (xy 283.914227 -407.914615) (xy 283.861934 -407.929974)
			(xy 283.807989 -407.937736) (xy 283.780738 -407.938224) (xy 282.917138 -407.938224) (xy 282.889885 -407.937731)
			(xy 282.835932 -407.929979) (xy 282.783632 -407.914627) (xy 282.734049 -407.891988) (xy 282.688193 -407.862522)
			(xy 282.646997 -407.82683) (xy 282.611301 -407.785638) (xy 282.581831 -407.739785) (xy 282.559186 -407.690204)
			(xy 282.543829 -407.637905) (xy 282.536071 -407.583953) (xy 280.68524 -407.583953) (xy 280.68524 -409.10256)
			(xy 280.684766 -409.12751) (xy 280.676946 -409.176794) (xy 280.661524 -409.224251) (xy 280.638877 -409.268716)
			(xy 280.609563 -409.309098) (xy 280.592276 -409.327096) (xy 276.749256 -413.170116) (xy 293.568894 -413.170116)
			(xy 293.572866 -412.991873) (xy 293.584774 -412.813984) (xy 293.604595 -412.636802) (xy 293.632289 -412.460678)
			(xy 293.667801 -412.285963) (xy 293.711061 -412.113004) (xy 293.761983 -411.942143) (xy 293.820466 -411.773721)
			(xy 293.886393 -411.608071) (xy 293.959634 -411.445522) (xy 294.040044 -411.286397) (xy 294.127462 -411.131012)
			(xy 294.221715 -410.979676) (xy 294.322616 -410.832688) (xy 294.429965 -410.690341) (xy 294.543548 -410.552918)
			(xy 294.663141 -410.420691) (xy 294.788505 -410.293922) (xy 294.919392 -410.172864) (xy 295.055541 -410.057757)
			(xy 295.196683 -409.948829) (xy 295.342538 -409.846297) (xy 295.492815 -409.750363) (xy 295.647216 -409.66122)
			(xy 295.805435 -409.579043) (xy 295.967158 -409.503995) (xy 296.132063 -409.436227) (xy 296.299824 -409.375871)
			(xy 296.470107 -409.323049) (xy 296.642574 -409.277865) (xy 296.816882 -409.240408) (xy 296.992686 -409.210754)
			(xy 297.169636 -409.188961) (xy 297.347382 -409.175071) (xy 297.525569 -409.169114) (xy 297.703846 -409.1711)
			(xy 297.881857 -409.181026) (xy 298.059249 -409.198872) (xy 298.235669 -409.224602) (xy 298.410769 -409.258166)
			(xy 298.5842 -409.299496) (xy 298.755617 -409.348512) (xy 298.92468 -409.405114) (xy 299.091055 -409.469192)
			(xy 299.254409 -409.540618) (xy 299.41442 -409.61925) (xy 299.570769 -409.704931) (xy 299.723146 -409.797493)
			(xy 299.871249 -409.89675) (xy 300.014783 -410.002507) (xy 300.153463 -410.114552) (xy 300.287014 -410.232664)
			(xy 300.415171 -410.356608) (xy 300.53768 -410.486138) (xy 300.654297 -410.620997) (xy 300.76479 -410.760917)
			(xy 300.868941 -410.90562) (xy 300.966543 -411.054819) (xy 301.057401 -411.208218) (xy 301.141335 -411.365512)
			(xy 301.21818 -411.526388) (xy 301.287781 -411.690529) (xy 301.350002 -411.857606) (xy 301.404718 -412.02729)
			(xy 301.45182 -412.199243) (xy 301.491216 -412.373123) (xy 301.522827 -412.548586) (xy 301.546591 -412.725282)
			(xy 301.559858 -412.873752) (xy 303.412875 -412.873752) (xy 303.412875 -412.819248) (xy 303.420632 -412.7653)
			(xy 303.435988 -412.713004) (xy 303.458629 -412.663426) (xy 303.488096 -412.617575) (xy 303.523789 -412.576384)
			(xy 303.56498 -412.540693) (xy 303.610831 -412.511226) (xy 303.66041 -412.488585) (xy 303.712706 -412.473231)
			(xy 303.766654 -412.465475) (xy 303.793906 -412.465012) (xy 304.657506 -412.465012) (xy 304.684758 -412.465458)
			(xy 304.738708 -412.473216) (xy 304.791005 -412.488572) (xy 304.840584 -412.511215) (xy 304.886436 -412.540683)
			(xy 304.927628 -412.576376) (xy 304.963321 -412.617569) (xy 304.992788 -412.663421) (xy 305.01543 -412.713001)
			(xy 305.030785 -412.765298) (xy 305.038542 -412.819248) (xy 305.038542 -412.873752) (xy 305.038542 -412.873754)
			(xy 306.476075 -412.873754) (xy 306.476075 -412.819246) (xy 306.483833 -412.765294) (xy 306.499191 -412.712996)
			(xy 306.521835 -412.663415) (xy 306.551306 -412.617562) (xy 306.587003 -412.57637) (xy 306.628199 -412.540679)
			(xy 306.674055 -412.511213) (xy 306.723639 -412.488575) (xy 306.775939 -412.473223) (xy 306.829892 -412.465472)
			(xy 306.857146 -412.465012) (xy 307.720746 -412.465012) (xy 307.747997 -412.465461) (xy 307.801942 -412.473223)
			(xy 307.854234 -412.488583) (xy 307.903808 -412.511228) (xy 307.949655 -412.540697) (xy 307.990842 -412.576391)
			(xy 308.02653 -412.617582) (xy 308.055994 -412.663432) (xy 308.078633 -412.713009) (xy 308.093987 -412.765303)
			(xy 308.101742 -412.819249) (xy 308.101742 -412.873749) (xy 309.539398 -412.873749) (xy 309.539398 -412.819251)
			(xy 309.547154 -412.765307) (xy 309.562508 -412.713016) (xy 309.585146 -412.663443) (xy 309.61461 -412.617596)
			(xy 309.650298 -412.576408) (xy 309.691484 -412.540718) (xy 309.73733 -412.511253) (xy 309.786903 -412.488612)
			(xy 309.839194 -412.473257) (xy 309.893137 -412.465499) (xy 309.920386 -412.465012) (xy 310.783986 -412.465012)
			(xy 310.811241 -412.465434) (xy 310.865196 -412.47319) (xy 310.917499 -412.488545) (xy 310.967083 -412.511188)
			(xy 311.012941 -412.540657) (xy 311.054137 -412.576353) (xy 311.089834 -412.617548) (xy 311.119305 -412.663405)
			(xy 311.14195 -412.712988) (xy 311.157307 -412.76529) (xy 311.165065 -412.819245) (xy 311.165065 -412.873753)
			(xy 312.602575 -412.873753) (xy 312.602575 -412.819247) (xy 312.610333 -412.765297) (xy 312.625689 -412.713)
			(xy 312.648332 -412.663421) (xy 312.677801 -412.617569) (xy 312.713496 -412.576377) (xy 312.754689 -412.540686)
			(xy 312.800543 -412.51122) (xy 312.850124 -412.48858) (xy 312.902422 -412.473227) (xy 312.956373 -412.465474)
			(xy 312.983626 -412.465012) (xy 313.847226 -412.465012) (xy 313.874477 -412.46546) (xy 313.928425 -412.47322)
			(xy 313.98072 -412.488578) (xy 314.030296 -412.511222) (xy 314.076146 -412.54069) (xy 314.117335 -412.576383)
			(xy 314.153026 -412.617575) (xy 314.182491 -412.663427) (xy 314.205131 -412.713005) (xy 314.220486 -412.7653)
			(xy 314.228242 -412.819249) (xy 314.228242 -412.873748) (xy 315.665898 -412.873748) (xy 315.665898 -412.819252)
			(xy 315.673653 -412.76531) (xy 315.689006 -412.713021) (xy 315.711643 -412.663448) (xy 315.741105 -412.617602)
			(xy 315.776791 -412.576415) (xy 315.817975 -412.540725) (xy 315.863818 -412.51126) (xy 315.913389 -412.488618)
			(xy 315.965677 -412.473261) (xy 316.019618 -412.465501) (xy 316.046866 -412.465012) (xy 316.910466 -412.465012)
			(xy 316.937722 -412.465433) (xy 316.991679 -412.473186) (xy 317.043984 -412.48854) (xy 317.093571 -412.511182)
			(xy 317.139431 -412.54065) (xy 317.18063 -412.576346) (xy 317.216329 -412.617542) (xy 317.245802 -412.663399)
			(xy 317.268448 -412.712984) (xy 317.283807 -412.765287) (xy 317.291565 -412.819244) (xy 317.291565 -412.873752)
			(xy 318.729075 -412.873752) (xy 318.729075 -412.819248) (xy 318.736832 -412.7653) (xy 318.752188 -412.713004)
			(xy 318.774829 -412.663426) (xy 318.804296 -412.617575) (xy 318.839989 -412.576384) (xy 318.88118 -412.540693)
			(xy 318.927031 -412.511226) (xy 318.97661 -412.488585) (xy 319.028906 -412.473231) (xy 319.082854 -412.465475)
			(xy 319.110106 -412.465012) (xy 319.973706 -412.465012) (xy 320.000958 -412.465458) (xy 320.054908 -412.473216)
			(xy 320.107205 -412.488572) (xy 320.156784 -412.511215) (xy 320.202636 -412.540683) (xy 320.243828 -412.576376)
			(xy 320.279521 -412.617569) (xy 320.308988 -412.663421) (xy 320.33163 -412.713001) (xy 320.346985 -412.765298)
			(xy 320.354742 -412.819248) (xy 320.354742 -412.873752) (xy 320.354742 -412.873754) (xy 321.792275 -412.873754)
			(xy 321.792275 -412.819246) (xy 321.800033 -412.765294) (xy 321.815391 -412.712996) (xy 321.838035 -412.663415)
			(xy 321.867506 -412.617562) (xy 321.903203 -412.57637) (xy 321.944399 -412.540679) (xy 321.990255 -412.511213)
			(xy 322.039839 -412.488575) (xy 322.092139 -412.473223) (xy 322.146092 -412.465472) (xy 322.173346 -412.465012)
			(xy 323.036946 -412.465012) (xy 323.064197 -412.465461) (xy 323.118142 -412.473223) (xy 323.170434 -412.488583)
			(xy 323.220008 -412.511228) (xy 323.265855 -412.540697) (xy 323.307042 -412.576391) (xy 323.34273 -412.617582)
			(xy 323.372194 -412.663432) (xy 323.394833 -412.713009) (xy 323.410187 -412.765303) (xy 323.417942 -412.819249)
			(xy 323.417942 -412.873749) (xy 324.855598 -412.873749) (xy 324.855598 -412.819251) (xy 324.863354 -412.765307)
			(xy 324.878708 -412.713016) (xy 324.901346 -412.663443) (xy 324.93081 -412.617596) (xy 324.966498 -412.576408)
			(xy 325.007684 -412.540718) (xy 325.05353 -412.511253) (xy 325.103103 -412.488612) (xy 325.155394 -412.473257)
			(xy 325.209337 -412.465499) (xy 325.236586 -412.465012) (xy 326.100186 -412.465012) (xy 326.127441 -412.465434)
			(xy 326.181396 -412.47319) (xy 326.233699 -412.488545) (xy 326.283283 -412.511188) (xy 326.329141 -412.540657)
			(xy 326.370337 -412.576353) (xy 326.406034 -412.617548) (xy 326.435505 -412.663405) (xy 326.45815 -412.712988)
			(xy 326.473507 -412.76529) (xy 326.481265 -412.819245) (xy 326.481265 -412.873753) (xy 327.918775 -412.873753)
			(xy 327.918775 -412.819247) (xy 327.926533 -412.765297) (xy 327.941889 -412.713) (xy 327.964532 -412.663421)
			(xy 327.994001 -412.617569) (xy 328.029696 -412.576377) (xy 328.070889 -412.540686) (xy 328.116743 -412.51122)
			(xy 328.166324 -412.48858) (xy 328.218622 -412.473227) (xy 328.272573 -412.465474) (xy 328.299826 -412.465012)
			(xy 329.163426 -412.465012) (xy 329.190677 -412.46546) (xy 329.244625 -412.47322) (xy 329.29692 -412.488578)
			(xy 329.346496 -412.511222) (xy 329.392346 -412.54069) (xy 329.433535 -412.576383) (xy 329.469226 -412.617575)
			(xy 329.498691 -412.663427) (xy 329.521331 -412.713005) (xy 329.536686 -412.7653) (xy 329.544442 -412.819249)
			(xy 329.544442 -412.873748) (xy 330.982098 -412.873748) (xy 330.982098 -412.819252) (xy 330.989853 -412.76531)
			(xy 331.005206 -412.713021) (xy 331.027843 -412.663448) (xy 331.057305 -412.617602) (xy 331.092991 -412.576415)
			(xy 331.134175 -412.540725) (xy 331.180018 -412.51126) (xy 331.229589 -412.488618) (xy 331.281877 -412.473261)
			(xy 331.335818 -412.465501) (xy 331.363066 -412.465012) (xy 332.226666 -412.465012) (xy 332.253922 -412.465433)
			(xy 332.307879 -412.473186) (xy 332.360184 -412.48854) (xy 332.409771 -412.511182) (xy 332.455631 -412.54065)
			(xy 332.49683 -412.576346) (xy 332.532529 -412.617542) (xy 332.562002 -412.663399) (xy 332.584648 -412.712984)
			(xy 332.600007 -412.765287) (xy 332.607765 -412.819244) (xy 332.607765 -412.873752) (xy 334.045275 -412.873752)
			(xy 334.045275 -412.819248) (xy 334.053032 -412.7653) (xy 334.068388 -412.713004) (xy 334.091029 -412.663426)
			(xy 334.120496 -412.617575) (xy 334.156189 -412.576384) (xy 334.19738 -412.540693) (xy 334.243231 -412.511226)
			(xy 334.29281 -412.488585) (xy 334.345106 -412.473231) (xy 334.399054 -412.465475) (xy 334.426306 -412.465012)
			(xy 335.289906 -412.465012) (xy 335.317158 -412.465458) (xy 335.371108 -412.473216) (xy 335.423405 -412.488572)
			(xy 335.472984 -412.511215) (xy 335.518836 -412.540683) (xy 335.560028 -412.576376) (xy 335.595721 -412.617569)
			(xy 335.625188 -412.663421) (xy 335.64783 -412.713001) (xy 335.663185 -412.765298) (xy 335.670942 -412.819248)
			(xy 335.670942 -412.873752) (xy 335.670942 -412.873754) (xy 337.108475 -412.873754) (xy 337.108475 -412.819246)
			(xy 337.116233 -412.765294) (xy 337.131591 -412.712996) (xy 337.154235 -412.663415) (xy 337.183706 -412.617562)
			(xy 337.219403 -412.57637) (xy 337.260599 -412.540679) (xy 337.306455 -412.511213) (xy 337.356039 -412.488575)
			(xy 337.408339 -412.473223) (xy 337.462292 -412.465472) (xy 337.489546 -412.465012) (xy 338.353146 -412.465012)
			(xy 338.380397 -412.465461) (xy 338.434342 -412.473223) (xy 338.486634 -412.488583) (xy 338.536208 -412.511228)
			(xy 338.582055 -412.540697) (xy 338.623242 -412.576391) (xy 338.65893 -412.617582) (xy 338.688394 -412.663432)
			(xy 338.711033 -412.713009) (xy 338.726387 -412.765303) (xy 338.734142 -412.819249) (xy 338.734142 -412.873749)
			(xy 340.171798 -412.873749) (xy 340.171798 -412.819251) (xy 340.179554 -412.765307) (xy 340.194908 -412.713016)
			(xy 340.217546 -412.663443) (xy 340.24701 -412.617596) (xy 340.282698 -412.576408) (xy 340.323884 -412.540718)
			(xy 340.36973 -412.511253) (xy 340.419303 -412.488612) (xy 340.471594 -412.473257) (xy 340.525537 -412.465499)
			(xy 340.552786 -412.465012) (xy 341.416386 -412.465012) (xy 341.443641 -412.465434) (xy 341.497596 -412.47319)
			(xy 341.549899 -412.488545) (xy 341.599483 -412.511188) (xy 341.645341 -412.540657) (xy 341.686537 -412.576353)
			(xy 341.722234 -412.617548) (xy 341.751705 -412.663405) (xy 341.77435 -412.712988) (xy 341.789707 -412.76529)
			(xy 341.797465 -412.819245) (xy 341.797465 -412.873753) (xy 343.234975 -412.873753) (xy 343.234975 -412.819247)
			(xy 343.242733 -412.765297) (xy 343.258089 -412.713) (xy 343.280732 -412.663421) (xy 343.310201 -412.617569)
			(xy 343.345896 -412.576377) (xy 343.387089 -412.540686) (xy 343.432943 -412.51122) (xy 343.482524 -412.48858)
			(xy 343.534822 -412.473227) (xy 343.588773 -412.465474) (xy 343.616026 -412.465012) (xy 344.479626 -412.465012)
			(xy 344.506877 -412.46546) (xy 344.560825 -412.47322) (xy 344.61312 -412.488578) (xy 344.662696 -412.511222)
			(xy 344.708546 -412.54069) (xy 344.749735 -412.576383) (xy 344.785426 -412.617575) (xy 344.814891 -412.663427)
			(xy 344.837531 -412.713005) (xy 344.852886 -412.7653) (xy 344.860642 -412.819249) (xy 344.860642 -412.873748)
			(xy 346.298298 -412.873748) (xy 346.298298 -412.819252) (xy 346.306053 -412.76531) (xy 346.321406 -412.713021)
			(xy 346.344043 -412.663448) (xy 346.373505 -412.617602) (xy 346.409191 -412.576415) (xy 346.450375 -412.540725)
			(xy 346.496218 -412.51126) (xy 346.545789 -412.488618) (xy 346.598077 -412.473261) (xy 346.652018 -412.465501)
			(xy 346.679266 -412.465012) (xy 347.542866 -412.465012) (xy 347.570122 -412.465433) (xy 347.624079 -412.473186)
			(xy 347.676384 -412.48854) (xy 347.725971 -412.511182) (xy 347.771831 -412.54065) (xy 347.81303 -412.576346)
			(xy 347.848729 -412.617542) (xy 347.878202 -412.663399) (xy 347.900848 -412.712984) (xy 347.916207 -412.765287)
			(xy 347.923965 -412.819244) (xy 347.923965 -412.873752) (xy 349.361475 -412.873752) (xy 349.361475 -412.819248)
			(xy 349.369232 -412.7653) (xy 349.384588 -412.713004) (xy 349.407229 -412.663426) (xy 349.436696 -412.617575)
			(xy 349.472389 -412.576384) (xy 349.51358 -412.540693) (xy 349.559431 -412.511226) (xy 349.60901 -412.488585)
			(xy 349.661306 -412.473231) (xy 349.715254 -412.465475) (xy 349.742506 -412.465012) (xy 350.606106 -412.465012)
			(xy 350.633358 -412.465458) (xy 350.687308 -412.473216) (xy 350.739605 -412.488572) (xy 350.789184 -412.511215)
			(xy 350.835036 -412.540683) (xy 350.876228 -412.576376) (xy 350.911921 -412.617569) (xy 350.941388 -412.663421)
			(xy 350.96403 -412.713001) (xy 350.979385 -412.765298) (xy 350.987142 -412.819248) (xy 350.987142 -412.873752)
			(xy 370.513075 -412.873752) (xy 370.513075 -412.819248) (xy 370.520832 -412.7653) (xy 370.536187 -412.713005)
			(xy 370.558829 -412.663427) (xy 370.588295 -412.617576) (xy 370.623987 -412.576386) (xy 370.665178 -412.540694)
			(xy 370.711029 -412.511228) (xy 370.760607 -412.488587) (xy 370.812902 -412.473231) (xy 370.86685 -412.465475)
			(xy 370.894102 -412.465012) (xy 371.757702 -412.465012) (xy 371.784955 -412.465458) (xy 371.838905 -412.473215)
			(xy 371.891202 -412.488571) (xy 371.940782 -412.511214) (xy 371.986634 -412.540682) (xy 372.027826 -412.576375)
			(xy 372.06352 -412.617567) (xy 372.092987 -412.66342) (xy 372.115629 -412.713) (xy 372.130985 -412.765297)
			(xy 372.138742 -412.819247) (xy 372.138742 -412.873753) (xy 373.576275 -412.873753) (xy 373.576275 -412.819247)
			(xy 373.584033 -412.765295) (xy 373.59939 -412.712996) (xy 373.622035 -412.663416) (xy 373.651505 -412.617563)
			(xy 373.687201 -412.576372) (xy 373.728397 -412.54068) (xy 373.774253 -412.511215) (xy 373.823836 -412.488576)
			(xy 373.876136 -412.473224) (xy 373.930089 -412.465472) (xy 373.957342 -412.465012) (xy 374.820942 -412.465012)
			(xy 374.848193 -412.465461) (xy 374.902139 -412.473222) (xy 374.954431 -412.488582) (xy 375.004006 -412.511227)
			(xy 375.049853 -412.540696) (xy 375.091041 -412.576389) (xy 375.126729 -412.61758) (xy 375.156193 -412.663431)
			(xy 375.178833 -412.713008) (xy 375.194186 -412.765302) (xy 375.201942 -412.819249) (xy 375.201942 -412.873749)
			(xy 376.639598 -412.873749) (xy 376.639598 -412.819251) (xy 376.647354 -412.765308) (xy 376.662707 -412.713017)
			(xy 376.685346 -412.663444) (xy 376.714809 -412.617597) (xy 376.750497 -412.576409) (xy 376.791682 -412.54072)
			(xy 376.837528 -412.511254) (xy 376.8871 -412.488613) (xy 376.93939 -412.473258) (xy 376.993333 -412.465499)
			(xy 377.020582 -412.465012) (xy 377.884182 -412.465012) (xy 377.911437 -412.465434) (xy 377.965393 -412.473189)
			(xy 378.017696 -412.488544) (xy 378.067281 -412.511187) (xy 378.113139 -412.540656) (xy 378.154336 -412.576352)
			(xy 378.190033 -412.617547) (xy 378.219504 -412.663403) (xy 378.242149 -412.712987) (xy 378.257507 -412.765289)
			(xy 378.265265 -412.819245) (xy 378.265265 -412.873752) (xy 379.702775 -412.873752) (xy 379.702775 -412.819248)
			(xy 379.710532 -412.765298) (xy 379.725889 -412.713001) (xy 379.748532 -412.663422) (xy 379.778 -412.61757)
			(xy 379.813694 -412.576379) (xy 379.854888 -412.540687) (xy 379.900741 -412.511221) (xy 379.950321 -412.488581)
			(xy 380.002619 -412.473228) (xy 380.05657 -412.465474) (xy 380.083822 -412.465012) (xy 380.947422 -412.465012)
			(xy 380.974674 -412.465459) (xy 381.028622 -412.473219) (xy 381.080917 -412.488577) (xy 381.130494 -412.51122)
			(xy 381.176344 -412.540689) (xy 381.217534 -412.576382) (xy 381.253225 -412.617574) (xy 381.28269 -412.663426)
			(xy 381.305331 -412.713004) (xy 381.320686 -412.7653) (xy 381.328442 -412.819248) (xy 381.328442 -412.873748)
			(xy 382.766098 -412.873748) (xy 382.766098 -412.819252) (xy 382.773853 -412.76531) (xy 382.789206 -412.713022)
			(xy 382.811843 -412.663449) (xy 382.841304 -412.617603) (xy 382.876989 -412.576416) (xy 382.918173 -412.540727)
			(xy 382.964016 -412.511261) (xy 383.013586 -412.488619) (xy 383.065873 -412.473261) (xy 383.119814 -412.465501)
			(xy 383.147062 -412.465012) (xy 384.010662 -412.465012) (xy 384.037918 -412.465432) (xy 384.091876 -412.473185)
			(xy 384.144181 -412.488539) (xy 384.193769 -412.51118) (xy 384.239629 -412.540649) (xy 384.280829 -412.576345)
			(xy 384.316528 -412.61754) (xy 384.346001 -412.663398) (xy 384.368648 -412.712983) (xy 384.384007 -412.765287)
			(xy 384.391765 -412.819244) (xy 384.391765 -412.873752) (xy 385.829275 -412.873752) (xy 385.829275 -412.819248)
			(xy 385.837032 -412.7653) (xy 385.852387 -412.713005) (xy 385.875029 -412.663427) (xy 385.904495 -412.617576)
			(xy 385.940187 -412.576386) (xy 385.981378 -412.540694) (xy 386.027229 -412.511228) (xy 386.076807 -412.488587)
			(xy 386.129102 -412.473231) (xy 386.18305 -412.465475) (xy 386.210302 -412.465012) (xy 387.073902 -412.465012)
			(xy 387.101155 -412.465458) (xy 387.155105 -412.473215) (xy 387.207402 -412.488571) (xy 387.256982 -412.511214)
			(xy 387.302834 -412.540682) (xy 387.344026 -412.576375) (xy 387.37972 -412.617567) (xy 387.409187 -412.66342)
			(xy 387.431829 -412.713) (xy 387.447185 -412.765297) (xy 387.454942 -412.819247) (xy 387.454942 -412.873753)
			(xy 388.892475 -412.873753) (xy 388.892475 -412.819247) (xy 388.900233 -412.765295) (xy 388.91559 -412.712996)
			(xy 388.938235 -412.663416) (xy 388.967705 -412.617563) (xy 389.003401 -412.576372) (xy 389.044597 -412.54068)
			(xy 389.090453 -412.511215) (xy 389.140036 -412.488576) (xy 389.192336 -412.473224) (xy 389.246289 -412.465472)
			(xy 389.273542 -412.465012) (xy 390.137142 -412.465012) (xy 390.164393 -412.465461) (xy 390.218339 -412.473222)
			(xy 390.270631 -412.488582) (xy 390.320206 -412.511227) (xy 390.366053 -412.540696) (xy 390.407241 -412.576389)
			(xy 390.442929 -412.61758) (xy 390.472393 -412.663431) (xy 390.495033 -412.713008) (xy 390.510386 -412.765302)
			(xy 390.518142 -412.819249) (xy 390.518142 -412.873749) (xy 391.955798 -412.873749) (xy 391.955798 -412.819251)
			(xy 391.963554 -412.765308) (xy 391.978907 -412.713017) (xy 392.001546 -412.663444) (xy 392.031009 -412.617597)
			(xy 392.066697 -412.576409) (xy 392.107882 -412.54072) (xy 392.153728 -412.511254) (xy 392.2033 -412.488613)
			(xy 392.25559 -412.473258) (xy 392.309533 -412.465499) (xy 392.336782 -412.465012) (xy 393.200382 -412.465012)
			(xy 393.227637 -412.465434) (xy 393.281593 -412.473189) (xy 393.333896 -412.488544) (xy 393.383481 -412.511187)
			(xy 393.429339 -412.540656) (xy 393.470536 -412.576352) (xy 393.506233 -412.617547) (xy 393.535704 -412.663403)
			(xy 393.558349 -412.712987) (xy 393.573707 -412.765289) (xy 393.581465 -412.819245) (xy 393.581465 -412.873752)
			(xy 395.018975 -412.873752) (xy 395.018975 -412.819248) (xy 395.026732 -412.765298) (xy 395.042089 -412.713001)
			(xy 395.064732 -412.663422) (xy 395.0942 -412.61757) (xy 395.129894 -412.576379) (xy 395.171088 -412.540687)
			(xy 395.216941 -412.511221) (xy 395.266521 -412.488581) (xy 395.318819 -412.473228) (xy 395.37277 -412.465474)
			(xy 395.400022 -412.465012) (xy 396.263622 -412.465012) (xy 396.290874 -412.465459) (xy 396.344822 -412.473219)
			(xy 396.397117 -412.488577) (xy 396.446694 -412.51122) (xy 396.492544 -412.540689) (xy 396.533734 -412.576382)
			(xy 396.569425 -412.617574) (xy 396.59889 -412.663426) (xy 396.621531 -412.713004) (xy 396.636886 -412.7653)
			(xy 396.644642 -412.819248) (xy 396.644642 -412.873748) (xy 398.082298 -412.873748) (xy 398.082298 -412.819252)
			(xy 398.090053 -412.76531) (xy 398.105406 -412.713022) (xy 398.128043 -412.663449) (xy 398.157504 -412.617603)
			(xy 398.193189 -412.576416) (xy 398.234373 -412.540727) (xy 398.280216 -412.511261) (xy 398.329786 -412.488619)
			(xy 398.382073 -412.473261) (xy 398.436014 -412.465501) (xy 398.463262 -412.465012) (xy 399.326862 -412.465012)
			(xy 399.354118 -412.465432) (xy 399.408076 -412.473185) (xy 399.460381 -412.488539) (xy 399.509969 -412.51118)
			(xy 399.555829 -412.540649) (xy 399.597029 -412.576345) (xy 399.632728 -412.61754) (xy 399.662201 -412.663398)
			(xy 399.684848 -412.712983) (xy 399.700207 -412.765287) (xy 399.707965 -412.819244) (xy 399.707965 -412.873752)
			(xy 401.145475 -412.873752) (xy 401.145475 -412.819248) (xy 401.153232 -412.7653) (xy 401.168587 -412.713005)
			(xy 401.191229 -412.663427) (xy 401.220695 -412.617576) (xy 401.256387 -412.576386) (xy 401.297578 -412.540694)
			(xy 401.343429 -412.511228) (xy 401.393007 -412.488587) (xy 401.445302 -412.473231) (xy 401.49925 -412.465475)
			(xy 401.526502 -412.465012) (xy 402.390102 -412.465012) (xy 402.417355 -412.465458) (xy 402.471305 -412.473215)
			(xy 402.523602 -412.488571) (xy 402.573182 -412.511214) (xy 402.619034 -412.540682) (xy 402.660226 -412.576375)
			(xy 402.69592 -412.617567) (xy 402.725387 -412.66342) (xy 402.748029 -412.713) (xy 402.763385 -412.765297)
			(xy 402.771142 -412.819247) (xy 402.771142 -412.873753) (xy 404.208675 -412.873753) (xy 404.208675 -412.819247)
			(xy 404.216433 -412.765295) (xy 404.23179 -412.712996) (xy 404.254435 -412.663416) (xy 404.283905 -412.617563)
			(xy 404.319601 -412.576372) (xy 404.360797 -412.54068) (xy 404.406653 -412.511215) (xy 404.456236 -412.488576)
			(xy 404.508536 -412.473224) (xy 404.562489 -412.465472) (xy 404.589742 -412.465012) (xy 405.453342 -412.465012)
			(xy 405.480593 -412.465461) (xy 405.534539 -412.473222) (xy 405.586831 -412.488582) (xy 405.636406 -412.511227)
			(xy 405.682253 -412.540696) (xy 405.723441 -412.576389) (xy 405.759129 -412.61758) (xy 405.788593 -412.663431)
			(xy 405.811233 -412.713008) (xy 405.826586 -412.765302) (xy 405.834342 -412.819249) (xy 405.834342 -412.873749)
			(xy 407.271998 -412.873749) (xy 407.271998 -412.819251) (xy 407.279754 -412.765308) (xy 407.295107 -412.713017)
			(xy 407.317746 -412.663444) (xy 407.347209 -412.617597) (xy 407.382897 -412.576409) (xy 407.424082 -412.54072)
			(xy 407.469928 -412.511254) (xy 407.5195 -412.488613) (xy 407.57179 -412.473258) (xy 407.625733 -412.465499)
			(xy 407.652982 -412.465012) (xy 408.516582 -412.465012) (xy 408.543837 -412.465434) (xy 408.597793 -412.473189)
			(xy 408.650096 -412.488544) (xy 408.699681 -412.511187) (xy 408.745539 -412.540656) (xy 408.786736 -412.576352)
			(xy 408.822433 -412.617547) (xy 408.851904 -412.663403) (xy 408.874549 -412.712987) (xy 408.889907 -412.765289)
			(xy 408.897665 -412.819245) (xy 408.897665 -412.873752) (xy 410.335175 -412.873752) (xy 410.335175 -412.819248)
			(xy 410.342932 -412.765298) (xy 410.358289 -412.713001) (xy 410.380932 -412.663422) (xy 410.4104 -412.61757)
			(xy 410.446094 -412.576379) (xy 410.487288 -412.540687) (xy 410.533141 -412.511221) (xy 410.582721 -412.488581)
			(xy 410.635019 -412.473228) (xy 410.68897 -412.465474) (xy 410.716222 -412.465012) (xy 411.579822 -412.465012)
			(xy 411.607074 -412.465459) (xy 411.661022 -412.473219) (xy 411.713317 -412.488577) (xy 411.762894 -412.51122)
			(xy 411.808744 -412.540689) (xy 411.849934 -412.576382) (xy 411.885625 -412.617574) (xy 411.91509 -412.663426)
			(xy 411.937731 -412.713004) (xy 411.953086 -412.7653) (xy 411.960842 -412.819248) (xy 411.960842 -412.873748)
			(xy 413.398498 -412.873748) (xy 413.398498 -412.819252) (xy 413.406253 -412.76531) (xy 413.421606 -412.713022)
			(xy 413.444243 -412.663449) (xy 413.473704 -412.617603) (xy 413.509389 -412.576416) (xy 413.550573 -412.540727)
			(xy 413.596416 -412.511261) (xy 413.645986 -412.488619) (xy 413.698273 -412.473261) (xy 413.752214 -412.465501)
			(xy 413.779462 -412.465012) (xy 414.643062 -412.465012) (xy 414.670318 -412.465432) (xy 414.724276 -412.473185)
			(xy 414.776581 -412.488539) (xy 414.826169 -412.51118) (xy 414.872029 -412.540649) (xy 414.913229 -412.576345)
			(xy 414.948928 -412.61754) (xy 414.978401 -412.663398) (xy 415.001048 -412.712983) (xy 415.016407 -412.765287)
			(xy 415.024165 -412.819244) (xy 415.024165 -412.873752) (xy 416.461675 -412.873752) (xy 416.461675 -412.819248)
			(xy 416.469432 -412.7653) (xy 416.484787 -412.713005) (xy 416.507429 -412.663427) (xy 416.536895 -412.617576)
			(xy 416.572587 -412.576386) (xy 416.613778 -412.540694) (xy 416.659629 -412.511228) (xy 416.709207 -412.488587)
			(xy 416.761502 -412.473231) (xy 416.81545 -412.465475) (xy 416.842702 -412.465012) (xy 417.706302 -412.465012)
			(xy 417.733555 -412.465458) (xy 417.787505 -412.473215) (xy 417.839802 -412.488571) (xy 417.889382 -412.511214)
			(xy 417.935234 -412.540682) (xy 417.976426 -412.576375) (xy 418.01212 -412.617567) (xy 418.041587 -412.66342)
			(xy 418.064229 -412.713) (xy 418.079585 -412.765297) (xy 418.087342 -412.819247) (xy 418.087342 -412.873753)
			(xy 418.079585 -412.927703) (xy 418.064229 -412.98) (xy 418.041587 -413.02958) (xy 418.01212 -413.075433)
			(xy 417.976426 -413.116625) (xy 417.935234 -413.152318) (xy 417.90754 -413.170116) (xy 422.998658 -413.170116)
			(xy 423.00263 -412.991873) (xy 423.014538 -412.813984) (xy 423.034359 -412.636802) (xy 423.062053 -412.460678)
			(xy 423.097565 -412.285963) (xy 423.140825 -412.113004) (xy 423.191747 -411.942143) (xy 423.25023 -411.773721)
			(xy 423.316157 -411.608071) (xy 423.389398 -411.445522) (xy 423.469808 -411.286397) (xy 423.557226 -411.131012)
			(xy 423.651479 -410.979676) (xy 423.75238 -410.832688) (xy 423.859729 -410.690341) (xy 423.973312 -410.552918)
			(xy 424.092905 -410.420691) (xy 424.218269 -410.293922) (xy 424.349156 -410.172864) (xy 424.485305 -410.057757)
			(xy 424.626447 -409.948829) (xy 424.772302 -409.846297) (xy 424.922579 -409.750363) (xy 425.07698 -409.66122)
			(xy 425.235199 -409.579043) (xy 425.396922 -409.503995) (xy 425.561827 -409.436227) (xy 425.729588 -409.375871)
			(xy 425.899871 -409.323049) (xy 426.072338 -409.277865) (xy 426.246646 -409.240408) (xy 426.42245 -409.210754)
			(xy 426.5994 -409.188961) (xy 426.777146 -409.175071) (xy 426.955333 -409.169114) (xy 427.13361 -409.1711)
			(xy 427.311621 -409.181026) (xy 427.489013 -409.198872) (xy 427.665433 -409.224602) (xy 427.840533 -409.258166)
			(xy 428.013964 -409.299496) (xy 428.185381 -409.348512) (xy 428.354444 -409.405114) (xy 428.520819 -409.469192)
			(xy 428.684173 -409.540618) (xy 428.844184 -409.61925) (xy 429.000533 -409.704931) (xy 429.15291 -409.797493)
			(xy 429.301013 -409.89675) (xy 429.444547 -410.002507) (xy 429.583227 -410.114552) (xy 429.716778 -410.232664)
			(xy 429.844935 -410.356608) (xy 429.967444 -410.486138) (xy 430.084061 -410.620997) (xy 430.194554 -410.760917)
			(xy 430.298705 -410.90562) (xy 430.396307 -411.054819) (xy 430.487165 -411.208218) (xy 430.571099 -411.365512)
			(xy 430.647944 -411.526388) (xy 430.717545 -411.690529) (xy 430.779766 -411.857606) (xy 430.834482 -412.02729)
			(xy 430.881584 -412.199243) (xy 430.92098 -412.373123) (xy 430.952591 -412.548586) (xy 430.976355 -412.725282)
			(xy 430.992223 -412.902862) (xy 431.000165 -413.080972) (xy 431.000662 -413.170116) (xy 431.000165 -413.25926)
			(xy 430.992223 -413.43737) (xy 430.976355 -413.61495) (xy 430.952591 -413.791646) (xy 430.92098 -413.967109)
			(xy 430.881584 -414.140989) (xy 430.834482 -414.312942) (xy 430.779766 -414.482626) (xy 430.717545 -414.649703)
			(xy 430.647944 -414.813844) (xy 430.571099 -414.97472) (xy 430.487165 -415.132014) (xy 430.396307 -415.285413)
			(xy 430.298705 -415.434612) (xy 430.194554 -415.579315) (xy 430.084061 -415.719235) (xy 429.967444 -415.854094)
			(xy 429.844935 -415.983624) (xy 429.716778 -416.107568) (xy 429.583227 -416.22568) (xy 429.444547 -416.337725)
			(xy 429.301013 -416.443482) (xy 429.15291 -416.542739) (xy 429.000533 -416.635301) (xy 428.844184 -416.720982)
			(xy 428.684173 -416.799614) (xy 428.520819 -416.87104) (xy 428.354444 -416.935118) (xy 428.185381 -416.99172)
			(xy 428.013964 -417.040736) (xy 427.840533 -417.082066) (xy 427.665433 -417.11563) (xy 427.489013 -417.14136)
			(xy 427.311621 -417.159206) (xy 427.13361 -417.169132) (xy 426.955333 -417.171118) (xy 426.777146 -417.165161)
			(xy 426.5994 -417.151271) (xy 426.42245 -417.129478) (xy 426.246646 -417.099824) (xy 426.072338 -417.062367)
			(xy 425.899871 -417.017183) (xy 425.729588 -416.964361) (xy 425.561827 -416.904005) (xy 425.396922 -416.836237)
			(xy 425.235199 -416.761189) (xy 425.07698 -416.679012) (xy 424.922579 -416.589869) (xy 424.772302 -416.493935)
			(xy 424.626447 -416.391403) (xy 424.485305 -416.282475) (xy 424.349156 -416.167368) (xy 424.218269 -416.04631)
			(xy 424.092905 -415.919541) (xy 423.973312 -415.787314) (xy 423.859729 -415.649891) (xy 423.75238 -415.507544)
			(xy 423.651479 -415.360556) (xy 423.557226 -415.20922) (xy 423.469808 -415.053835) (xy 423.389398 -414.89471)
			(xy 423.316157 -414.732161) (xy 423.25023 -414.566511) (xy 423.191747 -414.398089) (xy 423.140825 -414.227228)
			(xy 423.097565 -414.054269) (xy 423.062053 -413.879554) (xy 423.034359 -413.70343) (xy 423.014538 -413.526248)
			(xy 423.00263 -413.348359) (xy 422.998658 -413.170116) (xy 417.90754 -413.170116) (xy 417.889382 -413.181786)
			(xy 417.839802 -413.204429) (xy 417.787505 -413.219785) (xy 417.733555 -413.227542) (xy 417.706302 -413.228028)
			(xy 416.842702 -413.228028) (xy 416.81545 -413.227525) (xy 416.761502 -413.219769) (xy 416.709207 -413.204413)
			(xy 416.659629 -413.181772) (xy 416.613778 -413.152306) (xy 416.572587 -413.116614) (xy 416.536895 -413.075424)
			(xy 416.507429 -413.029573) (xy 416.484787 -412.979995) (xy 416.469432 -412.9277) (xy 416.461675 -412.873752)
			(xy 415.024165 -412.873752) (xy 415.024165 -412.873756) (xy 415.016407 -412.927713) (xy 415.001048 -412.980017)
			(xy 414.978401 -413.029602) (xy 414.948928 -413.07546) (xy 414.913229 -413.116655) (xy 414.872029 -413.152351)
			(xy 414.826169 -413.18182) (xy 414.776581 -413.204461) (xy 414.724276 -413.219815) (xy 414.670318 -413.227568)
			(xy 414.643062 -413.228028) (xy 413.779462 -413.228028) (xy 413.752214 -413.227499) (xy 413.698273 -413.219739)
			(xy 413.645986 -413.204381) (xy 413.596416 -413.181739) (xy 413.550573 -413.152273) (xy 413.509389 -413.116584)
			(xy 413.473704 -413.075397) (xy 413.444243 -413.029551) (xy 413.421606 -412.979978) (xy 413.406253 -412.92769)
			(xy 413.398498 -412.873748) (xy 411.960842 -412.873748) (xy 411.960842 -412.873752) (xy 411.953086 -412.9277)
			(xy 411.937731 -412.979996) (xy 411.91509 -413.029574) (xy 411.885625 -413.075426) (xy 411.849934 -413.116618)
			(xy 411.808744 -413.152311) (xy 411.762894 -413.18178) (xy 411.713317 -413.204423) (xy 411.661022 -413.219781)
			(xy 411.607074 -413.227541) (xy 411.579822 -413.228028) (xy 410.716222 -413.228028) (xy 410.68897 -413.227526)
			(xy 410.635019 -413.219772) (xy 410.582721 -413.204419) (xy 410.533141 -413.181779) (xy 410.487288 -413.152313)
			(xy 410.446094 -413.116621) (xy 410.4104 -413.07543) (xy 410.380932 -413.029578) (xy 410.358289 -412.979999)
			(xy 410.342932 -412.927702) (xy 410.335175 -412.873752) (xy 408.897665 -412.873752) (xy 408.897665 -412.873755)
			(xy 408.889907 -412.927711) (xy 408.874549 -412.980013) (xy 408.851904 -413.029597) (xy 408.822433 -413.075453)
			(xy 408.786736 -413.116648) (xy 408.745539 -413.152344) (xy 408.699681 -413.181813) (xy 408.650096 -413.204456)
			(xy 408.597793 -413.219811) (xy 408.543837 -413.227566) (xy 408.516582 -413.228028) (xy 407.652982 -413.228028)
			(xy 407.625733 -413.227501) (xy 407.57179 -413.219742) (xy 407.5195 -413.204387) (xy 407.469928 -413.181746)
			(xy 407.424082 -413.15228) (xy 407.382897 -413.116591) (xy 407.347209 -413.075403) (xy 407.317746 -413.029556)
			(xy 407.295107 -412.979983) (xy 407.279754 -412.927692) (xy 407.271998 -412.873749) (xy 405.834342 -412.873749)
			(xy 405.834342 -412.873751) (xy 405.826586 -412.927698) (xy 405.811233 -412.979992) (xy 405.788593 -413.029569)
			(xy 405.759129 -413.07542) (xy 405.723441 -413.116611) (xy 405.682253 -413.152304) (xy 405.636406 -413.181773)
			(xy 405.586831 -413.204418) (xy 405.534539 -413.219778) (xy 405.480593 -413.227539) (xy 405.453342 -413.228028)
			(xy 404.589742 -413.228028) (xy 404.562489 -413.227528) (xy 404.508536 -413.219776) (xy 404.456236 -413.204424)
			(xy 404.406653 -413.181785) (xy 404.360797 -413.15232) (xy 404.319601 -413.116628) (xy 404.283905 -413.075437)
			(xy 404.254435 -413.029584) (xy 404.23179 -412.980004) (xy 404.216433 -412.927705) (xy 404.208675 -412.873753)
			(xy 402.771142 -412.873753) (xy 402.763385 -412.927703) (xy 402.748029 -412.98) (xy 402.725387 -413.02958)
			(xy 402.69592 -413.075433) (xy 402.660226 -413.116625) (xy 402.619034 -413.152318) (xy 402.573182 -413.181786)
			(xy 402.523602 -413.204429) (xy 402.471305 -413.219785) (xy 402.417355 -413.227542) (xy 402.390102 -413.228028)
			(xy 401.526502 -413.228028) (xy 401.49925 -413.227525) (xy 401.445302 -413.219769) (xy 401.393007 -413.204413)
			(xy 401.343429 -413.181772) (xy 401.297578 -413.152306) (xy 401.256387 -413.116614) (xy 401.220695 -413.075424)
			(xy 401.191229 -413.029573) (xy 401.168587 -412.979995) (xy 401.153232 -412.9277) (xy 401.145475 -412.873752)
			(xy 399.707965 -412.873752) (xy 399.707965 -412.873756) (xy 399.700207 -412.927713) (xy 399.684848 -412.980017)
			(xy 399.662201 -413.029602) (xy 399.632728 -413.07546) (xy 399.597029 -413.116655) (xy 399.555829 -413.152351)
			(xy 399.509969 -413.18182) (xy 399.460381 -413.204461) (xy 399.408076 -413.219815) (xy 399.354118 -413.227568)
			(xy 399.326862 -413.228028) (xy 398.463262 -413.228028) (xy 398.436014 -413.227499) (xy 398.382073 -413.219739)
			(xy 398.329786 -413.204381) (xy 398.280216 -413.181739) (xy 398.234373 -413.152273) (xy 398.193189 -413.116584)
			(xy 398.157504 -413.075397) (xy 398.128043 -413.029551) (xy 398.105406 -412.979978) (xy 398.090053 -412.92769)
			(xy 398.082298 -412.873748) (xy 396.644642 -412.873748) (xy 396.644642 -412.873752) (xy 396.636886 -412.9277)
			(xy 396.621531 -412.979996) (xy 396.59889 -413.029574) (xy 396.569425 -413.075426) (xy 396.533734 -413.116618)
			(xy 396.492544 -413.152311) (xy 396.446694 -413.18178) (xy 396.397117 -413.204423) (xy 396.344822 -413.219781)
			(xy 396.290874 -413.227541) (xy 396.263622 -413.228028) (xy 395.400022 -413.228028) (xy 395.37277 -413.227526)
			(xy 395.318819 -413.219772) (xy 395.266521 -413.204419) (xy 395.216941 -413.181779) (xy 395.171088 -413.152313)
			(xy 395.129894 -413.116621) (xy 395.0942 -413.07543) (xy 395.064732 -413.029578) (xy 395.042089 -412.979999)
			(xy 395.026732 -412.927702) (xy 395.018975 -412.873752) (xy 393.581465 -412.873752) (xy 393.581465 -412.873755)
			(xy 393.573707 -412.927711) (xy 393.558349 -412.980013) (xy 393.535704 -413.029597) (xy 393.506233 -413.075453)
			(xy 393.470536 -413.116648) (xy 393.429339 -413.152344) (xy 393.383481 -413.181813) (xy 393.333896 -413.204456)
			(xy 393.281593 -413.219811) (xy 393.227637 -413.227566) (xy 393.200382 -413.228028) (xy 392.336782 -413.228028)
			(xy 392.309533 -413.227501) (xy 392.25559 -413.219742) (xy 392.2033 -413.204387) (xy 392.153728 -413.181746)
			(xy 392.107882 -413.15228) (xy 392.066697 -413.116591) (xy 392.031009 -413.075403) (xy 392.001546 -413.029556)
			(xy 391.978907 -412.979983) (xy 391.963554 -412.927692) (xy 391.955798 -412.873749) (xy 390.518142 -412.873749)
			(xy 390.518142 -412.873751) (xy 390.510386 -412.927698) (xy 390.495033 -412.979992) (xy 390.472393 -413.029569)
			(xy 390.442929 -413.07542) (xy 390.407241 -413.116611) (xy 390.366053 -413.152304) (xy 390.320206 -413.181773)
			(xy 390.270631 -413.204418) (xy 390.218339 -413.219778) (xy 390.164393 -413.227539) (xy 390.137142 -413.228028)
			(xy 389.273542 -413.228028) (xy 389.246289 -413.227528) (xy 389.192336 -413.219776) (xy 389.140036 -413.204424)
			(xy 389.090453 -413.181785) (xy 389.044597 -413.15232) (xy 389.003401 -413.116628) (xy 388.967705 -413.075437)
			(xy 388.938235 -413.029584) (xy 388.91559 -412.980004) (xy 388.900233 -412.927705) (xy 388.892475 -412.873753)
			(xy 387.454942 -412.873753) (xy 387.447185 -412.927703) (xy 387.431829 -412.98) (xy 387.409187 -413.02958)
			(xy 387.37972 -413.075433) (xy 387.344026 -413.116625) (xy 387.302834 -413.152318) (xy 387.256982 -413.181786)
			(xy 387.207402 -413.204429) (xy 387.155105 -413.219785) (xy 387.101155 -413.227542) (xy 387.073902 -413.228028)
			(xy 386.210302 -413.228028) (xy 386.18305 -413.227525) (xy 386.129102 -413.219769) (xy 386.076807 -413.204413)
			(xy 386.027229 -413.181772) (xy 385.981378 -413.152306) (xy 385.940187 -413.116614) (xy 385.904495 -413.075424)
			(xy 385.875029 -413.029573) (xy 385.852387 -412.979995) (xy 385.837032 -412.9277) (xy 385.829275 -412.873752)
			(xy 384.391765 -412.873752) (xy 384.391765 -412.873756) (xy 384.384007 -412.927713) (xy 384.368648 -412.980017)
			(xy 384.346001 -413.029602) (xy 384.316528 -413.07546) (xy 384.280829 -413.116655) (xy 384.239629 -413.152351)
			(xy 384.193769 -413.18182) (xy 384.144181 -413.204461) (xy 384.091876 -413.219815) (xy 384.037918 -413.227568)
			(xy 384.010662 -413.228028) (xy 383.147062 -413.228028) (xy 383.119814 -413.227499) (xy 383.065873 -413.219739)
			(xy 383.013586 -413.204381) (xy 382.964016 -413.181739) (xy 382.918173 -413.152273) (xy 382.876989 -413.116584)
			(xy 382.841304 -413.075397) (xy 382.811843 -413.029551) (xy 382.789206 -412.979978) (xy 382.773853 -412.92769)
			(xy 382.766098 -412.873748) (xy 381.328442 -412.873748) (xy 381.328442 -412.873752) (xy 381.320686 -412.9277)
			(xy 381.305331 -412.979996) (xy 381.28269 -413.029574) (xy 381.253225 -413.075426) (xy 381.217534 -413.116618)
			(xy 381.176344 -413.152311) (xy 381.130494 -413.18178) (xy 381.080917 -413.204423) (xy 381.028622 -413.219781)
			(xy 380.974674 -413.227541) (xy 380.947422 -413.228028) (xy 380.083822 -413.228028) (xy 380.05657 -413.227526)
			(xy 380.002619 -413.219772) (xy 379.950321 -413.204419) (xy 379.900741 -413.181779) (xy 379.854888 -413.152313)
			(xy 379.813694 -413.116621) (xy 379.778 -413.07543) (xy 379.748532 -413.029578) (xy 379.725889 -412.979999)
			(xy 379.710532 -412.927702) (xy 379.702775 -412.873752) (xy 378.265265 -412.873752) (xy 378.265265 -412.873755)
			(xy 378.257507 -412.927711) (xy 378.242149 -412.980013) (xy 378.219504 -413.029597) (xy 378.190033 -413.075453)
			(xy 378.154336 -413.116648) (xy 378.113139 -413.152344) (xy 378.067281 -413.181813) (xy 378.017696 -413.204456)
			(xy 377.965393 -413.219811) (xy 377.911437 -413.227566) (xy 377.884182 -413.228028) (xy 377.020582 -413.228028)
			(xy 376.993333 -413.227501) (xy 376.93939 -413.219742) (xy 376.8871 -413.204387) (xy 376.837528 -413.181746)
			(xy 376.791682 -413.15228) (xy 376.750497 -413.116591) (xy 376.714809 -413.075403) (xy 376.685346 -413.029556)
			(xy 376.662707 -412.979983) (xy 376.647354 -412.927692) (xy 376.639598 -412.873749) (xy 375.201942 -412.873749)
			(xy 375.201942 -412.873751) (xy 375.194186 -412.927698) (xy 375.178833 -412.979992) (xy 375.156193 -413.029569)
			(xy 375.126729 -413.07542) (xy 375.091041 -413.116611) (xy 375.049853 -413.152304) (xy 375.004006 -413.181773)
			(xy 374.954431 -413.204418) (xy 374.902139 -413.219778) (xy 374.848193 -413.227539) (xy 374.820942 -413.228028)
			(xy 373.957342 -413.228028) (xy 373.930089 -413.227528) (xy 373.876136 -413.219776) (xy 373.823836 -413.204424)
			(xy 373.774253 -413.181785) (xy 373.728397 -413.15232) (xy 373.687201 -413.116628) (xy 373.651505 -413.075437)
			(xy 373.622035 -413.029584) (xy 373.59939 -412.980004) (xy 373.584033 -412.927705) (xy 373.576275 -412.873753)
			(xy 372.138742 -412.873753) (xy 372.130985 -412.927703) (xy 372.115629 -412.98) (xy 372.092987 -413.02958)
			(xy 372.06352 -413.075433) (xy 372.027826 -413.116625) (xy 371.986634 -413.152318) (xy 371.940782 -413.181786)
			(xy 371.891202 -413.204429) (xy 371.838905 -413.219785) (xy 371.784955 -413.227542) (xy 371.757702 -413.228028)
			(xy 370.894102 -413.228028) (xy 370.86685 -413.227525) (xy 370.812902 -413.219769) (xy 370.760607 -413.204413)
			(xy 370.711029 -413.181772) (xy 370.665178 -413.152306) (xy 370.623987 -413.116614) (xy 370.588295 -413.075424)
			(xy 370.558829 -413.029573) (xy 370.536187 -412.979995) (xy 370.520832 -412.9277) (xy 370.513075 -412.873752)
			(xy 350.987142 -412.873752) (xy 350.979385 -412.927702) (xy 350.96403 -412.979999) (xy 350.941388 -413.029579)
			(xy 350.911921 -413.075431) (xy 350.876228 -413.116624) (xy 350.835036 -413.152317) (xy 350.789184 -413.181785)
			(xy 350.739605 -413.204428) (xy 350.687308 -413.219784) (xy 350.633358 -413.227542) (xy 350.606106 -413.228028)
			(xy 349.742506 -413.228028) (xy 349.715254 -413.227525) (xy 349.661306 -413.219769) (xy 349.60901 -413.204415)
			(xy 349.559431 -413.181774) (xy 349.51358 -413.152307) (xy 349.472389 -413.116616) (xy 349.436696 -413.075425)
			(xy 349.407229 -413.029574) (xy 349.384588 -412.979996) (xy 349.369232 -412.9277) (xy 349.361475 -412.873752)
			(xy 347.923965 -412.873752) (xy 347.923965 -412.873756) (xy 347.916207 -412.927713) (xy 347.900848 -412.980016)
			(xy 347.878202 -413.029601) (xy 347.848729 -413.075458) (xy 347.81303 -413.116654) (xy 347.771831 -413.15235)
			(xy 347.725971 -413.181818) (xy 347.676384 -413.20446) (xy 347.624079 -413.219814) (xy 347.570122 -413.227567)
			(xy 347.542866 -413.228028) (xy 346.679266 -413.228028) (xy 346.652018 -413.227499) (xy 346.598077 -413.219739)
			(xy 346.545789 -413.204382) (xy 346.496218 -413.18174) (xy 346.450375 -413.152275) (xy 346.409191 -413.116585)
			(xy 346.373505 -413.075398) (xy 346.344043 -413.029552) (xy 346.321406 -412.979979) (xy 346.306053 -412.92769)
			(xy 346.298298 -412.873748) (xy 344.860642 -412.873748) (xy 344.860642 -412.873751) (xy 344.852886 -412.9277)
			(xy 344.837531 -412.979995) (xy 344.814891 -413.029573) (xy 344.785426 -413.075425) (xy 344.749735 -413.116617)
			(xy 344.708546 -413.15231) (xy 344.662696 -413.181778) (xy 344.61312 -413.204422) (xy 344.560825 -413.21978)
			(xy 344.506877 -413.22754) (xy 344.479626 -413.228028) (xy 343.616026 -413.228028) (xy 343.588773 -413.227526)
			(xy 343.534822 -413.219773) (xy 343.482524 -413.20442) (xy 343.432943 -413.18178) (xy 343.387089 -413.152314)
			(xy 343.345896 -413.116623) (xy 343.310201 -413.075431) (xy 343.280732 -413.029579) (xy 343.258089 -412.98)
			(xy 343.242733 -412.927703) (xy 343.234975 -412.873753) (xy 341.797465 -412.873753) (xy 341.797465 -412.873755)
			(xy 341.789707 -412.92771) (xy 341.77435 -412.980012) (xy 341.751705 -413.029595) (xy 341.722234 -413.075452)
			(xy 341.686537 -413.116647) (xy 341.645341 -413.152343) (xy 341.599483 -413.181812) (xy 341.549899 -413.204455)
			(xy 341.497596 -413.21981) (xy 341.443641 -413.227566) (xy 341.416386 -413.228028) (xy 340.552786 -413.228028)
			(xy 340.525537 -413.227501) (xy 340.471594 -413.219743) (xy 340.419303 -413.204388) (xy 340.36973 -413.181747)
			(xy 340.323884 -413.152282) (xy 340.282698 -413.116592) (xy 340.24701 -413.075404) (xy 340.217546 -413.029557)
			(xy 340.194908 -412.979984) (xy 340.179554 -412.927693) (xy 340.171798 -412.873749) (xy 338.734142 -412.873749)
			(xy 338.734142 -412.873751) (xy 338.726387 -412.927697) (xy 338.711033 -412.979991) (xy 338.688394 -413.029568)
			(xy 338.65893 -413.075418) (xy 338.623242 -413.116609) (xy 338.582055 -413.152303) (xy 338.536208 -413.181772)
			(xy 338.486634 -413.204417) (xy 338.434342 -413.219777) (xy 338.380397 -413.227539) (xy 338.353146 -413.228028)
			(xy 337.489546 -413.228028) (xy 337.462292 -413.227528) (xy 337.408339 -413.219777) (xy 337.356039 -413.204425)
			(xy 337.306455 -413.181787) (xy 337.260599 -413.152321) (xy 337.219403 -413.11663) (xy 337.183706 -413.075438)
			(xy 337.154235 -413.029585) (xy 337.131591 -412.980004) (xy 337.116233 -412.927706) (xy 337.108475 -412.873754)
			(xy 335.670942 -412.873754) (xy 335.663185 -412.927702) (xy 335.64783 -412.979999) (xy 335.625188 -413.029579)
			(xy 335.595721 -413.075431) (xy 335.560028 -413.116624) (xy 335.518836 -413.152317) (xy 335.472984 -413.181785)
			(xy 335.423405 -413.204428) (xy 335.371108 -413.219784) (xy 335.317158 -413.227542) (xy 335.289906 -413.228028)
			(xy 334.426306 -413.228028) (xy 334.399054 -413.227525) (xy 334.345106 -413.219769) (xy 334.29281 -413.204415)
			(xy 334.243231 -413.181774) (xy 334.19738 -413.152307) (xy 334.156189 -413.116616) (xy 334.120496 -413.075425)
			(xy 334.091029 -413.029574) (xy 334.068388 -412.979996) (xy 334.053032 -412.9277) (xy 334.045275 -412.873752)
			(xy 332.607765 -412.873752) (xy 332.607765 -412.873756) (xy 332.600007 -412.927713) (xy 332.584648 -412.980016)
			(xy 332.562002 -413.029601) (xy 332.532529 -413.075458) (xy 332.49683 -413.116654) (xy 332.455631 -413.15235)
			(xy 332.409771 -413.181818) (xy 332.360184 -413.20446) (xy 332.307879 -413.219814) (xy 332.253922 -413.227567)
			(xy 332.226666 -413.228028) (xy 331.363066 -413.228028) (xy 331.335818 -413.227499) (xy 331.281877 -413.219739)
			(xy 331.229589 -413.204382) (xy 331.180018 -413.18174) (xy 331.134175 -413.152275) (xy 331.092991 -413.116585)
			(xy 331.057305 -413.075398) (xy 331.027843 -413.029552) (xy 331.005206 -412.979979) (xy 330.989853 -412.92769)
			(xy 330.982098 -412.873748) (xy 329.544442 -412.873748) (xy 329.544442 -412.873751) (xy 329.536686 -412.9277)
			(xy 329.521331 -412.979995) (xy 329.498691 -413.029573) (xy 329.469226 -413.075425) (xy 329.433535 -413.116617)
			(xy 329.392346 -413.15231) (xy 329.346496 -413.181778) (xy 329.29692 -413.204422) (xy 329.244625 -413.21978)
			(xy 329.190677 -413.22754) (xy 329.163426 -413.228028) (xy 328.299826 -413.228028) (xy 328.272573 -413.227526)
			(xy 328.218622 -413.219773) (xy 328.166324 -413.20442) (xy 328.116743 -413.18178) (xy 328.070889 -413.152314)
			(xy 328.029696 -413.116623) (xy 327.994001 -413.075431) (xy 327.964532 -413.029579) (xy 327.941889 -412.98)
			(xy 327.926533 -412.927703) (xy 327.918775 -412.873753) (xy 326.481265 -412.873753) (xy 326.481265 -412.873755)
			(xy 326.473507 -412.92771) (xy 326.45815 -412.980012) (xy 326.435505 -413.029595) (xy 326.406034 -413.075452)
			(xy 326.370337 -413.116647) (xy 326.329141 -413.152343) (xy 326.283283 -413.181812) (xy 326.233699 -413.204455)
			(xy 326.181396 -413.21981) (xy 326.127441 -413.227566) (xy 326.100186 -413.228028) (xy 325.236586 -413.228028)
			(xy 325.209337 -413.227501) (xy 325.155394 -413.219743) (xy 325.103103 -413.204388) (xy 325.05353 -413.181747)
			(xy 325.007684 -413.152282) (xy 324.966498 -413.116592) (xy 324.93081 -413.075404) (xy 324.901346 -413.029557)
			(xy 324.878708 -412.979984) (xy 324.863354 -412.927693) (xy 324.855598 -412.873749) (xy 323.417942 -412.873749)
			(xy 323.417942 -412.873751) (xy 323.410187 -412.927697) (xy 323.394833 -412.979991) (xy 323.372194 -413.029568)
			(xy 323.34273 -413.075418) (xy 323.307042 -413.116609) (xy 323.265855 -413.152303) (xy 323.220008 -413.181772)
			(xy 323.170434 -413.204417) (xy 323.118142 -413.219777) (xy 323.064197 -413.227539) (xy 323.036946 -413.228028)
			(xy 322.173346 -413.228028) (xy 322.146092 -413.227528) (xy 322.092139 -413.219777) (xy 322.039839 -413.204425)
			(xy 321.990255 -413.181787) (xy 321.944399 -413.152321) (xy 321.903203 -413.11663) (xy 321.867506 -413.075438)
			(xy 321.838035 -413.029585) (xy 321.815391 -412.980004) (xy 321.800033 -412.927706) (xy 321.792275 -412.873754)
			(xy 320.354742 -412.873754) (xy 320.346985 -412.927702) (xy 320.33163 -412.979999) (xy 320.308988 -413.029579)
			(xy 320.279521 -413.075431) (xy 320.243828 -413.116624) (xy 320.202636 -413.152317) (xy 320.156784 -413.181785)
			(xy 320.107205 -413.204428) (xy 320.054908 -413.219784) (xy 320.000958 -413.227542) (xy 319.973706 -413.228028)
			(xy 319.110106 -413.228028) (xy 319.082854 -413.227525) (xy 319.028906 -413.219769) (xy 318.97661 -413.204415)
			(xy 318.927031 -413.181774) (xy 318.88118 -413.152307) (xy 318.839989 -413.116616) (xy 318.804296 -413.075425)
			(xy 318.774829 -413.029574) (xy 318.752188 -412.979996) (xy 318.736832 -412.9277) (xy 318.729075 -412.873752)
			(xy 317.291565 -412.873752) (xy 317.291565 -412.873756) (xy 317.283807 -412.927713) (xy 317.268448 -412.980016)
			(xy 317.245802 -413.029601) (xy 317.216329 -413.075458) (xy 317.18063 -413.116654) (xy 317.139431 -413.15235)
			(xy 317.093571 -413.181818) (xy 317.043984 -413.20446) (xy 316.991679 -413.219814) (xy 316.937722 -413.227567)
			(xy 316.910466 -413.228028) (xy 316.046866 -413.228028) (xy 316.019618 -413.227499) (xy 315.965677 -413.219739)
			(xy 315.913389 -413.204382) (xy 315.863818 -413.18174) (xy 315.817975 -413.152275) (xy 315.776791 -413.116585)
			(xy 315.741105 -413.075398) (xy 315.711643 -413.029552) (xy 315.689006 -412.979979) (xy 315.673653 -412.92769)
			(xy 315.665898 -412.873748) (xy 314.228242 -412.873748) (xy 314.228242 -412.873751) (xy 314.220486 -412.9277)
			(xy 314.205131 -412.979995) (xy 314.182491 -413.029573) (xy 314.153026 -413.075425) (xy 314.117335 -413.116617)
			(xy 314.076146 -413.15231) (xy 314.030296 -413.181778) (xy 313.98072 -413.204422) (xy 313.928425 -413.21978)
			(xy 313.874477 -413.22754) (xy 313.847226 -413.228028) (xy 312.983626 -413.228028) (xy 312.956373 -413.227526)
			(xy 312.902422 -413.219773) (xy 312.850124 -413.20442) (xy 312.800543 -413.18178) (xy 312.754689 -413.152314)
			(xy 312.713496 -413.116623) (xy 312.677801 -413.075431) (xy 312.648332 -413.029579) (xy 312.625689 -412.98)
			(xy 312.610333 -412.927703) (xy 312.602575 -412.873753) (xy 311.165065 -412.873753) (xy 311.165065 -412.873755)
			(xy 311.157307 -412.92771) (xy 311.14195 -412.980012) (xy 311.119305 -413.029595) (xy 311.089834 -413.075452)
			(xy 311.054137 -413.116647) (xy 311.012941 -413.152343) (xy 310.967083 -413.181812) (xy 310.917499 -413.204455)
			(xy 310.865196 -413.21981) (xy 310.811241 -413.227566) (xy 310.783986 -413.228028) (xy 309.920386 -413.228028)
			(xy 309.893137 -413.227501) (xy 309.839194 -413.219743) (xy 309.786903 -413.204388) (xy 309.73733 -413.181747)
			(xy 309.691484 -413.152282) (xy 309.650298 -413.116592) (xy 309.61461 -413.075404) (xy 309.585146 -413.029557)
			(xy 309.562508 -412.979984) (xy 309.547154 -412.927693) (xy 309.539398 -412.873749) (xy 308.101742 -412.873749)
			(xy 308.101742 -412.873751) (xy 308.093987 -412.927697) (xy 308.078633 -412.979991) (xy 308.055994 -413.029568)
			(xy 308.02653 -413.075418) (xy 307.990842 -413.116609) (xy 307.949655 -413.152303) (xy 307.903808 -413.181772)
			(xy 307.854234 -413.204417) (xy 307.801942 -413.219777) (xy 307.747997 -413.227539) (xy 307.720746 -413.228028)
			(xy 306.857146 -413.228028) (xy 306.829892 -413.227528) (xy 306.775939 -413.219777) (xy 306.723639 -413.204425)
			(xy 306.674055 -413.181787) (xy 306.628199 -413.152321) (xy 306.587003 -413.11663) (xy 306.551306 -413.075438)
			(xy 306.521835 -413.029585) (xy 306.499191 -412.980004) (xy 306.483833 -412.927706) (xy 306.476075 -412.873754)
			(xy 305.038542 -412.873754) (xy 305.030785 -412.927702) (xy 305.01543 -412.979999) (xy 304.992788 -413.029579)
			(xy 304.963321 -413.075431) (xy 304.927628 -413.116624) (xy 304.886436 -413.152317) (xy 304.840584 -413.181785)
			(xy 304.791005 -413.204428) (xy 304.738708 -413.219784) (xy 304.684758 -413.227542) (xy 304.657506 -413.228028)
			(xy 303.793906 -413.228028) (xy 303.766654 -413.227525) (xy 303.712706 -413.219769) (xy 303.66041 -413.204415)
			(xy 303.610831 -413.181774) (xy 303.56498 -413.152307) (xy 303.523789 -413.116616) (xy 303.488096 -413.075425)
			(xy 303.458629 -413.029574) (xy 303.435988 -412.979996) (xy 303.420632 -412.9277) (xy 303.412875 -412.873752)
			(xy 301.559858 -412.873752) (xy 301.562459 -412.902862) (xy 301.570401 -413.080972) (xy 301.570898 -413.170116)
			(xy 301.570401 -413.25926) (xy 301.562459 -413.43737) (xy 301.546591 -413.61495) (xy 301.522827 -413.791646)
			(xy 301.491216 -413.967109) (xy 301.45182 -414.140989) (xy 301.404718 -414.312942) (xy 301.350002 -414.482626)
			(xy 301.287781 -414.649703) (xy 301.21818 -414.813844) (xy 301.141335 -414.97472) (xy 301.057401 -415.132014)
			(xy 300.966543 -415.285413) (xy 300.882586 -415.413753) (xy 304.944475 -415.413753) (xy 304.944475 -415.359247)
			(xy 304.952233 -415.305297) (xy 304.967589 -415.253) (xy 304.990232 -415.203421) (xy 305.019701 -415.157569)
			(xy 305.055396 -415.116377) (xy 305.096589 -415.080686) (xy 305.142443 -415.05122) (xy 305.192024 -415.02858)
			(xy 305.244322 -415.013227) (xy 305.298273 -415.005474) (xy 305.325526 -415.005012) (xy 306.189126 -415.005012)
			(xy 306.216377 -415.00546) (xy 306.270325 -415.01322) (xy 306.32262 -415.028578) (xy 306.372196 -415.051222)
			(xy 306.418046 -415.08069) (xy 306.459235 -415.116383) (xy 306.494926 -415.157575) (xy 306.524391 -415.203427)
			(xy 306.547031 -415.253005) (xy 306.562386 -415.3053) (xy 306.570142 -415.359249) (xy 306.570142 -415.413748)
			(xy 308.007798 -415.413748) (xy 308.007798 -415.359252) (xy 308.015553 -415.30531) (xy 308.030906 -415.253021)
			(xy 308.053543 -415.203448) (xy 308.083005 -415.157602) (xy 308.118691 -415.116415) (xy 308.159875 -415.080725)
			(xy 308.205718 -415.05126) (xy 308.255289 -415.028618) (xy 308.307577 -415.013261) (xy 308.361518 -415.005501)
			(xy 308.388766 -415.005012) (xy 309.252366 -415.005012) (xy 309.279622 -415.005433) (xy 309.333579 -415.013186)
			(xy 309.385884 -415.02854) (xy 309.435471 -415.051182) (xy 309.481331 -415.08065) (xy 309.52253 -415.116346)
			(xy 309.558229 -415.157542) (xy 309.587702 -415.203399) (xy 309.610348 -415.252984) (xy 309.625707 -415.305287)
			(xy 309.633465 -415.359244) (xy 309.633465 -415.413752) (xy 311.070975 -415.413752) (xy 311.070975 -415.359248)
			(xy 311.078732 -415.3053) (xy 311.094088 -415.253004) (xy 311.116729 -415.203426) (xy 311.146196 -415.157575)
			(xy 311.181889 -415.116384) (xy 311.22308 -415.080693) (xy 311.268931 -415.051226) (xy 311.31851 -415.028585)
			(xy 311.370806 -415.013231) (xy 311.424754 -415.005475) (xy 311.452006 -415.005012) (xy 312.315606 -415.005012)
			(xy 312.342858 -415.005458) (xy 312.396808 -415.013216) (xy 312.449105 -415.028572) (xy 312.498684 -415.051215)
			(xy 312.544536 -415.080683) (xy 312.585728 -415.116376) (xy 312.621421 -415.157569) (xy 312.650888 -415.203421)
			(xy 312.67353 -415.253001) (xy 312.688885 -415.305298) (xy 312.696642 -415.359248) (xy 312.696642 -415.413752)
			(xy 312.696642 -415.413754) (xy 314.134175 -415.413754) (xy 314.134175 -415.359246) (xy 314.141933 -415.305294)
			(xy 314.157291 -415.252996) (xy 314.179935 -415.203415) (xy 314.209406 -415.157562) (xy 314.245103 -415.11637)
			(xy 314.286299 -415.080679) (xy 314.332155 -415.051213) (xy 314.381739 -415.028575) (xy 314.434039 -415.013223)
			(xy 314.487992 -415.005472) (xy 314.515246 -415.005012) (xy 315.378846 -415.005012) (xy 315.406097 -415.005461)
			(xy 315.460042 -415.013223) (xy 315.512334 -415.028583) (xy 315.561908 -415.051228) (xy 315.607755 -415.080697)
			(xy 315.648942 -415.116391) (xy 315.68463 -415.157582) (xy 315.714094 -415.203432) (xy 315.736733 -415.253009)
			(xy 315.752087 -415.305303) (xy 315.759842 -415.359249) (xy 315.759842 -415.413749) (xy 317.197498 -415.413749)
			(xy 317.197498 -415.359251) (xy 317.205254 -415.305307) (xy 317.220608 -415.253016) (xy 317.243246 -415.203443)
			(xy 317.27271 -415.157596) (xy 317.308398 -415.116408) (xy 317.349584 -415.080718) (xy 317.39543 -415.051253)
			(xy 317.445003 -415.028612) (xy 317.497294 -415.013257) (xy 317.551237 -415.005499) (xy 317.578486 -415.005012)
			(xy 318.442086 -415.005012) (xy 318.469341 -415.005434) (xy 318.523296 -415.01319) (xy 318.575599 -415.028545)
			(xy 318.625183 -415.051188) (xy 318.671041 -415.080657) (xy 318.712237 -415.116353) (xy 318.747934 -415.157548)
			(xy 318.777405 -415.203405) (xy 318.80005 -415.252988) (xy 318.815407 -415.30529) (xy 318.823165 -415.359245)
			(xy 318.823165 -415.413753) (xy 320.260675 -415.413753) (xy 320.260675 -415.359247) (xy 320.268433 -415.305297)
			(xy 320.283789 -415.253) (xy 320.306432 -415.203421) (xy 320.335901 -415.157569) (xy 320.371596 -415.116377)
			(xy 320.412789 -415.080686) (xy 320.458643 -415.05122) (xy 320.508224 -415.02858) (xy 320.560522 -415.013227)
			(xy 320.614473 -415.005474) (xy 320.641726 -415.005012) (xy 321.505326 -415.005012) (xy 321.532577 -415.00546)
			(xy 321.586525 -415.01322) (xy 321.63882 -415.028578) (xy 321.688396 -415.051222) (xy 321.734246 -415.08069)
			(xy 321.775435 -415.116383) (xy 321.811126 -415.157575) (xy 321.840591 -415.203427) (xy 321.863231 -415.253005)
			(xy 321.878586 -415.3053) (xy 321.886342 -415.359249) (xy 321.886342 -415.413748) (xy 323.323998 -415.413748)
			(xy 323.323998 -415.359252) (xy 323.331753 -415.30531) (xy 323.347106 -415.253021) (xy 323.369743 -415.203448)
			(xy 323.399205 -415.157602) (xy 323.434891 -415.116415) (xy 323.476075 -415.080725) (xy 323.521918 -415.05126)
			(xy 323.571489 -415.028618) (xy 323.623777 -415.013261) (xy 323.677718 -415.005501) (xy 323.704966 -415.005012)
			(xy 324.568566 -415.005012) (xy 324.595822 -415.005433) (xy 324.649779 -415.013186) (xy 324.702084 -415.02854)
			(xy 324.751671 -415.051182) (xy 324.797531 -415.08065) (xy 324.83873 -415.116346) (xy 324.874429 -415.157542)
			(xy 324.903902 -415.203399) (xy 324.926548 -415.252984) (xy 324.941907 -415.305287) (xy 324.949665 -415.359244)
			(xy 324.949665 -415.413752) (xy 326.387175 -415.413752) (xy 326.387175 -415.359248) (xy 326.394932 -415.3053)
			(xy 326.410288 -415.253004) (xy 326.432929 -415.203426) (xy 326.462396 -415.157575) (xy 326.498089 -415.116384)
			(xy 326.53928 -415.080693) (xy 326.585131 -415.051226) (xy 326.63471 -415.028585) (xy 326.687006 -415.013231)
			(xy 326.740954 -415.005475) (xy 326.768206 -415.005012) (xy 327.631806 -415.005012) (xy 327.659058 -415.005458)
			(xy 327.713008 -415.013216) (xy 327.765305 -415.028572) (xy 327.814884 -415.051215) (xy 327.860736 -415.080683)
			(xy 327.901928 -415.116376) (xy 327.937621 -415.157569) (xy 327.967088 -415.203421) (xy 327.98973 -415.253001)
			(xy 328.005085 -415.305298) (xy 328.012842 -415.359248) (xy 328.012842 -415.413752) (xy 328.012842 -415.413754)
			(xy 329.450375 -415.413754) (xy 329.450375 -415.359246) (xy 329.458133 -415.305294) (xy 329.473491 -415.252996)
			(xy 329.496135 -415.203415) (xy 329.525606 -415.157562) (xy 329.561303 -415.11637) (xy 329.602499 -415.080679)
			(xy 329.648355 -415.051213) (xy 329.697939 -415.028575) (xy 329.750239 -415.013223) (xy 329.804192 -415.005472)
			(xy 329.831446 -415.005012) (xy 330.695046 -415.005012) (xy 330.722297 -415.005461) (xy 330.776242 -415.013223)
			(xy 330.828534 -415.028583) (xy 330.878108 -415.051228) (xy 330.923955 -415.080697) (xy 330.965142 -415.116391)
			(xy 331.00083 -415.157582) (xy 331.030294 -415.203432) (xy 331.052933 -415.253009) (xy 331.068287 -415.305303)
			(xy 331.076042 -415.359249) (xy 331.076042 -415.413749) (xy 332.513698 -415.413749) (xy 332.513698 -415.359251)
			(xy 332.521454 -415.305307) (xy 332.536808 -415.253016) (xy 332.559446 -415.203443) (xy 332.58891 -415.157596)
			(xy 332.624598 -415.116408) (xy 332.665784 -415.080718) (xy 332.71163 -415.051253) (xy 332.761203 -415.028612)
			(xy 332.813494 -415.013257) (xy 332.867437 -415.005499) (xy 332.894686 -415.005012) (xy 333.758286 -415.005012)
			(xy 333.785541 -415.005434) (xy 333.839496 -415.01319) (xy 333.891799 -415.028545) (xy 333.941383 -415.051188)
			(xy 333.987241 -415.080657) (xy 334.028437 -415.116353) (xy 334.064134 -415.157548) (xy 334.093605 -415.203405)
			(xy 334.11625 -415.252988) (xy 334.131607 -415.30529) (xy 334.139365 -415.359245) (xy 334.139365 -415.413753)
			(xy 335.576875 -415.413753) (xy 335.576875 -415.359247) (xy 335.584633 -415.305297) (xy 335.599989 -415.253)
			(xy 335.622632 -415.203421) (xy 335.652101 -415.157569) (xy 335.687796 -415.116377) (xy 335.728989 -415.080686)
			(xy 335.774843 -415.05122) (xy 335.824424 -415.02858) (xy 335.876722 -415.013227) (xy 335.930673 -415.005474)
			(xy 335.957926 -415.005012) (xy 336.821526 -415.005012) (xy 336.848777 -415.00546) (xy 336.902725 -415.01322)
			(xy 336.95502 -415.028578) (xy 337.004596 -415.051222) (xy 337.050446 -415.08069) (xy 337.091635 -415.116383)
			(xy 337.127326 -415.157575) (xy 337.156791 -415.203427) (xy 337.179431 -415.253005) (xy 337.194786 -415.3053)
			(xy 337.202542 -415.359249) (xy 337.202542 -415.413748) (xy 338.640198 -415.413748) (xy 338.640198 -415.359252)
			(xy 338.647953 -415.30531) (xy 338.663306 -415.253021) (xy 338.685943 -415.203448) (xy 338.715405 -415.157602)
			(xy 338.751091 -415.116415) (xy 338.792275 -415.080725) (xy 338.838118 -415.05126) (xy 338.887689 -415.028618)
			(xy 338.939977 -415.013261) (xy 338.993918 -415.005501) (xy 339.021166 -415.005012) (xy 339.884766 -415.005012)
			(xy 339.912022 -415.005433) (xy 339.965979 -415.013186) (xy 340.018284 -415.02854) (xy 340.067871 -415.051182)
			(xy 340.113731 -415.08065) (xy 340.15493 -415.116346) (xy 340.190629 -415.157542) (xy 340.220102 -415.203399)
			(xy 340.242748 -415.252984) (xy 340.258107 -415.305287) (xy 340.265865 -415.359244) (xy 340.265865 -415.413752)
			(xy 341.703375 -415.413752) (xy 341.703375 -415.359248) (xy 341.711132 -415.3053) (xy 341.726488 -415.253004)
			(xy 341.749129 -415.203426) (xy 341.778596 -415.157575) (xy 341.814289 -415.116384) (xy 341.85548 -415.080693)
			(xy 341.901331 -415.051226) (xy 341.95091 -415.028585) (xy 342.003206 -415.013231) (xy 342.057154 -415.005475)
			(xy 342.084406 -415.005012) (xy 342.948006 -415.005012) (xy 342.975258 -415.005458) (xy 343.029208 -415.013216)
			(xy 343.081505 -415.028572) (xy 343.131084 -415.051215) (xy 343.176936 -415.080683) (xy 343.218128 -415.116376)
			(xy 343.253821 -415.157569) (xy 343.283288 -415.203421) (xy 343.30593 -415.253001) (xy 343.321285 -415.305298)
			(xy 343.329042 -415.359248) (xy 343.329042 -415.413752) (xy 343.329042 -415.413754) (xy 344.766575 -415.413754)
			(xy 344.766575 -415.359246) (xy 344.774333 -415.305294) (xy 344.789691 -415.252996) (xy 344.812335 -415.203415)
			(xy 344.841806 -415.157562) (xy 344.877503 -415.11637) (xy 344.918699 -415.080679) (xy 344.964555 -415.051213)
			(xy 345.014139 -415.028575) (xy 345.066439 -415.013223) (xy 345.120392 -415.005472) (xy 345.147646 -415.005012)
			(xy 346.011246 -415.005012) (xy 346.038497 -415.005461) (xy 346.092442 -415.013223) (xy 346.144734 -415.028583)
			(xy 346.194308 -415.051228) (xy 346.240155 -415.080697) (xy 346.281342 -415.116391) (xy 346.31703 -415.157582)
			(xy 346.346494 -415.203432) (xy 346.369133 -415.253009) (xy 346.384487 -415.305303) (xy 346.392242 -415.359249)
			(xy 346.392242 -415.413749) (xy 347.829898 -415.413749) (xy 347.829898 -415.359251) (xy 347.837654 -415.305307)
			(xy 347.853008 -415.253016) (xy 347.875646 -415.203443) (xy 347.90511 -415.157596) (xy 347.940798 -415.116408)
			(xy 347.981984 -415.080718) (xy 348.02783 -415.051253) (xy 348.077403 -415.028612) (xy 348.129694 -415.013257)
			(xy 348.183637 -415.005499) (xy 348.210886 -415.005012) (xy 349.074486 -415.005012) (xy 349.101741 -415.005434)
			(xy 349.155696 -415.01319) (xy 349.207999 -415.028545) (xy 349.257583 -415.051188) (xy 349.303441 -415.080657)
			(xy 349.344637 -415.116353) (xy 349.380334 -415.157548) (xy 349.409805 -415.203405) (xy 349.43245 -415.252988)
			(xy 349.447807 -415.30529) (xy 349.455565 -415.359245) (xy 349.455565 -415.413753) (xy 350.893075 -415.413753)
			(xy 350.893075 -415.359247) (xy 350.900833 -415.305297) (xy 350.916189 -415.253) (xy 350.938832 -415.203421)
			(xy 350.968301 -415.157569) (xy 351.003996 -415.116377) (xy 351.045189 -415.080686) (xy 351.091043 -415.05122)
			(xy 351.140624 -415.02858) (xy 351.192922 -415.013227) (xy 351.246873 -415.005474) (xy 351.274126 -415.005012)
			(xy 352.137726 -415.005012) (xy 352.164977 -415.00546) (xy 352.218925 -415.01322) (xy 352.27122 -415.028578)
			(xy 352.320796 -415.051222) (xy 352.366646 -415.08069) (xy 352.407835 -415.116383) (xy 352.443526 -415.157575)
			(xy 352.472991 -415.203427) (xy 352.495631 -415.253005) (xy 352.510986 -415.3053) (xy 352.518742 -415.359249)
			(xy 352.518742 -415.413751) (xy 352.518742 -415.413752) (xy 372.044675 -415.413752) (xy 372.044675 -415.359248)
			(xy 372.052432 -415.305298) (xy 372.067789 -415.253001) (xy 372.090432 -415.203422) (xy 372.1199 -415.15757)
			(xy 372.155594 -415.116379) (xy 372.196788 -415.080687) (xy 372.242641 -415.051221) (xy 372.292221 -415.028581)
			(xy 372.344519 -415.013228) (xy 372.39847 -415.005474) (xy 372.425722 -415.005012) (xy 373.289322 -415.005012)
			(xy 373.316574 -415.005459) (xy 373.370522 -415.013219) (xy 373.422817 -415.028577) (xy 373.472394 -415.05122)
			(xy 373.518244 -415.080689) (xy 373.559434 -415.116382) (xy 373.595125 -415.157574) (xy 373.62459 -415.203426)
			(xy 373.647231 -415.253004) (xy 373.662586 -415.3053) (xy 373.670342 -415.359248) (xy 373.670342 -415.413748)
			(xy 375.107998 -415.413748) (xy 375.107998 -415.359252) (xy 375.115753 -415.30531) (xy 375.131106 -415.253022)
			(xy 375.153743 -415.203449) (xy 375.183204 -415.157603) (xy 375.218889 -415.116416) (xy 375.260073 -415.080727)
			(xy 375.305916 -415.051261) (xy 375.355486 -415.028619) (xy 375.407773 -415.013261) (xy 375.461714 -415.005501)
			(xy 375.488962 -415.005012) (xy 376.352562 -415.005012) (xy 376.379818 -415.005432) (xy 376.433776 -415.013185)
			(xy 376.486081 -415.028539) (xy 376.535669 -415.05118) (xy 376.581529 -415.080649) (xy 376.622729 -415.116345)
			(xy 376.658428 -415.15754) (xy 376.687901 -415.203398) (xy 376.710548 -415.252983) (xy 376.725907 -415.305287)
			(xy 376.733665 -415.359244) (xy 376.733665 -415.413752) (xy 378.171175 -415.413752) (xy 378.171175 -415.359248)
			(xy 378.178932 -415.3053) (xy 378.194287 -415.253005) (xy 378.216929 -415.203427) (xy 378.246395 -415.157576)
			(xy 378.282087 -415.116386) (xy 378.323278 -415.080694) (xy 378.369129 -415.051228) (xy 378.418707 -415.028587)
			(xy 378.471002 -415.013231) (xy 378.52495 -415.005475) (xy 378.552202 -415.005012) (xy 379.415802 -415.005012)
			(xy 379.443055 -415.005458) (xy 379.497005 -415.013215) (xy 379.549302 -415.028571) (xy 379.598882 -415.051214)
			(xy 379.644734 -415.080682) (xy 379.685926 -415.116375) (xy 379.72162 -415.157567) (xy 379.751087 -415.20342)
			(xy 379.773729 -415.253) (xy 379.789085 -415.305297) (xy 379.796842 -415.359247) (xy 379.796842 -415.413753)
			(xy 381.234375 -415.413753) (xy 381.234375 -415.359247) (xy 381.242133 -415.305295) (xy 381.25749 -415.252996)
			(xy 381.280135 -415.203416) (xy 381.309605 -415.157563) (xy 381.345301 -415.116372) (xy 381.386497 -415.08068)
			(xy 381.432353 -415.051215) (xy 381.481936 -415.028576) (xy 381.534236 -415.013224) (xy 381.588189 -415.005472)
			(xy 381.615442 -415.005012) (xy 382.479042 -415.005012) (xy 382.506293 -415.005461) (xy 382.560239 -415.013222)
			(xy 382.612531 -415.028582) (xy 382.662106 -415.051227) (xy 382.707953 -415.080696) (xy 382.749141 -415.116389)
			(xy 382.784829 -415.15758) (xy 382.814293 -415.203431) (xy 382.836933 -415.253008) (xy 382.852286 -415.305302)
			(xy 382.860042 -415.359249) (xy 382.860042 -415.413749) (xy 384.297698 -415.413749) (xy 384.297698 -415.359251)
			(xy 384.305454 -415.305308) (xy 384.320807 -415.253017) (xy 384.343446 -415.203444) (xy 384.372909 -415.157597)
			(xy 384.408597 -415.116409) (xy 384.449782 -415.08072) (xy 384.495628 -415.051254) (xy 384.5452 -415.028613)
			(xy 384.59749 -415.013258) (xy 384.651433 -415.005499) (xy 384.678682 -415.005012) (xy 385.542282 -415.005012)
			(xy 385.569537 -415.005434) (xy 385.623493 -415.013189) (xy 385.675796 -415.028544) (xy 385.725381 -415.051187)
			(xy 385.771239 -415.080656) (xy 385.812436 -415.116352) (xy 385.848133 -415.157547) (xy 385.877604 -415.203403)
			(xy 385.900249 -415.252987) (xy 385.915607 -415.305289) (xy 385.923365 -415.359245) (xy 385.923365 -415.413752)
			(xy 387.360875 -415.413752) (xy 387.360875 -415.359248) (xy 387.368632 -415.305298) (xy 387.383989 -415.253001)
			(xy 387.406632 -415.203422) (xy 387.4361 -415.15757) (xy 387.471794 -415.116379) (xy 387.512988 -415.080687)
			(xy 387.558841 -415.051221) (xy 387.608421 -415.028581) (xy 387.660719 -415.013228) (xy 387.71467 -415.005474)
			(xy 387.741922 -415.005012) (xy 388.605522 -415.005012) (xy 388.632774 -415.005459) (xy 388.686722 -415.013219)
			(xy 388.739017 -415.028577) (xy 388.788594 -415.05122) (xy 388.834444 -415.080689) (xy 388.875634 -415.116382)
			(xy 388.911325 -415.157574) (xy 388.94079 -415.203426) (xy 388.963431 -415.253004) (xy 388.978786 -415.3053)
			(xy 388.986542 -415.359248) (xy 388.986542 -415.413748) (xy 390.424198 -415.413748) (xy 390.424198 -415.359252)
			(xy 390.431953 -415.30531) (xy 390.447306 -415.253022) (xy 390.469943 -415.203449) (xy 390.499404 -415.157603)
			(xy 390.535089 -415.116416) (xy 390.576273 -415.080727) (xy 390.622116 -415.051261) (xy 390.671686 -415.028619)
			(xy 390.723973 -415.013261) (xy 390.777914 -415.005501) (xy 390.805162 -415.005012) (xy 391.668762 -415.005012)
			(xy 391.696018 -415.005432) (xy 391.749976 -415.013185) (xy 391.802281 -415.028539) (xy 391.851869 -415.05118)
			(xy 391.897729 -415.080649) (xy 391.938929 -415.116345) (xy 391.974628 -415.15754) (xy 392.004101 -415.203398)
			(xy 392.026748 -415.252983) (xy 392.042107 -415.305287) (xy 392.049865 -415.359244) (xy 392.049865 -415.413752)
			(xy 393.487375 -415.413752) (xy 393.487375 -415.359248) (xy 393.495132 -415.3053) (xy 393.510487 -415.253005)
			(xy 393.533129 -415.203427) (xy 393.562595 -415.157576) (xy 393.598287 -415.116386) (xy 393.639478 -415.080694)
			(xy 393.685329 -415.051228) (xy 393.734907 -415.028587) (xy 393.787202 -415.013231) (xy 393.84115 -415.005475)
			(xy 393.868402 -415.005012) (xy 394.732002 -415.005012) (xy 394.759255 -415.005458) (xy 394.813205 -415.013215)
			(xy 394.865502 -415.028571) (xy 394.915082 -415.051214) (xy 394.960934 -415.080682) (xy 395.002126 -415.116375)
			(xy 395.03782 -415.157567) (xy 395.067287 -415.20342) (xy 395.089929 -415.253) (xy 395.105285 -415.305297)
			(xy 395.113042 -415.359247) (xy 395.113042 -415.413753) (xy 396.550575 -415.413753) (xy 396.550575 -415.359247)
			(xy 396.558333 -415.305295) (xy 396.57369 -415.252996) (xy 396.596335 -415.203416) (xy 396.625805 -415.157563)
			(xy 396.661501 -415.116372) (xy 396.702697 -415.08068) (xy 396.748553 -415.051215) (xy 396.798136 -415.028576)
			(xy 396.850436 -415.013224) (xy 396.904389 -415.005472) (xy 396.931642 -415.005012) (xy 397.795242 -415.005012)
			(xy 397.822493 -415.005461) (xy 397.876439 -415.013222) (xy 397.928731 -415.028582) (xy 397.978306 -415.051227)
			(xy 398.024153 -415.080696) (xy 398.065341 -415.116389) (xy 398.101029 -415.15758) (xy 398.130493 -415.203431)
			(xy 398.153133 -415.253008) (xy 398.168486 -415.305302) (xy 398.176242 -415.359249) (xy 398.176242 -415.413749)
			(xy 399.613898 -415.413749) (xy 399.613898 -415.359251) (xy 399.621654 -415.305308) (xy 399.637007 -415.253017)
			(xy 399.659646 -415.203444) (xy 399.689109 -415.157597) (xy 399.724797 -415.116409) (xy 399.765982 -415.08072)
			(xy 399.811828 -415.051254) (xy 399.8614 -415.028613) (xy 399.91369 -415.013258) (xy 399.967633 -415.005499)
			(xy 399.994882 -415.005012) (xy 400.858482 -415.005012) (xy 400.885737 -415.005434) (xy 400.939693 -415.013189)
			(xy 400.991996 -415.028544) (xy 401.041581 -415.051187) (xy 401.087439 -415.080656) (xy 401.128636 -415.116352)
			(xy 401.164333 -415.157547) (xy 401.193804 -415.203403) (xy 401.216449 -415.252987) (xy 401.231807 -415.305289)
			(xy 401.239565 -415.359245) (xy 401.239565 -415.413752) (xy 402.677075 -415.413752) (xy 402.677075 -415.359248)
			(xy 402.684832 -415.305298) (xy 402.700189 -415.253001) (xy 402.722832 -415.203422) (xy 402.7523 -415.15757)
			(xy 402.787994 -415.116379) (xy 402.829188 -415.080687) (xy 402.875041 -415.051221) (xy 402.924621 -415.028581)
			(xy 402.976919 -415.013228) (xy 403.03087 -415.005474) (xy 403.058122 -415.005012) (xy 403.921722 -415.005012)
			(xy 403.948974 -415.005459) (xy 404.002922 -415.013219) (xy 404.055217 -415.028577) (xy 404.104794 -415.05122)
			(xy 404.150644 -415.080689) (xy 404.191834 -415.116382) (xy 404.227525 -415.157574) (xy 404.25699 -415.203426)
			(xy 404.279631 -415.253004) (xy 404.294986 -415.3053) (xy 404.302742 -415.359248) (xy 404.302742 -415.413748)
			(xy 405.740398 -415.413748) (xy 405.740398 -415.359252) (xy 405.748153 -415.30531) (xy 405.763506 -415.253022)
			(xy 405.786143 -415.203449) (xy 405.815604 -415.157603) (xy 405.851289 -415.116416) (xy 405.892473 -415.080727)
			(xy 405.938316 -415.051261) (xy 405.987886 -415.028619) (xy 406.040173 -415.013261) (xy 406.094114 -415.005501)
			(xy 406.121362 -415.005012) (xy 406.984962 -415.005012) (xy 407.012218 -415.005432) (xy 407.066176 -415.013185)
			(xy 407.118481 -415.028539) (xy 407.168069 -415.05118) (xy 407.213929 -415.080649) (xy 407.255129 -415.116345)
			(xy 407.290828 -415.15754) (xy 407.320301 -415.203398) (xy 407.342948 -415.252983) (xy 407.358307 -415.305287)
			(xy 407.366065 -415.359244) (xy 407.366065 -415.413752) (xy 408.803575 -415.413752) (xy 408.803575 -415.359248)
			(xy 408.811332 -415.3053) (xy 408.826687 -415.253005) (xy 408.849329 -415.203427) (xy 408.878795 -415.157576)
			(xy 408.914487 -415.116386) (xy 408.955678 -415.080694) (xy 409.001529 -415.051228) (xy 409.051107 -415.028587)
			(xy 409.103402 -415.013231) (xy 409.15735 -415.005475) (xy 409.184602 -415.005012) (xy 410.048202 -415.005012)
			(xy 410.075455 -415.005458) (xy 410.129405 -415.013215) (xy 410.181702 -415.028571) (xy 410.231282 -415.051214)
			(xy 410.277134 -415.080682) (xy 410.318326 -415.116375) (xy 410.35402 -415.157567) (xy 410.383487 -415.20342)
			(xy 410.406129 -415.253) (xy 410.421485 -415.305297) (xy 410.429242 -415.359247) (xy 410.429242 -415.413753)
			(xy 411.866775 -415.413753) (xy 411.866775 -415.359247) (xy 411.874533 -415.305295) (xy 411.88989 -415.252996)
			(xy 411.912535 -415.203416) (xy 411.942005 -415.157563) (xy 411.977701 -415.116372) (xy 412.018897 -415.08068)
			(xy 412.064753 -415.051215) (xy 412.114336 -415.028576) (xy 412.166636 -415.013224) (xy 412.220589 -415.005472)
			(xy 412.247842 -415.005012) (xy 413.111442 -415.005012) (xy 413.138693 -415.005461) (xy 413.192639 -415.013222)
			(xy 413.244931 -415.028582) (xy 413.294506 -415.051227) (xy 413.340353 -415.080696) (xy 413.381541 -415.116389)
			(xy 413.417229 -415.15758) (xy 413.446693 -415.203431) (xy 413.469333 -415.253008) (xy 413.484686 -415.305302)
			(xy 413.492442 -415.359249) (xy 413.492442 -415.413749) (xy 414.930098 -415.413749) (xy 414.930098 -415.359251)
			(xy 414.937854 -415.305308) (xy 414.953207 -415.253017) (xy 414.975846 -415.203444) (xy 415.005309 -415.157597)
			(xy 415.040997 -415.116409) (xy 415.082182 -415.08072) (xy 415.128028 -415.051254) (xy 415.1776 -415.028613)
			(xy 415.22989 -415.013258) (xy 415.283833 -415.005499) (xy 415.311082 -415.005012) (xy 416.174682 -415.005012)
			(xy 416.201937 -415.005434) (xy 416.255893 -415.013189) (xy 416.308196 -415.028544) (xy 416.357781 -415.051187)
			(xy 416.403639 -415.080656) (xy 416.444836 -415.116352) (xy 416.480533 -415.157547) (xy 416.510004 -415.203403)
			(xy 416.532649 -415.252987) (xy 416.548007 -415.305289) (xy 416.555765 -415.359245) (xy 416.555765 -415.413752)
			(xy 417.993275 -415.413752) (xy 417.993275 -415.359248) (xy 418.001032 -415.305298) (xy 418.016389 -415.253001)
			(xy 418.039032 -415.203422) (xy 418.0685 -415.15757) (xy 418.104194 -415.116379) (xy 418.145388 -415.080687)
			(xy 418.191241 -415.051221) (xy 418.240821 -415.028581) (xy 418.293119 -415.013228) (xy 418.34707 -415.005474)
			(xy 418.374322 -415.005012) (xy 419.237922 -415.005012) (xy 419.265174 -415.005459) (xy 419.319122 -415.013219)
			(xy 419.371417 -415.028577) (xy 419.420994 -415.05122) (xy 419.466844 -415.080689) (xy 419.508034 -415.116382)
			(xy 419.543725 -415.157574) (xy 419.57319 -415.203426) (xy 419.595831 -415.253004) (xy 419.611186 -415.3053)
			(xy 419.618942 -415.359248) (xy 419.618942 -415.413752) (xy 419.611186 -415.4677) (xy 419.595831 -415.519996)
			(xy 419.57319 -415.569574) (xy 419.543725 -415.615426) (xy 419.508034 -415.656618) (xy 419.466844 -415.692311)
			(xy 419.420994 -415.72178) (xy 419.371417 -415.744423) (xy 419.319122 -415.759781) (xy 419.265174 -415.767541)
			(xy 419.237922 -415.768028) (xy 418.374322 -415.768028) (xy 418.34707 -415.767526) (xy 418.293119 -415.759772)
			(xy 418.240821 -415.744419) (xy 418.191241 -415.721779) (xy 418.145388 -415.692313) (xy 418.104194 -415.656621)
			(xy 418.0685 -415.61543) (xy 418.039032 -415.569578) (xy 418.016389 -415.519999) (xy 418.001032 -415.467702)
			(xy 417.993275 -415.413752) (xy 416.555765 -415.413752) (xy 416.555765 -415.413755) (xy 416.548007 -415.467711)
			(xy 416.532649 -415.520013) (xy 416.510004 -415.569597) (xy 416.480533 -415.615453) (xy 416.444836 -415.656648)
			(xy 416.403639 -415.692344) (xy 416.357781 -415.721813) (xy 416.308196 -415.744456) (xy 416.255893 -415.759811)
			(xy 416.201937 -415.767566) (xy 416.174682 -415.768028) (xy 415.311082 -415.768028) (xy 415.283833 -415.767501)
			(xy 415.22989 -415.759742) (xy 415.1776 -415.744387) (xy 415.128028 -415.721746) (xy 415.082182 -415.69228)
			(xy 415.040997 -415.656591) (xy 415.005309 -415.615403) (xy 414.975846 -415.569556) (xy 414.953207 -415.519983)
			(xy 414.937854 -415.467692) (xy 414.930098 -415.413749) (xy 413.492442 -415.413749) (xy 413.492442 -415.413751)
			(xy 413.484686 -415.467698) (xy 413.469333 -415.519992) (xy 413.446693 -415.569569) (xy 413.417229 -415.61542)
			(xy 413.381541 -415.656611) (xy 413.340353 -415.692304) (xy 413.294506 -415.721773) (xy 413.244931 -415.744418)
			(xy 413.192639 -415.759778) (xy 413.138693 -415.767539) (xy 413.111442 -415.768028) (xy 412.247842 -415.768028)
			(xy 412.220589 -415.767528) (xy 412.166636 -415.759776) (xy 412.114336 -415.744424) (xy 412.064753 -415.721785)
			(xy 412.018897 -415.69232) (xy 411.977701 -415.656628) (xy 411.942005 -415.615437) (xy 411.912535 -415.569584)
			(xy 411.88989 -415.520004) (xy 411.874533 -415.467705) (xy 411.866775 -415.413753) (xy 410.429242 -415.413753)
			(xy 410.421485 -415.467703) (xy 410.406129 -415.52) (xy 410.383487 -415.56958) (xy 410.35402 -415.615433)
			(xy 410.318326 -415.656625) (xy 410.277134 -415.692318) (xy 410.231282 -415.721786) (xy 410.181702 -415.744429)
			(xy 410.129405 -415.759785) (xy 410.075455 -415.767542) (xy 410.048202 -415.768028) (xy 409.184602 -415.768028)
			(xy 409.15735 -415.767525) (xy 409.103402 -415.759769) (xy 409.051107 -415.744413) (xy 409.001529 -415.721772)
			(xy 408.955678 -415.692306) (xy 408.914487 -415.656614) (xy 408.878795 -415.615424) (xy 408.849329 -415.569573)
			(xy 408.826687 -415.519995) (xy 408.811332 -415.4677) (xy 408.803575 -415.413752) (xy 407.366065 -415.413752)
			(xy 407.366065 -415.413756) (xy 407.358307 -415.467713) (xy 407.342948 -415.520017) (xy 407.320301 -415.569602)
			(xy 407.290828 -415.61546) (xy 407.255129 -415.656655) (xy 407.213929 -415.692351) (xy 407.168069 -415.72182)
			(xy 407.118481 -415.744461) (xy 407.066176 -415.759815) (xy 407.012218 -415.767568) (xy 406.984962 -415.768028)
			(xy 406.121362 -415.768028) (xy 406.094114 -415.767499) (xy 406.040173 -415.759739) (xy 405.987886 -415.744381)
			(xy 405.938316 -415.721739) (xy 405.892473 -415.692273) (xy 405.851289 -415.656584) (xy 405.815604 -415.615397)
			(xy 405.786143 -415.569551) (xy 405.763506 -415.519978) (xy 405.748153 -415.46769) (xy 405.740398 -415.413748)
			(xy 404.302742 -415.413748) (xy 404.302742 -415.413752) (xy 404.294986 -415.4677) (xy 404.279631 -415.519996)
			(xy 404.25699 -415.569574) (xy 404.227525 -415.615426) (xy 404.191834 -415.656618) (xy 404.150644 -415.692311)
			(xy 404.104794 -415.72178) (xy 404.055217 -415.744423) (xy 404.002922 -415.759781) (xy 403.948974 -415.767541)
			(xy 403.921722 -415.768028) (xy 403.058122 -415.768028) (xy 403.03087 -415.767526) (xy 402.976919 -415.759772)
			(xy 402.924621 -415.744419) (xy 402.875041 -415.721779) (xy 402.829188 -415.692313) (xy 402.787994 -415.656621)
			(xy 402.7523 -415.61543) (xy 402.722832 -415.569578) (xy 402.700189 -415.519999) (xy 402.684832 -415.467702)
			(xy 402.677075 -415.413752) (xy 401.239565 -415.413752) (xy 401.239565 -415.413755) (xy 401.231807 -415.467711)
			(xy 401.216449 -415.520013) (xy 401.193804 -415.569597) (xy 401.164333 -415.615453) (xy 401.128636 -415.656648)
			(xy 401.087439 -415.692344) (xy 401.041581 -415.721813) (xy 400.991996 -415.744456) (xy 400.939693 -415.759811)
			(xy 400.885737 -415.767566) (xy 400.858482 -415.768028) (xy 399.994882 -415.768028) (xy 399.967633 -415.767501)
			(xy 399.91369 -415.759742) (xy 399.8614 -415.744387) (xy 399.811828 -415.721746) (xy 399.765982 -415.69228)
			(xy 399.724797 -415.656591) (xy 399.689109 -415.615403) (xy 399.659646 -415.569556) (xy 399.637007 -415.519983)
			(xy 399.621654 -415.467692) (xy 399.613898 -415.413749) (xy 398.176242 -415.413749) (xy 398.176242 -415.413751)
			(xy 398.168486 -415.467698) (xy 398.153133 -415.519992) (xy 398.130493 -415.569569) (xy 398.101029 -415.61542)
			(xy 398.065341 -415.656611) (xy 398.024153 -415.692304) (xy 397.978306 -415.721773) (xy 397.928731 -415.744418)
			(xy 397.876439 -415.759778) (xy 397.822493 -415.767539) (xy 397.795242 -415.768028) (xy 396.931642 -415.768028)
			(xy 396.904389 -415.767528) (xy 396.850436 -415.759776) (xy 396.798136 -415.744424) (xy 396.748553 -415.721785)
			(xy 396.702697 -415.69232) (xy 396.661501 -415.656628) (xy 396.625805 -415.615437) (xy 396.596335 -415.569584)
			(xy 396.57369 -415.520004) (xy 396.558333 -415.467705) (xy 396.550575 -415.413753) (xy 395.113042 -415.413753)
			(xy 395.105285 -415.467703) (xy 395.089929 -415.52) (xy 395.067287 -415.56958) (xy 395.03782 -415.615433)
			(xy 395.002126 -415.656625) (xy 394.960934 -415.692318) (xy 394.915082 -415.721786) (xy 394.865502 -415.744429)
			(xy 394.813205 -415.759785) (xy 394.759255 -415.767542) (xy 394.732002 -415.768028) (xy 393.868402 -415.768028)
			(xy 393.84115 -415.767525) (xy 393.787202 -415.759769) (xy 393.734907 -415.744413) (xy 393.685329 -415.721772)
			(xy 393.639478 -415.692306) (xy 393.598287 -415.656614) (xy 393.562595 -415.615424) (xy 393.533129 -415.569573)
			(xy 393.510487 -415.519995) (xy 393.495132 -415.4677) (xy 393.487375 -415.413752) (xy 392.049865 -415.413752)
			(xy 392.049865 -415.413756) (xy 392.042107 -415.467713) (xy 392.026748 -415.520017) (xy 392.004101 -415.569602)
			(xy 391.974628 -415.61546) (xy 391.938929 -415.656655) (xy 391.897729 -415.692351) (xy 391.851869 -415.72182)
			(xy 391.802281 -415.744461) (xy 391.749976 -415.759815) (xy 391.696018 -415.767568) (xy 391.668762 -415.768028)
			(xy 390.805162 -415.768028) (xy 390.777914 -415.767499) (xy 390.723973 -415.759739) (xy 390.671686 -415.744381)
			(xy 390.622116 -415.721739) (xy 390.576273 -415.692273) (xy 390.535089 -415.656584) (xy 390.499404 -415.615397)
			(xy 390.469943 -415.569551) (xy 390.447306 -415.519978) (xy 390.431953 -415.46769) (xy 390.424198 -415.413748)
			(xy 388.986542 -415.413748) (xy 388.986542 -415.413752) (xy 388.978786 -415.4677) (xy 388.963431 -415.519996)
			(xy 388.94079 -415.569574) (xy 388.911325 -415.615426) (xy 388.875634 -415.656618) (xy 388.834444 -415.692311)
			(xy 388.788594 -415.72178) (xy 388.739017 -415.744423) (xy 388.686722 -415.759781) (xy 388.632774 -415.767541)
			(xy 388.605522 -415.768028) (xy 387.741922 -415.768028) (xy 387.71467 -415.767526) (xy 387.660719 -415.759772)
			(xy 387.608421 -415.744419) (xy 387.558841 -415.721779) (xy 387.512988 -415.692313) (xy 387.471794 -415.656621)
			(xy 387.4361 -415.61543) (xy 387.406632 -415.569578) (xy 387.383989 -415.519999) (xy 387.368632 -415.467702)
			(xy 387.360875 -415.413752) (xy 385.923365 -415.413752) (xy 385.923365 -415.413755) (xy 385.915607 -415.467711)
			(xy 385.900249 -415.520013) (xy 385.877604 -415.569597) (xy 385.848133 -415.615453) (xy 385.812436 -415.656648)
			(xy 385.771239 -415.692344) (xy 385.725381 -415.721813) (xy 385.675796 -415.744456) (xy 385.623493 -415.759811)
			(xy 385.569537 -415.767566) (xy 385.542282 -415.768028) (xy 384.678682 -415.768028) (xy 384.651433 -415.767501)
			(xy 384.59749 -415.759742) (xy 384.5452 -415.744387) (xy 384.495628 -415.721746) (xy 384.449782 -415.69228)
			(xy 384.408597 -415.656591) (xy 384.372909 -415.615403) (xy 384.343446 -415.569556) (xy 384.320807 -415.519983)
			(xy 384.305454 -415.467692) (xy 384.297698 -415.413749) (xy 382.860042 -415.413749) (xy 382.860042 -415.413751)
			(xy 382.852286 -415.467698) (xy 382.836933 -415.519992) (xy 382.814293 -415.569569) (xy 382.784829 -415.61542)
			(xy 382.749141 -415.656611) (xy 382.707953 -415.692304) (xy 382.662106 -415.721773) (xy 382.612531 -415.744418)
			(xy 382.560239 -415.759778) (xy 382.506293 -415.767539) (xy 382.479042 -415.768028) (xy 381.615442 -415.768028)
			(xy 381.588189 -415.767528) (xy 381.534236 -415.759776) (xy 381.481936 -415.744424) (xy 381.432353 -415.721785)
			(xy 381.386497 -415.69232) (xy 381.345301 -415.656628) (xy 381.309605 -415.615437) (xy 381.280135 -415.569584)
			(xy 381.25749 -415.520004) (xy 381.242133 -415.467705) (xy 381.234375 -415.413753) (xy 379.796842 -415.413753)
			(xy 379.789085 -415.467703) (xy 379.773729 -415.52) (xy 379.751087 -415.56958) (xy 379.72162 -415.615433)
			(xy 379.685926 -415.656625) (xy 379.644734 -415.692318) (xy 379.598882 -415.721786) (xy 379.549302 -415.744429)
			(xy 379.497005 -415.759785) (xy 379.443055 -415.767542) (xy 379.415802 -415.768028) (xy 378.552202 -415.768028)
			(xy 378.52495 -415.767525) (xy 378.471002 -415.759769) (xy 378.418707 -415.744413) (xy 378.369129 -415.721772)
			(xy 378.323278 -415.692306) (xy 378.282087 -415.656614) (xy 378.246395 -415.615424) (xy 378.216929 -415.569573)
			(xy 378.194287 -415.519995) (xy 378.178932 -415.4677) (xy 378.171175 -415.413752) (xy 376.733665 -415.413752)
			(xy 376.733665 -415.413756) (xy 376.725907 -415.467713) (xy 376.710548 -415.520017) (xy 376.687901 -415.569602)
			(xy 376.658428 -415.61546) (xy 376.622729 -415.656655) (xy 376.581529 -415.692351) (xy 376.535669 -415.72182)
			(xy 376.486081 -415.744461) (xy 376.433776 -415.759815) (xy 376.379818 -415.767568) (xy 376.352562 -415.768028)
			(xy 375.488962 -415.768028) (xy 375.461714 -415.767499) (xy 375.407773 -415.759739) (xy 375.355486 -415.744381)
			(xy 375.305916 -415.721739) (xy 375.260073 -415.692273) (xy 375.218889 -415.656584) (xy 375.183204 -415.615397)
			(xy 375.153743 -415.569551) (xy 375.131106 -415.519978) (xy 375.115753 -415.46769) (xy 375.107998 -415.413748)
			(xy 373.670342 -415.413748) (xy 373.670342 -415.413752) (xy 373.662586 -415.4677) (xy 373.647231 -415.519996)
			(xy 373.62459 -415.569574) (xy 373.595125 -415.615426) (xy 373.559434 -415.656618) (xy 373.518244 -415.692311)
			(xy 373.472394 -415.72178) (xy 373.422817 -415.744423) (xy 373.370522 -415.759781) (xy 373.316574 -415.767541)
			(xy 373.289322 -415.768028) (xy 372.425722 -415.768028) (xy 372.39847 -415.767526) (xy 372.344519 -415.759772)
			(xy 372.292221 -415.744419) (xy 372.242641 -415.721779) (xy 372.196788 -415.692313) (xy 372.155594 -415.656621)
			(xy 372.1199 -415.61543) (xy 372.090432 -415.569578) (xy 372.067789 -415.519999) (xy 372.052432 -415.467702)
			(xy 372.044675 -415.413752) (xy 352.518742 -415.413752) (xy 352.510986 -415.4677) (xy 352.495631 -415.519995)
			(xy 352.472991 -415.569573) (xy 352.443526 -415.615425) (xy 352.407835 -415.656617) (xy 352.366646 -415.69231)
			(xy 352.320796 -415.721778) (xy 352.27122 -415.744422) (xy 352.218925 -415.75978) (xy 352.164977 -415.76754)
			(xy 352.137726 -415.768028) (xy 351.274126 -415.768028) (xy 351.246873 -415.767526) (xy 351.192922 -415.759773)
			(xy 351.140624 -415.74442) (xy 351.091043 -415.72178) (xy 351.045189 -415.692314) (xy 351.003996 -415.656623)
			(xy 350.968301 -415.615431) (xy 350.938832 -415.569579) (xy 350.916189 -415.52) (xy 350.900833 -415.467703)
			(xy 350.893075 -415.413753) (xy 349.455565 -415.413753) (xy 349.455565 -415.413755) (xy 349.447807 -415.46771)
			(xy 349.43245 -415.520012) (xy 349.409805 -415.569595) (xy 349.380334 -415.615452) (xy 349.344637 -415.656647)
			(xy 349.303441 -415.692343) (xy 349.257583 -415.721812) (xy 349.207999 -415.744455) (xy 349.155696 -415.75981)
			(xy 349.101741 -415.767566) (xy 349.074486 -415.768028) (xy 348.210886 -415.768028) (xy 348.183637 -415.767501)
			(xy 348.129694 -415.759743) (xy 348.077403 -415.744388) (xy 348.02783 -415.721747) (xy 347.981984 -415.692282)
			(xy 347.940798 -415.656592) (xy 347.90511 -415.615404) (xy 347.875646 -415.569557) (xy 347.853008 -415.519984)
			(xy 347.837654 -415.467693) (xy 347.829898 -415.413749) (xy 346.392242 -415.413749) (xy 346.392242 -415.413751)
			(xy 346.384487 -415.467697) (xy 346.369133 -415.519991) (xy 346.346494 -415.569568) (xy 346.31703 -415.615418)
			(xy 346.281342 -415.656609) (xy 346.240155 -415.692303) (xy 346.194308 -415.721772) (xy 346.144734 -415.744417)
			(xy 346.092442 -415.759777) (xy 346.038497 -415.767539) (xy 346.011246 -415.768028) (xy 345.147646 -415.768028)
			(xy 345.120392 -415.767528) (xy 345.066439 -415.759777) (xy 345.014139 -415.744425) (xy 344.964555 -415.721787)
			(xy 344.918699 -415.692321) (xy 344.877503 -415.65663) (xy 344.841806 -415.615438) (xy 344.812335 -415.569585)
			(xy 344.789691 -415.520004) (xy 344.774333 -415.467706) (xy 344.766575 -415.413754) (xy 343.329042 -415.413754)
			(xy 343.321285 -415.467702) (xy 343.30593 -415.519999) (xy 343.283288 -415.569579) (xy 343.253821 -415.615431)
			(xy 343.218128 -415.656624) (xy 343.176936 -415.692317) (xy 343.131084 -415.721785) (xy 343.081505 -415.744428)
			(xy 343.029208 -415.759784) (xy 342.975258 -415.767542) (xy 342.948006 -415.768028) (xy 342.084406 -415.768028)
			(xy 342.057154 -415.767525) (xy 342.003206 -415.759769) (xy 341.95091 -415.744415) (xy 341.901331 -415.721774)
			(xy 341.85548 -415.692307) (xy 341.814289 -415.656616) (xy 341.778596 -415.615425) (xy 341.749129 -415.569574)
			(xy 341.726488 -415.519996) (xy 341.711132 -415.4677) (xy 341.703375 -415.413752) (xy 340.265865 -415.413752)
			(xy 340.265865 -415.413756) (xy 340.258107 -415.467713) (xy 340.242748 -415.520016) (xy 340.220102 -415.569601)
			(xy 340.190629 -415.615458) (xy 340.15493 -415.656654) (xy 340.113731 -415.69235) (xy 340.067871 -415.721818)
			(xy 340.018284 -415.74446) (xy 339.965979 -415.759814) (xy 339.912022 -415.767567) (xy 339.884766 -415.768028)
			(xy 339.021166 -415.768028) (xy 338.993918 -415.767499) (xy 338.939977 -415.759739) (xy 338.887689 -415.744382)
			(xy 338.838118 -415.72174) (xy 338.792275 -415.692275) (xy 338.751091 -415.656585) (xy 338.715405 -415.615398)
			(xy 338.685943 -415.569552) (xy 338.663306 -415.519979) (xy 338.647953 -415.46769) (xy 338.640198 -415.413748)
			(xy 337.202542 -415.413748) (xy 337.202542 -415.413751) (xy 337.194786 -415.4677) (xy 337.179431 -415.519995)
			(xy 337.156791 -415.569573) (xy 337.127326 -415.615425) (xy 337.091635 -415.656617) (xy 337.050446 -415.69231)
			(xy 337.004596 -415.721778) (xy 336.95502 -415.744422) (xy 336.902725 -415.75978) (xy 336.848777 -415.76754)
			(xy 336.821526 -415.768028) (xy 335.957926 -415.768028) (xy 335.930673 -415.767526) (xy 335.876722 -415.759773)
			(xy 335.824424 -415.74442) (xy 335.774843 -415.72178) (xy 335.728989 -415.692314) (xy 335.687796 -415.656623)
			(xy 335.652101 -415.615431) (xy 335.622632 -415.569579) (xy 335.599989 -415.52) (xy 335.584633 -415.467703)
			(xy 335.576875 -415.413753) (xy 334.139365 -415.413753) (xy 334.139365 -415.413755) (xy 334.131607 -415.46771)
			(xy 334.11625 -415.520012) (xy 334.093605 -415.569595) (xy 334.064134 -415.615452) (xy 334.028437 -415.656647)
			(xy 333.987241 -415.692343) (xy 333.941383 -415.721812) (xy 333.891799 -415.744455) (xy 333.839496 -415.75981)
			(xy 333.785541 -415.767566) (xy 333.758286 -415.768028) (xy 332.894686 -415.768028) (xy 332.867437 -415.767501)
			(xy 332.813494 -415.759743) (xy 332.761203 -415.744388) (xy 332.71163 -415.721747) (xy 332.665784 -415.692282)
			(xy 332.624598 -415.656592) (xy 332.58891 -415.615404) (xy 332.559446 -415.569557) (xy 332.536808 -415.519984)
			(xy 332.521454 -415.467693) (xy 332.513698 -415.413749) (xy 331.076042 -415.413749) (xy 331.076042 -415.413751)
			(xy 331.068287 -415.467697) (xy 331.052933 -415.519991) (xy 331.030294 -415.569568) (xy 331.00083 -415.615418)
			(xy 330.965142 -415.656609) (xy 330.923955 -415.692303) (xy 330.878108 -415.721772) (xy 330.828534 -415.744417)
			(xy 330.776242 -415.759777) (xy 330.722297 -415.767539) (xy 330.695046 -415.768028) (xy 329.831446 -415.768028)
			(xy 329.804192 -415.767528) (xy 329.750239 -415.759777) (xy 329.697939 -415.744425) (xy 329.648355 -415.721787)
			(xy 329.602499 -415.692321) (xy 329.561303 -415.65663) (xy 329.525606 -415.615438) (xy 329.496135 -415.569585)
			(xy 329.473491 -415.520004) (xy 329.458133 -415.467706) (xy 329.450375 -415.413754) (xy 328.012842 -415.413754)
			(xy 328.005085 -415.467702) (xy 327.98973 -415.519999) (xy 327.967088 -415.569579) (xy 327.937621 -415.615431)
			(xy 327.901928 -415.656624) (xy 327.860736 -415.692317) (xy 327.814884 -415.721785) (xy 327.765305 -415.744428)
			(xy 327.713008 -415.759784) (xy 327.659058 -415.767542) (xy 327.631806 -415.768028) (xy 326.768206 -415.768028)
			(xy 326.740954 -415.767525) (xy 326.687006 -415.759769) (xy 326.63471 -415.744415) (xy 326.585131 -415.721774)
			(xy 326.53928 -415.692307) (xy 326.498089 -415.656616) (xy 326.462396 -415.615425) (xy 326.432929 -415.569574)
			(xy 326.410288 -415.519996) (xy 326.394932 -415.4677) (xy 326.387175 -415.413752) (xy 324.949665 -415.413752)
			(xy 324.949665 -415.413756) (xy 324.941907 -415.467713) (xy 324.926548 -415.520016) (xy 324.903902 -415.569601)
			(xy 324.874429 -415.615458) (xy 324.83873 -415.656654) (xy 324.797531 -415.69235) (xy 324.751671 -415.721818)
			(xy 324.702084 -415.74446) (xy 324.649779 -415.759814) (xy 324.595822 -415.767567) (xy 324.568566 -415.768028)
			(xy 323.704966 -415.768028) (xy 323.677718 -415.767499) (xy 323.623777 -415.759739) (xy 323.571489 -415.744382)
			(xy 323.521918 -415.72174) (xy 323.476075 -415.692275) (xy 323.434891 -415.656585) (xy 323.399205 -415.615398)
			(xy 323.369743 -415.569552) (xy 323.347106 -415.519979) (xy 323.331753 -415.46769) (xy 323.323998 -415.413748)
			(xy 321.886342 -415.413748) (xy 321.886342 -415.413751) (xy 321.878586 -415.4677) (xy 321.863231 -415.519995)
			(xy 321.840591 -415.569573) (xy 321.811126 -415.615425) (xy 321.775435 -415.656617) (xy 321.734246 -415.69231)
			(xy 321.688396 -415.721778) (xy 321.63882 -415.744422) (xy 321.586525 -415.75978) (xy 321.532577 -415.76754)
			(xy 321.505326 -415.768028) (xy 320.641726 -415.768028) (xy 320.614473 -415.767526) (xy 320.560522 -415.759773)
			(xy 320.508224 -415.74442) (xy 320.458643 -415.72178) (xy 320.412789 -415.692314) (xy 320.371596 -415.656623)
			(xy 320.335901 -415.615431) (xy 320.306432 -415.569579) (xy 320.283789 -415.52) (xy 320.268433 -415.467703)
			(xy 320.260675 -415.413753) (xy 318.823165 -415.413753) (xy 318.823165 -415.413755) (xy 318.815407 -415.46771)
			(xy 318.80005 -415.520012) (xy 318.777405 -415.569595) (xy 318.747934 -415.615452) (xy 318.712237 -415.656647)
			(xy 318.671041 -415.692343) (xy 318.625183 -415.721812) (xy 318.575599 -415.744455) (xy 318.523296 -415.75981)
			(xy 318.469341 -415.767566) (xy 318.442086 -415.768028) (xy 317.578486 -415.768028) (xy 317.551237 -415.767501)
			(xy 317.497294 -415.759743) (xy 317.445003 -415.744388) (xy 317.39543 -415.721747) (xy 317.349584 -415.692282)
			(xy 317.308398 -415.656592) (xy 317.27271 -415.615404) (xy 317.243246 -415.569557) (xy 317.220608 -415.519984)
			(xy 317.205254 -415.467693) (xy 317.197498 -415.413749) (xy 315.759842 -415.413749) (xy 315.759842 -415.413751)
			(xy 315.752087 -415.467697) (xy 315.736733 -415.519991) (xy 315.714094 -415.569568) (xy 315.68463 -415.615418)
			(xy 315.648942 -415.656609) (xy 315.607755 -415.692303) (xy 315.561908 -415.721772) (xy 315.512334 -415.744417)
			(xy 315.460042 -415.759777) (xy 315.406097 -415.767539) (xy 315.378846 -415.768028) (xy 314.515246 -415.768028)
			(xy 314.487992 -415.767528) (xy 314.434039 -415.759777) (xy 314.381739 -415.744425) (xy 314.332155 -415.721787)
			(xy 314.286299 -415.692321) (xy 314.245103 -415.65663) (xy 314.209406 -415.615438) (xy 314.179935 -415.569585)
			(xy 314.157291 -415.520004) (xy 314.141933 -415.467706) (xy 314.134175 -415.413754) (xy 312.696642 -415.413754)
			(xy 312.688885 -415.467702) (xy 312.67353 -415.519999) (xy 312.650888 -415.569579) (xy 312.621421 -415.615431)
			(xy 312.585728 -415.656624) (xy 312.544536 -415.692317) (xy 312.498684 -415.721785) (xy 312.449105 -415.744428)
			(xy 312.396808 -415.759784) (xy 312.342858 -415.767542) (xy 312.315606 -415.768028) (xy 311.452006 -415.768028)
			(xy 311.424754 -415.767525) (xy 311.370806 -415.759769) (xy 311.31851 -415.744415) (xy 311.268931 -415.721774)
			(xy 311.22308 -415.692307) (xy 311.181889 -415.656616) (xy 311.146196 -415.615425) (xy 311.116729 -415.569574)
			(xy 311.094088 -415.519996) (xy 311.078732 -415.4677) (xy 311.070975 -415.413752) (xy 309.633465 -415.413752)
			(xy 309.633465 -415.413756) (xy 309.625707 -415.467713) (xy 309.610348 -415.520016) (xy 309.587702 -415.569601)
			(xy 309.558229 -415.615458) (xy 309.52253 -415.656654) (xy 309.481331 -415.69235) (xy 309.435471 -415.721818)
			(xy 309.385884 -415.74446) (xy 309.333579 -415.759814) (xy 309.279622 -415.767567) (xy 309.252366 -415.768028)
			(xy 308.388766 -415.768028) (xy 308.361518 -415.767499) (xy 308.307577 -415.759739) (xy 308.255289 -415.744382)
			(xy 308.205718 -415.72174) (xy 308.159875 -415.692275) (xy 308.118691 -415.656585) (xy 308.083005 -415.615398)
			(xy 308.053543 -415.569552) (xy 308.030906 -415.519979) (xy 308.015553 -415.46769) (xy 308.007798 -415.413748)
			(xy 306.570142 -415.413748) (xy 306.570142 -415.413751) (xy 306.562386 -415.4677) (xy 306.547031 -415.519995)
			(xy 306.524391 -415.569573) (xy 306.494926 -415.615425) (xy 306.459235 -415.656617) (xy 306.418046 -415.69231)
			(xy 306.372196 -415.721778) (xy 306.32262 -415.744422) (xy 306.270325 -415.75978) (xy 306.216377 -415.76754)
			(xy 306.189126 -415.768028) (xy 305.325526 -415.768028) (xy 305.298273 -415.767526) (xy 305.244322 -415.759773)
			(xy 305.192024 -415.74442) (xy 305.142443 -415.72178) (xy 305.096589 -415.692314) (xy 305.055396 -415.656623)
			(xy 305.019701 -415.615431) (xy 304.990232 -415.569579) (xy 304.967589 -415.52) (xy 304.952233 -415.467703)
			(xy 304.944475 -415.413753) (xy 300.882586 -415.413753) (xy 300.868941 -415.434612) (xy 300.76479 -415.579315)
			(xy 300.654297 -415.719235) (xy 300.53768 -415.854094) (xy 300.415171 -415.983624) (xy 300.287014 -416.107568)
			(xy 300.153463 -416.22568) (xy 300.014783 -416.337725) (xy 299.871249 -416.443482) (xy 299.723146 -416.542739)
			(xy 299.570769 -416.635301) (xy 299.41442 -416.720982) (xy 299.254409 -416.799614) (xy 299.091055 -416.87104)
			(xy 298.92468 -416.935118) (xy 298.755617 -416.99172) (xy 298.5842 -417.040736) (xy 298.410769 -417.082066)
			(xy 298.235669 -417.11563) (xy 298.059249 -417.14136) (xy 297.881857 -417.159206) (xy 297.703846 -417.169132)
			(xy 297.525569 -417.171118) (xy 297.347382 -417.165161) (xy 297.169636 -417.151271) (xy 296.992686 -417.129478)
			(xy 296.816882 -417.099824) (xy 296.642574 -417.062367) (xy 296.470107 -417.017183) (xy 296.299824 -416.964361)
			(xy 296.132063 -416.904005) (xy 295.967158 -416.836237) (xy 295.805435 -416.761189) (xy 295.647216 -416.679012)
			(xy 295.492815 -416.589869) (xy 295.342538 -416.493935) (xy 295.196683 -416.391403) (xy 295.055541 -416.282475)
			(xy 294.919392 -416.167368) (xy 294.788505 -416.04631) (xy 294.663141 -415.919541) (xy 294.543548 -415.787314)
			(xy 294.429965 -415.649891) (xy 294.322616 -415.507544) (xy 294.221715 -415.360556) (xy 294.127462 -415.20922)
			(xy 294.040044 -415.053835) (xy 293.959634 -414.89471) (xy 293.886393 -414.732161) (xy 293.820466 -414.566511)
			(xy 293.761983 -414.398089) (xy 293.711061 -414.227228) (xy 293.667801 -414.054269) (xy 293.632289 -413.879554)
			(xy 293.604595 -413.70343) (xy 293.584774 -413.526248) (xy 293.572866 -413.348359) (xy 293.568894 -413.170116)
			(xy 276.749256 -413.170116) (xy 272.414746 -417.504626) (xy 272.396783 -417.521953) (xy 272.356401 -417.55128)
			(xy 272.311928 -417.573928) (xy 272.264459 -417.589339) (xy 272.215164 -417.597133) (xy 272.19021 -417.59759)
			(xy 235.05033 -417.59759) (xy 235.040259 -417.598007) (xy 235.02166 -417.605731) (xy 235.014262 -417.612576)
			(xy 233.545126 -419.081712) (xy 276.721824 -419.081712) (xy 276.721824 -418.218112) (xy 276.72231 -418.190861)
			(xy 276.730066 -418.136913) (xy 276.745421 -418.084618) (xy 276.768063 -418.035041) (xy 276.797529 -417.989191)
			(xy 276.83322 -417.948) (xy 276.874411 -417.912309) (xy 276.920261 -417.882843) (xy 276.969838 -417.860201)
			(xy 277.022133 -417.844846) (xy 277.076081 -417.83709) (xy 277.130583 -417.83709) (xy 277.184531 -417.844846)
			(xy 277.236826 -417.860201) (xy 277.286403 -417.882843) (xy 277.332253 -417.912309) (xy 277.373444 -417.948)
			(xy 277.409135 -417.989191) (xy 277.438601 -418.035041) (xy 277.461243 -418.084618) (xy 277.476598 -418.136913)
			(xy 277.484354 -418.190861) (xy 277.48484 -418.218112) (xy 277.48484 -418.254688) (xy 289.453828 -418.254688)
			(xy 289.453828 -417.391088) (xy 289.454314 -417.363837) (xy 289.46207 -417.309889) (xy 289.477425 -417.257594)
			(xy 289.500067 -417.208017) (xy 289.529533 -417.162167) (xy 289.565224 -417.120976) (xy 289.606415 -417.085285)
			(xy 289.652265 -417.055819) (xy 289.701842 -417.033177) (xy 289.754137 -417.017822) (xy 289.808085 -417.010066)
			(xy 289.862587 -417.010066) (xy 289.916535 -417.017822) (xy 289.96883 -417.033177) (xy 290.018407 -417.055819)
			(xy 290.064257 -417.085285) (xy 290.105448 -417.120976) (xy 290.141139 -417.162167) (xy 290.170605 -417.208017)
			(xy 290.193247 -417.257594) (xy 290.208602 -417.309889) (xy 290.216358 -417.363837) (xy 290.216844 -417.391088)
			(xy 290.216844 -418.254688) (xy 290.216358 -418.281939) (xy 290.208602 -418.335887) (xy 290.193247 -418.388182)
			(xy 290.170605 -418.437759) (xy 290.169514 -418.439456) (xy 304.944423 -418.439456) (xy 304.944423 -418.384944)
			(xy 304.952181 -418.330986) (xy 304.96754 -418.278681) (xy 304.990186 -418.229095) (xy 305.019659 -418.183237)
			(xy 305.055359 -418.14204) (xy 305.096558 -418.106344) (xy 305.142418 -418.076874) (xy 305.192006 -418.054231)
			(xy 305.244311 -418.038876) (xy 305.29827 -418.031121) (xy 305.325526 -418.03066) (xy 306.189126 -418.03066)
			(xy 306.216374 -418.031212) (xy 306.270314 -418.038971) (xy 306.322601 -418.054327) (xy 306.372171 -418.076968)
			(xy 306.418014 -418.106432) (xy 306.459198 -418.142121) (xy 306.494884 -418.183307) (xy 306.524345 -418.229152)
			(xy 306.546982 -418.278723) (xy 306.562335 -418.331011) (xy 306.57009 -418.384952) (xy 306.57009 -418.439448)
			(xy 306.570089 -418.439452) (xy 308.007746 -418.439452) (xy 308.007746 -418.384948) (xy 308.015502 -418.330999)
			(xy 308.030857 -418.278702) (xy 308.053497 -418.229123) (xy 308.082963 -418.183271) (xy 308.118654 -418.142078)
			(xy 308.159843 -418.106383) (xy 308.205693 -418.076914) (xy 308.25527 -418.054269) (xy 308.307565 -418.038909)
			(xy 308.361514 -418.031148) (xy 308.388766 -418.03066) (xy 309.252366 -418.03066) (xy 309.279618 -418.031185)
			(xy 309.333568 -418.038937) (xy 309.385866 -418.054289) (xy 309.435446 -418.076928) (xy 309.4813 -418.106392)
			(xy 309.522493 -418.142083) (xy 309.558187 -418.183273) (xy 309.587656 -418.229124) (xy 309.610299 -418.278702)
			(xy 309.625655 -418.330999) (xy 309.633413 -418.384948) (xy 309.633413 -418.439452) (xy 309.633413 -418.439455)
			(xy 311.070923 -418.439455) (xy 311.070923 -418.384945) (xy 311.078681 -418.330989) (xy 311.094038 -418.278686)
			(xy 311.116683 -418.229101) (xy 311.146154 -418.183244) (xy 311.181852 -418.142047) (xy 311.223049 -418.106351)
			(xy 311.268906 -418.07688) (xy 311.318491 -418.054236) (xy 311.370794 -418.038879) (xy 311.424751 -418.031123)
			(xy 311.452006 -418.03066) (xy 312.315606 -418.03066) (xy 312.342855 -418.031211) (xy 312.396797 -418.038967)
			(xy 312.449087 -418.054321) (xy 312.498659 -418.076961) (xy 312.544505 -418.106425) (xy 312.585691 -418.142113)
			(xy 312.621379 -418.1833) (xy 312.650842 -418.229146) (xy 312.673481 -418.278719) (xy 312.688834 -418.331009)
			(xy 312.69659 -418.384951) (xy 312.69659 -418.439449) (xy 312.696589 -418.439457) (xy 314.134123 -418.439457)
			(xy 314.134123 -418.384943) (xy 314.141882 -418.330983) (xy 314.157242 -418.278677) (xy 314.179889 -418.22909)
			(xy 314.209364 -418.183231) (xy 314.245066 -418.142033) (xy 314.286267 -418.106337) (xy 314.33213 -418.076867)
			(xy 314.38172 -418.054225) (xy 314.434028 -418.038872) (xy 314.487989 -418.03112) (xy 314.515246 -418.03066)
			(xy 315.378846 -418.03066) (xy 315.406093 -418.031213) (xy 315.460031 -418.038975) (xy 315.512316 -418.054332)
			(xy 315.561883 -418.076974) (xy 315.607724 -418.106439) (xy 315.648905 -418.142128) (xy 315.684588 -418.183313)
			(xy 315.714048 -418.229157) (xy 315.736684 -418.278727) (xy 315.752035 -418.331014) (xy 315.75979 -418.384953)
			(xy 315.75979 -418.439447) (xy 315.759789 -418.439453) (xy 317.197446 -418.439453) (xy 317.197446 -418.384947)
			(xy 317.205203 -418.330996) (xy 317.220558 -418.278698) (xy 317.2432 -418.229118) (xy 317.272668 -418.183264)
			(xy 317.308361 -418.142071) (xy 317.349553 -418.106376) (xy 317.395405 -418.076907) (xy 317.444985 -418.054263)
			(xy 317.497282 -418.038906) (xy 317.551233 -418.031147) (xy 317.578486 -418.03066) (xy 318.442086 -418.03066)
			(xy 318.469337 -418.031186) (xy 318.523285 -418.038941) (xy 318.57558 -418.054295) (xy 318.625158 -418.076934)
			(xy 318.671009 -418.106399) (xy 318.7122 -418.14209) (xy 318.747892 -418.18328) (xy 318.777359 -418.22913)
			(xy 318.800001 -418.278707) (xy 318.815356 -418.331001) (xy 318.823113 -418.384949) (xy 318.823113 -418.439451)
			(xy 318.823112 -418.439456) (xy 320.260623 -418.439456) (xy 320.260623 -418.384944) (xy 320.268381 -418.330986)
			(xy 320.28374 -418.278681) (xy 320.306386 -418.229095) (xy 320.335859 -418.183237) (xy 320.371559 -418.14204)
			(xy 320.412758 -418.106344) (xy 320.458618 -418.076874) (xy 320.508206 -418.054231) (xy 320.560511 -418.038876)
			(xy 320.61447 -418.031121) (xy 320.641726 -418.03066) (xy 321.505326 -418.03066) (xy 321.532574 -418.031212)
			(xy 321.586514 -418.038971) (xy 321.638801 -418.054327) (xy 321.688371 -418.076968) (xy 321.734214 -418.106432)
			(xy 321.775398 -418.142121) (xy 321.811084 -418.183307) (xy 321.840545 -418.229152) (xy 321.863182 -418.278723)
			(xy 321.878535 -418.331011) (xy 321.88629 -418.384952) (xy 321.88629 -418.439448) (xy 321.886289 -418.439452)
			(xy 323.323946 -418.439452) (xy 323.323946 -418.384948) (xy 323.331702 -418.330999) (xy 323.347057 -418.278702)
			(xy 323.369697 -418.229123) (xy 323.399163 -418.183271) (xy 323.434854 -418.142078) (xy 323.476043 -418.106383)
			(xy 323.521893 -418.076914) (xy 323.57147 -418.054269) (xy 323.623765 -418.038909) (xy 323.677714 -418.031148)
			(xy 323.704966 -418.03066) (xy 324.568566 -418.03066) (xy 324.595818 -418.031185) (xy 324.649768 -418.038937)
			(xy 324.702066 -418.054289) (xy 324.751646 -418.076928) (xy 324.7975 -418.106392) (xy 324.838693 -418.142083)
			(xy 324.874387 -418.183273) (xy 324.903856 -418.229124) (xy 324.926499 -418.278702) (xy 324.941855 -418.330999)
			(xy 324.949613 -418.384948) (xy 324.949613 -418.439452) (xy 324.949613 -418.439455) (xy 326.387123 -418.439455)
			(xy 326.387123 -418.384945) (xy 326.394881 -418.330989) (xy 326.410238 -418.278686) (xy 326.432883 -418.229101)
			(xy 326.462354 -418.183244) (xy 326.498052 -418.142047) (xy 326.539249 -418.106351) (xy 326.585106 -418.07688)
			(xy 326.634691 -418.054236) (xy 326.686994 -418.038879) (xy 326.740951 -418.031123) (xy 326.768206 -418.03066)
			(xy 327.631806 -418.03066) (xy 327.659055 -418.031211) (xy 327.712997 -418.038967) (xy 327.765287 -418.054321)
			(xy 327.814859 -418.076961) (xy 327.860705 -418.106425) (xy 327.901891 -418.142113) (xy 327.937579 -418.1833)
			(xy 327.967042 -418.229146) (xy 327.989681 -418.278719) (xy 328.005034 -418.331009) (xy 328.01279 -418.384951)
			(xy 328.01279 -418.439449) (xy 328.012789 -418.439457) (xy 329.450323 -418.439457) (xy 329.450323 -418.384943)
			(xy 329.458082 -418.330983) (xy 329.473442 -418.278677) (xy 329.496089 -418.22909) (xy 329.525564 -418.183231)
			(xy 329.561266 -418.142033) (xy 329.602467 -418.106337) (xy 329.64833 -418.076867) (xy 329.69792 -418.054225)
			(xy 329.750228 -418.038872) (xy 329.804189 -418.03112) (xy 329.831446 -418.03066) (xy 330.695046 -418.03066)
			(xy 330.722293 -418.031213) (xy 330.776231 -418.038975) (xy 330.828516 -418.054332) (xy 330.878083 -418.076974)
			(xy 330.923924 -418.106439) (xy 330.965105 -418.142128) (xy 331.000788 -418.183313) (xy 331.030248 -418.229157)
			(xy 331.052884 -418.278727) (xy 331.068235 -418.331014) (xy 331.07599 -418.384953) (xy 331.07599 -418.439447)
			(xy 331.075989 -418.439453) (xy 332.513646 -418.439453) (xy 332.513646 -418.384947) (xy 332.521403 -418.330996)
			(xy 332.536758 -418.278698) (xy 332.5594 -418.229118) (xy 332.588868 -418.183264) (xy 332.624561 -418.142071)
			(xy 332.665753 -418.106376) (xy 332.711605 -418.076907) (xy 332.761185 -418.054263) (xy 332.813482 -418.038906)
			(xy 332.867433 -418.031147) (xy 332.894686 -418.03066) (xy 333.758286 -418.03066) (xy 333.785537 -418.031186)
			(xy 333.839485 -418.038941) (xy 333.89178 -418.054295) (xy 333.941358 -418.076934) (xy 333.987209 -418.106399)
			(xy 334.0284 -418.14209) (xy 334.064092 -418.18328) (xy 334.093559 -418.22913) (xy 334.116201 -418.278707)
			(xy 334.131556 -418.331001) (xy 334.139313 -418.384949) (xy 334.139313 -418.439451) (xy 334.139312 -418.439456)
			(xy 335.576823 -418.439456) (xy 335.576823 -418.384944) (xy 335.584581 -418.330986) (xy 335.59994 -418.278681)
			(xy 335.622586 -418.229095) (xy 335.652059 -418.183237) (xy 335.687759 -418.14204) (xy 335.728958 -418.106344)
			(xy 335.774818 -418.076874) (xy 335.824406 -418.054231) (xy 335.876711 -418.038876) (xy 335.93067 -418.031121)
			(xy 335.957926 -418.03066) (xy 336.821526 -418.03066) (xy 336.848774 -418.031212) (xy 336.902714 -418.038971)
			(xy 336.955001 -418.054327) (xy 337.004571 -418.076968) (xy 337.050414 -418.106432) (xy 337.091598 -418.142121)
			(xy 337.127284 -418.183307) (xy 337.156745 -418.229152) (xy 337.179382 -418.278723) (xy 337.194735 -418.331011)
			(xy 337.20249 -418.384952) (xy 337.20249 -418.439448) (xy 337.202489 -418.439452) (xy 338.640146 -418.439452)
			(xy 338.640146 -418.384948) (xy 338.647902 -418.330999) (xy 338.663257 -418.278702) (xy 338.685897 -418.229123)
			(xy 338.715363 -418.183271) (xy 338.751054 -418.142078) (xy 338.792243 -418.106383) (xy 338.838093 -418.076914)
			(xy 338.88767 -418.054269) (xy 338.939965 -418.038909) (xy 338.993914 -418.031148) (xy 339.021166 -418.03066)
			(xy 339.884766 -418.03066) (xy 339.912018 -418.031185) (xy 339.965968 -418.038937) (xy 340.018266 -418.054289)
			(xy 340.067846 -418.076928) (xy 340.1137 -418.106392) (xy 340.154893 -418.142083) (xy 340.190587 -418.183273)
			(xy 340.220056 -418.229124) (xy 340.242699 -418.278702) (xy 340.258055 -418.330999) (xy 340.265813 -418.384948)
			(xy 340.265813 -418.439452) (xy 340.265813 -418.439455) (xy 341.703323 -418.439455) (xy 341.703323 -418.384945)
			(xy 341.711081 -418.330989) (xy 341.726438 -418.278686) (xy 341.749083 -418.229101) (xy 341.778554 -418.183244)
			(xy 341.814252 -418.142047) (xy 341.855449 -418.106351) (xy 341.901306 -418.07688) (xy 341.950891 -418.054236)
			(xy 342.003194 -418.038879) (xy 342.057151 -418.031123) (xy 342.084406 -418.03066) (xy 342.948006 -418.03066)
			(xy 342.975255 -418.031211) (xy 343.029197 -418.038967) (xy 343.081487 -418.054321) (xy 343.131059 -418.076961)
			(xy 343.176905 -418.106425) (xy 343.218091 -418.142113) (xy 343.253779 -418.1833) (xy 343.283242 -418.229146)
			(xy 343.305881 -418.278719) (xy 343.321234 -418.331009) (xy 343.32899 -418.384951) (xy 343.32899 -418.439449)
			(xy 343.328989 -418.439457) (xy 344.766523 -418.439457) (xy 344.766523 -418.384943) (xy 344.774282 -418.330983)
			(xy 344.789642 -418.278677) (xy 344.812289 -418.22909) (xy 344.841764 -418.183231) (xy 344.877466 -418.142033)
			(xy 344.918667 -418.106337) (xy 344.96453 -418.076867) (xy 345.01412 -418.054225) (xy 345.066428 -418.038872)
			(xy 345.120389 -418.03112) (xy 345.147646 -418.03066) (xy 346.011246 -418.03066) (xy 346.038493 -418.031213)
			(xy 346.092431 -418.038975) (xy 346.144716 -418.054332) (xy 346.194283 -418.076974) (xy 346.240124 -418.106439)
			(xy 346.281305 -418.142128) (xy 346.316988 -418.183313) (xy 346.346448 -418.229157) (xy 346.369084 -418.278727)
			(xy 346.384435 -418.331014) (xy 346.39219 -418.384953) (xy 346.39219 -418.439447) (xy 346.392189 -418.439453)
			(xy 347.829846 -418.439453) (xy 347.829846 -418.384947) (xy 347.837603 -418.330996) (xy 347.852958 -418.278698)
			(xy 347.8756 -418.229118) (xy 347.905068 -418.183264) (xy 347.940761 -418.142071) (xy 347.981953 -418.106376)
			(xy 348.027805 -418.076907) (xy 348.077385 -418.054263) (xy 348.129682 -418.038906) (xy 348.183633 -418.031147)
			(xy 348.210886 -418.03066) (xy 349.074486 -418.03066) (xy 349.101737 -418.031186) (xy 349.155685 -418.038941)
			(xy 349.20798 -418.054295) (xy 349.257558 -418.076934) (xy 349.303409 -418.106399) (xy 349.3446 -418.14209)
			(xy 349.380292 -418.18328) (xy 349.409759 -418.22913) (xy 349.432401 -418.278707) (xy 349.447756 -418.331001)
			(xy 349.455513 -418.384949) (xy 349.455513 -418.439451) (xy 349.455512 -418.439456) (xy 350.893023 -418.439456)
			(xy 350.893023 -418.384944) (xy 350.900781 -418.330986) (xy 350.91614 -418.278681) (xy 350.938786 -418.229095)
			(xy 350.968259 -418.183237) (xy 351.003959 -418.14204) (xy 351.045158 -418.106344) (xy 351.091018 -418.076874)
			(xy 351.140606 -418.054231) (xy 351.192911 -418.038876) (xy 351.24687 -418.031121) (xy 351.274126 -418.03066)
			(xy 352.137726 -418.03066) (xy 352.164974 -418.031212) (xy 352.218914 -418.038971) (xy 352.271201 -418.054327)
			(xy 352.320771 -418.076968) (xy 352.366614 -418.106432) (xy 352.407798 -418.142121) (xy 352.443484 -418.183307)
			(xy 352.472945 -418.229152) (xy 352.495582 -418.278723) (xy 352.510935 -418.331011) (xy 352.51869 -418.384952)
			(xy 352.51869 -418.439448) (xy 352.510935 -418.493389) (xy 352.495582 -418.545677) (xy 352.472945 -418.595248)
			(xy 352.443484 -418.641093) (xy 352.407798 -418.682279) (xy 352.366614 -418.717968) (xy 352.320771 -418.747432)
			(xy 352.271201 -418.770073) (xy 352.218914 -418.785429) (xy 352.164974 -418.793188) (xy 352.137726 -418.793676)
			(xy 351.274126 -418.793676) (xy 351.24687 -418.793279) (xy 351.192911 -418.785524) (xy 351.140606 -418.770169)
			(xy 351.091018 -418.747526) (xy 351.045158 -418.718056) (xy 351.003959 -418.68236) (xy 350.968259 -418.641163)
			(xy 350.938786 -418.595305) (xy 350.91614 -418.545719) (xy 350.900781 -418.493414) (xy 350.893023 -418.439456)
			(xy 349.455512 -418.439456) (xy 349.447756 -418.493399) (xy 349.432401 -418.545693) (xy 349.409759 -418.59527)
			(xy 349.380292 -418.64112) (xy 349.3446 -418.68231) (xy 349.303409 -418.718001) (xy 349.257558 -418.747466)
			(xy 349.20798 -418.770105) (xy 349.155685 -418.785459) (xy 349.101737 -418.793214) (xy 349.074486 -418.793676)
			(xy 348.210886 -418.793676) (xy 348.183633 -418.793253) (xy 348.129682 -418.785494) (xy 348.077385 -418.770137)
			(xy 348.027805 -418.747493) (xy 347.981953 -418.718024) (xy 347.940761 -418.682329) (xy 347.905068 -418.641136)
			(xy 347.8756 -418.595282) (xy 347.852958 -418.545702) (xy 347.837603 -418.493404) (xy 347.829846 -418.439453)
			(xy 346.392189 -418.439453) (xy 346.384435 -418.493386) (xy 346.369084 -418.545673) (xy 346.346448 -418.595243)
			(xy 346.316988 -418.641087) (xy 346.281305 -418.682272) (xy 346.240124 -418.717961) (xy 346.194283 -418.747426)
			(xy 346.144716 -418.770068) (xy 346.092431 -418.785425) (xy 346.038493 -418.793187) (xy 346.011246 -418.793676)
			(xy 345.147646 -418.793676) (xy 345.120389 -418.79328) (xy 345.066428 -418.785528) (xy 345.01412 -418.770175)
			(xy 344.96453 -418.747533) (xy 344.918667 -418.718063) (xy 344.877466 -418.682367) (xy 344.841764 -418.641169)
			(xy 344.812289 -418.59531) (xy 344.789642 -418.545723) (xy 344.774282 -418.493417) (xy 344.766523 -418.439457)
			(xy 343.328989 -418.439457) (xy 343.321234 -418.493391) (xy 343.305881 -418.545681) (xy 343.283242 -418.595254)
			(xy 343.253779 -418.6411) (xy 343.218091 -418.682287) (xy 343.176905 -418.717975) (xy 343.131059 -418.747439)
			(xy 343.081487 -418.770079) (xy 343.029197 -418.785433) (xy 342.975255 -418.793189) (xy 342.948006 -418.793676)
			(xy 342.084406 -418.793676) (xy 342.057151 -418.793277) (xy 342.003194 -418.785521) (xy 341.950891 -418.770164)
			(xy 341.901306 -418.74752) (xy 341.855449 -418.718049) (xy 341.814252 -418.682353) (xy 341.778554 -418.641156)
			(xy 341.749083 -418.595299) (xy 341.726438 -418.545714) (xy 341.711081 -418.493411) (xy 341.703323 -418.439455)
			(xy 340.265813 -418.439455) (xy 340.258055 -418.493402) (xy 340.242699 -418.545698) (xy 340.220056 -418.595276)
			(xy 340.190587 -418.641127) (xy 340.154893 -418.682317) (xy 340.1137 -418.718008) (xy 340.067846 -418.747472)
			(xy 340.018266 -418.770111) (xy 339.965968 -418.785463) (xy 339.912018 -418.793215) (xy 339.884766 -418.793676)
			(xy 339.021166 -418.793676) (xy 338.993914 -418.793252) (xy 338.939965 -418.785491) (xy 338.88767 -418.770131)
			(xy 338.838093 -418.747486) (xy 338.792243 -418.718017) (xy 338.751054 -418.682322) (xy 338.715363 -418.641129)
			(xy 338.685897 -418.595277) (xy 338.663257 -418.545698) (xy 338.647902 -418.493401) (xy 338.640146 -418.439452)
			(xy 337.202489 -418.439452) (xy 337.194735 -418.493389) (xy 337.179382 -418.545677) (xy 337.156745 -418.595248)
			(xy 337.127284 -418.641093) (xy 337.091598 -418.682279) (xy 337.050414 -418.717968) (xy 337.004571 -418.747432)
			(xy 336.955001 -418.770073) (xy 336.902714 -418.785429) (xy 336.848774 -418.793188) (xy 336.821526 -418.793676)
			(xy 335.957926 -418.793676) (xy 335.93067 -418.793279) (xy 335.876711 -418.785524) (xy 335.824406 -418.770169)
			(xy 335.774818 -418.747526) (xy 335.728958 -418.718056) (xy 335.687759 -418.68236) (xy 335.652059 -418.641163)
			(xy 335.622586 -418.595305) (xy 335.59994 -418.545719) (xy 335.584581 -418.493414) (xy 335.576823 -418.439456)
			(xy 334.139312 -418.439456) (xy 334.131556 -418.493399) (xy 334.116201 -418.545693) (xy 334.093559 -418.59527)
			(xy 334.064092 -418.64112) (xy 334.0284 -418.68231) (xy 333.987209 -418.718001) (xy 333.941358 -418.747466)
			(xy 333.89178 -418.770105) (xy 333.839485 -418.785459) (xy 333.785537 -418.793214) (xy 333.758286 -418.793676)
			(xy 332.894686 -418.793676) (xy 332.867433 -418.793253) (xy 332.813482 -418.785494) (xy 332.761185 -418.770137)
			(xy 332.711605 -418.747493) (xy 332.665753 -418.718024) (xy 332.624561 -418.682329) (xy 332.588868 -418.641136)
			(xy 332.5594 -418.595282) (xy 332.536758 -418.545702) (xy 332.521403 -418.493404) (xy 332.513646 -418.439453)
			(xy 331.075989 -418.439453) (xy 331.068235 -418.493386) (xy 331.052884 -418.545673) (xy 331.030248 -418.595243)
			(xy 331.000788 -418.641087) (xy 330.965105 -418.682272) (xy 330.923924 -418.717961) (xy 330.878083 -418.747426)
			(xy 330.828516 -418.770068) (xy 330.776231 -418.785425) (xy 330.722293 -418.793187) (xy 330.695046 -418.793676)
			(xy 329.831446 -418.793676) (xy 329.804189 -418.79328) (xy 329.750228 -418.785528) (xy 329.69792 -418.770175)
			(xy 329.64833 -418.747533) (xy 329.602467 -418.718063) (xy 329.561266 -418.682367) (xy 329.525564 -418.641169)
			(xy 329.496089 -418.59531) (xy 329.473442 -418.545723) (xy 329.458082 -418.493417) (xy 329.450323 -418.439457)
			(xy 328.012789 -418.439457) (xy 328.005034 -418.493391) (xy 327.989681 -418.545681) (xy 327.967042 -418.595254)
			(xy 327.937579 -418.6411) (xy 327.901891 -418.682287) (xy 327.860705 -418.717975) (xy 327.814859 -418.747439)
			(xy 327.765287 -418.770079) (xy 327.712997 -418.785433) (xy 327.659055 -418.793189) (xy 327.631806 -418.793676)
			(xy 326.768206 -418.793676) (xy 326.740951 -418.793277) (xy 326.686994 -418.785521) (xy 326.634691 -418.770164)
			(xy 326.585106 -418.74752) (xy 326.539249 -418.718049) (xy 326.498052 -418.682353) (xy 326.462354 -418.641156)
			(xy 326.432883 -418.595299) (xy 326.410238 -418.545714) (xy 326.394881 -418.493411) (xy 326.387123 -418.439455)
			(xy 324.949613 -418.439455) (xy 324.941855 -418.493402) (xy 324.926499 -418.545698) (xy 324.903856 -418.595276)
			(xy 324.874387 -418.641127) (xy 324.838693 -418.682317) (xy 324.7975 -418.718008) (xy 324.751646 -418.747472)
			(xy 324.702066 -418.770111) (xy 324.649768 -418.785463) (xy 324.595818 -418.793215) (xy 324.568566 -418.793676)
			(xy 323.704966 -418.793676) (xy 323.677714 -418.793252) (xy 323.623765 -418.785491) (xy 323.57147 -418.770131)
			(xy 323.521893 -418.747486) (xy 323.476043 -418.718017) (xy 323.434854 -418.682322) (xy 323.399163 -418.641129)
			(xy 323.369697 -418.595277) (xy 323.347057 -418.545698) (xy 323.331702 -418.493401) (xy 323.323946 -418.439452)
			(xy 321.886289 -418.439452) (xy 321.878535 -418.493389) (xy 321.863182 -418.545677) (xy 321.840545 -418.595248)
			(xy 321.811084 -418.641093) (xy 321.775398 -418.682279) (xy 321.734214 -418.717968) (xy 321.688371 -418.747432)
			(xy 321.638801 -418.770073) (xy 321.586514 -418.785429) (xy 321.532574 -418.793188) (xy 321.505326 -418.793676)
			(xy 320.641726 -418.793676) (xy 320.61447 -418.793279) (xy 320.560511 -418.785524) (xy 320.508206 -418.770169)
			(xy 320.458618 -418.747526) (xy 320.412758 -418.718056) (xy 320.371559 -418.68236) (xy 320.335859 -418.641163)
			(xy 320.306386 -418.595305) (xy 320.28374 -418.545719) (xy 320.268381 -418.493414) (xy 320.260623 -418.439456)
			(xy 318.823112 -418.439456) (xy 318.815356 -418.493399) (xy 318.800001 -418.545693) (xy 318.777359 -418.59527)
			(xy 318.747892 -418.64112) (xy 318.7122 -418.68231) (xy 318.671009 -418.718001) (xy 318.625158 -418.747466)
			(xy 318.57558 -418.770105) (xy 318.523285 -418.785459) (xy 318.469337 -418.793214) (xy 318.442086 -418.793676)
			(xy 317.578486 -418.793676) (xy 317.551233 -418.793253) (xy 317.497282 -418.785494) (xy 317.444985 -418.770137)
			(xy 317.395405 -418.747493) (xy 317.349553 -418.718024) (xy 317.308361 -418.682329) (xy 317.272668 -418.641136)
			(xy 317.2432 -418.595282) (xy 317.220558 -418.545702) (xy 317.205203 -418.493404) (xy 317.197446 -418.439453)
			(xy 315.759789 -418.439453) (xy 315.752035 -418.493386) (xy 315.736684 -418.545673) (xy 315.714048 -418.595243)
			(xy 315.684588 -418.641087) (xy 315.648905 -418.682272) (xy 315.607724 -418.717961) (xy 315.561883 -418.747426)
			(xy 315.512316 -418.770068) (xy 315.460031 -418.785425) (xy 315.406093 -418.793187) (xy 315.378846 -418.793676)
			(xy 314.515246 -418.793676) (xy 314.487989 -418.79328) (xy 314.434028 -418.785528) (xy 314.38172 -418.770175)
			(xy 314.33213 -418.747533) (xy 314.286267 -418.718063) (xy 314.245066 -418.682367) (xy 314.209364 -418.641169)
			(xy 314.179889 -418.59531) (xy 314.157242 -418.545723) (xy 314.141882 -418.493417) (xy 314.134123 -418.439457)
			(xy 312.696589 -418.439457) (xy 312.688834 -418.493391) (xy 312.673481 -418.545681) (xy 312.650842 -418.595254)
			(xy 312.621379 -418.6411) (xy 312.585691 -418.682287) (xy 312.544505 -418.717975) (xy 312.498659 -418.747439)
			(xy 312.449087 -418.770079) (xy 312.396797 -418.785433) (xy 312.342855 -418.793189) (xy 312.315606 -418.793676)
			(xy 311.452006 -418.793676) (xy 311.424751 -418.793277) (xy 311.370794 -418.785521) (xy 311.318491 -418.770164)
			(xy 311.268906 -418.74752) (xy 311.223049 -418.718049) (xy 311.181852 -418.682353) (xy 311.146154 -418.641156)
			(xy 311.116683 -418.595299) (xy 311.094038 -418.545714) (xy 311.078681 -418.493411) (xy 311.070923 -418.439455)
			(xy 309.633413 -418.439455) (xy 309.625655 -418.493402) (xy 309.610299 -418.545698) (xy 309.587656 -418.595276)
			(xy 309.558187 -418.641127) (xy 309.522493 -418.682317) (xy 309.4813 -418.718008) (xy 309.435446 -418.747472)
			(xy 309.385866 -418.770111) (xy 309.333568 -418.785463) (xy 309.279618 -418.793215) (xy 309.252366 -418.793676)
			(xy 308.388766 -418.793676) (xy 308.361514 -418.793252) (xy 308.307565 -418.785491) (xy 308.25527 -418.770131)
			(xy 308.205693 -418.747486) (xy 308.159843 -418.718017) (xy 308.118654 -418.682322) (xy 308.082963 -418.641129)
			(xy 308.053497 -418.595277) (xy 308.030857 -418.545698) (xy 308.015502 -418.493401) (xy 308.007746 -418.439452)
			(xy 306.570089 -418.439452) (xy 306.562335 -418.493389) (xy 306.546982 -418.545677) (xy 306.524345 -418.595248)
			(xy 306.494884 -418.641093) (xy 306.459198 -418.682279) (xy 306.418014 -418.717968) (xy 306.372171 -418.747432)
			(xy 306.322601 -418.770073) (xy 306.270314 -418.785429) (xy 306.216374 -418.793188) (xy 306.189126 -418.793676)
			(xy 305.325526 -418.793676) (xy 305.29827 -418.793279) (xy 305.244311 -418.785524) (xy 305.192006 -418.770169)
			(xy 305.142418 -418.747526) (xy 305.096558 -418.718056) (xy 305.055359 -418.68236) (xy 305.019659 -418.641163)
			(xy 304.990186 -418.595305) (xy 304.96754 -418.545719) (xy 304.952181 -418.493414) (xy 304.944423 -418.439456)
			(xy 290.169514 -418.439456) (xy 290.141139 -418.483609) (xy 290.105448 -418.5248) (xy 290.064257 -418.560491)
			(xy 290.018407 -418.589957) (xy 289.96883 -418.612599) (xy 289.916535 -418.627954) (xy 289.862587 -418.63571)
			(xy 289.808085 -418.63571) (xy 289.754137 -418.627954) (xy 289.701842 -418.612599) (xy 289.652265 -418.589957)
			(xy 289.606415 -418.560491) (xy 289.565224 -418.5248) (xy 289.529533 -418.483609) (xy 289.500067 -418.437759)
			(xy 289.477425 -418.388182) (xy 289.46207 -418.335887) (xy 289.454314 -418.281939) (xy 289.453828 -418.254688)
			(xy 277.48484 -418.254688) (xy 277.48484 -419.081712) (xy 277.484354 -419.108963) (xy 277.476598 -419.162911)
			(xy 277.461243 -419.215206) (xy 277.438601 -419.264783) (xy 277.409135 -419.310633) (xy 277.373444 -419.351824)
			(xy 277.332253 -419.387515) (xy 277.286403 -419.416981) (xy 277.236826 -419.439623) (xy 277.184531 -419.454978)
			(xy 277.130583 -419.462734) (xy 277.076081 -419.462734) (xy 277.022133 -419.454978) (xy 276.969838 -419.439623)
			(xy 276.920261 -419.416981) (xy 276.874411 -419.387515) (xy 276.83322 -419.351824) (xy 276.797529 -419.310633)
			(xy 276.768063 -419.264783) (xy 276.745421 -419.215206) (xy 276.730066 -419.162911) (xy 276.72231 -419.108963)
			(xy 276.721824 -419.081712) (xy 233.545126 -419.081712) (xy 232.102406 -420.524432) (xy 290.829492 -420.524432)
			(xy 290.829492 -419.660832) (xy 290.829978 -419.633563) (xy 290.83774 -419.579579) (xy 290.853105 -419.527249)
			(xy 290.875762 -419.477639) (xy 290.905248 -419.431758) (xy 290.940963 -419.390541) (xy 290.98218 -419.354826)
			(xy 291.028061 -419.32534) (xy 291.077671 -419.302683) (xy 291.130001 -419.287318) (xy 291.183985 -419.279556)
			(xy 291.238523 -419.279556) (xy 291.292507 -419.287318) (xy 291.344837 -419.302683) (xy 291.394447 -419.32534)
			(xy 291.440328 -419.354826) (xy 291.481545 -419.390541) (xy 291.51726 -419.431758) (xy 291.546746 -419.477639)
			(xy 291.569403 -419.527249) (xy 291.584768 -419.579579) (xy 291.59253 -419.633563) (xy 291.593016 -419.660832)
			(xy 291.593016 -420.524432) (xy 291.59253 -420.551701) (xy 291.584768 -420.605685) (xy 291.569403 -420.658015)
			(xy 291.546746 -420.707625) (xy 291.51726 -420.753506) (xy 291.481545 -420.794723) (xy 291.440328 -420.830438)
			(xy 291.394447 -420.859924) (xy 291.344837 -420.882581) (xy 291.292507 -420.897946) (xy 291.238523 -420.905708)
			(xy 291.183985 -420.905708) (xy 291.130001 -420.897946) (xy 291.077671 -420.882581) (xy 291.028061 -420.859924)
			(xy 290.98218 -420.830438) (xy 290.940963 -420.794723) (xy 290.905248 -420.753506) (xy 290.875762 -420.707625)
			(xy 290.853105 -420.658015) (xy 290.83774 -420.605685) (xy 290.829978 -420.551701) (xy 290.829492 -420.524432)
			(xy 232.102406 -420.524432) (xy 231.647383 -420.979455) (xy 303.412823 -420.979455) (xy 303.412823 -420.924945)
			(xy 303.420581 -420.870989) (xy 303.435938 -420.818686) (xy 303.458583 -420.769101) (xy 303.488054 -420.723244)
			(xy 303.523752 -420.682047) (xy 303.564949 -420.646351) (xy 303.610806 -420.61688) (xy 303.660391 -420.594236)
			(xy 303.712694 -420.578879) (xy 303.766651 -420.571123) (xy 303.793906 -420.57066) (xy 304.657506 -420.57066)
			(xy 304.684755 -420.571211) (xy 304.738697 -420.578967) (xy 304.790987 -420.594321) (xy 304.840559 -420.616961)
			(xy 304.886405 -420.646425) (xy 304.927591 -420.682113) (xy 304.963279 -420.7233) (xy 304.992742 -420.769146)
			(xy 305.015381 -420.818719) (xy 305.030734 -420.871009) (xy 305.03849 -420.924951) (xy 305.03849 -420.979449)
			(xy 305.038489 -420.979457) (xy 306.476023 -420.979457) (xy 306.476023 -420.924943) (xy 306.483782 -420.870983)
			(xy 306.499142 -420.818677) (xy 306.521789 -420.76909) (xy 306.551264 -420.723231) (xy 306.586966 -420.682033)
			(xy 306.628167 -420.646337) (xy 306.67403 -420.616867) (xy 306.72362 -420.594225) (xy 306.775928 -420.578872)
			(xy 306.829889 -420.57112) (xy 306.857146 -420.57066) (xy 307.720746 -420.57066) (xy 307.747993 -420.571213)
			(xy 307.801931 -420.578975) (xy 307.854216 -420.594332) (xy 307.903783 -420.616974) (xy 307.949624 -420.646439)
			(xy 307.990805 -420.682128) (xy 308.026488 -420.723313) (xy 308.055948 -420.769157) (xy 308.078584 -420.818727)
			(xy 308.093935 -420.871014) (xy 308.10169 -420.924953) (xy 308.10169 -420.979447) (xy 308.101689 -420.979453)
			(xy 309.539346 -420.979453) (xy 309.539346 -420.924947) (xy 309.547103 -420.870996) (xy 309.562458 -420.818698)
			(xy 309.5851 -420.769118) (xy 309.614568 -420.723264) (xy 309.650261 -420.682071) (xy 309.691453 -420.646376)
			(xy 309.737305 -420.616907) (xy 309.786885 -420.594263) (xy 309.839182 -420.578906) (xy 309.893133 -420.571147)
			(xy 309.920386 -420.57066) (xy 310.783986 -420.57066) (xy 310.811237 -420.571186) (xy 310.865185 -420.578941)
			(xy 310.91748 -420.594295) (xy 310.967058 -420.616934) (xy 311.012909 -420.646399) (xy 311.0541 -420.68209)
			(xy 311.089792 -420.72328) (xy 311.119259 -420.76913) (xy 311.141901 -420.818707) (xy 311.157256 -420.871001)
			(xy 311.165013 -420.924949) (xy 311.165013 -420.979451) (xy 311.165012 -420.979456) (xy 312.602523 -420.979456)
			(xy 312.602523 -420.924944) (xy 312.610281 -420.870986) (xy 312.62564 -420.818681) (xy 312.648286 -420.769095)
			(xy 312.677759 -420.723237) (xy 312.713459 -420.68204) (xy 312.754658 -420.646344) (xy 312.800518 -420.616874)
			(xy 312.850106 -420.594231) (xy 312.902411 -420.578876) (xy 312.95637 -420.571121) (xy 312.983626 -420.57066)
			(xy 313.847226 -420.57066) (xy 313.874474 -420.571212) (xy 313.928414 -420.578971) (xy 313.980701 -420.594327)
			(xy 314.030271 -420.616968) (xy 314.076114 -420.646432) (xy 314.117298 -420.682121) (xy 314.152984 -420.723307)
			(xy 314.182445 -420.769152) (xy 314.205082 -420.818723) (xy 314.220435 -420.871011) (xy 314.22819 -420.924952)
			(xy 314.22819 -420.979448) (xy 314.228189 -420.979452) (xy 315.665846 -420.979452) (xy 315.665846 -420.924948)
			(xy 315.673602 -420.870999) (xy 315.688957 -420.818702) (xy 315.711597 -420.769123) (xy 315.741063 -420.723271)
			(xy 315.776754 -420.682078) (xy 315.817943 -420.646383) (xy 315.863793 -420.616914) (xy 315.91337 -420.594269)
			(xy 315.965665 -420.578909) (xy 316.019614 -420.571148) (xy 316.046866 -420.57066) (xy 316.910466 -420.57066)
			(xy 316.937718 -420.571185) (xy 316.991668 -420.578937) (xy 317.043966 -420.594289) (xy 317.093546 -420.616928)
			(xy 317.1394 -420.646392) (xy 317.180593 -420.682083) (xy 317.216287 -420.723273) (xy 317.245756 -420.769124)
			(xy 317.268399 -420.818702) (xy 317.283755 -420.870999) (xy 317.291513 -420.924948) (xy 317.291513 -420.979452)
			(xy 317.291513 -420.979455) (xy 318.729023 -420.979455) (xy 318.729023 -420.924945) (xy 318.736781 -420.870989)
			(xy 318.752138 -420.818686) (xy 318.774783 -420.769101) (xy 318.804254 -420.723244) (xy 318.839952 -420.682047)
			(xy 318.881149 -420.646351) (xy 318.927006 -420.61688) (xy 318.976591 -420.594236) (xy 319.028894 -420.578879)
			(xy 319.082851 -420.571123) (xy 319.110106 -420.57066) (xy 319.973706 -420.57066) (xy 320.000955 -420.571211)
			(xy 320.054897 -420.578967) (xy 320.107187 -420.594321) (xy 320.156759 -420.616961) (xy 320.202605 -420.646425)
			(xy 320.243791 -420.682113) (xy 320.279479 -420.7233) (xy 320.308942 -420.769146) (xy 320.331581 -420.818719)
			(xy 320.346934 -420.871009) (xy 320.35469 -420.924951) (xy 320.35469 -420.979449) (xy 320.354689 -420.979457)
			(xy 321.792223 -420.979457) (xy 321.792223 -420.924943) (xy 321.799982 -420.870983) (xy 321.815342 -420.818677)
			(xy 321.837989 -420.76909) (xy 321.867464 -420.723231) (xy 321.903166 -420.682033) (xy 321.944367 -420.646337)
			(xy 321.99023 -420.616867) (xy 322.03982 -420.594225) (xy 322.092128 -420.578872) (xy 322.146089 -420.57112)
			(xy 322.173346 -420.57066) (xy 323.036946 -420.57066) (xy 323.064193 -420.571213) (xy 323.118131 -420.578975)
			(xy 323.170416 -420.594332) (xy 323.219983 -420.616974) (xy 323.265824 -420.646439) (xy 323.307005 -420.682128)
			(xy 323.342688 -420.723313) (xy 323.372148 -420.769157) (xy 323.394784 -420.818727) (xy 323.410135 -420.871014)
			(xy 323.41789 -420.924953) (xy 323.41789 -420.979447) (xy 323.417889 -420.979453) (xy 324.855546 -420.979453)
			(xy 324.855546 -420.924947) (xy 324.863303 -420.870996) (xy 324.878658 -420.818698) (xy 324.9013 -420.769118)
			(xy 324.930768 -420.723264) (xy 324.966461 -420.682071) (xy 325.007653 -420.646376) (xy 325.053505 -420.616907)
			(xy 325.103085 -420.594263) (xy 325.155382 -420.578906) (xy 325.209333 -420.571147) (xy 325.236586 -420.57066)
			(xy 326.100186 -420.57066) (xy 326.127437 -420.571186) (xy 326.181385 -420.578941) (xy 326.23368 -420.594295)
			(xy 326.283258 -420.616934) (xy 326.329109 -420.646399) (xy 326.3703 -420.68209) (xy 326.405992 -420.72328)
			(xy 326.435459 -420.76913) (xy 326.458101 -420.818707) (xy 326.473456 -420.871001) (xy 326.481213 -420.924949)
			(xy 326.481213 -420.979451) (xy 326.481212 -420.979456) (xy 327.918723 -420.979456) (xy 327.918723 -420.924944)
			(xy 327.926481 -420.870986) (xy 327.94184 -420.818681) (xy 327.964486 -420.769095) (xy 327.993959 -420.723237)
			(xy 328.029659 -420.68204) (xy 328.070858 -420.646344) (xy 328.116718 -420.616874) (xy 328.166306 -420.594231)
			(xy 328.218611 -420.578876) (xy 328.27257 -420.571121) (xy 328.299826 -420.57066) (xy 329.163426 -420.57066)
			(xy 329.190674 -420.571212) (xy 329.244614 -420.578971) (xy 329.296901 -420.594327) (xy 329.346471 -420.616968)
			(xy 329.392314 -420.646432) (xy 329.433498 -420.682121) (xy 329.469184 -420.723307) (xy 329.498645 -420.769152)
			(xy 329.521282 -420.818723) (xy 329.536635 -420.871011) (xy 329.54439 -420.924952) (xy 329.54439 -420.979448)
			(xy 329.544389 -420.979452) (xy 330.982046 -420.979452) (xy 330.982046 -420.924948) (xy 330.989802 -420.870999)
			(xy 331.005157 -420.818702) (xy 331.027797 -420.769123) (xy 331.057263 -420.723271) (xy 331.092954 -420.682078)
			(xy 331.134143 -420.646383) (xy 331.179993 -420.616914) (xy 331.22957 -420.594269) (xy 331.281865 -420.578909)
			(xy 331.335814 -420.571148) (xy 331.363066 -420.57066) (xy 332.226666 -420.57066) (xy 332.253918 -420.571185)
			(xy 332.307868 -420.578937) (xy 332.360166 -420.594289) (xy 332.409746 -420.616928) (xy 332.4556 -420.646392)
			(xy 332.496793 -420.682083) (xy 332.532487 -420.723273) (xy 332.561956 -420.769124) (xy 332.584599 -420.818702)
			(xy 332.599955 -420.870999) (xy 332.607713 -420.924948) (xy 332.607713 -420.979452) (xy 332.607713 -420.979455)
			(xy 334.045223 -420.979455) (xy 334.045223 -420.924945) (xy 334.052981 -420.870989) (xy 334.068338 -420.818686)
			(xy 334.090983 -420.769101) (xy 334.120454 -420.723244) (xy 334.156152 -420.682047) (xy 334.197349 -420.646351)
			(xy 334.243206 -420.61688) (xy 334.292791 -420.594236) (xy 334.345094 -420.578879) (xy 334.399051 -420.571123)
			(xy 334.426306 -420.57066) (xy 335.289906 -420.57066) (xy 335.317155 -420.571211) (xy 335.371097 -420.578967)
			(xy 335.423387 -420.594321) (xy 335.472959 -420.616961) (xy 335.518805 -420.646425) (xy 335.559991 -420.682113)
			(xy 335.595679 -420.7233) (xy 335.625142 -420.769146) (xy 335.647781 -420.818719) (xy 335.663134 -420.871009)
			(xy 335.67089 -420.924951) (xy 335.67089 -420.979449) (xy 335.670889 -420.979457) (xy 337.108423 -420.979457)
			(xy 337.108423 -420.924943) (xy 337.116182 -420.870983) (xy 337.131542 -420.818677) (xy 337.154189 -420.76909)
			(xy 337.183664 -420.723231) (xy 337.219366 -420.682033) (xy 337.260567 -420.646337) (xy 337.30643 -420.616867)
			(xy 337.35602 -420.594225) (xy 337.408328 -420.578872) (xy 337.462289 -420.57112) (xy 337.489546 -420.57066)
			(xy 338.353146 -420.57066) (xy 338.380393 -420.571213) (xy 338.434331 -420.578975) (xy 338.486616 -420.594332)
			(xy 338.536183 -420.616974) (xy 338.582024 -420.646439) (xy 338.623205 -420.682128) (xy 338.658888 -420.723313)
			(xy 338.688348 -420.769157) (xy 338.710984 -420.818727) (xy 338.726335 -420.871014) (xy 338.73409 -420.924953)
			(xy 338.73409 -420.979447) (xy 338.734089 -420.979453) (xy 340.171746 -420.979453) (xy 340.171746 -420.924947)
			(xy 340.179503 -420.870996) (xy 340.194858 -420.818698) (xy 340.2175 -420.769118) (xy 340.246968 -420.723264)
			(xy 340.282661 -420.682071) (xy 340.323853 -420.646376) (xy 340.369705 -420.616907) (xy 340.419285 -420.594263)
			(xy 340.471582 -420.578906) (xy 340.525533 -420.571147) (xy 340.552786 -420.57066) (xy 341.416386 -420.57066)
			(xy 341.443637 -420.571186) (xy 341.497585 -420.578941) (xy 341.54988 -420.594295) (xy 341.599458 -420.616934)
			(xy 341.645309 -420.646399) (xy 341.6865 -420.68209) (xy 341.722192 -420.72328) (xy 341.751659 -420.76913)
			(xy 341.774301 -420.818707) (xy 341.789656 -420.871001) (xy 341.797413 -420.924949) (xy 341.797413 -420.979451)
			(xy 341.797412 -420.979456) (xy 343.234923 -420.979456) (xy 343.234923 -420.924944) (xy 343.242681 -420.870986)
			(xy 343.25804 -420.818681) (xy 343.280686 -420.769095) (xy 343.310159 -420.723237) (xy 343.345859 -420.68204)
			(xy 343.387058 -420.646344) (xy 343.432918 -420.616874) (xy 343.482506 -420.594231) (xy 343.534811 -420.578876)
			(xy 343.58877 -420.571121) (xy 343.616026 -420.57066) (xy 344.479626 -420.57066) (xy 344.506874 -420.571212)
			(xy 344.560814 -420.578971) (xy 344.613101 -420.594327) (xy 344.662671 -420.616968) (xy 344.708514 -420.646432)
			(xy 344.749698 -420.682121) (xy 344.785384 -420.723307) (xy 344.814845 -420.769152) (xy 344.837482 -420.818723)
			(xy 344.852835 -420.871011) (xy 344.86059 -420.924952) (xy 344.86059 -420.979448) (xy 344.860589 -420.979452)
			(xy 346.298246 -420.979452) (xy 346.298246 -420.924948) (xy 346.306002 -420.870999) (xy 346.321357 -420.818702)
			(xy 346.343997 -420.769123) (xy 346.373463 -420.723271) (xy 346.409154 -420.682078) (xy 346.450343 -420.646383)
			(xy 346.496193 -420.616914) (xy 346.54577 -420.594269) (xy 346.598065 -420.578909) (xy 346.652014 -420.571148)
			(xy 346.679266 -420.57066) (xy 347.542866 -420.57066) (xy 347.570118 -420.571185) (xy 347.624068 -420.578937)
			(xy 347.676366 -420.594289) (xy 347.725946 -420.616928) (xy 347.7718 -420.646392) (xy 347.812993 -420.682083)
			(xy 347.848687 -420.723273) (xy 347.878156 -420.769124) (xy 347.900799 -420.818702) (xy 347.916155 -420.870999)
			(xy 347.923913 -420.924948) (xy 347.923913 -420.979452) (xy 347.923913 -420.979455) (xy 349.361423 -420.979455)
			(xy 349.361423 -420.924945) (xy 349.369181 -420.870989) (xy 349.384538 -420.818686) (xy 349.407183 -420.769101)
			(xy 349.436654 -420.723244) (xy 349.472352 -420.682047) (xy 349.513549 -420.646351) (xy 349.559406 -420.61688)
			(xy 349.608991 -420.594236) (xy 349.661294 -420.578879) (xy 349.715251 -420.571123) (xy 349.742506 -420.57066)
			(xy 350.606106 -420.57066) (xy 350.633355 -420.571211) (xy 350.687297 -420.578967) (xy 350.739587 -420.594321)
			(xy 350.789159 -420.616961) (xy 350.835005 -420.646425) (xy 350.876191 -420.682113) (xy 350.911879 -420.7233)
			(xy 350.941342 -420.769146) (xy 350.963981 -420.818719) (xy 350.979334 -420.871009) (xy 350.98709 -420.924951)
			(xy 350.98709 -420.979449) (xy 350.979334 -421.033391) (xy 350.963981 -421.085681) (xy 350.941342 -421.135254)
			(xy 350.911879 -421.1811) (xy 350.876191 -421.222287) (xy 350.835005 -421.257975) (xy 350.789159 -421.287439)
			(xy 350.739587 -421.310079) (xy 350.687297 -421.325433) (xy 350.633355 -421.333189) (xy 350.606106 -421.333676)
			(xy 349.742506 -421.333676) (xy 349.715251 -421.333277) (xy 349.661294 -421.325521) (xy 349.608991 -421.310164)
			(xy 349.559406 -421.28752) (xy 349.513549 -421.258049) (xy 349.472352 -421.222353) (xy 349.436654 -421.181156)
			(xy 349.407183 -421.135299) (xy 349.384538 -421.085714) (xy 349.369181 -421.033411) (xy 349.361423 -420.979455)
			(xy 347.923913 -420.979455) (xy 347.916155 -421.033402) (xy 347.900799 -421.085698) (xy 347.878156 -421.135276)
			(xy 347.848687 -421.181127) (xy 347.812993 -421.222317) (xy 347.7718 -421.258008) (xy 347.725946 -421.287472)
			(xy 347.676366 -421.310111) (xy 347.624068 -421.325463) (xy 347.570118 -421.333215) (xy 347.542866 -421.333676)
			(xy 346.679266 -421.333676) (xy 346.652014 -421.333252) (xy 346.598065 -421.325491) (xy 346.54577 -421.310131)
			(xy 346.496193 -421.287486) (xy 346.450343 -421.258017) (xy 346.409154 -421.222322) (xy 346.373463 -421.181129)
			(xy 346.343997 -421.135277) (xy 346.321357 -421.085698) (xy 346.306002 -421.033401) (xy 346.298246 -420.979452)
			(xy 344.860589 -420.979452) (xy 344.852835 -421.033389) (xy 344.837482 -421.085677) (xy 344.814845 -421.135248)
			(xy 344.785384 -421.181093) (xy 344.749698 -421.222279) (xy 344.708514 -421.257968) (xy 344.662671 -421.287432)
			(xy 344.613101 -421.310073) (xy 344.560814 -421.325429) (xy 344.506874 -421.333188) (xy 344.479626 -421.333676)
			(xy 343.616026 -421.333676) (xy 343.58877 -421.333279) (xy 343.534811 -421.325524) (xy 343.482506 -421.310169)
			(xy 343.432918 -421.287526) (xy 343.387058 -421.258056) (xy 343.345859 -421.22236) (xy 343.310159 -421.181163)
			(xy 343.280686 -421.135305) (xy 343.25804 -421.085719) (xy 343.242681 -421.033414) (xy 343.234923 -420.979456)
			(xy 341.797412 -420.979456) (xy 341.789656 -421.033399) (xy 341.774301 -421.085693) (xy 341.751659 -421.13527)
			(xy 341.722192 -421.18112) (xy 341.6865 -421.22231) (xy 341.645309 -421.258001) (xy 341.599458 -421.287466)
			(xy 341.54988 -421.310105) (xy 341.497585 -421.325459) (xy 341.443637 -421.333214) (xy 341.416386 -421.333676)
			(xy 340.552786 -421.333676) (xy 340.525533 -421.333253) (xy 340.471582 -421.325494) (xy 340.419285 -421.310137)
			(xy 340.369705 -421.287493) (xy 340.323853 -421.258024) (xy 340.282661 -421.222329) (xy 340.246968 -421.181136)
			(xy 340.2175 -421.135282) (xy 340.194858 -421.085702) (xy 340.179503 -421.033404) (xy 340.171746 -420.979453)
			(xy 338.734089 -420.979453) (xy 338.726335 -421.033386) (xy 338.710984 -421.085673) (xy 338.688348 -421.135243)
			(xy 338.658888 -421.181087) (xy 338.623205 -421.222272) (xy 338.582024 -421.257961) (xy 338.536183 -421.287426)
			(xy 338.486616 -421.310068) (xy 338.434331 -421.325425) (xy 338.380393 -421.333187) (xy 338.353146 -421.333676)
			(xy 337.489546 -421.333676) (xy 337.462289 -421.33328) (xy 337.408328 -421.325528) (xy 337.35602 -421.310175)
			(xy 337.30643 -421.287533) (xy 337.260567 -421.258063) (xy 337.219366 -421.222367) (xy 337.183664 -421.181169)
			(xy 337.154189 -421.13531) (xy 337.131542 -421.085723) (xy 337.116182 -421.033417) (xy 337.108423 -420.979457)
			(xy 335.670889 -420.979457) (xy 335.663134 -421.033391) (xy 335.647781 -421.085681) (xy 335.625142 -421.135254)
			(xy 335.595679 -421.1811) (xy 335.559991 -421.222287) (xy 335.518805 -421.257975) (xy 335.472959 -421.287439)
			(xy 335.423387 -421.310079) (xy 335.371097 -421.325433) (xy 335.317155 -421.333189) (xy 335.289906 -421.333676)
			(xy 334.426306 -421.333676) (xy 334.399051 -421.333277) (xy 334.345094 -421.325521) (xy 334.292791 -421.310164)
			(xy 334.243206 -421.28752) (xy 334.197349 -421.258049) (xy 334.156152 -421.222353) (xy 334.120454 -421.181156)
			(xy 334.090983 -421.135299) (xy 334.068338 -421.085714) (xy 334.052981 -421.033411) (xy 334.045223 -420.979455)
			(xy 332.607713 -420.979455) (xy 332.599955 -421.033402) (xy 332.584599 -421.085698) (xy 332.561956 -421.135276)
			(xy 332.532487 -421.181127) (xy 332.496793 -421.222317) (xy 332.4556 -421.258008) (xy 332.409746 -421.287472)
			(xy 332.360166 -421.310111) (xy 332.307868 -421.325463) (xy 332.253918 -421.333215) (xy 332.226666 -421.333676)
			(xy 331.363066 -421.333676) (xy 331.335814 -421.333252) (xy 331.281865 -421.325491) (xy 331.22957 -421.310131)
			(xy 331.179993 -421.287486) (xy 331.134143 -421.258017) (xy 331.092954 -421.222322) (xy 331.057263 -421.181129)
			(xy 331.027797 -421.135277) (xy 331.005157 -421.085698) (xy 330.989802 -421.033401) (xy 330.982046 -420.979452)
			(xy 329.544389 -420.979452) (xy 329.536635 -421.033389) (xy 329.521282 -421.085677) (xy 329.498645 -421.135248)
			(xy 329.469184 -421.181093) (xy 329.433498 -421.222279) (xy 329.392314 -421.257968) (xy 329.346471 -421.287432)
			(xy 329.296901 -421.310073) (xy 329.244614 -421.325429) (xy 329.190674 -421.333188) (xy 329.163426 -421.333676)
			(xy 328.299826 -421.333676) (xy 328.27257 -421.333279) (xy 328.218611 -421.325524) (xy 328.166306 -421.310169)
			(xy 328.116718 -421.287526) (xy 328.070858 -421.258056) (xy 328.029659 -421.22236) (xy 327.993959 -421.181163)
			(xy 327.964486 -421.135305) (xy 327.94184 -421.085719) (xy 327.926481 -421.033414) (xy 327.918723 -420.979456)
			(xy 326.481212 -420.979456) (xy 326.473456 -421.033399) (xy 326.458101 -421.085693) (xy 326.435459 -421.13527)
			(xy 326.405992 -421.18112) (xy 326.3703 -421.22231) (xy 326.329109 -421.258001) (xy 326.283258 -421.287466)
			(xy 326.23368 -421.310105) (xy 326.181385 -421.325459) (xy 326.127437 -421.333214) (xy 326.100186 -421.333676)
			(xy 325.236586 -421.333676) (xy 325.209333 -421.333253) (xy 325.155382 -421.325494) (xy 325.103085 -421.310137)
			(xy 325.053505 -421.287493) (xy 325.007653 -421.258024) (xy 324.966461 -421.222329) (xy 324.930768 -421.181136)
			(xy 324.9013 -421.135282) (xy 324.878658 -421.085702) (xy 324.863303 -421.033404) (xy 324.855546 -420.979453)
			(xy 323.417889 -420.979453) (xy 323.410135 -421.033386) (xy 323.394784 -421.085673) (xy 323.372148 -421.135243)
			(xy 323.342688 -421.181087) (xy 323.307005 -421.222272) (xy 323.265824 -421.257961) (xy 323.219983 -421.287426)
			(xy 323.170416 -421.310068) (xy 323.118131 -421.325425) (xy 323.064193 -421.333187) (xy 323.036946 -421.333676)
			(xy 322.173346 -421.333676) (xy 322.146089 -421.33328) (xy 322.092128 -421.325528) (xy 322.03982 -421.310175)
			(xy 321.99023 -421.287533) (xy 321.944367 -421.258063) (xy 321.903166 -421.222367) (xy 321.867464 -421.181169)
			(xy 321.837989 -421.13531) (xy 321.815342 -421.085723) (xy 321.799982 -421.033417) (xy 321.792223 -420.979457)
			(xy 320.354689 -420.979457) (xy 320.346934 -421.033391) (xy 320.331581 -421.085681) (xy 320.308942 -421.135254)
			(xy 320.279479 -421.1811) (xy 320.243791 -421.222287) (xy 320.202605 -421.257975) (xy 320.156759 -421.287439)
			(xy 320.107187 -421.310079) (xy 320.054897 -421.325433) (xy 320.000955 -421.333189) (xy 319.973706 -421.333676)
			(xy 319.110106 -421.333676) (xy 319.082851 -421.333277) (xy 319.028894 -421.325521) (xy 318.976591 -421.310164)
			(xy 318.927006 -421.28752) (xy 318.881149 -421.258049) (xy 318.839952 -421.222353) (xy 318.804254 -421.181156)
			(xy 318.774783 -421.135299) (xy 318.752138 -421.085714) (xy 318.736781 -421.033411) (xy 318.729023 -420.979455)
			(xy 317.291513 -420.979455) (xy 317.283755 -421.033402) (xy 317.268399 -421.085698) (xy 317.245756 -421.135276)
			(xy 317.216287 -421.181127) (xy 317.180593 -421.222317) (xy 317.1394 -421.258008) (xy 317.093546 -421.287472)
			(xy 317.043966 -421.310111) (xy 316.991668 -421.325463) (xy 316.937718 -421.333215) (xy 316.910466 -421.333676)
			(xy 316.046866 -421.333676) (xy 316.019614 -421.333252) (xy 315.965665 -421.325491) (xy 315.91337 -421.310131)
			(xy 315.863793 -421.287486) (xy 315.817943 -421.258017) (xy 315.776754 -421.222322) (xy 315.741063 -421.181129)
			(xy 315.711597 -421.135277) (xy 315.688957 -421.085698) (xy 315.673602 -421.033401) (xy 315.665846 -420.979452)
			(xy 314.228189 -420.979452) (xy 314.220435 -421.033389) (xy 314.205082 -421.085677) (xy 314.182445 -421.135248)
			(xy 314.152984 -421.181093) (xy 314.117298 -421.222279) (xy 314.076114 -421.257968) (xy 314.030271 -421.287432)
			(xy 313.980701 -421.310073) (xy 313.928414 -421.325429) (xy 313.874474 -421.333188) (xy 313.847226 -421.333676)
			(xy 312.983626 -421.333676) (xy 312.95637 -421.333279) (xy 312.902411 -421.325524) (xy 312.850106 -421.310169)
			(xy 312.800518 -421.287526) (xy 312.754658 -421.258056) (xy 312.713459 -421.22236) (xy 312.677759 -421.181163)
			(xy 312.648286 -421.135305) (xy 312.62564 -421.085719) (xy 312.610281 -421.033414) (xy 312.602523 -420.979456)
			(xy 311.165012 -420.979456) (xy 311.157256 -421.033399) (xy 311.141901 -421.085693) (xy 311.119259 -421.13527)
			(xy 311.089792 -421.18112) (xy 311.0541 -421.22231) (xy 311.012909 -421.258001) (xy 310.967058 -421.287466)
			(xy 310.91748 -421.310105) (xy 310.865185 -421.325459) (xy 310.811237 -421.333214) (xy 310.783986 -421.333676)
			(xy 309.920386 -421.333676) (xy 309.893133 -421.333253) (xy 309.839182 -421.325494) (xy 309.786885 -421.310137)
			(xy 309.737305 -421.287493) (xy 309.691453 -421.258024) (xy 309.650261 -421.222329) (xy 309.614568 -421.181136)
			(xy 309.5851 -421.135282) (xy 309.562458 -421.085702) (xy 309.547103 -421.033404) (xy 309.539346 -420.979453)
			(xy 308.101689 -420.979453) (xy 308.093935 -421.033386) (xy 308.078584 -421.085673) (xy 308.055948 -421.135243)
			(xy 308.026488 -421.181087) (xy 307.990805 -421.222272) (xy 307.949624 -421.257961) (xy 307.903783 -421.287426)
			(xy 307.854216 -421.310068) (xy 307.801931 -421.325425) (xy 307.747993 -421.333187) (xy 307.720746 -421.333676)
			(xy 306.857146 -421.333676) (xy 306.829889 -421.33328) (xy 306.775928 -421.325528) (xy 306.72362 -421.310175)
			(xy 306.67403 -421.287533) (xy 306.628167 -421.258063) (xy 306.586966 -421.222367) (xy 306.551264 -421.181169)
			(xy 306.521789 -421.13531) (xy 306.499142 -421.085723) (xy 306.483782 -421.033417) (xy 306.476023 -420.979457)
			(xy 305.038489 -420.979457) (xy 305.030734 -421.033391) (xy 305.015381 -421.085681) (xy 304.992742 -421.135254)
			(xy 304.963279 -421.1811) (xy 304.927591 -421.222287) (xy 304.886405 -421.257975) (xy 304.840559 -421.287439)
			(xy 304.790987 -421.310079) (xy 304.738697 -421.325433) (xy 304.684755 -421.333189) (xy 304.657506 -421.333676)
			(xy 303.793906 -421.333676) (xy 303.766651 -421.333277) (xy 303.712694 -421.325521) (xy 303.660391 -421.310164)
			(xy 303.610806 -421.28752) (xy 303.564949 -421.258049) (xy 303.523752 -421.222353) (xy 303.488054 -421.181156)
			(xy 303.458583 -421.135299) (xy 303.435938 -421.085714) (xy 303.420581 -421.033411) (xy 303.412823 -420.979455)
			(xy 231.647383 -420.979455) (xy 230.329486 -422.297352) (xy 230.322673 -422.304773) (xy 230.314938 -422.323356)
			(xy 230.3145 -422.33342) (xy 230.3145 -422.354375) (xy 285.567772 -422.354375) (xy 285.567772 -422.299825)
			(xy 285.575535 -422.245831) (xy 285.590905 -422.193491) (xy 285.613567 -422.143872) (xy 285.64306 -422.097983)
			(xy 285.678784 -422.056759) (xy 285.720012 -422.021038) (xy 285.765903 -421.991549) (xy 285.815525 -421.968892)
			(xy 285.867866 -421.953528) (xy 285.921861 -421.945769) (xy 285.949136 -421.945308) (xy 286.812736 -421.945308)
			(xy 286.840002 -421.945857) (xy 286.893977 -421.953622) (xy 286.946298 -421.968989) (xy 286.9959 -421.991646)
			(xy 287.041773 -422.02113) (xy 287.082983 -422.056843) (xy 287.118691 -422.098056) (xy 287.148172 -422.143932)
			(xy 287.170823 -422.193536) (xy 287.186186 -422.245858) (xy 287.193946 -422.299834) (xy 287.193946 -422.354366)
			(xy 287.186186 -422.408342) (xy 287.170823 -422.460664) (xy 287.148172 -422.510268) (xy 287.118691 -422.556144)
			(xy 287.082983 -422.597357) (xy 287.041773 -422.63307) (xy 286.9959 -422.662554) (xy 286.946298 -422.685211)
			(xy 286.893977 -422.700578) (xy 286.840002 -422.708343) (xy 286.812736 -422.708832) (xy 285.949136 -422.708832)
			(xy 285.921861 -422.708431) (xy 285.867866 -422.700672) (xy 285.815525 -422.685308) (xy 285.765903 -422.662651)
			(xy 285.720012 -422.633162) (xy 285.678784 -422.597441) (xy 285.64306 -422.556217) (xy 285.613567 -422.510328)
			(xy 285.590905 -422.460709) (xy 285.575535 -422.408369) (xy 285.567772 -422.354375) (xy 230.3145 -422.354375)
			(xy 230.3145 -424.80464) (xy 357.679233 -424.80464) (xy 357.679233 -424.6755) (xy 357.687183 -424.546605)
			(xy 357.703053 -424.418445) (xy 357.726782 -424.291504) (xy 357.758281 -424.166265) (xy 357.79743 -424.043202)
			(xy 357.844081 -423.922783) (xy 357.898056 -423.805464) (xy 357.959151 -423.69169) (xy 358.027134 -423.581893)
			(xy 358.101748 -423.47649) (xy 358.182709 -423.37588) (xy 358.269709 -423.280445) (xy 358.36242 -423.190546)
			(xy 358.46049 -423.106525) (xy 358.563545 -423.028701) (xy 358.671196 -422.957369) (xy 358.783035 -422.892799)
			(xy 358.898636 -422.835237) (xy 359.017561 -422.7849) (xy 359.13936 -422.74198) (xy 359.26357 -422.706639)
			(xy 359.389719 -422.679012) (xy 359.517331 -422.659203) (xy 359.64592 -422.647287) (xy 359.774998 -422.643311)
			(xy 359.904076 -422.647287) (xy 360.032665 -422.659203) (xy 360.160277 -422.679012) (xy 360.222212 -422.692576)
			(xy 365.310928 -422.692576) (xy 365.310928 -415.898584) (xy 365.3113 -415.888356) (xy 365.319137 -415.86946)
			(xy 365.33361 -415.855003) (xy 365.352515 -415.847188) (xy 365.362744 -415.846768) (xy 370.261388 -415.846768)
			(xy 370.271593 -415.847291) (xy 370.290451 -415.855097) (xy 370.304887 -415.869525) (xy 370.312703 -415.888379)
			(xy 370.313204 -415.898584) (xy 370.313204 -418.439456) (xy 372.044623 -418.439456) (xy 372.044623 -418.384944)
			(xy 372.052381 -418.330986) (xy 372.06774 -418.278682) (xy 372.090386 -418.229097) (xy 372.119858 -418.183238)
			(xy 372.155557 -418.142042) (xy 372.196756 -418.106345) (xy 372.242616 -418.076875) (xy 372.292203 -418.054232)
			(xy 372.344508 -418.038877) (xy 372.398466 -418.031121) (xy 372.425722 -418.03066) (xy 373.289322 -418.03066)
			(xy 373.31657 -418.031212) (xy 373.370511 -418.03897) (xy 373.422798 -418.054326) (xy 373.472369 -418.076966)
			(xy 373.518212 -418.106431) (xy 373.559396 -418.142119) (xy 373.595083 -418.183305) (xy 373.624544 -418.229151)
			(xy 373.647182 -418.278722) (xy 373.662535 -418.331011) (xy 373.67029 -418.384952) (xy 373.67029 -418.439448)
			(xy 373.670289 -418.439452) (xy 375.107946 -418.439452) (xy 375.107946 -418.384948) (xy 375.115702 -418.330999)
			(xy 375.131056 -418.278703) (xy 375.153697 -418.229124) (xy 375.183162 -418.183272) (xy 375.218852 -418.142079)
			(xy 375.260041 -418.106385) (xy 375.305891 -418.076915) (xy 375.355468 -418.05427) (xy 375.407762 -418.03891)
			(xy 375.46171 -418.031148) (xy 375.488962 -418.03066) (xy 376.352562 -418.03066) (xy 376.379814 -418.031185)
			(xy 376.433765 -418.038937) (xy 376.486063 -418.054288) (xy 376.535644 -418.076926) (xy 376.581498 -418.106391)
			(xy 376.622691 -418.142082) (xy 376.658386 -418.183272) (xy 376.687855 -418.229123) (xy 376.710499 -418.278701)
			(xy 376.725855 -418.330998) (xy 376.733613 -418.384948) (xy 376.733613 -418.439452) (xy 376.733613 -418.439455)
			(xy 378.171123 -418.439455) (xy 378.171123 -418.384945) (xy 378.178881 -418.330989) (xy 378.194238 -418.278687)
			(xy 378.216883 -418.229102) (xy 378.246353 -418.183245) (xy 378.28205 -418.142049) (xy 378.323247 -418.106352)
			(xy 378.369104 -418.076882) (xy 378.418688 -418.054237) (xy 378.470991 -418.03888) (xy 378.524947 -418.031123)
			(xy 378.552202 -418.03066) (xy 379.415802 -418.03066) (xy 379.443051 -418.03121) (xy 379.496994 -418.038966)
			(xy 379.549284 -418.05432) (xy 379.598857 -418.07696) (xy 379.644703 -418.106424) (xy 379.685889 -418.142112)
			(xy 379.721578 -418.183299) (xy 379.751041 -418.229145) (xy 379.77368 -418.278718) (xy 379.789034 -418.331008)
			(xy 379.79679 -418.384951) (xy 379.79679 -418.439449) (xy 379.796789 -418.439457) (xy 381.234323 -418.439457)
			(xy 381.234323 -418.384943) (xy 381.242082 -418.330984) (xy 381.257441 -418.278678) (xy 381.280089 -418.229091)
			(xy 381.309563 -418.183232) (xy 381.345264 -418.142035) (xy 381.386466 -418.106338) (xy 381.432328 -418.076869)
			(xy 381.481917 -418.054227) (xy 381.534225 -418.038873) (xy 381.588185 -418.03112) (xy 381.615442 -418.03066)
			(xy 382.479042 -418.03066) (xy 382.506289 -418.031213) (xy 382.560228 -418.038974) (xy 382.612513 -418.054331)
			(xy 382.662081 -418.076973) (xy 382.707922 -418.106438) (xy 382.749103 -418.142126) (xy 382.784787 -418.183312)
			(xy 382.814247 -418.229156) (xy 382.836883 -418.278727) (xy 382.852235 -418.331014) (xy 382.85999 -418.384953)
			(xy 382.85999 -418.439447) (xy 382.859989 -418.439453) (xy 384.297646 -418.439453) (xy 384.297646 -418.384947)
			(xy 384.305403 -418.330997) (xy 384.320758 -418.278699) (xy 384.3434 -418.229119) (xy 384.372867 -418.183265)
			(xy 384.408559 -418.142072) (xy 384.449751 -418.106378) (xy 384.495603 -418.076908) (xy 384.545182 -418.054264)
			(xy 384.597479 -418.038906) (xy 384.651429 -418.031147) (xy 384.678682 -418.03066) (xy 385.542282 -418.03066)
			(xy 385.569533 -418.031186) (xy 385.623482 -418.03894) (xy 385.675777 -418.054293) (xy 385.725356 -418.076933)
			(xy 385.771207 -418.106398) (xy 385.812399 -418.142089) (xy 385.848091 -418.183278) (xy 385.877558 -418.229129)
			(xy 385.9002 -418.278706) (xy 385.915556 -418.331001) (xy 385.923313 -418.384949) (xy 385.923313 -418.439451)
			(xy 385.923312 -418.439456) (xy 387.360823 -418.439456) (xy 387.360823 -418.384944) (xy 387.368581 -418.330986)
			(xy 387.38394 -418.278682) (xy 387.406586 -418.229097) (xy 387.436058 -418.183238) (xy 387.471757 -418.142042)
			(xy 387.512956 -418.106345) (xy 387.558816 -418.076875) (xy 387.608403 -418.054232) (xy 387.660708 -418.038877)
			(xy 387.714666 -418.031121) (xy 387.741922 -418.03066) (xy 388.605522 -418.03066) (xy 388.63277 -418.031212)
			(xy 388.686711 -418.03897) (xy 388.738998 -418.054326) (xy 388.788569 -418.076966) (xy 388.834412 -418.106431)
			(xy 388.875596 -418.142119) (xy 388.911283 -418.183305) (xy 388.940744 -418.229151) (xy 388.963382 -418.278722)
			(xy 388.978735 -418.331011) (xy 388.98649 -418.384952) (xy 388.98649 -418.439448) (xy 388.986489 -418.439452)
			(xy 390.424146 -418.439452) (xy 390.424146 -418.384948) (xy 390.431902 -418.330999) (xy 390.447256 -418.278703)
			(xy 390.469897 -418.229124) (xy 390.499362 -418.183272) (xy 390.535052 -418.142079) (xy 390.576241 -418.106385)
			(xy 390.622091 -418.076915) (xy 390.671668 -418.05427) (xy 390.723962 -418.03891) (xy 390.77791 -418.031148)
			(xy 390.805162 -418.03066) (xy 391.668762 -418.03066) (xy 391.696014 -418.031185) (xy 391.749965 -418.038937)
			(xy 391.802263 -418.054288) (xy 391.851844 -418.076926) (xy 391.897698 -418.106391) (xy 391.938891 -418.142082)
			(xy 391.974586 -418.183272) (xy 392.004055 -418.229123) (xy 392.026699 -418.278701) (xy 392.042055 -418.330998)
			(xy 392.049813 -418.384948) (xy 392.049813 -418.439452) (xy 392.049813 -418.439455) (xy 393.487323 -418.439455)
			(xy 393.487323 -418.384945) (xy 393.495081 -418.330989) (xy 393.510438 -418.278687) (xy 393.533083 -418.229102)
			(xy 393.562553 -418.183245) (xy 393.59825 -418.142049) (xy 393.639447 -418.106352) (xy 393.685304 -418.076882)
			(xy 393.734888 -418.054237) (xy 393.787191 -418.03888) (xy 393.841147 -418.031123) (xy 393.868402 -418.03066)
			(xy 394.732002 -418.03066) (xy 394.759251 -418.03121) (xy 394.813194 -418.038966) (xy 394.865484 -418.05432)
			(xy 394.915057 -418.07696) (xy 394.960903 -418.106424) (xy 395.002089 -418.142112) (xy 395.037778 -418.183299)
			(xy 395.067241 -418.229145) (xy 395.08988 -418.278718) (xy 395.105234 -418.331008) (xy 395.11299 -418.384951)
			(xy 395.11299 -418.439449) (xy 395.112989 -418.439457) (xy 396.550523 -418.439457) (xy 396.550523 -418.384943)
			(xy 396.558282 -418.330984) (xy 396.573641 -418.278678) (xy 396.596289 -418.229091) (xy 396.625763 -418.183232)
			(xy 396.661464 -418.142035) (xy 396.702666 -418.106338) (xy 396.748528 -418.076869) (xy 396.798117 -418.054227)
			(xy 396.850425 -418.038873) (xy 396.904385 -418.03112) (xy 396.931642 -418.03066) (xy 397.795242 -418.03066)
			(xy 397.822489 -418.031213) (xy 397.876428 -418.038974) (xy 397.928713 -418.054331) (xy 397.978281 -418.076973)
			(xy 398.024122 -418.106438) (xy 398.065303 -418.142126) (xy 398.100987 -418.183312) (xy 398.130447 -418.229156)
			(xy 398.153083 -418.278727) (xy 398.168435 -418.331014) (xy 398.17619 -418.384953) (xy 398.17619 -418.439447)
			(xy 398.176189 -418.439453) (xy 399.613846 -418.439453) (xy 399.613846 -418.384947) (xy 399.621603 -418.330997)
			(xy 399.636958 -418.278699) (xy 399.6596 -418.229119) (xy 399.689067 -418.183265) (xy 399.724759 -418.142072)
			(xy 399.765951 -418.106378) (xy 399.811803 -418.076908) (xy 399.861382 -418.054264) (xy 399.913679 -418.038906)
			(xy 399.967629 -418.031147) (xy 399.994882 -418.03066) (xy 400.858482 -418.03066) (xy 400.885733 -418.031186)
			(xy 400.939682 -418.03894) (xy 400.991977 -418.054293) (xy 401.041556 -418.076933) (xy 401.087407 -418.106398)
			(xy 401.128599 -418.142089) (xy 401.164291 -418.183278) (xy 401.193758 -418.229129) (xy 401.2164 -418.278706)
			(xy 401.231756 -418.331001) (xy 401.239513 -418.384949) (xy 401.239513 -418.439451) (xy 401.239512 -418.439456)
			(xy 402.677023 -418.439456) (xy 402.677023 -418.384944) (xy 402.684781 -418.330986) (xy 402.70014 -418.278682)
			(xy 402.722786 -418.229097) (xy 402.752258 -418.183238) (xy 402.787957 -418.142042) (xy 402.829156 -418.106345)
			(xy 402.875016 -418.076875) (xy 402.924603 -418.054232) (xy 402.976908 -418.038877) (xy 403.030866 -418.031121)
			(xy 403.058122 -418.03066) (xy 403.921722 -418.03066) (xy 403.94897 -418.031212) (xy 404.002911 -418.03897)
			(xy 404.055198 -418.054326) (xy 404.104769 -418.076966) (xy 404.150612 -418.106431) (xy 404.191796 -418.142119)
			(xy 404.227483 -418.183305) (xy 404.256944 -418.229151) (xy 404.279582 -418.278722) (xy 404.294935 -418.331011)
			(xy 404.30269 -418.384952) (xy 404.30269 -418.439448) (xy 404.302689 -418.439452) (xy 405.740346 -418.439452)
			(xy 405.740346 -418.384948) (xy 405.748102 -418.330999) (xy 405.763456 -418.278703) (xy 405.786097 -418.229124)
			(xy 405.815562 -418.183272) (xy 405.851252 -418.142079) (xy 405.892441 -418.106385) (xy 405.938291 -418.076915)
			(xy 405.987868 -418.05427) (xy 406.040162 -418.03891) (xy 406.09411 -418.031148) (xy 406.121362 -418.03066)
			(xy 406.984962 -418.03066) (xy 407.012214 -418.031185) (xy 407.066165 -418.038937) (xy 407.118463 -418.054288)
			(xy 407.168044 -418.076926) (xy 407.213898 -418.106391) (xy 407.255091 -418.142082) (xy 407.290786 -418.183272)
			(xy 407.320255 -418.229123) (xy 407.342899 -418.278701) (xy 407.358255 -418.330998) (xy 407.366013 -418.384948)
			(xy 407.366013 -418.439452) (xy 407.366013 -418.439455) (xy 408.803523 -418.439455) (xy 408.803523 -418.384945)
			(xy 408.811281 -418.330989) (xy 408.826638 -418.278687) (xy 408.849283 -418.229102) (xy 408.878753 -418.183245)
			(xy 408.91445 -418.142049) (xy 408.955647 -418.106352) (xy 409.001504 -418.076882) (xy 409.051088 -418.054237)
			(xy 409.103391 -418.03888) (xy 409.157347 -418.031123) (xy 409.184602 -418.03066) (xy 410.048202 -418.03066)
			(xy 410.075451 -418.03121) (xy 410.129394 -418.038966) (xy 410.181684 -418.05432) (xy 410.231257 -418.07696)
			(xy 410.277103 -418.106424) (xy 410.318289 -418.142112) (xy 410.353978 -418.183299) (xy 410.383441 -418.229145)
			(xy 410.40608 -418.278718) (xy 410.421434 -418.331008) (xy 410.42919 -418.384951) (xy 410.42919 -418.439449)
			(xy 410.429189 -418.439457) (xy 411.866723 -418.439457) (xy 411.866723 -418.384943) (xy 411.874482 -418.330984)
			(xy 411.889841 -418.278678) (xy 411.912489 -418.229091) (xy 411.941963 -418.183232) (xy 411.977664 -418.142035)
			(xy 412.018866 -418.106338) (xy 412.064728 -418.076869) (xy 412.114317 -418.054227) (xy 412.166625 -418.038873)
			(xy 412.220585 -418.03112) (xy 412.247842 -418.03066) (xy 413.111442 -418.03066) (xy 413.138689 -418.031213)
			(xy 413.192628 -418.038974) (xy 413.244913 -418.054331) (xy 413.294481 -418.076973) (xy 413.340322 -418.106438)
			(xy 413.381503 -418.142126) (xy 413.417187 -418.183312) (xy 413.446647 -418.229156) (xy 413.469283 -418.278727)
			(xy 413.484635 -418.331014) (xy 413.49239 -418.384953) (xy 413.49239 -418.439447) (xy 413.492389 -418.439453)
			(xy 414.930046 -418.439453) (xy 414.930046 -418.384947) (xy 414.937803 -418.330997) (xy 414.953158 -418.278699)
			(xy 414.9758 -418.229119) (xy 415.005267 -418.183265) (xy 415.040959 -418.142072) (xy 415.082151 -418.106378)
			(xy 415.128003 -418.076908) (xy 415.177582 -418.054264) (xy 415.229879 -418.038906) (xy 415.283829 -418.031147)
			(xy 415.311082 -418.03066) (xy 416.174682 -418.03066) (xy 416.201933 -418.031186) (xy 416.255882 -418.03894)
			(xy 416.308177 -418.054293) (xy 416.357756 -418.076933) (xy 416.403607 -418.106398) (xy 416.444799 -418.142089)
			(xy 416.480491 -418.183278) (xy 416.509958 -418.229129) (xy 416.5326 -418.278706) (xy 416.547956 -418.331001)
			(xy 416.555713 -418.384949) (xy 416.555713 -418.439451) (xy 416.555712 -418.439456) (xy 417.993223 -418.439456)
			(xy 417.993223 -418.384944) (xy 418.000981 -418.330986) (xy 418.01634 -418.278682) (xy 418.038986 -418.229097)
			(xy 418.068458 -418.183238) (xy 418.104157 -418.142042) (xy 418.145356 -418.106345) (xy 418.191216 -418.076875)
			(xy 418.240803 -418.054232) (xy 418.293108 -418.038877) (xy 418.347066 -418.031121) (xy 418.374322 -418.03066)
			(xy 419.237922 -418.03066) (xy 419.26517 -418.031212) (xy 419.319111 -418.03897) (xy 419.371398 -418.054326)
			(xy 419.420969 -418.076966) (xy 419.466812 -418.106431) (xy 419.507996 -418.142119) (xy 419.543683 -418.183305)
			(xy 419.573144 -418.229151) (xy 419.595782 -418.278722) (xy 419.611135 -418.331011) (xy 419.61889 -418.384952)
			(xy 419.61889 -418.439448) (xy 419.611135 -418.493389) (xy 419.595782 -418.545678) (xy 419.573144 -418.595249)
			(xy 419.543683 -418.641095) (xy 419.507996 -418.682281) (xy 419.466812 -418.717969) (xy 419.420969 -418.747434)
			(xy 419.371398 -418.770074) (xy 419.319111 -418.78543) (xy 419.26517 -418.793188) (xy 419.237922 -418.793676)
			(xy 418.374322 -418.793676) (xy 418.347066 -418.793279) (xy 418.293108 -418.785523) (xy 418.240803 -418.770168)
			(xy 418.191216 -418.747525) (xy 418.145356 -418.718055) (xy 418.104157 -418.682358) (xy 418.068458 -418.641162)
			(xy 418.038986 -418.595303) (xy 418.01634 -418.545718) (xy 418.000981 -418.493414) (xy 417.993223 -418.439456)
			(xy 416.555712 -418.439456) (xy 416.547956 -418.493399) (xy 416.5326 -418.545694) (xy 416.509958 -418.595271)
			(xy 416.480491 -418.641122) (xy 416.444799 -418.682311) (xy 416.403607 -418.718002) (xy 416.357756 -418.747467)
			(xy 416.308177 -418.770107) (xy 416.255882 -418.78546) (xy 416.201933 -418.793214) (xy 416.174682 -418.793676)
			(xy 415.311082 -418.793676) (xy 415.283829 -418.793253) (xy 415.229879 -418.785494) (xy 415.177582 -418.770136)
			(xy 415.128003 -418.747492) (xy 415.082151 -418.718022) (xy 415.040959 -418.682328) (xy 415.005267 -418.641135)
			(xy 414.9758 -418.595281) (xy 414.953158 -418.545701) (xy 414.937803 -418.493403) (xy 414.930046 -418.439453)
			(xy 413.492389 -418.439453) (xy 413.484635 -418.493386) (xy 413.469283 -418.545673) (xy 413.446647 -418.595244)
			(xy 413.417187 -418.641088) (xy 413.381503 -418.682274) (xy 413.340322 -418.717962) (xy 413.294481 -418.747427)
			(xy 413.244913 -418.770069) (xy 413.192628 -418.785426) (xy 413.138689 -418.793187) (xy 413.111442 -418.793676)
			(xy 412.247842 -418.793676) (xy 412.220585 -418.79328) (xy 412.166625 -418.785527) (xy 412.114317 -418.770173)
			(xy 412.064728 -418.747531) (xy 412.018866 -418.718062) (xy 411.977664 -418.682365) (xy 411.941963 -418.641168)
			(xy 411.912489 -418.595309) (xy 411.889841 -418.545722) (xy 411.874482 -418.493416) (xy 411.866723 -418.439457)
			(xy 410.429189 -418.439457) (xy 410.421434 -418.493392) (xy 410.40608 -418.545682) (xy 410.383441 -418.595255)
			(xy 410.353978 -418.641101) (xy 410.318289 -418.682288) (xy 410.277103 -418.717976) (xy 410.231257 -418.74744)
			(xy 410.181684 -418.77008) (xy 410.129394 -418.785434) (xy 410.075451 -418.79319) (xy 410.048202 -418.793676)
			(xy 409.184602 -418.793676) (xy 409.157347 -418.793277) (xy 409.103391 -418.78552) (xy 409.051088 -418.770163)
			(xy 409.001504 -418.747518) (xy 408.955647 -418.718048) (xy 408.91445 -418.682351) (xy 408.878753 -418.641155)
			(xy 408.849283 -418.595298) (xy 408.826638 -418.545713) (xy 408.811281 -418.493411) (xy 408.803523 -418.439455)
			(xy 407.366013 -418.439455) (xy 407.358255 -418.493402) (xy 407.342899 -418.545699) (xy 407.320255 -418.595277)
			(xy 407.290786 -418.641128) (xy 407.255091 -418.682318) (xy 407.213898 -418.718009) (xy 407.168044 -418.747474)
			(xy 407.118463 -418.770112) (xy 407.066165 -418.785463) (xy 407.012214 -418.793215) (xy 406.984962 -418.793676)
			(xy 406.121362 -418.793676) (xy 406.09411 -418.793252) (xy 406.040162 -418.78549) (xy 405.987868 -418.77013)
			(xy 405.938291 -418.747485) (xy 405.892441 -418.718015) (xy 405.851252 -418.682321) (xy 405.815562 -418.641128)
			(xy 405.786097 -418.595276) (xy 405.763456 -418.545697) (xy 405.748102 -418.493401) (xy 405.740346 -418.439452)
			(xy 404.302689 -418.439452) (xy 404.294935 -418.493389) (xy 404.279582 -418.545678) (xy 404.256944 -418.595249)
			(xy 404.227483 -418.641095) (xy 404.191796 -418.682281) (xy 404.150612 -418.717969) (xy 404.104769 -418.747434)
			(xy 404.055198 -418.770074) (xy 404.002911 -418.78543) (xy 403.94897 -418.793188) (xy 403.921722 -418.793676)
			(xy 403.058122 -418.793676) (xy 403.030866 -418.793279) (xy 402.976908 -418.785523) (xy 402.924603 -418.770168)
			(xy 402.875016 -418.747525) (xy 402.829156 -418.718055) (xy 402.787957 -418.682358) (xy 402.752258 -418.641162)
			(xy 402.722786 -418.595303) (xy 402.70014 -418.545718) (xy 402.684781 -418.493414) (xy 402.677023 -418.439456)
			(xy 401.239512 -418.439456) (xy 401.231756 -418.493399) (xy 401.2164 -418.545694) (xy 401.193758 -418.595271)
			(xy 401.164291 -418.641122) (xy 401.128599 -418.682311) (xy 401.087407 -418.718002) (xy 401.041556 -418.747467)
			(xy 400.991977 -418.770107) (xy 400.939682 -418.78546) (xy 400.885733 -418.793214) (xy 400.858482 -418.793676)
			(xy 399.994882 -418.793676) (xy 399.967629 -418.793253) (xy 399.913679 -418.785494) (xy 399.861382 -418.770136)
			(xy 399.811803 -418.747492) (xy 399.765951 -418.718022) (xy 399.724759 -418.682328) (xy 399.689067 -418.641135)
			(xy 399.6596 -418.595281) (xy 399.636958 -418.545701) (xy 399.621603 -418.493403) (xy 399.613846 -418.439453)
			(xy 398.176189 -418.439453) (xy 398.168435 -418.493386) (xy 398.153083 -418.545673) (xy 398.130447 -418.595244)
			(xy 398.100987 -418.641088) (xy 398.065303 -418.682274) (xy 398.024122 -418.717962) (xy 397.978281 -418.747427)
			(xy 397.928713 -418.770069) (xy 397.876428 -418.785426) (xy 397.822489 -418.793187) (xy 397.795242 -418.793676)
			(xy 396.931642 -418.793676) (xy 396.904385 -418.79328) (xy 396.850425 -418.785527) (xy 396.798117 -418.770173)
			(xy 396.748528 -418.747531) (xy 396.702666 -418.718062) (xy 396.661464 -418.682365) (xy 396.625763 -418.641168)
			(xy 396.596289 -418.595309) (xy 396.573641 -418.545722) (xy 396.558282 -418.493416) (xy 396.550523 -418.439457)
			(xy 395.112989 -418.439457) (xy 395.105234 -418.493392) (xy 395.08988 -418.545682) (xy 395.067241 -418.595255)
			(xy 395.037778 -418.641101) (xy 395.002089 -418.682288) (xy 394.960903 -418.717976) (xy 394.915057 -418.74744)
			(xy 394.865484 -418.77008) (xy 394.813194 -418.785434) (xy 394.759251 -418.79319) (xy 394.732002 -418.793676)
			(xy 393.868402 -418.793676) (xy 393.841147 -418.793277) (xy 393.787191 -418.78552) (xy 393.734888 -418.770163)
			(xy 393.685304 -418.747518) (xy 393.639447 -418.718048) (xy 393.59825 -418.682351) (xy 393.562553 -418.641155)
			(xy 393.533083 -418.595298) (xy 393.510438 -418.545713) (xy 393.495081 -418.493411) (xy 393.487323 -418.439455)
			(xy 392.049813 -418.439455) (xy 392.042055 -418.493402) (xy 392.026699 -418.545699) (xy 392.004055 -418.595277)
			(xy 391.974586 -418.641128) (xy 391.938891 -418.682318) (xy 391.897698 -418.718009) (xy 391.851844 -418.747474)
			(xy 391.802263 -418.770112) (xy 391.749965 -418.785463) (xy 391.696014 -418.793215) (xy 391.668762 -418.793676)
			(xy 390.805162 -418.793676) (xy 390.77791 -418.793252) (xy 390.723962 -418.78549) (xy 390.671668 -418.77013)
			(xy 390.622091 -418.747485) (xy 390.576241 -418.718015) (xy 390.535052 -418.682321) (xy 390.499362 -418.641128)
			(xy 390.469897 -418.595276) (xy 390.447256 -418.545697) (xy 390.431902 -418.493401) (xy 390.424146 -418.439452)
			(xy 388.986489 -418.439452) (xy 388.978735 -418.493389) (xy 388.963382 -418.545678) (xy 388.940744 -418.595249)
			(xy 388.911283 -418.641095) (xy 388.875596 -418.682281) (xy 388.834412 -418.717969) (xy 388.788569 -418.747434)
			(xy 388.738998 -418.770074) (xy 388.686711 -418.78543) (xy 388.63277 -418.793188) (xy 388.605522 -418.793676)
			(xy 387.741922 -418.793676) (xy 387.714666 -418.793279) (xy 387.660708 -418.785523) (xy 387.608403 -418.770168)
			(xy 387.558816 -418.747525) (xy 387.512956 -418.718055) (xy 387.471757 -418.682358) (xy 387.436058 -418.641162)
			(xy 387.406586 -418.595303) (xy 387.38394 -418.545718) (xy 387.368581 -418.493414) (xy 387.360823 -418.439456)
			(xy 385.923312 -418.439456) (xy 385.915556 -418.493399) (xy 385.9002 -418.545694) (xy 385.877558 -418.595271)
			(xy 385.848091 -418.641122) (xy 385.812399 -418.682311) (xy 385.771207 -418.718002) (xy 385.725356 -418.747467)
			(xy 385.675777 -418.770107) (xy 385.623482 -418.78546) (xy 385.569533 -418.793214) (xy 385.542282 -418.793676)
			(xy 384.678682 -418.793676) (xy 384.651429 -418.793253) (xy 384.597479 -418.785494) (xy 384.545182 -418.770136)
			(xy 384.495603 -418.747492) (xy 384.449751 -418.718022) (xy 384.408559 -418.682328) (xy 384.372867 -418.641135)
			(xy 384.3434 -418.595281) (xy 384.320758 -418.545701) (xy 384.305403 -418.493403) (xy 384.297646 -418.439453)
			(xy 382.859989 -418.439453) (xy 382.852235 -418.493386) (xy 382.836883 -418.545673) (xy 382.814247 -418.595244)
			(xy 382.784787 -418.641088) (xy 382.749103 -418.682274) (xy 382.707922 -418.717962) (xy 382.662081 -418.747427)
			(xy 382.612513 -418.770069) (xy 382.560228 -418.785426) (xy 382.506289 -418.793187) (xy 382.479042 -418.793676)
			(xy 381.615442 -418.793676) (xy 381.588185 -418.79328) (xy 381.534225 -418.785527) (xy 381.481917 -418.770173)
			(xy 381.432328 -418.747531) (xy 381.386466 -418.718062) (xy 381.345264 -418.682365) (xy 381.309563 -418.641168)
			(xy 381.280089 -418.595309) (xy 381.257441 -418.545722) (xy 381.242082 -418.493416) (xy 381.234323 -418.439457)
			(xy 379.796789 -418.439457) (xy 379.789034 -418.493392) (xy 379.77368 -418.545682) (xy 379.751041 -418.595255)
			(xy 379.721578 -418.641101) (xy 379.685889 -418.682288) (xy 379.644703 -418.717976) (xy 379.598857 -418.74744)
			(xy 379.549284 -418.77008) (xy 379.496994 -418.785434) (xy 379.443051 -418.79319) (xy 379.415802 -418.793676)
			(xy 378.552202 -418.793676) (xy 378.524947 -418.793277) (xy 378.470991 -418.78552) (xy 378.418688 -418.770163)
			(xy 378.369104 -418.747518) (xy 378.323247 -418.718048) (xy 378.28205 -418.682351) (xy 378.246353 -418.641155)
			(xy 378.216883 -418.595298) (xy 378.194238 -418.545713) (xy 378.178881 -418.493411) (xy 378.171123 -418.439455)
			(xy 376.733613 -418.439455) (xy 376.725855 -418.493402) (xy 376.710499 -418.545699) (xy 376.687855 -418.595277)
			(xy 376.658386 -418.641128) (xy 376.622691 -418.682318) (xy 376.581498 -418.718009) (xy 376.535644 -418.747474)
			(xy 376.486063 -418.770112) (xy 376.433765 -418.785463) (xy 376.379814 -418.793215) (xy 376.352562 -418.793676)
			(xy 375.488962 -418.793676) (xy 375.46171 -418.793252) (xy 375.407762 -418.78549) (xy 375.355468 -418.77013)
			(xy 375.305891 -418.747485) (xy 375.260041 -418.718015) (xy 375.218852 -418.682321) (xy 375.183162 -418.641128)
			(xy 375.153697 -418.595276) (xy 375.131056 -418.545697) (xy 375.115702 -418.493401) (xy 375.107946 -418.439452)
			(xy 373.670289 -418.439452) (xy 373.662535 -418.493389) (xy 373.647182 -418.545678) (xy 373.624544 -418.595249)
			(xy 373.595083 -418.641095) (xy 373.559396 -418.682281) (xy 373.518212 -418.717969) (xy 373.472369 -418.747434)
			(xy 373.422798 -418.770074) (xy 373.370511 -418.78543) (xy 373.31657 -418.793188) (xy 373.289322 -418.793676)
			(xy 372.425722 -418.793676) (xy 372.398466 -418.793279) (xy 372.344508 -418.785523) (xy 372.292203 -418.770168)
			(xy 372.242616 -418.747525) (xy 372.196756 -418.718055) (xy 372.155557 -418.682358) (xy 372.119858 -418.641162)
			(xy 372.090386 -418.595303) (xy 372.06774 -418.545718) (xy 372.052381 -418.493414) (xy 372.044623 -418.439456)
			(xy 370.313204 -418.439456) (xy 370.313204 -420.692072) (xy 370.313204 -420.739316) (xy 370.262404 -420.739316)
			(xy 370.16182 -420.739316) (xy 370.150438 -420.74117) (xy 370.131001 -420.753543) (xy 370.118864 -420.773128)
			(xy 370.117116 -420.784528) (xy 370.117116 -420.979455) (xy 370.513023 -420.979455) (xy 370.513023 -420.924945)
			(xy 370.520781 -420.870989) (xy 370.536138 -420.818687) (xy 370.558783 -420.769102) (xy 370.588253 -420.723245)
			(xy 370.62395 -420.682049) (xy 370.665147 -420.646352) (xy 370.711004 -420.616882) (xy 370.760588 -420.594237)
			(xy 370.812891 -420.57888) (xy 370.866847 -420.571123) (xy 370.894102 -420.57066) (xy 371.757702 -420.57066)
			(xy 371.784951 -420.57121) (xy 371.838894 -420.578966) (xy 371.891184 -420.59432) (xy 371.940757 -420.61696)
			(xy 371.986603 -420.646424) (xy 372.027789 -420.682112) (xy 372.063478 -420.723299) (xy 372.092941 -420.769145)
			(xy 372.11558 -420.818718) (xy 372.130934 -420.871008) (xy 372.13869 -420.924951) (xy 372.13869 -420.979449)
			(xy 372.138689 -420.979457) (xy 373.576223 -420.979457) (xy 373.576223 -420.924943) (xy 373.583982 -420.870984)
			(xy 373.599341 -420.818678) (xy 373.621989 -420.769091) (xy 373.651463 -420.723232) (xy 373.687164 -420.682035)
			(xy 373.728366 -420.646338) (xy 373.774228 -420.616869) (xy 373.823817 -420.594227) (xy 373.876125 -420.578873)
			(xy 373.930085 -420.57112) (xy 373.957342 -420.57066) (xy 374.820942 -420.57066) (xy 374.848189 -420.571213)
			(xy 374.902128 -420.578974) (xy 374.954413 -420.594331) (xy 375.003981 -420.616973) (xy 375.049822 -420.646438)
			(xy 375.091003 -420.682126) (xy 375.126687 -420.723312) (xy 375.156147 -420.769156) (xy 375.178783 -420.818727)
			(xy 375.194135 -420.871014) (xy 375.20189 -420.924953) (xy 375.20189 -420.979447) (xy 375.201889 -420.979453)
			(xy 376.639546 -420.979453) (xy 376.639546 -420.924947) (xy 376.647303 -420.870997) (xy 376.662658 -420.818699)
			(xy 376.6853 -420.769119) (xy 376.714767 -420.723265) (xy 376.750459 -420.682072) (xy 376.791651 -420.646378)
			(xy 376.837503 -420.616908) (xy 376.887082 -420.594264) (xy 376.939379 -420.578906) (xy 376.993329 -420.571147)
			(xy 377.020582 -420.57066) (xy 377.884182 -420.57066) (xy 377.911433 -420.571186) (xy 377.965382 -420.57894)
			(xy 378.017677 -420.594293) (xy 378.067256 -420.616933) (xy 378.113107 -420.646398) (xy 378.154299 -420.682089)
			(xy 378.189991 -420.723278) (xy 378.219458 -420.769129) (xy 378.2421 -420.818706) (xy 378.257456 -420.871001)
			(xy 378.265213 -420.924949) (xy 378.265213 -420.979451) (xy 378.265212 -420.979456) (xy 379.702723 -420.979456)
			(xy 379.702723 -420.924944) (xy 379.710481 -420.870986) (xy 379.72584 -420.818682) (xy 379.748486 -420.769097)
			(xy 379.777958 -420.723238) (xy 379.813657 -420.682042) (xy 379.854856 -420.646345) (xy 379.900716 -420.616875)
			(xy 379.950303 -420.594232) (xy 380.002608 -420.578877) (xy 380.056566 -420.571121) (xy 380.083822 -420.57066)
			(xy 380.947422 -420.57066) (xy 380.97467 -420.571212) (xy 381.028611 -420.57897) (xy 381.080898 -420.594326)
			(xy 381.130469 -420.616966) (xy 381.176312 -420.646431) (xy 381.217496 -420.682119) (xy 381.253183 -420.723305)
			(xy 381.282644 -420.769151) (xy 381.305282 -420.818722) (xy 381.320635 -420.871011) (xy 381.32839 -420.924952)
			(xy 381.32839 -420.979448) (xy 381.328389 -420.979452) (xy 382.766046 -420.979452) (xy 382.766046 -420.924948)
			(xy 382.773802 -420.870999) (xy 382.789156 -420.818703) (xy 382.811797 -420.769124) (xy 382.841262 -420.723272)
			(xy 382.876952 -420.682079) (xy 382.918141 -420.646385) (xy 382.963991 -420.616915) (xy 383.013568 -420.59427)
			(xy 383.065862 -420.57891) (xy 383.11981 -420.571148) (xy 383.147062 -420.57066) (xy 384.010662 -420.57066)
			(xy 384.037914 -420.571185) (xy 384.091865 -420.578937) (xy 384.144163 -420.594288) (xy 384.193744 -420.616926)
			(xy 384.239598 -420.646391) (xy 384.280791 -420.682082) (xy 384.316486 -420.723272) (xy 384.345955 -420.769123)
			(xy 384.368599 -420.818701) (xy 384.383955 -420.870998) (xy 384.391713 -420.924948) (xy 384.391713 -420.979452)
			(xy 384.391713 -420.979455) (xy 385.829223 -420.979455) (xy 385.829223 -420.924945) (xy 385.836981 -420.870989)
			(xy 385.852338 -420.818687) (xy 385.874983 -420.769102) (xy 385.904453 -420.723245) (xy 385.94015 -420.682049)
			(xy 385.981347 -420.646352) (xy 386.027204 -420.616882) (xy 386.076788 -420.594237) (xy 386.129091 -420.57888)
			(xy 386.183047 -420.571123) (xy 386.210302 -420.57066) (xy 387.073902 -420.57066) (xy 387.101151 -420.57121)
			(xy 387.155094 -420.578966) (xy 387.207384 -420.59432) (xy 387.256957 -420.61696) (xy 387.302803 -420.646424)
			(xy 387.343989 -420.682112) (xy 387.379678 -420.723299) (xy 387.409141 -420.769145) (xy 387.43178 -420.818718)
			(xy 387.447134 -420.871008) (xy 387.45489 -420.924951) (xy 387.45489 -420.979449) (xy 387.454889 -420.979457)
			(xy 388.892423 -420.979457) (xy 388.892423 -420.924943) (xy 388.900182 -420.870984) (xy 388.915541 -420.818678)
			(xy 388.938189 -420.769091) (xy 388.967663 -420.723232) (xy 389.003364 -420.682035) (xy 389.044566 -420.646338)
			(xy 389.090428 -420.616869) (xy 389.140017 -420.594227) (xy 389.192325 -420.578873) (xy 389.246285 -420.57112)
			(xy 389.273542 -420.57066) (xy 390.137142 -420.57066) (xy 390.164389 -420.571213) (xy 390.218328 -420.578974)
			(xy 390.270613 -420.594331) (xy 390.320181 -420.616973) (xy 390.366022 -420.646438) (xy 390.407203 -420.682126)
			(xy 390.442887 -420.723312) (xy 390.472347 -420.769156) (xy 390.494983 -420.818727) (xy 390.510335 -420.871014)
			(xy 390.51809 -420.924953) (xy 390.51809 -420.979447) (xy 390.518089 -420.979453) (xy 391.955746 -420.979453)
			(xy 391.955746 -420.924947) (xy 391.963503 -420.870997) (xy 391.978858 -420.818699) (xy 392.0015 -420.769119)
			(xy 392.030967 -420.723265) (xy 392.066659 -420.682072) (xy 392.107851 -420.646378) (xy 392.153703 -420.616908)
			(xy 392.203282 -420.594264) (xy 392.255579 -420.578906) (xy 392.309529 -420.571147) (xy 392.336782 -420.57066)
			(xy 393.200382 -420.57066) (xy 393.227633 -420.571186) (xy 393.281582 -420.57894) (xy 393.333877 -420.594293)
			(xy 393.383456 -420.616933) (xy 393.429307 -420.646398) (xy 393.470499 -420.682089) (xy 393.506191 -420.723278)
			(xy 393.535658 -420.769129) (xy 393.5583 -420.818706) (xy 393.573656 -420.871001) (xy 393.581413 -420.924949)
			(xy 393.581413 -420.979451) (xy 393.581412 -420.979456) (xy 395.018923 -420.979456) (xy 395.018923 -420.924944)
			(xy 395.026681 -420.870986) (xy 395.04204 -420.818682) (xy 395.064686 -420.769097) (xy 395.094158 -420.723238)
			(xy 395.129857 -420.682042) (xy 395.171056 -420.646345) (xy 395.216916 -420.616875) (xy 395.266503 -420.594232)
			(xy 395.318808 -420.578877) (xy 395.372766 -420.571121) (xy 395.400022 -420.57066) (xy 396.263622 -420.57066)
			(xy 396.29087 -420.571212) (xy 396.344811 -420.57897) (xy 396.397098 -420.594326) (xy 396.446669 -420.616966)
			(xy 396.492512 -420.646431) (xy 396.533696 -420.682119) (xy 396.569383 -420.723305) (xy 396.598844 -420.769151)
			(xy 396.621482 -420.818722) (xy 396.636835 -420.871011) (xy 396.64459 -420.924952) (xy 396.64459 -420.979448)
			(xy 396.644589 -420.979452) (xy 398.082246 -420.979452) (xy 398.082246 -420.924948) (xy 398.090002 -420.870999)
			(xy 398.105356 -420.818703) (xy 398.127997 -420.769124) (xy 398.157462 -420.723272) (xy 398.193152 -420.682079)
			(xy 398.234341 -420.646385) (xy 398.280191 -420.616915) (xy 398.329768 -420.59427) (xy 398.382062 -420.57891)
			(xy 398.43601 -420.571148) (xy 398.463262 -420.57066) (xy 399.326862 -420.57066) (xy 399.354114 -420.571185)
			(xy 399.408065 -420.578937) (xy 399.460363 -420.594288) (xy 399.509944 -420.616926) (xy 399.555798 -420.646391)
			(xy 399.596991 -420.682082) (xy 399.632686 -420.723272) (xy 399.662155 -420.769123) (xy 399.684799 -420.818701)
			(xy 399.700155 -420.870998) (xy 399.707913 -420.924948) (xy 399.707913 -420.979452) (xy 399.707913 -420.979455)
			(xy 401.145423 -420.979455) (xy 401.145423 -420.924945) (xy 401.153181 -420.870989) (xy 401.168538 -420.818687)
			(xy 401.191183 -420.769102) (xy 401.220653 -420.723245) (xy 401.25635 -420.682049) (xy 401.297547 -420.646352)
			(xy 401.343404 -420.616882) (xy 401.392988 -420.594237) (xy 401.445291 -420.57888) (xy 401.499247 -420.571123)
			(xy 401.526502 -420.57066) (xy 402.390102 -420.57066) (xy 402.417351 -420.57121) (xy 402.471294 -420.578966)
			(xy 402.523584 -420.59432) (xy 402.573157 -420.61696) (xy 402.619003 -420.646424) (xy 402.660189 -420.682112)
			(xy 402.695878 -420.723299) (xy 402.725341 -420.769145) (xy 402.74798 -420.818718) (xy 402.763334 -420.871008)
			(xy 402.77109 -420.924951) (xy 402.77109 -420.979449) (xy 402.771089 -420.979457) (xy 404.208623 -420.979457)
			(xy 404.208623 -420.924943) (xy 404.216382 -420.870984) (xy 404.231741 -420.818678) (xy 404.254389 -420.769091)
			(xy 404.283863 -420.723232) (xy 404.319564 -420.682035) (xy 404.360766 -420.646338) (xy 404.406628 -420.616869)
			(xy 404.456217 -420.594227) (xy 404.508525 -420.578873) (xy 404.562485 -420.57112) (xy 404.589742 -420.57066)
			(xy 405.453342 -420.57066) (xy 405.480589 -420.571213) (xy 405.534528 -420.578974) (xy 405.586813 -420.594331)
			(xy 405.636381 -420.616973) (xy 405.682222 -420.646438) (xy 405.723403 -420.682126) (xy 405.759087 -420.723312)
			(xy 405.788547 -420.769156) (xy 405.811183 -420.818727) (xy 405.826535 -420.871014) (xy 405.83429 -420.924953)
			(xy 405.83429 -420.979447) (xy 405.834289 -420.979453) (xy 407.271946 -420.979453) (xy 407.271946 -420.924947)
			(xy 407.279703 -420.870997) (xy 407.295058 -420.818699) (xy 407.3177 -420.769119) (xy 407.347167 -420.723265)
			(xy 407.382859 -420.682072) (xy 407.424051 -420.646378) (xy 407.469903 -420.616908) (xy 407.519482 -420.594264)
			(xy 407.571779 -420.578906) (xy 407.625729 -420.571147) (xy 407.652982 -420.57066) (xy 408.516582 -420.57066)
			(xy 408.543833 -420.571186) (xy 408.597782 -420.57894) (xy 408.650077 -420.594293) (xy 408.699656 -420.616933)
			(xy 408.745507 -420.646398) (xy 408.786699 -420.682089) (xy 408.822391 -420.723278) (xy 408.851858 -420.769129)
			(xy 408.8745 -420.818706) (xy 408.889856 -420.871001) (xy 408.897613 -420.924949) (xy 408.897613 -420.979451)
			(xy 408.897612 -420.979456) (xy 410.335123 -420.979456) (xy 410.335123 -420.924944) (xy 410.342881 -420.870986)
			(xy 410.35824 -420.818682) (xy 410.380886 -420.769097) (xy 410.410358 -420.723238) (xy 410.446057 -420.682042)
			(xy 410.487256 -420.646345) (xy 410.533116 -420.616875) (xy 410.582703 -420.594232) (xy 410.635008 -420.578877)
			(xy 410.688966 -420.571121) (xy 410.716222 -420.57066) (xy 411.579822 -420.57066) (xy 411.60707 -420.571212)
			(xy 411.661011 -420.57897) (xy 411.713298 -420.594326) (xy 411.762869 -420.616966) (xy 411.808712 -420.646431)
			(xy 411.849896 -420.682119) (xy 411.885583 -420.723305) (xy 411.915044 -420.769151) (xy 411.937682 -420.818722)
			(xy 411.953035 -420.871011) (xy 411.96079 -420.924952) (xy 411.96079 -420.979448) (xy 411.960789 -420.979452)
			(xy 413.398446 -420.979452) (xy 413.398446 -420.924948) (xy 413.406202 -420.870999) (xy 413.421556 -420.818703)
			(xy 413.444197 -420.769124) (xy 413.473662 -420.723272) (xy 413.509352 -420.682079) (xy 413.550541 -420.646385)
			(xy 413.596391 -420.616915) (xy 413.645968 -420.59427) (xy 413.698262 -420.57891) (xy 413.75221 -420.571148)
			(xy 413.779462 -420.57066) (xy 414.643062 -420.57066) (xy 414.670314 -420.571185) (xy 414.724265 -420.578937)
			(xy 414.776563 -420.594288) (xy 414.826144 -420.616926) (xy 414.871998 -420.646391) (xy 414.913191 -420.682082)
			(xy 414.948886 -420.723272) (xy 414.978355 -420.769123) (xy 415.000999 -420.818701) (xy 415.016355 -420.870998)
			(xy 415.024113 -420.924948) (xy 415.024113 -420.979452) (xy 415.024113 -420.979455) (xy 416.461623 -420.979455)
			(xy 416.461623 -420.924945) (xy 416.469381 -420.870989) (xy 416.484738 -420.818687) (xy 416.507383 -420.769102)
			(xy 416.536853 -420.723245) (xy 416.57255 -420.682049) (xy 416.613747 -420.646352) (xy 416.659604 -420.616882)
			(xy 416.709188 -420.594237) (xy 416.761491 -420.57888) (xy 416.815447 -420.571123) (xy 416.842702 -420.57066)
			(xy 417.706302 -420.57066) (xy 417.733551 -420.57121) (xy 417.787494 -420.578966) (xy 417.839784 -420.59432)
			(xy 417.889357 -420.61696) (xy 417.935203 -420.646424) (xy 417.976389 -420.682112) (xy 418.012078 -420.723299)
			(xy 418.041541 -420.769145) (xy 418.06418 -420.818718) (xy 418.079534 -420.871008) (xy 418.08729 -420.924951)
			(xy 418.08729 -420.979449) (xy 418.079534 -421.033392) (xy 418.06418 -421.085682) (xy 418.041541 -421.135255)
			(xy 418.012078 -421.181101) (xy 417.976389 -421.222288) (xy 417.935203 -421.257976) (xy 417.889357 -421.28744)
			(xy 417.839784 -421.31008) (xy 417.787494 -421.325434) (xy 417.733551 -421.33319) (xy 417.706302 -421.333676)
			(xy 416.842702 -421.333676) (xy 416.815447 -421.333277) (xy 416.761491 -421.32552) (xy 416.709188 -421.310163)
			(xy 416.659604 -421.287518) (xy 416.613747 -421.258048) (xy 416.57255 -421.222351) (xy 416.536853 -421.181155)
			(xy 416.507383 -421.135298) (xy 416.484738 -421.085713) (xy 416.469381 -421.033411) (xy 416.461623 -420.979455)
			(xy 415.024113 -420.979455) (xy 415.016355 -421.033402) (xy 415.000999 -421.085699) (xy 414.978355 -421.135277)
			(xy 414.948886 -421.181128) (xy 414.913191 -421.222318) (xy 414.871998 -421.258009) (xy 414.826144 -421.287474)
			(xy 414.776563 -421.310112) (xy 414.724265 -421.325463) (xy 414.670314 -421.333215) (xy 414.643062 -421.333676)
			(xy 413.779462 -421.333676) (xy 413.75221 -421.333252) (xy 413.698262 -421.32549) (xy 413.645968 -421.31013)
			(xy 413.596391 -421.287485) (xy 413.550541 -421.258015) (xy 413.509352 -421.222321) (xy 413.473662 -421.181128)
			(xy 413.444197 -421.135276) (xy 413.421556 -421.085697) (xy 413.406202 -421.033401) (xy 413.398446 -420.979452)
			(xy 411.960789 -420.979452) (xy 411.953035 -421.033389) (xy 411.937682 -421.085678) (xy 411.915044 -421.135249)
			(xy 411.885583 -421.181095) (xy 411.849896 -421.222281) (xy 411.808712 -421.257969) (xy 411.762869 -421.287434)
			(xy 411.713298 -421.310074) (xy 411.661011 -421.32543) (xy 411.60707 -421.333188) (xy 411.579822 -421.333676)
			(xy 410.716222 -421.333676) (xy 410.688966 -421.333279) (xy 410.635008 -421.325523) (xy 410.582703 -421.310168)
			(xy 410.533116 -421.287525) (xy 410.487256 -421.258055) (xy 410.446057 -421.222358) (xy 410.410358 -421.181162)
			(xy 410.380886 -421.135303) (xy 410.35824 -421.085718) (xy 410.342881 -421.033414) (xy 410.335123 -420.979456)
			(xy 408.897612 -420.979456) (xy 408.889856 -421.033399) (xy 408.8745 -421.085694) (xy 408.851858 -421.135271)
			(xy 408.822391 -421.181122) (xy 408.786699 -421.222311) (xy 408.745507 -421.258002) (xy 408.699656 -421.287467)
			(xy 408.650077 -421.310107) (xy 408.597782 -421.32546) (xy 408.543833 -421.333214) (xy 408.516582 -421.333676)
			(xy 407.652982 -421.333676) (xy 407.625729 -421.333253) (xy 407.571779 -421.325494) (xy 407.519482 -421.310136)
			(xy 407.469903 -421.287492) (xy 407.424051 -421.258022) (xy 407.382859 -421.222328) (xy 407.347167 -421.181135)
			(xy 407.3177 -421.135281) (xy 407.295058 -421.085701) (xy 407.279703 -421.033403) (xy 407.271946 -420.979453)
			(xy 405.834289 -420.979453) (xy 405.826535 -421.033386) (xy 405.811183 -421.085673) (xy 405.788547 -421.135244)
			(xy 405.759087 -421.181088) (xy 405.723403 -421.222274) (xy 405.682222 -421.257962) (xy 405.636381 -421.287427)
			(xy 405.586813 -421.310069) (xy 405.534528 -421.325426) (xy 405.480589 -421.333187) (xy 405.453342 -421.333676)
			(xy 404.589742 -421.333676) (xy 404.562485 -421.33328) (xy 404.508525 -421.325527) (xy 404.456217 -421.310173)
			(xy 404.406628 -421.287531) (xy 404.360766 -421.258062) (xy 404.319564 -421.222365) (xy 404.283863 -421.181168)
			(xy 404.254389 -421.135309) (xy 404.231741 -421.085722) (xy 404.216382 -421.033416) (xy 404.208623 -420.979457)
			(xy 402.771089 -420.979457) (xy 402.763334 -421.033392) (xy 402.74798 -421.085682) (xy 402.725341 -421.135255)
			(xy 402.695878 -421.181101) (xy 402.660189 -421.222288) (xy 402.619003 -421.257976) (xy 402.573157 -421.28744)
			(xy 402.523584 -421.31008) (xy 402.471294 -421.325434) (xy 402.417351 -421.33319) (xy 402.390102 -421.333676)
			(xy 401.526502 -421.333676) (xy 401.499247 -421.333277) (xy 401.445291 -421.32552) (xy 401.392988 -421.310163)
			(xy 401.343404 -421.287518) (xy 401.297547 -421.258048) (xy 401.25635 -421.222351) (xy 401.220653 -421.181155)
			(xy 401.191183 -421.135298) (xy 401.168538 -421.085713) (xy 401.153181 -421.033411) (xy 401.145423 -420.979455)
			(xy 399.707913 -420.979455) (xy 399.700155 -421.033402) (xy 399.684799 -421.085699) (xy 399.662155 -421.135277)
			(xy 399.632686 -421.181128) (xy 399.596991 -421.222318) (xy 399.555798 -421.258009) (xy 399.509944 -421.287474)
			(xy 399.460363 -421.310112) (xy 399.408065 -421.325463) (xy 399.354114 -421.333215) (xy 399.326862 -421.333676)
			(xy 398.463262 -421.333676) (xy 398.43601 -421.333252) (xy 398.382062 -421.32549) (xy 398.329768 -421.31013)
			(xy 398.280191 -421.287485) (xy 398.234341 -421.258015) (xy 398.193152 -421.222321) (xy 398.157462 -421.181128)
			(xy 398.127997 -421.135276) (xy 398.105356 -421.085697) (xy 398.090002 -421.033401) (xy 398.082246 -420.979452)
			(xy 396.644589 -420.979452) (xy 396.636835 -421.033389) (xy 396.621482 -421.085678) (xy 396.598844 -421.135249)
			(xy 396.569383 -421.181095) (xy 396.533696 -421.222281) (xy 396.492512 -421.257969) (xy 396.446669 -421.287434)
			(xy 396.397098 -421.310074) (xy 396.344811 -421.32543) (xy 396.29087 -421.333188) (xy 396.263622 -421.333676)
			(xy 395.400022 -421.333676) (xy 395.372766 -421.333279) (xy 395.318808 -421.325523) (xy 395.266503 -421.310168)
			(xy 395.216916 -421.287525) (xy 395.171056 -421.258055) (xy 395.129857 -421.222358) (xy 395.094158 -421.181162)
			(xy 395.064686 -421.135303) (xy 395.04204 -421.085718) (xy 395.026681 -421.033414) (xy 395.018923 -420.979456)
			(xy 393.581412 -420.979456) (xy 393.573656 -421.033399) (xy 393.5583 -421.085694) (xy 393.535658 -421.135271)
			(xy 393.506191 -421.181122) (xy 393.470499 -421.222311) (xy 393.429307 -421.258002) (xy 393.383456 -421.287467)
			(xy 393.333877 -421.310107) (xy 393.281582 -421.32546) (xy 393.227633 -421.333214) (xy 393.200382 -421.333676)
			(xy 392.336782 -421.333676) (xy 392.309529 -421.333253) (xy 392.255579 -421.325494) (xy 392.203282 -421.310136)
			(xy 392.153703 -421.287492) (xy 392.107851 -421.258022) (xy 392.066659 -421.222328) (xy 392.030967 -421.181135)
			(xy 392.0015 -421.135281) (xy 391.978858 -421.085701) (xy 391.963503 -421.033403) (xy 391.955746 -420.979453)
			(xy 390.518089 -420.979453) (xy 390.510335 -421.033386) (xy 390.494983 -421.085673) (xy 390.472347 -421.135244)
			(xy 390.442887 -421.181088) (xy 390.407203 -421.222274) (xy 390.366022 -421.257962) (xy 390.320181 -421.287427)
			(xy 390.270613 -421.310069) (xy 390.218328 -421.325426) (xy 390.164389 -421.333187) (xy 390.137142 -421.333676)
			(xy 389.273542 -421.333676) (xy 389.246285 -421.33328) (xy 389.192325 -421.325527) (xy 389.140017 -421.310173)
			(xy 389.090428 -421.287531) (xy 389.044566 -421.258062) (xy 389.003364 -421.222365) (xy 388.967663 -421.181168)
			(xy 388.938189 -421.135309) (xy 388.915541 -421.085722) (xy 388.900182 -421.033416) (xy 388.892423 -420.979457)
			(xy 387.454889 -420.979457) (xy 387.447134 -421.033392) (xy 387.43178 -421.085682) (xy 387.409141 -421.135255)
			(xy 387.379678 -421.181101) (xy 387.343989 -421.222288) (xy 387.302803 -421.257976) (xy 387.256957 -421.28744)
			(xy 387.207384 -421.31008) (xy 387.155094 -421.325434) (xy 387.101151 -421.33319) (xy 387.073902 -421.333676)
			(xy 386.210302 -421.333676) (xy 386.183047 -421.333277) (xy 386.129091 -421.32552) (xy 386.076788 -421.310163)
			(xy 386.027204 -421.287518) (xy 385.981347 -421.258048) (xy 385.94015 -421.222351) (xy 385.904453 -421.181155)
			(xy 385.874983 -421.135298) (xy 385.852338 -421.085713) (xy 385.836981 -421.033411) (xy 385.829223 -420.979455)
			(xy 384.391713 -420.979455) (xy 384.383955 -421.033402) (xy 384.368599 -421.085699) (xy 384.345955 -421.135277)
			(xy 384.316486 -421.181128) (xy 384.280791 -421.222318) (xy 384.239598 -421.258009) (xy 384.193744 -421.287474)
			(xy 384.144163 -421.310112) (xy 384.091865 -421.325463) (xy 384.037914 -421.333215) (xy 384.010662 -421.333676)
			(xy 383.147062 -421.333676) (xy 383.11981 -421.333252) (xy 383.065862 -421.32549) (xy 383.013568 -421.31013)
			(xy 382.963991 -421.287485) (xy 382.918141 -421.258015) (xy 382.876952 -421.222321) (xy 382.841262 -421.181128)
			(xy 382.811797 -421.135276) (xy 382.789156 -421.085697) (xy 382.773802 -421.033401) (xy 382.766046 -420.979452)
			(xy 381.328389 -420.979452) (xy 381.320635 -421.033389) (xy 381.305282 -421.085678) (xy 381.282644 -421.135249)
			(xy 381.253183 -421.181095) (xy 381.217496 -421.222281) (xy 381.176312 -421.257969) (xy 381.130469 -421.287434)
			(xy 381.080898 -421.310074) (xy 381.028611 -421.32543) (xy 380.97467 -421.333188) (xy 380.947422 -421.333676)
			(xy 380.083822 -421.333676) (xy 380.056566 -421.333279) (xy 380.002608 -421.325523) (xy 379.950303 -421.310168)
			(xy 379.900716 -421.287525) (xy 379.854856 -421.258055) (xy 379.813657 -421.222358) (xy 379.777958 -421.181162)
			(xy 379.748486 -421.135303) (xy 379.72584 -421.085718) (xy 379.710481 -421.033414) (xy 379.702723 -420.979456)
			(xy 378.265212 -420.979456) (xy 378.257456 -421.033399) (xy 378.2421 -421.085694) (xy 378.219458 -421.135271)
			(xy 378.189991 -421.181122) (xy 378.154299 -421.222311) (xy 378.113107 -421.258002) (xy 378.067256 -421.287467)
			(xy 378.017677 -421.310107) (xy 377.965382 -421.32546) (xy 377.911433 -421.333214) (xy 377.884182 -421.333676)
			(xy 377.020582 -421.333676) (xy 376.993329 -421.333253) (xy 376.939379 -421.325494) (xy 376.887082 -421.310136)
			(xy 376.837503 -421.287492) (xy 376.791651 -421.258022) (xy 376.750459 -421.222328) (xy 376.714767 -421.181135)
			(xy 376.6853 -421.135281) (xy 376.662658 -421.085701) (xy 376.647303 -421.033403) (xy 376.639546 -420.979453)
			(xy 375.201889 -420.979453) (xy 375.194135 -421.033386) (xy 375.178783 -421.085673) (xy 375.156147 -421.135244)
			(xy 375.126687 -421.181088) (xy 375.091003 -421.222274) (xy 375.049822 -421.257962) (xy 375.003981 -421.287427)
			(xy 374.954413 -421.310069) (xy 374.902128 -421.325426) (xy 374.848189 -421.333187) (xy 374.820942 -421.333676)
			(xy 373.957342 -421.333676) (xy 373.930085 -421.33328) (xy 373.876125 -421.325527) (xy 373.823817 -421.310173)
			(xy 373.774228 -421.287531) (xy 373.728366 -421.258062) (xy 373.687164 -421.222365) (xy 373.651463 -421.181168)
			(xy 373.621989 -421.135309) (xy 373.599341 -421.085722) (xy 373.583982 -421.033416) (xy 373.576223 -420.979457)
			(xy 372.138689 -420.979457) (xy 372.130934 -421.033392) (xy 372.11558 -421.085682) (xy 372.092941 -421.135255)
			(xy 372.063478 -421.181101) (xy 372.027789 -421.222288) (xy 371.986603 -421.257976) (xy 371.940757 -421.28744)
			(xy 371.891184 -421.31008) (xy 371.838894 -421.325434) (xy 371.784951 -421.33319) (xy 371.757702 -421.333676)
			(xy 370.894102 -421.333676) (xy 370.866847 -421.333277) (xy 370.812891 -421.32552) (xy 370.760588 -421.310163)
			(xy 370.711004 -421.287518) (xy 370.665147 -421.258048) (xy 370.62395 -421.222351) (xy 370.588253 -421.181155)
			(xy 370.558783 -421.135298) (xy 370.536138 -421.085713) (xy 370.520781 -421.033411) (xy 370.513023 -420.979455)
			(xy 370.117116 -420.979455) (xy 370.117116 -421.134032) (xy 370.118827 -421.145443) (xy 370.130963 -421.165042)
			(xy 370.150431 -421.17739) (xy 370.16182 -421.179244) (xy 370.26596 -421.179244) (xy 370.313204 -421.179244)
			(xy 370.313204 -421.230044) (xy 370.313204 -422.692576) (xy 370.312768 -422.702798) (xy 370.30495 -422.721687)
			(xy 370.290497 -422.736144) (xy 370.27161 -422.743966) (xy 370.261388 -422.744392) (xy 365.362744 -422.744392)
			(xy 365.352522 -422.743952) (xy 365.333631 -422.736138) (xy 365.319173 -422.721686) (xy 365.311352 -422.702798)
			(xy 365.310928 -422.692576) (xy 360.222212 -422.692576) (xy 360.286426 -422.706639) (xy 360.410636 -422.74198)
			(xy 360.532435 -422.7849) (xy 360.65136 -422.835237) (xy 360.766961 -422.892799) (xy 360.8788 -422.957369)
			(xy 360.986451 -423.028701) (xy 361.089506 -423.106525) (xy 361.187576 -423.190546) (xy 361.280287 -423.280445)
			(xy 361.367287 -423.37588) (xy 361.448248 -423.47649) (xy 361.505055 -423.556738) (xy 456.285335 -423.556738)
			(xy 456.285335 -423.427598) (xy 456.293285 -423.298703) (xy 456.309155 -423.170543) (xy 456.332884 -423.043602)
			(xy 456.364383 -422.918363) (xy 456.403532 -422.7953) (xy 456.450183 -422.674881) (xy 456.504158 -422.557562)
			(xy 456.565253 -422.443788) (xy 456.633236 -422.333991) (xy 456.70785 -422.228588) (xy 456.788811 -422.127978)
			(xy 456.875811 -422.032543) (xy 456.968522 -421.942644) (xy 457.066592 -421.858623) (xy 457.169647 -421.780799)
			(xy 457.277298 -421.709467) (xy 457.389137 -421.644897) (xy 457.504738 -421.587335) (xy 457.623663 -421.536998)
			(xy 457.745462 -421.494078) (xy 457.869672 -421.458737) (xy 457.995821 -421.43111) (xy 458.123433 -421.411301)
			(xy 458.252022 -421.399385) (xy 458.3811 -421.395409) (xy 458.510178 -421.399385) (xy 458.638767 -421.411301)
			(xy 458.766379 -421.43111) (xy 458.892528 -421.458737) (xy 459.016738 -421.494078) (xy 459.138537 -421.536998)
			(xy 459.257462 -421.587335) (xy 459.373063 -421.644897) (xy 459.484902 -421.709467) (xy 459.592553 -421.780799)
			(xy 459.695608 -421.858623) (xy 459.793678 -421.942644) (xy 459.886389 -422.032543) (xy 459.973389 -422.127978)
			(xy 460.05435 -422.228588) (xy 460.128964 -422.333991) (xy 460.196947 -422.443788) (xy 460.258042 -422.557562)
			(xy 460.312017 -422.674881) (xy 460.358668 -422.7953) (xy 460.397817 -422.918363) (xy 460.429316 -423.043602)
			(xy 460.453045 -423.170543) (xy 460.468915 -423.298703) (xy 460.476865 -423.427598) (xy 460.477362 -423.492168)
			(xy 460.476865 -423.556738) (xy 460.468915 -423.685633) (xy 460.453045 -423.813793) (xy 460.429316 -423.940734)
			(xy 460.397817 -424.065973) (xy 460.358668 -424.189036) (xy 460.312017 -424.309455) (xy 460.258042 -424.426774)
			(xy 460.196947 -424.540548) (xy 460.128964 -424.650345) (xy 460.05435 -424.755748) (xy 459.973389 -424.856358)
			(xy 459.886389 -424.951793) (xy 459.793678 -425.041692) (xy 459.695608 -425.125713) (xy 459.592553 -425.203537)
			(xy 459.484902 -425.274869) (xy 459.373063 -425.339439) (xy 459.257462 -425.397001) (xy 459.138537 -425.447338)
			(xy 459.016738 -425.490258) (xy 458.892528 -425.525599) (xy 458.766379 -425.553226) (xy 458.638767 -425.573035)
			(xy 458.510178 -425.584951) (xy 458.3811 -425.588928) (xy 458.252022 -425.584951) (xy 458.123433 -425.573035)
			(xy 457.995821 -425.553226) (xy 457.869672 -425.525599) (xy 457.745462 -425.490258) (xy 457.623663 -425.447338)
			(xy 457.504738 -425.397001) (xy 457.389137 -425.339439) (xy 457.277298 -425.274869) (xy 457.169647 -425.203537)
			(xy 457.066592 -425.125713) (xy 456.968522 -425.041692) (xy 456.875811 -424.951793) (xy 456.788811 -424.856358)
			(xy 456.70785 -424.755748) (xy 456.633236 -424.650345) (xy 456.565253 -424.540548) (xy 456.504158 -424.426774)
			(xy 456.450183 -424.309455) (xy 456.403532 -424.189036) (xy 456.364383 -424.065973) (xy 456.332884 -423.940734)
			(xy 456.309155 -423.813793) (xy 456.293285 -423.685633) (xy 456.285335 -423.556738) (xy 361.505055 -423.556738)
			(xy 361.522862 -423.581893) (xy 361.590845 -423.69169) (xy 361.65194 -423.805464) (xy 361.705915 -423.922783)
			(xy 361.752566 -424.043202) (xy 361.791715 -424.166265) (xy 361.823214 -424.291504) (xy 361.846943 -424.418445)
			(xy 361.862813 -424.546605) (xy 361.870763 -424.6755) (xy 361.87126 -424.74007) (xy 361.870763 -424.80464)
			(xy 361.862813 -424.933535) (xy 361.846943 -425.061695) (xy 361.823214 -425.188636) (xy 361.791715 -425.313875)
			(xy 361.752566 -425.436938) (xy 361.705915 -425.557357) (xy 361.65194 -425.674676) (xy 361.590845 -425.78845)
			(xy 361.522862 -425.898247) (xy 361.448248 -426.00365) (xy 361.367287 -426.10426) (xy 361.280287 -426.199695)
			(xy 361.187576 -426.289594) (xy 361.089506 -426.373615) (xy 360.986451 -426.451439) (xy 360.8788 -426.522771)
			(xy 360.766961 -426.587341) (xy 360.65136 -426.644903) (xy 360.532435 -426.69524) (xy 360.410636 -426.73816)
			(xy 360.286426 -426.773501) (xy 360.160277 -426.801128) (xy 360.032665 -426.820937) (xy 359.904076 -426.832853)
			(xy 359.774998 -426.83683) (xy 359.64592 -426.832853) (xy 359.517331 -426.820937) (xy 359.389719 -426.801128)
			(xy 359.26357 -426.773501) (xy 359.13936 -426.73816) (xy 359.017561 -426.69524) (xy 358.898636 -426.644903)
			(xy 358.783035 -426.587341) (xy 358.671196 -426.522771) (xy 358.563545 -426.451439) (xy 358.46049 -426.373615)
			(xy 358.36242 -426.289594) (xy 358.269709 -426.199695) (xy 358.182709 -426.10426) (xy 358.101748 -426.00365)
			(xy 358.027134 -425.898247) (xy 357.959151 -425.78845) (xy 357.898056 -425.674676) (xy 357.844081 -425.557357)
			(xy 357.79743 -425.436938) (xy 357.758281 -425.313875) (xy 357.726782 -425.188636) (xy 357.703053 -425.061695)
			(xy 357.687183 -424.933535) (xy 357.679233 -424.80464) (xy 230.3145 -424.80464) (xy 230.3145 -427.960536)
			(xy 314.141104 -427.960536) (xy 314.141104 -425.419012) (xy 314.141527 -425.406903) (xy 314.149023 -425.383876)
			(xy 314.163283 -425.364302) (xy 314.182904 -425.350107) (xy 314.205956 -425.342687) (xy 314.218066 -425.342304)
			(xy 315.157866 -425.342304) (xy 315.16995 -425.342836) (xy 315.192944 -425.350279) (xy 315.212521 -425.36445)
			(xy 315.226774 -425.383968) (xy 315.234313 -425.40693) (xy 315.234828 -425.419012) (xy 315.234828 -427.960536)
			(xy 315.234415 -427.972644) (xy 315.226909 -427.995668) (xy 315.212645 -428.015238) (xy 315.193025 -428.029432)
			(xy 315.169975 -428.036857) (xy 315.157866 -428.037244) (xy 314.218066 -428.037244) (xy 314.205973 -428.036821)
			(xy 314.182969 -428.029353) (xy 314.163388 -428.015156) (xy 314.149139 -427.995612) (xy 314.141611 -427.972628)
			(xy 314.141104 -427.960536) (xy 230.3145 -427.960536) (xy 230.3145 -433.130695) (xy 266.885917 -433.130695)
			(xy 266.885917 -432.953425) (xy 266.89387 -432.776334) (xy 266.909761 -432.599778) (xy 266.933556 -432.424113)
			(xy 266.965209 -432.249692) (xy 267.004655 -432.076867) (xy 267.051815 -431.905986) (xy 267.106594 -431.737392)
			(xy 267.168882 -431.571427) (xy 267.238554 -431.408422) (xy 267.315468 -431.248708) (xy 267.399471 -431.092605)
			(xy 267.490392 -430.940428) (xy 267.588049 -430.792484) (xy 267.692246 -430.64907) (xy 267.802772 -430.510475)
			(xy 267.919404 -430.376978) (xy 268.041909 -430.248849) (xy 268.170038 -430.126344) (xy 268.303535 -430.009712)
			(xy 268.44213 -429.899186) (xy 268.585544 -429.794989) (xy 268.733488 -429.697332) (xy 268.885665 -429.606411)
			(xy 269.041768 -429.522408) (xy 269.201482 -429.445494) (xy 269.364487 -429.375822) (xy 269.530452 -429.313534)
			(xy 269.699046 -429.258755) (xy 269.869927 -429.211595) (xy 270.042752 -429.172149) (xy 270.217173 -429.140496)
			(xy 270.392838 -429.116701) (xy 270.569394 -429.10081) (xy 270.746485 -429.092857) (xy 270.923755 -429.092857)
			(xy 271.100846 -429.10081) (xy 271.277402 -429.116701) (xy 271.453067 -429.140496) (xy 271.627488 -429.172149)
			(xy 271.800313 -429.211595) (xy 271.971194 -429.258755) (xy 272.139788 -429.313534) (xy 272.305753 -429.375822)
			(xy 272.468758 -429.445494) (xy 272.628472 -429.522408) (xy 272.784575 -429.606411) (xy 272.936752 -429.697332)
			(xy 273.084696 -429.794989) (xy 273.22811 -429.899186) (xy 273.366705 -430.009712) (xy 273.500202 -430.126344)
			(xy 273.628331 -430.248849) (xy 273.750836 -430.376978) (xy 273.867468 -430.510475) (xy 273.977994 -430.64907)
			(xy 274.082191 -430.792484) (xy 274.179848 -430.940428) (xy 274.270769 -431.092605) (xy 274.354772 -431.248708)
			(xy 274.431686 -431.408422) (xy 274.496678 -431.560478) (xy 314.141104 -431.560478) (xy 314.141104 -429.018954)
			(xy 314.141572 -429.00684) (xy 314.149068 -428.983801) (xy 314.163312 -428.964203) (xy 314.182912 -428.949962)
			(xy 314.205952 -428.94247) (xy 314.218066 -428.941992) (xy 315.157866 -428.941992) (xy 315.169974 -428.94254)
			(xy 315.193009 -428.950012) (xy 315.207506 -428.960534) (xy 316.1411 -428.960534) (xy 316.1411 -426.41901)
			(xy 316.14162 -426.4069) (xy 316.1491 -426.383863) (xy 316.163331 -426.364265) (xy 316.18292 -426.350022)
			(xy 316.205952 -426.342527) (xy 316.218062 -426.342048) (xy 317.157862 -426.342048) (xy 317.169984 -426.342492)
			(xy 317.193043 -426.349975) (xy 317.21266 -426.36422) (xy 317.226912 -426.383832) (xy 317.234403 -426.406888)
			(xy 317.234824 -426.41901) (xy 317.234824 -427.960536) (xy 318.141096 -427.960536) (xy 318.141096 -425.419012)
			(xy 318.141527 -425.406904) (xy 318.149022 -425.383878) (xy 318.16328 -425.364305) (xy 318.182899 -425.35011)
			(xy 318.205949 -425.342688) (xy 318.218058 -425.342304) (xy 319.157858 -425.342304) (xy 319.169942 -425.342842)
			(xy 319.192935 -425.350283) (xy 319.212513 -425.364453) (xy 319.226766 -425.383969) (xy 319.234305 -425.40693)
			(xy 319.23482 -425.419012) (xy 319.23482 -427.960536) (xy 319.234415 -427.972645) (xy 319.226908 -427.99567)
			(xy 319.212643 -428.01524) (xy 319.19302 -428.029435) (xy 319.169968 -428.036858) (xy 319.157858 -428.037244)
			(xy 318.218058 -428.037244) (xy 318.205965 -428.036828) (xy 318.18296 -428.029358) (xy 318.163379 -428.015159)
			(xy 318.149131 -427.995614) (xy 318.141603 -427.972628) (xy 318.141096 -427.960536) (xy 317.234824 -427.960536)
			(xy 317.234824 -428.960534) (xy 317.234469 -428.972662) (xy 317.226962 -428.995729) (xy 317.212695 -429.015347)
			(xy 317.193064 -429.029595) (xy 317.169991 -429.03708) (xy 317.157862 -429.037496) (xy 316.218062 -429.037496)
			(xy 316.205949 -429.037021) (xy 316.18291 -429.029528) (xy 316.163312 -429.015285) (xy 316.14907 -428.995686)
			(xy 316.141578 -428.972647) (xy 316.1411 -428.960534) (xy 315.207506 -428.960534) (xy 315.212607 -428.964236)
			(xy 315.226851 -428.98382) (xy 315.234347 -429.006846) (xy 315.234828 -429.018954) (xy 315.234828 -431.560478)
			(xy 315.234421 -431.572603) (xy 315.22693 -431.595667) (xy 315.212677 -431.615285) (xy 315.193056 -431.629536)
			(xy 315.169991 -431.637023) (xy 315.157866 -431.63744) (xy 314.218066 -431.63744) (xy 314.205947 -431.637017)
			(xy 314.182899 -431.629518) (xy 314.163296 -431.615264) (xy 314.149057 -431.59565) (xy 314.141574 -431.572597)
			(xy 314.141104 -431.560478) (xy 274.496678 -431.560478) (xy 274.501358 -431.571427) (xy 274.563646 -431.737392)
			(xy 274.618425 -431.905986) (xy 274.665585 -432.076867) (xy 274.705031 -432.249692) (xy 274.736684 -432.424113)
			(xy 274.760479 -432.599778) (xy 274.77637 -432.776334) (xy 274.784323 -432.953425) (xy 274.78482 -433.04206)
			(xy 274.784323 -433.130695) (xy 274.77637 -433.307786) (xy 274.760479 -433.484342) (xy 274.736684 -433.660007)
			(xy 274.705031 -433.834428) (xy 274.665585 -434.007253) (xy 274.618425 -434.178134) (xy 274.563646 -434.346728)
			(xy 274.501358 -434.512693) (xy 274.431686 -434.675698) (xy 274.354772 -434.835412) (xy 274.270769 -434.991515)
			(xy 274.179848 -435.143692) (xy 274.168638 -435.160674) (xy 314.141104 -435.160674) (xy 314.141104 -434.433726)
			(xy 314.141332 -434.424905) (xy 314.145313 -434.407717) (xy 314.148978 -434.39969) (xy 314.382404 -433.92344)
			(xy 314.387135 -433.912935) (xy 314.390614 -433.890169) (xy 314.387116 -433.867406) (xy 314.382404 -433.856892)
			(xy 314.148978 -433.380642) (xy 314.145305 -433.372617) (xy 314.141322 -433.355429) (xy 314.141104 -433.346606)
			(xy 314.141104 -432.61915) (xy 314.141649 -432.607067) (xy 314.149088 -432.584074) (xy 314.163255 -432.564496)
			(xy 314.182771 -432.550242) (xy 314.205731 -432.542703) (xy 314.217812 -432.542188) (xy 315.157612 -432.542188)
			(xy 315.16972 -432.542606) (xy 315.192746 -432.550107) (xy 315.206976 -432.560476) (xy 316.1411 -432.560476)
			(xy 316.1411 -430.018952) (xy 316.141476 -430.006841) (xy 316.148988 -429.983812) (xy 316.16326 -429.96424)
			(xy 316.18289 -429.950047) (xy 316.205949 -429.942627) (xy 316.218062 -429.942244) (xy 317.157862 -429.942244)
			(xy 317.16995 -429.94274) (xy 317.19295 -429.950187) (xy 317.212531 -429.964366) (xy 317.226783 -429.983894)
			(xy 317.234315 -430.006866) (xy 317.234824 -430.018952) (xy 317.234824 -431.560478) (xy 318.141096 -431.560478)
			(xy 318.141096 -429.018954) (xy 318.141572 -429.006841) (xy 318.149067 -428.983804) (xy 318.163309 -428.964206)
			(xy 318.182907 -428.949965) (xy 318.205945 -428.942471) (xy 318.218058 -428.941992) (xy 319.157858 -428.941992)
			(xy 319.169966 -428.942547) (xy 319.193 -428.950017) (xy 319.207492 -428.960534) (xy 320.141092 -428.960534)
			(xy 320.141092 -426.41901) (xy 320.14162 -426.406901) (xy 320.149099 -426.383865) (xy 320.163328 -426.364268)
			(xy 320.182915 -426.350024) (xy 320.205945 -426.342528) (xy 320.218054 -426.342048) (xy 321.157854 -426.342048)
			(xy 321.169975 -426.342499) (xy 321.193034 -426.34998) (xy 321.212651 -426.364223) (xy 321.226904 -426.383833)
			(xy 321.234395 -426.406889) (xy 321.234816 -426.41901) (xy 321.234816 -427.960536) (xy 322.141088 -427.960536)
			(xy 322.141088 -425.419012) (xy 322.141527 -425.406905) (xy 322.149021 -425.38388) (xy 322.163277 -425.364308)
			(xy 322.182894 -425.350113) (xy 322.205942 -425.342689) (xy 322.21805 -425.342304) (xy 323.15785 -425.342304)
			(xy 323.169933 -425.342849) (xy 323.192926 -425.350288) (xy 323.212504 -425.364455) (xy 323.226758 -425.383971)
			(xy 323.234297 -425.406931) (xy 323.234812 -425.419012) (xy 323.234812 -427.960536) (xy 323.234414 -427.972646)
			(xy 323.226907 -427.995672) (xy 323.21264 -428.015243) (xy 323.193015 -428.029437) (xy 323.169961 -428.036859)
			(xy 323.15785 -428.037244) (xy 322.21805 -428.037244) (xy 322.205961 -428.03675) (xy 322.18296 -428.029305)
			(xy 322.163378 -428.015126) (xy 322.149126 -427.995597) (xy 322.141595 -427.972623) (xy 322.141088 -427.960536)
			(xy 321.234816 -427.960536) (xy 321.234816 -428.960534) (xy 321.234468 -428.972663) (xy 321.226961 -428.995731)
			(xy 321.212692 -429.015349) (xy 321.193059 -429.029598) (xy 321.169984 -429.037081) (xy 321.157854 -429.037496)
			(xy 320.218054 -429.037496) (xy 320.20594 -429.037028) (xy 320.182901 -429.029532) (xy 320.163303 -429.015288)
			(xy 320.149062 -428.995688) (xy 320.14157 -428.972648) (xy 320.141092 -428.960534) (xy 319.207492 -428.960534)
			(xy 319.212598 -428.964239) (xy 319.226843 -428.983821) (xy 319.234339 -429.006847) (xy 319.23482 -429.018954)
			(xy 319.23482 -431.560478) (xy 319.234421 -431.572604) (xy 319.226929 -431.595669) (xy 319.212674 -431.615288)
			(xy 319.193051 -431.629538) (xy 319.169984 -431.637024) (xy 319.157858 -431.63744) (xy 318.218058 -431.63744)
			(xy 318.205939 -431.637024) (xy 318.182891 -431.629522) (xy 318.163288 -431.615267) (xy 318.149048 -431.595652)
			(xy 318.141566 -431.572597) (xy 318.141096 -431.560478) (xy 317.234824 -431.560478) (xy 317.234824 -432.560476)
			(xy 317.234363 -432.572581) (xy 317.226874 -432.595604) (xy 317.212623 -432.615175) (xy 317.193012 -432.629371)
			(xy 317.169968 -432.636797) (xy 317.157862 -432.637184) (xy 316.218062 -432.637184) (xy 316.205973 -432.636726)
			(xy 316.182975 -432.629261) (xy 316.163398 -432.615072) (xy 316.149148 -432.595538) (xy 316.141612 -432.572564)
			(xy 316.1411 -432.560476) (xy 315.206976 -432.560476) (xy 315.212318 -432.564369) (xy 315.226513 -432.583989)
			(xy 315.233935 -432.60704) (xy 315.23432 -432.61915) (xy 315.23432 -435.160674) (xy 315.23387 -435.172766)
			(xy 315.226415 -435.195773) (xy 315.212226 -435.215356) (xy 315.192686 -435.229606) (xy 315.169703 -435.237132)
			(xy 315.157612 -435.237636) (xy 314.217812 -435.237636) (xy 314.205707 -435.237174) (xy 314.182687 -435.229682)
			(xy 314.163117 -435.215431) (xy 314.14892 -435.195821) (xy 314.141493 -435.17278) (xy 314.141104 -435.160674)
			(xy 274.168638 -435.160674) (xy 274.082191 -435.291636) (xy 273.977994 -435.43505) (xy 273.867468 -435.573645)
			(xy 273.750836 -435.707142) (xy 273.628331 -435.835271) (xy 273.500202 -435.957776) (xy 273.366705 -436.074408)
			(xy 273.22811 -436.184934) (xy 273.084696 -436.289131) (xy 272.936752 -436.386788) (xy 272.784575 -436.477709)
			(xy 272.628472 -436.561712) (xy 272.468758 -436.638626) (xy 272.305753 -436.708298) (xy 272.139788 -436.770586)
			(xy 271.971194 -436.825365) (xy 271.800313 -436.872525) (xy 271.627488 -436.911971) (xy 271.453067 -436.943624)
			(xy 271.277402 -436.967419) (xy 271.100846 -436.98331) (xy 270.923755 -436.991263) (xy 270.746485 -436.991263)
			(xy 270.569394 -436.98331) (xy 270.392838 -436.967419) (xy 270.217173 -436.943624) (xy 270.042752 -436.911971)
			(xy 269.869927 -436.872525) (xy 269.699046 -436.825365) (xy 269.530452 -436.770586) (xy 269.364487 -436.708298)
			(xy 269.201482 -436.638626) (xy 269.041768 -436.561712) (xy 268.885665 -436.477709) (xy 268.733488 -436.386788)
			(xy 268.585544 -436.289131) (xy 268.44213 -436.184934) (xy 268.303535 -436.074408) (xy 268.170038 -435.957776)
			(xy 268.041909 -435.835271) (xy 267.919404 -435.707142) (xy 267.802772 -435.573645) (xy 267.692246 -435.43505)
			(xy 267.588049 -435.291636) (xy 267.490392 -435.143692) (xy 267.399471 -434.991515) (xy 267.315468 -434.835412)
			(xy 267.238554 -434.675698) (xy 267.168882 -434.512693) (xy 267.106594 -434.346728) (xy 267.051815 -434.178134)
			(xy 267.004655 -434.007253) (xy 266.965209 -433.834428) (xy 266.933556 -433.660007) (xy 266.909761 -433.484342)
			(xy 266.89387 -433.307786) (xy 266.885917 -433.130695) (xy 230.3145 -433.130695) (xy 230.3145 -435.873652)
			(xy 230.314033 -435.898602) (xy 230.306213 -435.947887) (xy 230.29079 -435.995345) (xy 230.268141 -436.03981)
			(xy 230.238824 -436.080191) (xy 230.221536 -436.098188) (xy 229.299008 -437.020716) (xy 229.281016 -437.03801)
			(xy 229.240639 -437.067332) (xy 229.196172 -437.089979) (xy 229.148711 -437.105393) (xy 229.099423 -437.113193)
			(xy 229.074472 -437.11368) (xy 207.302608 -437.11368) (xy 207.27766 -437.113152) (xy 207.22838 -437.105344)
			(xy 207.180923 -437.089933) (xy 207.136457 -437.067299) (xy 207.096072 -437.037997) (xy 207.078072 -437.020716)
			(xy 205.512924 -435.455568) (xy 205.495618 -435.437587) (xy 205.466295 -435.397208) (xy 205.44365 -435.352738)
			(xy 205.42824 -435.305274) (xy 205.420444 -435.255984) (xy 205.41996 -435.231032) (xy 205.41996 -431.836068)
			(xy 205.419562 -431.825996) (xy 205.411823 -431.807397) (xy 205.404974 -431.8) (xy 204.586586 -430.981612)
			(xy 204.579871 -430.975414) (xy 204.563254 -430.96784) (xy 204.545036 -430.96659) (xy 204.52754 -430.971821)
			(xy 204.520038 -430.97704) (xy 204.424534 -431.04943) (xy 204.416914 -431.086514) (xy 204.426312 -431.103278)
			(xy 204.471058 -431.183788) (xy 204.553904 -431.348323) (xy 204.628987 -431.516542) (xy 204.696145 -431.688079)
			(xy 204.75523 -431.862561) (xy 204.806115 -432.039609) (xy 204.848688 -432.218837) (xy 204.882858 -432.399855)
			(xy 204.908549 -432.58227) (xy 204.925705 -432.765684) (xy 204.934291 -432.949699) (xy 204.93482 -433.041806)
			(xy 204.93482 -433.04206) (xy 204.934323 -433.130695) (xy 204.92637 -433.307786) (xy 204.910479 -433.484342)
			(xy 204.886684 -433.660007) (xy 204.855031 -433.834428) (xy 204.815585 -434.007253) (xy 204.768425 -434.178134)
			(xy 204.713646 -434.346728) (xy 204.651358 -434.512693) (xy 204.581686 -434.675698) (xy 204.504772 -434.835412)
			(xy 204.420769 -434.991515) (xy 204.329848 -435.143692) (xy 204.232191 -435.291636) (xy 204.127994 -435.43505)
			(xy 204.017468 -435.573645) (xy 203.900836 -435.707142) (xy 203.778331 -435.835271) (xy 203.650202 -435.957776)
			(xy 203.516705 -436.074408) (xy 203.37811 -436.184934) (xy 203.234696 -436.289131) (xy 203.086752 -436.386788)
			(xy 202.934575 -436.477709) (xy 202.778472 -436.561712) (xy 202.618758 -436.638626) (xy 202.455753 -436.708298)
			(xy 202.289788 -436.770586) (xy 202.121194 -436.825365) (xy 201.950313 -436.872525) (xy 201.777488 -436.911971)
			(xy 201.603067 -436.943624) (xy 201.427402 -436.967419) (xy 201.250846 -436.98331) (xy 201.073755 -436.991263)
			(xy 200.896485 -436.991263) (xy 200.719394 -436.98331) (xy 200.542838 -436.967419) (xy 200.367173 -436.943624)
			(xy 200.192752 -436.911971) (xy 200.019927 -436.872525) (xy 199.849046 -436.825365) (xy 199.680452 -436.770586)
			(xy 199.514487 -436.708298) (xy 199.351482 -436.638626) (xy 199.191768 -436.561712) (xy 199.035665 -436.477709)
			(xy 198.883488 -436.386788) (xy 198.735544 -436.289131) (xy 198.59213 -436.184934) (xy 198.453535 -436.074408)
			(xy 198.320038 -435.957776) (xy 198.191909 -435.835271) (xy 198.069404 -435.707142) (xy 197.952772 -435.573645)
			(xy 197.842246 -435.43505) (xy 197.738049 -435.291636) (xy 197.640392 -435.143692) (xy 197.549471 -434.991515)
			(xy 197.465468 -434.835412) (xy 197.388554 -434.675698) (xy 197.318882 -434.512693) (xy 197.256594 -434.346728)
			(xy 197.201815 -434.178134) (xy 197.154655 -434.007253) (xy 197.115209 -433.834428) (xy 197.083556 -433.660007)
			(xy 197.059761 -433.484342) (xy 197.04387 -433.307786) (xy 197.035917 -433.130695) (xy 197.035917 -432.953425)
			(xy 197.04387 -432.776334) (xy 197.059761 -432.599778) (xy 197.083556 -432.424113) (xy 197.115209 -432.249692)
			(xy 197.154655 -432.076867) (xy 197.201815 -431.905986) (xy 197.256594 -431.737392) (xy 197.318882 -431.571427)
			(xy 197.388554 -431.408422) (xy 197.465468 -431.248708) (xy 197.549471 -431.092605) (xy 197.640392 -430.940428)
			(xy 197.738049 -430.792484) (xy 197.842246 -430.64907) (xy 197.952772 -430.510475) (xy 198.069404 -430.376978)
			(xy 198.191909 -430.248849) (xy 198.320038 -430.126344) (xy 198.453535 -430.009712) (xy 198.59213 -429.899186)
			(xy 198.735544 -429.794989) (xy 198.883488 -429.697332) (xy 199.035665 -429.606411) (xy 199.191768 -429.522408)
			(xy 199.351482 -429.445494) (xy 199.514487 -429.375822) (xy 199.680452 -429.313534) (xy 199.849046 -429.258755)
			(xy 200.019927 -429.211595) (xy 200.192752 -429.172149) (xy 200.367173 -429.140496) (xy 200.542838 -429.116701)
			(xy 200.719394 -429.10081) (xy 200.896485 -429.092857) (xy 200.98512 -429.09236) (xy 200.985374 -429.09236)
			(xy 201.07748 -429.092926) (xy 201.261492 -429.101525) (xy 201.444903 -429.118692) (xy 201.627315 -429.144389)
			(xy 201.80833 -429.17856) (xy 201.987556 -429.221132) (xy 202.164603 -429.272011) (xy 202.339086 -429.331088)
			(xy 202.510625 -429.398233) (xy 202.678849 -429.4733) (xy 202.84339 -429.556127) (xy 202.923902 -429.600868)
			(xy 202.932044 -429.605072) (xy 202.950138 -429.607899) (xy 202.968075 -429.604204) (xy 202.983579 -429.594457)
			(xy 202.989434 -429.587406) (xy 203.05014 -429.507396) (xy 203.055391 -429.49992) (xy 203.060685 -429.482447)
			(xy 203.059501 -429.464229) (xy 203.05199 -429.447588) (xy 203.045822 -429.440848) (xy 194.790822 -421.185594)
			(xy 194.763915 -421.158053) (xy 194.715832 -421.097913) (xy 194.674792 -421.032763) (xy 194.641312 -420.963424)
			(xy 194.615814 -420.89077) (xy 194.598619 -420.815716) (xy 194.589944 -420.739207) (xy 194.5894 -420.700708)
			(xy 102.15118 -420.700708) (xy 102.15118 -421.122094) (xy 102.150662 -421.132249) (xy 102.142893 -421.151015)
			(xy 102.128535 -421.16538) (xy 102.109773 -421.173157) (xy 102.099618 -421.173656) (xy 97.200974 -421.173656)
			(xy 97.190814 -421.173188) (xy 97.172043 -421.165404) (xy 97.157678 -421.15103) (xy 97.149906 -421.132255)
			(xy 97.149412 -421.122094) (xy 75.844472 -421.122094) (xy 75.826048 -421.150762) (xy 75.790333 -421.191979)
			(xy 75.749116 -421.227694) (xy 75.703235 -421.25718) (xy 75.653625 -421.279837) (xy 75.601295 -421.295202)
			(xy 75.547311 -421.302964) (xy 75.492773 -421.302964) (xy 75.438789 -421.295202) (xy 75.386459 -421.279837)
			(xy 75.336849 -421.25718) (xy 75.290968 -421.227694) (xy 75.249751 -421.191979) (xy 75.214036 -421.150762)
			(xy 75.18455 -421.104881) (xy 75.161893 -421.055271) (xy 75.146528 -421.002941) (xy 75.138766 -420.948957)
			(xy 75.13828 -420.921688) (xy 73.234804 -420.921688) (xy 73.234804 -421.760396) (xy 73.234381 -421.772504)
			(xy 73.226883 -421.795531) (xy 73.212623 -421.815104) (xy 73.193003 -421.829299) (xy 73.169952 -421.83672)
			(xy 73.157842 -421.837104) (xy 72.218042 -421.837104) (xy 72.205959 -421.836558) (xy 72.182967 -421.829118)
			(xy 72.16339 -421.81495) (xy 72.149137 -421.795436) (xy 72.141596 -421.772477) (xy 72.14108 -421.760396)
			(xy 71.207209 -421.760396) (xy 71.212598 -421.764313) (xy 71.226839 -421.783915) (xy 71.23433 -421.806956)
			(xy 71.234808 -421.81907) (xy 71.234808 -424.360594) (xy 71.234284 -424.372704) (xy 71.226804 -424.395739)
			(xy 71.212574 -424.415337) (xy 71.192985 -424.42958) (xy 71.169955 -424.437076) (xy 71.157846 -424.437556)
			(xy 70.218046 -424.437556) (xy 70.205925 -424.437101) (xy 70.182867 -424.429621) (xy 70.16325 -424.415378)
			(xy 70.148998 -424.395769) (xy 70.141505 -424.372715) (xy 70.141084 -424.360594) (xy 69.234812 -424.360594)
			(xy 69.234812 -425.360592) (xy 69.234377 -425.372699) (xy 69.226881 -425.395724) (xy 69.212624 -425.415297)
			(xy 69.193007 -425.429492) (xy 69.169959 -425.436915) (xy 69.15785 -425.4373) (xy 68.21805 -425.4373)
			(xy 68.205967 -425.436751) (xy 68.182975 -425.429313) (xy 68.163397 -425.415146) (xy 68.149144 -425.395632)
			(xy 68.141603 -425.372673) (xy 68.141088 -425.360592) (xy 67.207172 -425.360592) (xy 67.212508 -425.364454)
			(xy 67.226762 -425.38397) (xy 67.234301 -425.40693) (xy 67.234816 -425.419012) (xy 67.234816 -427.960536)
			(xy 67.234415 -427.972645) (xy 67.226907 -427.995671) (xy 67.212641 -428.015242) (xy 67.193018 -428.029436)
			(xy 67.169965 -428.036859) (xy 67.157854 -428.037244) (xy 66.218054 -428.037244) (xy 66.20596 -428.036832)
			(xy 66.182956 -428.02936) (xy 66.163375 -428.01516) (xy 66.149127 -427.995615) (xy 66.141599 -427.972628)
			(xy 66.141092 -427.960536) (xy 65.23482 -427.960536) (xy 65.23482 -428.960534) (xy 65.234469 -428.972663)
			(xy 65.226962 -428.99573) (xy 65.212694 -429.015348) (xy 65.193062 -429.029597) (xy 65.169987 -429.03708)
			(xy 65.157858 -429.037496) (xy 64.218058 -429.037496) (xy 64.205945 -429.037025) (xy 64.182906 -429.02953)
			(xy 64.163308 -429.015287) (xy 64.149066 -428.995687) (xy 64.141574 -428.972647) (xy 64.141096 -428.960534)
			(xy 63.207499 -428.960534) (xy 63.212603 -428.964238) (xy 63.226847 -428.98382) (xy 63.234343 -429.006847)
			(xy 63.234824 -429.018954) (xy 63.234824 -431.560478) (xy 63.234421 -431.572603) (xy 63.22693 -431.595668)
			(xy 63.212675 -431.615287) (xy 63.193054 -431.629537) (xy 63.169987 -431.637023) (xy 63.157862 -431.63744)
			(xy 62.218062 -431.63744) (xy 62.205943 -431.63702) (xy 62.182895 -431.62952) (xy 62.163292 -431.615265)
			(xy 62.149053 -431.595651) (xy 62.14157 -431.572597) (xy 62.1411 -431.560478) (xy 61.234828 -431.560478)
			(xy 61.234828 -432.560476) (xy 61.234363 -432.572581) (xy 61.226874 -432.595602) (xy 61.212624 -432.615174)
			(xy 61.193014 -432.62937) (xy 61.169972 -432.636796) (xy 61.157866 -432.637184) (xy 60.218066 -432.637184)
			(xy 60.205977 -432.636722) (xy 60.182979 -432.629259) (xy 60.163402 -432.61507) (xy 60.149152 -432.595538)
			(xy 60.141616 -432.572563) (xy 60.141104 -432.560476) (xy 59.207158 -432.560476) (xy 59.21261 -432.564433)
			(xy 59.226854 -432.584016) (xy 59.234351 -432.607042) (xy 59.234832 -432.61915) (xy 59.234832 -435.160674)
			(xy 59.234417 -435.172798) (xy 59.226929 -435.195861) (xy 59.212677 -435.21548) (xy 59.193058 -435.229731)
			(xy 59.169994 -435.237218) (xy 59.15787 -435.237636) (xy 58.21807 -435.237636) (xy 58.205951 -435.237214)
			(xy 58.182903 -435.229715) (xy 58.163299 -435.215461) (xy 58.14906 -435.195847) (xy 58.141578 -435.172793)
			(xy 58.141108 -435.160674) (xy 7.00913 -435.160674) (xy 7.00913 -438.760616) (xy 58.141108 -438.760616)
			(xy 58.141108 -438.033668) (xy 58.141416 -438.024835) (xy 58.145512 -438.007647) (xy 58.149236 -437.999632)
			(xy 58.382662 -437.523382) (xy 58.387361 -437.512865) (xy 58.390848 -437.490107) (xy 58.387365 -437.467349)
			(xy 58.382662 -437.456834) (xy 58.149236 -436.980584) (xy 58.145476 -436.97258) (xy 58.141362 -436.955387)
			(xy 58.141108 -436.946548) (xy 58.141108 -436.219092) (xy 58.141509 -436.206982) (xy 58.149012 -436.183953)
			(xy 58.163277 -436.164379) (xy 58.182902 -436.150185) (xy 58.205958 -436.142766) (xy 58.21807 -436.142384)
			(xy 59.15787 -436.142384) (xy 59.169962 -436.142834) (xy 59.192969 -436.150288) (xy 59.207302 -436.160672)
			(xy 60.141104 -436.160672) (xy 60.141104 -435.433724) (xy 60.141398 -435.42489) (xy 60.145504 -435.407702)
			(xy 60.149232 -435.399688) (xy 60.382658 -434.923438) (xy 60.387387 -434.912933) (xy 60.390864 -434.890167)
			(xy 60.387368 -434.867405) (xy 60.382658 -434.85689) (xy 60.149232 -434.38064) (xy 60.145458 -434.372642)
			(xy 60.141353 -434.355444) (xy 60.141104 -434.346604) (xy 60.141104 -433.619148) (xy 60.141557 -433.607041)
			(xy 60.149044 -433.584015) (xy 60.163296 -433.564441) (xy 60.18291 -433.550244) (xy 60.205958 -433.542823)
			(xy 60.218066 -433.54244) (xy 61.157866 -433.54244) (xy 61.169954 -433.542936) (xy 61.192953 -433.550384)
			(xy 61.212534 -433.564563) (xy 61.226786 -433.58409) (xy 61.234318 -433.607062) (xy 61.234828 -433.619148)
			(xy 61.234828 -435.160674) (xy 62.1411 -435.160674) (xy 62.1411 -434.433726) (xy 62.141395 -434.424892)
			(xy 62.1455 -434.407704) (xy 62.149228 -434.39969) (xy 62.382654 -433.92344) (xy 62.387382 -433.912934)
			(xy 62.390859 -433.890169) (xy 62.387364 -433.867407) (xy 62.382654 -433.856892) (xy 62.149228 -433.380642)
			(xy 62.145455 -433.372644) (xy 62.141349 -433.355446) (xy 62.1411 -433.346606) (xy 62.1411 -432.61915)
			(xy 62.141569 -432.607037) (xy 62.149065 -432.583998) (xy 62.163309 -432.564401) (xy 62.182909 -432.550159)
			(xy 62.205949 -432.542667) (xy 62.218062 -432.542188) (xy 63.157862 -432.542188) (xy 63.16997 -432.542743)
			(xy 63.193003 -432.550214) (xy 63.207144 -432.560476) (xy 64.141096 -432.560476) (xy 64.141096 -430.018952)
			(xy 64.141476 -430.006841) (xy 64.148988 -429.983813) (xy 64.163259 -429.964241) (xy 64.182888 -429.950048)
			(xy 64.205945 -429.942628) (xy 64.218058 -429.942244) (xy 65.157858 -429.942244) (xy 65.169946 -429.942743)
			(xy 65.192946 -429.950189) (xy 65.212527 -429.964367) (xy 65.226779 -429.983894) (xy 65.234311 -430.006866)
			(xy 65.23482 -430.018952) (xy 65.23482 -431.560478) (xy 66.141092 -431.560478) (xy 66.141092 -429.018954)
			(xy 66.141572 -429.006842) (xy 66.149066 -428.983805) (xy 66.163308 -428.964208) (xy 66.182905 -428.949966)
			(xy 66.205942 -428.942472) (xy 66.218054 -428.941992) (xy 67.157854 -428.941992) (xy 67.169962 -428.94255)
			(xy 67.192996 -428.950019) (xy 67.207487 -428.960534) (xy 68.141088 -428.960534) (xy 68.141088 -426.41901)
			(xy 68.14162 -426.406901) (xy 68.149098 -426.383867) (xy 68.163326 -426.364269) (xy 68.182913 -426.350025)
			(xy 68.205941 -426.342529) (xy 68.21805 -426.342048) (xy 69.15785 -426.342048) (xy 69.169968 -426.342469)
			(xy 69.193015 -426.349972) (xy 69.212616 -426.364226) (xy 69.226856 -426.383839) (xy 69.23434 -426.406891)
			(xy 69.234812 -426.41901) (xy 69.234812 -427.960536) (xy 70.141084 -427.960536) (xy 70.141084 -425.419012)
			(xy 70.141527 -425.406905) (xy 70.149021 -425.383881) (xy 70.163276 -425.364309) (xy 70.182891 -425.350114)
			(xy 70.205938 -425.34269) (xy 70.218046 -425.342304) (xy 71.157846 -425.342304) (xy 71.169934 -425.342767)
			(xy 71.19293 -425.350232) (xy 71.207224 -425.360592) (xy 72.14108 -425.360592) (xy 72.14108 -422.819068)
			(xy 72.141489 -422.806959) (xy 72.148995 -422.783935) (xy 72.163259 -422.764364) (xy 72.18288 -422.75017)
			(xy 72.205932 -422.742746) (xy 72.218042 -422.74236) (xy 73.157842 -422.74236) (xy 73.169936 -422.742772)
			(xy 73.192941 -422.750243) (xy 73.212522 -422.764443) (xy 73.226771 -422.783989) (xy 73.234298 -422.806975)
			(xy 73.234804 -422.819068) (xy 73.234804 -424.80464) (xy 109.929157 -424.80464) (xy 109.929157 -424.6755)
			(xy 109.937107 -424.546605) (xy 109.952977 -424.418445) (xy 109.976706 -424.291504) (xy 110.008205 -424.166265)
			(xy 110.047354 -424.043202) (xy 110.094005 -423.922783) (xy 110.14798 -423.805464) (xy 110.209075 -423.69169)
			(xy 110.277058 -423.581893) (xy 110.351672 -423.47649) (xy 110.432633 -423.37588) (xy 110.519633 -423.280445)
			(xy 110.612344 -423.190546) (xy 110.710414 -423.106525) (xy 110.813469 -423.028701) (xy 110.92112 -422.957369)
			(xy 111.032959 -422.892799) (xy 111.14856 -422.835237) (xy 111.267485 -422.7849) (xy 111.389284 -422.74198)
			(xy 111.513494 -422.706639) (xy 111.639643 -422.679012) (xy 111.767255 -422.659203) (xy 111.895844 -422.647287)
			(xy 112.024922 -422.643311) (xy 112.154 -422.647287) (xy 112.282589 -422.659203) (xy 112.410201 -422.679012)
			(xy 112.53635 -422.706639) (xy 112.66056 -422.74198) (xy 112.782359 -422.7849) (xy 112.901284 -422.835237)
			(xy 113.016885 -422.892799) (xy 113.128724 -422.957369) (xy 113.236375 -423.028701) (xy 113.33943 -423.106525)
			(xy 113.4375 -423.190546) (xy 113.530211 -423.280445) (xy 113.617211 -423.37588) (xy 113.698172 -423.47649)
			(xy 113.772786 -423.581893) (xy 113.840769 -423.69169) (xy 113.901864 -423.805464) (xy 113.955839 -423.922783)
			(xy 114.00249 -424.043202) (xy 114.041639 -424.166265) (xy 114.073138 -424.291504) (xy 114.096867 -424.418445)
			(xy 114.112737 -424.546605) (xy 114.120687 -424.6755) (xy 114.121184 -424.74007) (xy 114.120687 -424.80464)
			(xy 114.112737 -424.933535) (xy 114.096867 -425.061695) (xy 114.073138 -425.188636) (xy 114.041639 -425.313875)
			(xy 114.00249 -425.436938) (xy 113.955839 -425.557357) (xy 113.901864 -425.674676) (xy 113.840769 -425.78845)
			(xy 113.772786 -425.898247) (xy 113.698172 -426.00365) (xy 113.617211 -426.10426) (xy 113.530211 -426.199695)
			(xy 113.4375 -426.289594) (xy 113.33943 -426.373615) (xy 113.236375 -426.451439) (xy 113.128724 -426.522771)
			(xy 113.016885 -426.587341) (xy 112.901284 -426.644903) (xy 112.782359 -426.69524) (xy 112.66056 -426.73816)
			(xy 112.53635 -426.773501) (xy 112.410201 -426.801128) (xy 112.282589 -426.820937) (xy 112.154 -426.832853)
			(xy 112.024922 -426.83683) (xy 111.895844 -426.832853) (xy 111.767255 -426.820937) (xy 111.639643 -426.801128)
			(xy 111.513494 -426.773501) (xy 111.389284 -426.73816) (xy 111.267485 -426.69524) (xy 111.14856 -426.644903)
			(xy 111.032959 -426.587341) (xy 110.92112 -426.522771) (xy 110.813469 -426.451439) (xy 110.710414 -426.373615)
			(xy 110.612344 -426.289594) (xy 110.519633 -426.199695) (xy 110.432633 -426.10426) (xy 110.351672 -426.00365)
			(xy 110.277058 -425.898247) (xy 110.209075 -425.78845) (xy 110.14798 -425.674676) (xy 110.094005 -425.557357)
			(xy 110.047354 -425.436938) (xy 110.008205 -425.313875) (xy 109.976706 -425.188636) (xy 109.952977 -425.061695)
			(xy 109.937107 -424.933535) (xy 109.929157 -424.80464) (xy 73.234804 -424.80464) (xy 73.234804 -425.360592)
			(xy 73.234377 -425.3727) (xy 73.22688 -425.395727) (xy 73.212621 -425.415299) (xy 73.193002 -425.429495)
			(xy 73.169951 -425.436916) (xy 73.157842 -425.4373) (xy 72.218042 -425.4373) (xy 72.205959 -425.436758)
			(xy 72.182966 -425.429317) (xy 72.163389 -425.415149) (xy 72.149135 -425.395633) (xy 72.141595 -425.372673)
			(xy 72.14108 -425.360592) (xy 71.207224 -425.360592) (xy 71.212507 -425.364421) (xy 71.226757 -425.383953)
			(xy 71.234294 -425.406925) (xy 71.234808 -425.419012) (xy 71.234808 -427.960536) (xy 71.234414 -427.972646)
			(xy 71.226906 -427.995673) (xy 71.212638 -428.015245) (xy 71.193013 -428.029438) (xy 71.169957 -428.03686)
			(xy 71.157846 -428.037244) (xy 70.218046 -428.037244) (xy 70.205957 -428.036753) (xy 70.182955 -428.029307)
			(xy 70.163373 -428.015127) (xy 70.149122 -427.995597) (xy 70.141591 -427.972623) (xy 70.141084 -427.960536)
			(xy 69.234812 -427.960536) (xy 69.234812 -428.960534) (xy 69.234318 -428.972645) (xy 69.226828 -428.995681)
			(xy 69.21259 -429.015278) (xy 69.192996 -429.02952) (xy 69.169961 -429.037016) (xy 69.15785 -429.037496)
			(xy 68.21805 -429.037496) (xy 68.205936 -429.037031) (xy 68.182897 -429.029535) (xy 68.163299 -429.015289)
			(xy 68.149058 -428.995689) (xy 68.141566 -428.972648) (xy 68.141088 -428.960534) (xy 67.207487 -428.960534)
			(xy 67.212594 -428.96424) (xy 67.226839 -428.983822) (xy 67.234335 -429.006847) (xy 67.234816 -429.018954)
			(xy 67.234816 -431.560478) (xy 67.234421 -431.572604) (xy 67.226929 -431.59567) (xy 67.212672 -431.61529)
			(xy 67.193049 -431.62954) (xy 67.16998 -431.637024) (xy 67.157854 -431.63744) (xy 66.218054 -431.63744)
			(xy 66.205935 -431.637027) (xy 66.182886 -431.629525) (xy 66.163284 -431.615268) (xy 66.149044 -431.595653)
			(xy 66.141562 -431.572598) (xy 66.141092 -431.560478) (xy 65.23482 -431.560478) (xy 65.23482 -432.560476)
			(xy 65.234363 -432.572582) (xy 65.226873 -432.595605) (xy 65.212621 -432.615176) (xy 65.193009 -432.629373)
			(xy 65.169965 -432.636797) (xy 65.157858 -432.637184) (xy 64.218058 -432.637184) (xy 64.205969 -432.636729)
			(xy 64.182971 -432.629264) (xy 64.163393 -432.615073) (xy 64.149143 -432.595539) (xy 64.141608 -432.572564)
			(xy 64.141096 -432.560476) (xy 63.207144 -432.560476) (xy 63.212601 -432.564436) (xy 63.226846 -432.584018)
			(xy 63.234343 -432.607043) (xy 63.234824 -432.61915) (xy 63.234824 -435.160674) (xy 63.234417 -435.172799)
			(xy 63.226928 -435.195864) (xy 63.212674 -435.215482) (xy 63.193053 -435.229733) (xy 63.169987 -435.237219)
			(xy 63.157862 -435.237636) (xy 62.218062 -435.237636) (xy 62.205943 -435.23722) (xy 62.182894 -435.229719)
			(xy 62.163291 -435.215464) (xy 62.149051 -435.195849) (xy 62.14157 -435.172794) (xy 62.1411 -435.160674)
			(xy 61.234828 -435.160674) (xy 61.234828 -436.160672) (xy 61.23436 -436.172777) (xy 61.226872 -436.195798)
			(xy 61.212623 -436.215369) (xy 61.193013 -436.229566) (xy 61.169972 -436.236992) (xy 61.157866 -436.23738)
			(xy 60.218066 -436.23738) (xy 60.205977 -436.236922) (xy 60.182978 -436.229458) (xy 60.163401 -436.215269)
			(xy 60.14915 -436.195735) (xy 60.141616 -436.17276) (xy 60.141104 -436.160672) (xy 59.207302 -436.160672)
			(xy 59.212554 -436.164477) (xy 59.226804 -436.184017) (xy 59.234329 -436.207001) (xy 59.234832 -436.219092)
			(xy 59.234832 -438.760616) (xy 59.234398 -438.772723) (xy 59.226898 -438.795745) (xy 59.21264 -438.815315)
			(xy 59.193024 -438.82951) (xy 59.169978 -438.836936) (xy 59.15787 -438.837324) (xy 58.21807 -438.837324)
			(xy 58.205975 -438.836918) (xy 58.182968 -438.829448) (xy 58.163385 -438.815247) (xy 58.149137 -438.795699)
			(xy 58.141612 -438.77271) (xy 58.141108 -438.760616) (xy 7.00913 -438.760616) (xy 7.00913 -439.760614)
			(xy 60.141104 -439.760614) (xy 60.141104 -439.033666) (xy 60.141411 -439.024833) (xy 60.145508 -439.007645)
			(xy 60.149232 -438.99963) (xy 60.382658 -438.52338) (xy 60.387358 -438.512863) (xy 60.390845 -438.490105)
			(xy 60.387362 -438.467347) (xy 60.382658 -438.456832) (xy 60.149232 -437.980582) (xy 60.145471 -437.972578)
			(xy 60.141358 -437.955385) (xy 60.141104 -437.946546) (xy 60.141104 -437.21909) (xy 60.141603 -437.206978)
			(xy 60.149089 -437.183941) (xy 60.163325 -437.164342) (xy 60.182919 -437.1501) (xy 60.205954 -437.142607)
			(xy 60.218066 -437.142128) (xy 61.157866 -437.142128) (xy 61.169986 -437.142589) (xy 61.193042 -437.15007)
			(xy 61.212657 -437.164312) (xy 61.22691 -437.183918) (xy 61.234404 -437.20697) (xy 61.234828 -437.21909)
			(xy 61.234828 -438.760616) (xy 62.1411 -438.760616) (xy 62.1411 -438.033668) (xy 62.141409 -438.024835)
			(xy 62.145504 -438.007647) (xy 62.149228 -437.999632) (xy 62.382654 -437.523382) (xy 62.387353 -437.512865)
			(xy 62.390841 -437.490107) (xy 62.387357 -437.467349) (xy 62.382654 -437.456834) (xy 62.149228 -436.980584)
			(xy 62.145468 -436.97258) (xy 62.141354 -436.955387) (xy 62.1411 -436.946548) (xy 62.1411 -436.219092)
			(xy 62.141509 -436.206983) (xy 62.149011 -436.183955) (xy 62.163274 -436.164382) (xy 62.182897 -436.150188)
			(xy 62.205951 -436.142767) (xy 62.218062 -436.142384) (xy 63.157862 -436.142384) (xy 63.169954 -436.142841)
			(xy 63.192961 -436.150292) (xy 63.207289 -436.160672) (xy 64.141096 -436.160672) (xy 64.141096 -435.433724)
			(xy 64.141391 -435.42489) (xy 64.145496 -435.407702) (xy 64.149224 -435.399688) (xy 64.38265 -434.923438)
			(xy 64.38738 -434.912933) (xy 64.390857 -434.890167) (xy 64.38736 -434.867405) (xy 64.38265 -434.85689)
			(xy 64.149224 -434.38064) (xy 64.14545 -434.372642) (xy 64.141345 -434.355444) (xy 64.141096 -434.346604)
			(xy 64.141096 -433.619148) (xy 64.141557 -433.607042) (xy 64.149043 -433.584017) (xy 64.163293 -433.564443)
			(xy 64.182905 -433.550247) (xy 64.205951 -433.542824) (xy 64.218058 -433.54244) (xy 65.157858 -433.54244)
			(xy 65.169945 -433.542943) (xy 65.192945 -433.550388) (xy 65.212525 -433.564566) (xy 65.226777 -433.584092)
			(xy 65.23431 -433.607062) (xy 65.23482 -433.619148) (xy 65.23482 -435.160674) (xy 66.141092 -435.160674)
			(xy 66.141092 -434.433726) (xy 66.141388 -434.424892) (xy 66.145492 -434.407704) (xy 66.14922 -434.39969)
			(xy 66.382646 -433.92344) (xy 66.387375 -433.912934) (xy 66.390852 -433.890169) (xy 66.387356 -433.867407)
			(xy 66.382646 -433.856892) (xy 66.14922 -433.380642) (xy 66.145446 -433.372644) (xy 66.141341 -433.355446)
			(xy 66.141092 -433.346606) (xy 66.141092 -432.61915) (xy 66.141568 -432.607037) (xy 66.149064 -432.584)
			(xy 66.163306 -432.564403) (xy 66.182904 -432.550162) (xy 66.205941 -432.542668) (xy 66.218054 -432.542188)
			(xy 67.157854 -432.542188) (xy 67.169961 -432.54275) (xy 67.192995 -432.550219) (xy 67.207131 -432.560476)
			(xy 68.141088 -432.560476) (xy 68.141088 -430.018952) (xy 68.141475 -430.006842) (xy 68.148987 -429.983815)
			(xy 68.163256 -429.964244) (xy 68.182883 -429.95005) (xy 68.205938 -429.942629) (xy 68.21805 -429.942244)
			(xy 69.15785 -429.942244) (xy 69.169937 -429.94275) (xy 69.192937 -429.950193) (xy 69.212518 -429.96437)
			(xy 69.22677 -429.983896) (xy 69.234303 -430.006866) (xy 69.234812 -430.018952) (xy 69.234812 -431.560478)
			(xy 70.141084 -431.560478) (xy 70.141084 -429.018954) (xy 70.141473 -429.006832) (xy 70.148979 -428.98378)
			(xy 70.16324 -428.964175) (xy 70.182862 -428.949937) (xy 70.205924 -428.942459) (xy 70.218046 -428.941992)
			(xy 71.157846 -428.941992) (xy 71.169958 -428.942472) (xy 71.192995 -428.949966) (xy 71.207537 -428.960534)
			(xy 72.14108 -428.960534) (xy 72.14108 -426.41901) (xy 72.141469 -426.406884) (xy 72.148964 -426.383818)
			(xy 72.163222 -426.364199) (xy 72.182847 -426.349949) (xy 72.205915 -426.342464) (xy 72.218042 -426.342048)
			(xy 73.157842 -426.342048) (xy 73.16996 -426.342476) (xy 73.193006 -426.349976) (xy 73.212608 -426.364229)
			(xy 73.226848 -426.383841) (xy 73.234332 -426.406892) (xy 73.234804 -426.41901) (xy 73.234804 -427.960536)
			(xy 75.141328 -427.960536) (xy 75.141328 -425.419012) (xy 75.141724 -425.406926) (xy 75.149192 -425.383938)
			(xy 75.163402 -425.364384) (xy 75.18296 -425.350181) (xy 75.20595 -425.34272) (xy 75.218036 -425.342304)
			(xy 76.157836 -425.342304) (xy 76.169914 -425.342734) (xy 76.192884 -425.350207) (xy 76.212422 -425.364413)
			(xy 76.226615 -425.383959) (xy 76.234074 -425.406934) (xy 76.234544 -425.419012) (xy 76.234544 -427.960536)
			(xy 76.234067 -427.972609) (xy 76.226599 -427.995571) (xy 76.212405 -428.015105) (xy 76.192871 -428.029299)
			(xy 76.169909 -428.036767) (xy 76.157836 -428.037244) (xy 75.218036 -428.037244) (xy 75.205967 -428.036706)
			(xy 75.183007 -428.029258) (xy 75.163472 -428.015079) (xy 75.149275 -427.995558) (xy 75.141806 -427.972605)
			(xy 75.141328 -427.960536) (xy 73.234804 -427.960536) (xy 73.234804 -428.960534) (xy 73.234318 -428.972646)
			(xy 73.226827 -428.995683) (xy 73.212587 -429.015281) (xy 73.192991 -429.029523) (xy 73.169954 -429.037017)
			(xy 73.157842 -429.037496) (xy 72.218042 -429.037496) (xy 72.205925 -429.037005) (xy 72.182873 -429.029528)
			(xy 72.16326 -429.015294) (xy 72.149006 -428.995695) (xy 72.141507 -428.972651) (xy 72.14108 -428.960534)
			(xy 71.207537 -428.960534) (xy 71.212592 -428.964208) (xy 71.226834 -428.983805) (xy 71.234328 -429.006842)
			(xy 71.234808 -429.018954) (xy 71.234808 -431.560478) (xy 71.23427 -431.572587) (xy 71.226795 -431.595622)
			(xy 71.212568 -431.61522) (xy 71.192983 -431.629464) (xy 71.169954 -431.636959) (xy 71.157846 -431.63744)
			(xy 70.218046 -431.63744) (xy 70.205923 -431.637001) (xy 70.182862 -431.629518) (xy 70.163245 -431.615273)
			(xy 70.148993 -431.595659) (xy 70.141503 -431.5726) (xy 70.141084 -431.560478) (xy 69.234812 -431.560478)
			(xy 69.234812 -432.560476) (xy 69.234363 -432.572582) (xy 69.226872 -432.595607) (xy 69.212618 -432.615179)
			(xy 69.193004 -432.629375) (xy 69.169958 -432.636799) (xy 69.15785 -432.637184) (xy 68.21805 -432.637184)
			(xy 68.205965 -432.636651) (xy 68.18297 -432.62921) (xy 68.163392 -432.61504) (xy 68.149139 -432.595522)
			(xy 68.141601 -432.572559) (xy 68.141088 -432.560476) (xy 67.207131 -432.560476) (xy 67.212593 -432.564439)
			(xy 67.226838 -432.584019) (xy 67.234335 -432.607043) (xy 67.234816 -432.61915) (xy 67.234816 -435.160674)
			(xy 67.234417 -435.1728) (xy 67.226927 -435.195866) (xy 67.212671 -435.215485) (xy 67.193048 -435.229736)
			(xy 67.16998 -435.23722) (xy 67.157854 -435.237636) (xy 66.218054 -435.237636) (xy 66.205934 -435.237227)
			(xy 66.182885 -435.229724) (xy 66.163282 -435.215467) (xy 66.149043 -435.19585) (xy 66.141562 -435.172794)
			(xy 66.141092 -435.160674) (xy 65.23482 -435.160674) (xy 65.23482 -436.160672) (xy 65.23436 -436.172777)
			(xy 65.226871 -436.1958) (xy 65.21262 -436.215372) (xy 65.193008 -436.229568) (xy 65.169964 -436.236993)
			(xy 65.157858 -436.23738) (xy 64.218058 -436.23738) (xy 64.205968 -436.236929) (xy 64.18297 -436.229463)
			(xy 64.163392 -436.215272) (xy 64.149142 -436.195737) (xy 64.141608 -436.17276) (xy 64.141096 -436.160672)
			(xy 63.207289 -436.160672) (xy 63.212545 -436.16448) (xy 63.226795 -436.184019) (xy 63.234321 -436.207002)
			(xy 63.234824 -436.219092) (xy 63.234824 -438.760616) (xy 63.234398 -438.772723) (xy 63.226897 -438.795747)
			(xy 63.212637 -438.815318) (xy 63.193019 -438.829513) (xy 63.169971 -438.836937) (xy 63.157862 -438.837324)
			(xy 62.218062 -438.837324) (xy 62.205967 -438.836924) (xy 62.182959 -438.829453) (xy 62.163377 -438.81525)
			(xy 62.149129 -438.795701) (xy 62.141604 -438.77271) (xy 62.1411 -438.760616) (xy 61.234828 -438.760616)
			(xy 61.234828 -439.760614) (xy 64.141096 -439.760614) (xy 64.141096 -439.033666) (xy 64.141404 -439.024833)
			(xy 64.1455 -439.007645) (xy 64.149224 -438.99963) (xy 64.38265 -438.52338) (xy 64.387351 -438.512864)
			(xy 64.390838 -438.490105) (xy 64.387354 -438.467347) (xy 64.38265 -438.456832) (xy 64.149224 -437.980582)
			(xy 64.145463 -437.972579) (xy 64.14135 -437.955385) (xy 64.141096 -437.946546) (xy 64.141096 -437.21909)
			(xy 64.141603 -437.206979) (xy 64.149088 -437.183943) (xy 64.163322 -437.164345) (xy 64.182914 -437.150102)
			(xy 64.205947 -437.142608) (xy 64.218058 -437.142128) (xy 65.157858 -437.142128) (xy 65.169978 -437.142595)
			(xy 65.193033 -437.150075) (xy 65.212648 -437.164315) (xy 65.226901 -437.18392) (xy 65.234396 -437.206971)
			(xy 65.23482 -437.21909) (xy 65.23482 -438.760616) (xy 66.141092 -438.760616) (xy 66.141092 -438.033668)
			(xy 66.141401 -438.024835) (xy 66.145497 -438.007647) (xy 66.14922 -437.999632) (xy 66.382646 -437.523382)
			(xy 66.387346 -437.512865) (xy 66.390834 -437.490107) (xy 66.38735 -437.467349) (xy 66.382646 -437.456834)
			(xy 66.14922 -436.980584) (xy 66.145459 -436.97258) (xy 66.141346 -436.955387) (xy 66.141092 -436.946548)
			(xy 66.141092 -436.219092) (xy 66.141509 -436.206983) (xy 66.14901 -436.183957) (xy 66.163272 -436.164385)
			(xy 66.182892 -436.15019) (xy 66.205944 -436.142768) (xy 66.218054 -436.142384) (xy 67.157854 -436.142384)
			(xy 67.169946 -436.142847) (xy 67.192952 -436.150297) (xy 67.207276 -436.160672) (xy 68.141088 -436.160672)
			(xy 68.141088 -435.433724) (xy 68.141383 -435.42489) (xy 68.145488 -435.407702) (xy 68.149216 -435.399688)
			(xy 68.382642 -434.923438) (xy 68.387372 -434.912933) (xy 68.390849 -434.890167) (xy 68.387353 -434.867405)
			(xy 68.382642 -434.85689) (xy 68.149216 -434.38064) (xy 68.145441 -434.372642) (xy 68.141337 -434.355444)
			(xy 68.141088 -434.346604) (xy 68.141088 -433.619148) (xy 68.141557 -433.607043) (xy 68.149042 -433.584019)
			(xy 68.16329 -433.564446) (xy 68.1829 -433.55025) (xy 68.205944 -433.542826) (xy 68.21805 -433.54244)
			(xy 69.15785 -433.54244) (xy 69.169937 -433.54295) (xy 69.192936 -433.550393) (xy 69.212517 -433.564568)
			(xy 69.226769 -433.584093) (xy 69.234302 -433.607063) (xy 69.234812 -433.619148) (xy 69.234812 -435.160674)
			(xy 70.141084 -435.160674) (xy 70.141084 -434.433726) (xy 70.14138 -434.424892) (xy 70.145485 -434.407704)
			(xy 70.149212 -434.39969) (xy 70.382638 -433.92344) (xy 70.387367 -433.912935) (xy 70.390845 -433.890169)
			(xy 70.387349 -433.867407) (xy 70.382638 -433.856892) (xy 70.149212 -433.380642) (xy 70.145438 -433.372644)
			(xy 70.141333 -433.355446) (xy 70.141084 -433.346606) (xy 70.141084 -432.61915) (xy 70.14147 -432.607028)
			(xy 70.148976 -432.583976) (xy 70.163239 -432.564371) (xy 70.182862 -432.550133) (xy 70.205924 -432.542655)
			(xy 70.218046 -432.542188) (xy 71.157846 -432.542188) (xy 71.169958 -432.542672) (xy 71.192994 -432.550166)
			(xy 71.207183 -432.560476) (xy 72.14108 -432.560476) (xy 72.14108 -430.018952) (xy 72.141475 -430.006843)
			(xy 72.148986 -429.983817) (xy 72.163253 -429.964247) (xy 72.182877 -429.950053) (xy 72.205931 -429.94263)
			(xy 72.218042 -429.942244) (xy 73.157842 -429.942244) (xy 73.169934 -429.942672) (xy 73.192937 -429.95014)
			(xy 73.212516 -429.964337) (xy 73.226765 -429.983879) (xy 73.234296 -430.006861) (xy 73.234804 -430.018952)
			(xy 73.234804 -431.560478) (xy 75.141328 -431.560478) (xy 75.141328 -429.018954) (xy 75.141768 -429.006863)
			(xy 75.149236 -428.983863) (xy 75.16343 -428.964285) (xy 75.182968 -428.950036) (xy 75.205947 -428.942503)
			(xy 75.218036 -428.941992) (xy 76.157836 -428.941992) (xy 76.169946 -428.942386) (xy 76.192973 -428.949894)
			(xy 76.207568 -428.960534) (xy 77.141324 -428.960534) (xy 77.141324 -426.41901) (xy 77.141816 -426.406923)
			(xy 77.149268 -426.383925) (xy 77.163449 -426.364346) (xy 77.182976 -426.350095) (xy 77.205946 -426.34256)
			(xy 77.218032 -426.342048) (xy 78.157832 -426.342048) (xy 78.169937 -426.342488) (xy 78.192957 -426.34999)
			(xy 78.212525 -426.364248) (xy 78.22672 -426.38386) (xy 78.234149 -426.406903) (xy 78.23454 -426.41901)
			(xy 78.23454 -427.960536) (xy 79.14132 -427.960536) (xy 79.14132 -425.419012) (xy 79.141724 -425.406927)
			(xy 79.149191 -425.38394) (xy 79.163399 -425.364387) (xy 79.182954 -425.350184) (xy 79.205943 -425.342721)
			(xy 79.218028 -425.342304) (xy 80.157828 -425.342304) (xy 80.169905 -425.34274) (xy 80.192875 -425.350212)
			(xy 80.212413 -425.364415) (xy 80.226606 -425.38396) (xy 80.234066 -425.406935) (xy 80.234536 -425.419012)
			(xy 80.234536 -427.960536) (xy 80.234067 -427.97261) (xy 80.226598 -427.995573) (xy 80.212402 -428.015107)
			(xy 80.192866 -428.029302) (xy 80.169902 -428.036768) (xy 80.157828 -428.037244) (xy 79.218028 -428.037244)
			(xy 79.205958 -428.036713) (xy 79.182998 -428.029262) (xy 79.163464 -428.015082) (xy 79.149267 -427.995559)
			(xy 79.141797 -427.972605) (xy 79.14132 -427.960536) (xy 78.23454 -427.960536) (xy 78.23454 -428.960534)
			(xy 78.234121 -428.972627) (xy 78.226653 -428.995632) (xy 78.212454 -429.015214) (xy 78.19291 -429.029462)
			(xy 78.169924 -429.03699) (xy 78.157832 -429.037496) (xy 77.218032 -429.037496) (xy 77.205924 -429.037056)
			(xy 77.182898 -429.029565) (xy 77.163324 -429.01531) (xy 77.149128 -428.995692) (xy 77.141707 -428.972643)
			(xy 77.141324 -428.960534) (xy 76.207568 -428.960534) (xy 76.212545 -428.964162) (xy 76.226738 -428.983787)
			(xy 76.23416 -429.006843) (xy 76.234544 -429.018954) (xy 76.234544 -431.560478) (xy 76.234074 -431.572568)
			(xy 76.226621 -431.595571) (xy 76.212436 -431.615152) (xy 76.192902 -431.629403) (xy 76.169924 -431.636933)
			(xy 76.157836 -431.63744) (xy 75.218036 -431.63744) (xy 75.205933 -431.636953) (xy 75.182914 -431.629469)
			(xy 75.163344 -431.615224) (xy 75.149146 -431.595619) (xy 75.141718 -431.572582) (xy 75.141328 -431.560478)
			(xy 73.234804 -431.560478) (xy 73.234804 -432.560476) (xy 73.234363 -432.572583) (xy 73.226871 -432.595609)
			(xy 73.212615 -432.615182) (xy 73.192999 -432.629378) (xy 73.16995 -432.6368) (xy 73.157842 -432.637184)
			(xy 72.218042 -432.637184) (xy 72.205957 -432.636657) (xy 72.182962 -432.629215) (xy 72.163383 -432.615043)
			(xy 72.14913 -432.595523) (xy 72.141593 -432.572559) (xy 72.14108 -432.560476) (xy 71.207183 -432.560476)
			(xy 71.212591 -432.564406) (xy 71.226833 -432.584002) (xy 71.234328 -432.607038) (xy 71.234808 -432.61915)
			(xy 71.234808 -435.160674) (xy 71.234267 -435.172783) (xy 71.226792 -435.195817) (xy 71.212567 -435.215415)
			(xy 71.192982 -435.229659) (xy 71.169954 -435.237155) (xy 71.157846 -435.237636) (xy 70.218046 -435.237636)
			(xy 70.205923 -435.237201) (xy 70.182861 -435.229718) (xy 70.163243 -435.215471) (xy 70.148991 -435.195857)
			(xy 70.141503 -435.172797) (xy 70.141084 -435.160674) (xy 69.234812 -435.160674) (xy 69.234812 -436.160672)
			(xy 69.23436 -436.172778) (xy 69.22687 -436.195802) (xy 69.212617 -436.215375) (xy 69.193003 -436.229571)
			(xy 69.169957 -436.236994) (xy 69.15785 -436.23738) (xy 68.21805 -436.23738) (xy 68.205965 -436.23685)
			(xy 68.182969 -436.22941) (xy 68.16339 -436.215239) (xy 68.149137 -436.195719) (xy 68.141601 -436.172755)
			(xy 68.141088 -436.160672) (xy 67.207276 -436.160672) (xy 67.212537 -436.164483) (xy 67.226787 -436.18402)
			(xy 67.234312 -436.207002) (xy 67.234816 -436.219092) (xy 67.234816 -438.760616) (xy 67.234398 -438.772724)
			(xy 67.226896 -438.795749) (xy 67.212634 -438.815321) (xy 67.193014 -438.829515) (xy 67.169963 -438.836939)
			(xy 67.157854 -438.837324) (xy 66.218054 -438.837324) (xy 66.205958 -438.836931) (xy 66.18295 -438.829457)
			(xy 66.163368 -438.815253) (xy 66.14912 -438.795702) (xy 66.141596 -438.77271) (xy 66.141092 -438.760616)
			(xy 65.23482 -438.760616) (xy 65.23482 -439.760614) (xy 68.141088 -439.760614) (xy 68.141088 -439.033666)
			(xy 68.141397 -439.024833) (xy 68.145493 -439.007645) (xy 68.149216 -438.99963) (xy 68.382642 -438.52338)
			(xy 68.387343 -438.512864) (xy 68.390831 -438.490105) (xy 68.387346 -438.467347) (xy 68.382642 -438.456832)
			(xy 68.149216 -437.980582) (xy 68.145455 -437.972579) (xy 68.141342 -437.955385) (xy 68.141088 -437.946546)
			(xy 68.141088 -437.21909) (xy 68.141603 -437.20698) (xy 68.149087 -437.183945) (xy 68.163319 -437.164348)
			(xy 68.182909 -437.150105) (xy 68.20594 -437.142609) (xy 68.21805 -437.142128) (xy 69.15785 -437.142128)
			(xy 69.169966 -437.142569) (xy 69.193009 -437.150069) (xy 69.212609 -437.164319) (xy 69.22685 -437.183927)
			(xy 69.234337 -437.206974) (xy 69.234812 -437.21909) (xy 69.234812 -438.760616) (xy 70.141084 -438.760616)
			(xy 70.141084 -438.033668) (xy 70.141394 -438.024835) (xy 70.145489 -438.007647) (xy 70.149212 -437.999632)
			(xy 70.382638 -437.523382) (xy 70.387338 -437.512865) (xy 70.390826 -437.490107) (xy 70.387342 -437.467349)
			(xy 70.382638 -437.456834) (xy 70.149212 -436.980584) (xy 70.145451 -436.972581) (xy 70.141338 -436.955387)
			(xy 70.141084 -436.946548) (xy 70.141084 -436.219092) (xy 70.141509 -436.206984) (xy 70.149009 -436.183959)
			(xy 70.163269 -436.164388) (xy 70.182887 -436.150193) (xy 70.205937 -436.142769) (xy 70.218046 -436.142384)
			(xy 71.157846 -436.142384) (xy 71.169942 -436.142769) (xy 71.192952 -436.150244) (xy 71.207327 -436.160672)
			(xy 72.14108 -436.160672) (xy 72.14108 -435.433724) (xy 72.141376 -435.42489) (xy 72.145481 -435.407702)
			(xy 72.149208 -435.399688) (xy 72.382634 -434.923438) (xy 72.387365 -434.912933) (xy 72.390842 -434.890167)
			(xy 72.387345 -434.867405) (xy 72.382634 -434.85689) (xy 72.149208 -434.38064) (xy 72.145433 -434.372643)
			(xy 72.141329 -434.355444) (xy 72.14108 -434.346604) (xy 72.14108 -433.619148) (xy 72.141557 -433.607044)
			(xy 72.149041 -433.584021) (xy 72.163287 -433.564449) (xy 72.182895 -433.550252) (xy 72.205937 -433.542827)
			(xy 72.218042 -433.54244) (xy 73.157842 -433.54244) (xy 73.169934 -433.542872) (xy 73.192936 -433.55034)
			(xy 73.212515 -433.564536) (xy 73.226764 -433.584076) (xy 73.234295 -433.607058) (xy 73.234804 -433.619148)
			(xy 73.234804 -435.160674) (xy 75.141328 -435.160674) (xy 75.141328 -434.433726) (xy 75.141554 -434.424905)
			(xy 75.145536 -434.407717) (xy 75.149202 -434.39969) (xy 75.382628 -433.92344) (xy 75.387358 -433.912935)
			(xy 75.390836 -433.890169) (xy 75.387339 -433.867407) (xy 75.382628 -433.856892) (xy 75.149202 -433.380642)
			(xy 75.145531 -433.372616) (xy 75.141546 -433.355429) (xy 75.141328 -433.346606) (xy 75.141328 -432.61915)
			(xy 75.14185 -432.607064) (xy 75.149291 -432.584067) (xy 75.163464 -432.564487) (xy 75.182986 -432.550235)
			(xy 75.205952 -432.542699) (xy 75.218036 -432.542188) (xy 76.157836 -432.542188) (xy 76.169946 -432.542586)
			(xy 76.192972 -432.550093) (xy 76.207215 -432.560476) (xy 77.141324 -432.560476) (xy 77.141324 -430.018952)
			(xy 77.141724 -430.006872) (xy 77.149203 -429.983898) (xy 77.163415 -429.964358) (xy 77.182969 -429.950167)
			(xy 77.205951 -429.942711) (xy 77.218032 -429.942244) (xy 78.157832 -429.942244) (xy 78.169903 -429.942736)
			(xy 78.192864 -429.950201) (xy 78.212396 -429.964393) (xy 78.226591 -429.983922) (xy 78.234062 -430.006881)
			(xy 78.23454 -430.018952) (xy 78.23454 -431.560478) (xy 79.14132 -431.560478) (xy 79.14132 -429.018954)
			(xy 79.141768 -429.006864) (xy 79.149235 -428.983865) (xy 79.163427 -428.964288) (xy 79.182963 -428.950038)
			(xy 79.205939 -428.942504) (xy 79.218028 -428.941992) (xy 80.157828 -428.941992) (xy 80.169938 -428.942392)
			(xy 80.192964 -428.949899) (xy 80.207555 -428.960534) (xy 81.141316 -428.960534) (xy 81.141316 -426.41901)
			(xy 81.141816 -426.406923) (xy 81.149267 -426.383927) (xy 81.163446 -426.364349) (xy 81.182971 -426.350097)
			(xy 81.205939 -426.342561) (xy 81.218024 -426.342048) (xy 82.157824 -426.342048) (xy 82.169929 -426.342495)
			(xy 82.192948 -426.349995) (xy 82.212516 -426.36425) (xy 82.226712 -426.383862) (xy 82.234141 -426.406904)
			(xy 82.234532 -426.41901) (xy 82.234532 -427.960536) (xy 83.141312 -427.960536) (xy 83.141312 -425.419012)
			(xy 83.141723 -425.406928) (xy 83.14919 -425.383942) (xy 83.163396 -425.36439) (xy 83.182949 -425.350186)
			(xy 83.205936 -425.342722) (xy 83.21802 -425.342304) (xy 84.15782 -425.342304) (xy 84.169897 -425.342748)
			(xy 84.192867 -425.350217) (xy 84.212404 -425.364419) (xy 84.226598 -425.383962) (xy 84.234057 -425.406935)
			(xy 84.234528 -425.419012) (xy 84.234528 -427.960536) (xy 84.234067 -427.97261) (xy 84.226597 -427.995576)
			(xy 84.212399 -428.01511) (xy 84.192861 -428.029304) (xy 84.169895 -428.036769) (xy 84.15782 -428.037244)
			(xy 83.21802 -428.037244) (xy 83.20595 -428.036719) (xy 83.18299 -428.029267) (xy 83.163455 -428.015085)
			(xy 83.149259 -427.995561) (xy 83.141789 -427.972606) (xy 83.141312 -427.960536) (xy 82.234532 -427.960536)
			(xy 82.234532 -428.960534) (xy 82.234121 -428.972628) (xy 82.226652 -428.995635) (xy 82.212452 -429.015216)
			(xy 82.192905 -429.029465) (xy 82.169917 -429.036991) (xy 82.157824 -429.037496) (xy 81.218024 -429.037496)
			(xy 81.205916 -429.037063) (xy 81.182889 -429.02957) (xy 81.163315 -429.015313) (xy 81.14912 -428.995694)
			(xy 81.141699 -428.972643) (xy 81.141316 -428.960534) (xy 80.207555 -428.960534) (xy 80.212536 -428.964165)
			(xy 80.22673 -428.983789) (xy 80.234152 -429.006843) (xy 80.234536 -429.018954) (xy 80.234536 -431.560478)
			(xy 80.234073 -431.572569) (xy 80.22662 -431.595573) (xy 80.212433 -431.615155) (xy 80.192897 -431.629405)
			(xy 80.169917 -431.636934) (xy 80.157828 -431.63744) (xy 79.218028 -431.63744) (xy 79.205925 -431.63696)
			(xy 79.182905 -431.629473) (xy 79.163335 -431.615227) (xy 79.149138 -431.595621) (xy 79.141709 -431.572582)
			(xy 79.14132 -431.560478) (xy 78.23454 -431.560478) (xy 78.23454 -432.560476) (xy 78.234016 -432.572546)
			(xy 78.226564 -432.595507) (xy 78.212382 -432.615042) (xy 78.192857 -432.629238) (xy 78.169902 -432.636707)
			(xy 78.157832 -432.637184) (xy 77.218032 -432.637184) (xy 77.205949 -432.63676) (xy 77.182963 -432.629298)
			(xy 77.16341 -432.615096) (xy 77.149206 -432.595544) (xy 77.141742 -432.572559) (xy 77.141324 -432.560476)
			(xy 76.207215 -432.560476) (xy 76.212543 -432.56436) (xy 76.226737 -432.583985) (xy 76.234159 -432.607039)
			(xy 76.234544 -432.61915) (xy 76.234544 -435.160674) (xy 76.23407 -435.172764) (xy 76.226619 -435.195766)
			(xy 76.212434 -435.215348) (xy 76.192901 -435.229599) (xy 76.169924 -435.237129) (xy 76.157836 -435.237636)
			(xy 75.218036 -435.237636) (xy 75.205933 -435.237153) (xy 75.182913 -435.229668) (xy 75.163342 -435.215423)
			(xy 75.149145 -435.195817) (xy 75.141717 -435.172778) (xy 75.141328 -435.160674) (xy 73.234804 -435.160674)
			(xy 73.234804 -436.160672) (xy 73.23436 -436.172779) (xy 73.226869 -436.195805) (xy 73.212614 -436.215378)
			(xy 73.192998 -436.229574) (xy 73.16995 -436.236996) (xy 73.157842 -436.23738) (xy 72.218042 -436.23738)
			(xy 72.205957 -436.236857) (xy 72.182961 -436.229415) (xy 72.163382 -436.215242) (xy 72.149129 -436.195721)
			(xy 72.141593 -436.172755) (xy 72.14108 -436.160672) (xy 71.207327 -436.160672) (xy 71.212535 -436.16445)
			(xy 71.226782 -436.184003) (xy 71.234305 -436.206997) (xy 71.234808 -436.219092) (xy 71.234808 -438.760616)
			(xy 71.234398 -438.772725) (xy 71.226895 -438.795751) (xy 71.212631 -438.815324) (xy 71.193009 -438.829518)
			(xy 71.169956 -438.83694) (xy 71.157846 -438.837324) (xy 70.218046 -438.837324) (xy 70.205955 -438.836853)
			(xy 70.18295 -438.829404) (xy 70.163366 -438.81522) (xy 70.149115 -438.795685) (xy 70.141589 -438.772705)
			(xy 70.141084 -438.760616) (xy 69.234812 -438.760616) (xy 69.234812 -439.760614) (xy 72.14108 -439.760614)
			(xy 72.14108 -439.033666) (xy 72.14139 -439.024833) (xy 72.145485 -439.007645) (xy 72.149208 -438.99963)
			(xy 72.382634 -438.52338) (xy 72.387336 -438.512864) (xy 72.390824 -438.490105) (xy 72.387339 -438.467347)
			(xy 72.382634 -438.456832) (xy 72.149208 -437.980582) (xy 72.145446 -437.972579) (xy 72.141334 -437.955385)
			(xy 72.14108 -437.946546) (xy 72.14108 -437.21909) (xy 72.141452 -437.206963) (xy 72.148952 -437.183896)
			(xy 72.163215 -437.164278) (xy 72.182843 -437.150029) (xy 72.205914 -437.142544) (xy 72.218042 -437.142128)
			(xy 73.157842 -437.142128) (xy 73.169958 -437.142576) (xy 73.193001 -437.150073) (xy 73.212601 -437.164322)
			(xy 73.226841 -437.183928) (xy 73.234329 -437.206974) (xy 73.234804 -437.21909) (xy 73.234804 -438.760616)
			(xy 75.141328 -438.760616) (xy 75.141328 -438.033668) (xy 75.141567 -438.024847) (xy 75.14554 -438.00766)
			(xy 75.149202 -437.999632) (xy 75.382628 -437.523382) (xy 75.387329 -437.512865) (xy 75.390817 -437.490107)
			(xy 75.387333 -437.467348) (xy 75.382628 -437.456834) (xy 75.149202 -436.980584) (xy 75.145512 -436.972566)
			(xy 75.14154 -436.955372) (xy 75.141328 -436.946548) (xy 75.141328 -436.219092) (xy 75.141706 -436.207005)
			(xy 75.14918 -436.184016) (xy 75.163394 -436.164463) (xy 75.182956 -436.15026) (xy 75.205949 -436.142799)
			(xy 75.218036 -436.142384) (xy 76.157836 -436.142384) (xy 76.169912 -436.142833) (xy 76.192879 -436.150305)
			(xy 76.207142 -436.160672) (xy 77.141324 -436.160672) (xy 77.141324 -435.433724) (xy 77.141549 -435.424903)
			(xy 77.145532 -435.407715) (xy 77.149198 -435.399688) (xy 77.382624 -434.923438) (xy 77.387355 -434.912933)
			(xy 77.390833 -434.890167) (xy 77.387336 -434.867405) (xy 77.382624 -434.85689) (xy 77.149198 -434.38064)
			(xy 77.145526 -434.372614) (xy 77.141542 -434.355427) (xy 77.141324 -434.346604) (xy 77.141324 -433.619148)
			(xy 77.141754 -433.607065) (xy 77.149212 -433.584078) (xy 77.163413 -433.564524) (xy 77.182964 -433.55032)
			(xy 77.205949 -433.542857) (xy 77.218032 -433.54244) (xy 78.157832 -433.54244) (xy 78.169921 -433.542786)
			(xy 78.192913 -433.550268) (xy 78.212467 -433.56449) (xy 78.226668 -433.584059) (xy 78.234126 -433.607058)
			(xy 78.23454 -433.619148) (xy 78.23454 -435.160674) (xy 79.14132 -435.160674) (xy 79.14132 -434.433726)
			(xy 79.141547 -434.424905) (xy 79.145528 -434.407717) (xy 79.149194 -434.39969) (xy 79.38262 -433.92344)
			(xy 79.38735 -433.912935) (xy 79.390829 -433.890169) (xy 79.387332 -433.867407) (xy 79.38262 -433.856892)
			(xy 79.149194 -433.380642) (xy 79.145522 -433.372616) (xy 79.141538 -433.355429) (xy 79.14132 -433.346606)
			(xy 79.14132 -432.61915) (xy 79.14185 -432.607065) (xy 79.14929 -432.584069) (xy 79.163461 -432.56449)
			(xy 79.182981 -432.550237) (xy 79.205945 -432.542701) (xy 79.218028 -432.542188) (xy 80.157828 -432.542188)
			(xy 80.169937 -432.542592) (xy 80.192963 -432.550098) (xy 80.207202 -432.560476) (xy 81.141316 -432.560476)
			(xy 81.141316 -430.018952) (xy 81.141724 -430.006873) (xy 81.149202 -429.9839) (xy 81.163413 -429.964361)
			(xy 81.182964 -429.950169) (xy 81.205944 -429.942712) (xy 81.218024 -429.942244) (xy 82.157824 -429.942244)
			(xy 82.169895 -429.942743) (xy 82.192855 -429.950206) (xy 82.212387 -429.964396) (xy 82.226583 -429.983924)
			(xy 82.234053 -430.006881) (xy 82.234532 -430.018952) (xy 82.234532 -431.560478) (xy 83.141312 -431.560478)
			(xy 83.141312 -429.018954) (xy 83.141768 -429.006865) (xy 83.149234 -428.983867) (xy 83.163424 -428.964291)
			(xy 83.182958 -428.950041) (xy 83.205932 -428.942505) (xy 83.21802 -428.941992) (xy 84.15782 -428.941992)
			(xy 84.169929 -428.942399) (xy 84.192956 -428.949903) (xy 84.207543 -428.960534) (xy 85.141308 -428.960534)
			(xy 85.141308 -426.41901) (xy 85.141815 -426.406924) (xy 85.149265 -426.383929) (xy 85.163443 -426.364352)
			(xy 85.182966 -426.3501) (xy 85.205932 -426.342562) (xy 85.218016 -426.342048) (xy 86.157816 -426.342048)
			(xy 86.169921 -426.342502) (xy 86.192939 -426.349999) (xy 86.212508 -426.364253) (xy 86.226704 -426.383863)
			(xy 86.234133 -426.406904) (xy 86.234524 -426.41901) (xy 86.234524 -427.960536) (xy 87.141304 -427.960536)
			(xy 87.141304 -425.419012) (xy 87.141723 -425.406929) (xy 87.149189 -425.383944) (xy 87.163393 -425.364393)
			(xy 87.182944 -425.350189) (xy 87.205929 -425.342723) (xy 87.218012 -425.342304) (xy 88.157812 -425.342304)
			(xy 88.169888 -425.342754) (xy 88.192858 -425.350222) (xy 88.212396 -425.364421) (xy 88.226589 -425.383964)
			(xy 88.234049 -425.406935) (xy 88.23452 -425.419012) (xy 88.23452 -427.960536) (xy 88.234067 -427.972611)
			(xy 88.226596 -427.995578) (xy 88.212396 -428.015113) (xy 88.192856 -428.029307) (xy 88.169887 -428.036771)
			(xy 88.157812 -428.037244) (xy 87.218012 -428.037244) (xy 87.205942 -428.036726) (xy 87.182981 -428.029271)
			(xy 87.163447 -428.015087) (xy 87.149251 -427.995562) (xy 87.141781 -427.972606) (xy 87.141304 -427.960536)
			(xy 86.234524 -427.960536) (xy 86.234524 -428.960534) (xy 86.234121 -428.972629) (xy 86.226651 -428.995637)
			(xy 86.212449 -429.015219) (xy 86.1929 -429.029467) (xy 86.16991 -429.036992) (xy 86.157816 -429.037496)
			(xy 85.218016 -429.037496) (xy 85.205908 -429.03707) (xy 85.18288 -429.029574) (xy 85.163307 -429.015315)
			(xy 85.149112 -428.995695) (xy 85.141691 -428.972644) (xy 85.141308 -428.960534) (xy 84.207543 -428.960534)
			(xy 84.212528 -428.964167) (xy 84.226722 -428.98379) (xy 84.234144 -429.006843) (xy 84.234528 -429.018954)
			(xy 84.234528 -431.560478) (xy 84.234073 -431.57257) (xy 84.226619 -431.595575) (xy 84.21243 -431.615158)
			(xy 84.192892 -431.629408) (xy 84.16991 -431.636935) (xy 84.15782 -431.63744) (xy 83.21802 -431.63744)
			(xy 83.205916 -431.636967) (xy 83.182896 -431.629478) (xy 83.163327 -431.61523) (xy 83.14913 -431.595622)
			(xy 83.141701 -431.572583) (xy 83.141312 -431.560478) (xy 82.234532 -431.560478) (xy 82.234532 -432.560476)
			(xy 82.234016 -432.572547) (xy 82.226563 -432.595509) (xy 82.212379 -432.615045) (xy 82.192852 -432.629241)
			(xy 82.169895 -432.636708) (xy 82.157824 -432.637184) (xy 81.218024 -432.637184) (xy 81.20594 -432.636766)
			(xy 81.182954 -432.629303) (xy 81.163401 -432.615099) (xy 81.149197 -432.595546) (xy 81.141734 -432.57256)
			(xy 81.141316 -432.560476) (xy 80.207202 -432.560476) (xy 80.212535 -432.564363) (xy 80.226729 -432.583986)
			(xy 80.234151 -432.607039) (xy 80.234536 -432.61915) (xy 80.234536 -435.160674) (xy 80.23407 -435.172765)
			(xy 80.226618 -435.195768) (xy 80.212432 -435.215351) (xy 80.192896 -435.229601) (xy 80.169917 -435.23713)
			(xy 80.157828 -435.237636) (xy 79.218028 -435.237636) (xy 79.205924 -435.23716) (xy 79.182904 -435.229673)
			(xy 79.163334 -435.215425) (xy 79.149137 -435.195818) (xy 79.141709 -435.172779) (xy 79.14132 -435.160674)
			(xy 78.23454 -435.160674) (xy 78.23454 -436.160672) (xy 78.234013 -436.172742) (xy 78.226562 -436.195703)
			(xy 78.21238 -436.215238) (xy 78.192857 -436.229434) (xy 78.169902 -436.236903) (xy 78.157832 -436.23738)
			(xy 77.218032 -436.23738) (xy 77.205948 -436.23696) (xy 77.182962 -436.229497) (xy 77.163409 -436.215294)
			(xy 77.149204 -436.195742) (xy 77.141741 -436.172756) (xy 77.141324 -436.160672) (xy 76.207142 -436.160672)
			(xy 76.212415 -436.164505) (xy 76.226608 -436.184046) (xy 76.234071 -436.207016) (xy 76.234544 -436.219092)
			(xy 76.234544 -438.760616) (xy 76.23405 -438.772688) (xy 76.226587 -438.795649) (xy 76.212397 -438.815183)
			(xy 76.192867 -438.829378) (xy 76.169908 -438.836847) (xy 76.157836 -438.837324) (xy 75.218036 -438.837324)
			(xy 75.205957 -438.836857) (xy 75.182978 -438.829401) (xy 75.163428 -438.815209) (xy 75.149223 -438.795669)
			(xy 75.141751 -438.772695) (xy 75.141328 -438.760616) (xy 73.234804 -438.760616) (xy 73.234804 -439.760614)
			(xy 77.141324 -439.760614) (xy 77.141324 -439.033666) (xy 77.141563 -439.024845) (xy 77.145536 -439.007658)
			(xy 77.149198 -438.99963) (xy 77.382624 -438.52338) (xy 77.387326 -438.512864) (xy 77.390815 -438.490105)
			(xy 77.387329 -438.467346) (xy 77.382624 -438.456832) (xy 77.149198 -437.980582) (xy 77.145508 -437.972564)
			(xy 77.141536 -437.95537) (xy 77.141324 -437.946546) (xy 77.141324 -437.21909) (xy 77.141799 -437.207002)
			(xy 77.149256 -437.184003) (xy 77.163441 -437.164425) (xy 77.182972 -437.150174) (xy 77.205945 -437.14264)
			(xy 77.218032 -437.142128) (xy 78.157832 -437.142128) (xy 78.169945 -437.142489) (xy 78.192978 -437.150001)
			(xy 78.212553 -437.164276) (xy 78.226746 -437.183911) (xy 78.234161 -437.206975) (xy 78.23454 -437.21909)
			(xy 78.23454 -438.760616) (xy 79.14132 -438.760616) (xy 79.14132 -438.033668) (xy 79.14156 -438.024848)
			(xy 79.145533 -438.00766) (xy 79.149194 -437.999632) (xy 79.38262 -437.523382) (xy 79.387321 -437.512865)
			(xy 79.39081 -437.490107) (xy 79.387325 -437.467348) (xy 79.38262 -437.456834) (xy 79.149194 -436.980584)
			(xy 79.145504 -436.972566) (xy 79.141532 -436.955372) (xy 79.14132 -436.946548) (xy 79.14132 -436.219092)
			(xy 79.141706 -436.207006) (xy 79.149179 -436.184018) (xy 79.163391 -436.164466) (xy 79.182951 -436.150263)
			(xy 79.205942 -436.1428) (xy 79.218028 -436.142384) (xy 80.157828 -436.142384) (xy 80.169903 -436.14284)
			(xy 80.19287 -436.150309) (xy 80.207128 -436.160672) (xy 81.141316 -436.160672) (xy 81.141316 -435.433724)
			(xy 81.141542 -435.424903) (xy 81.145524 -435.407715) (xy 81.14919 -435.399688) (xy 81.382616 -434.923438)
			(xy 81.387348 -434.912933) (xy 81.390826 -434.890167) (xy 81.387328 -434.867405) (xy 81.382616 -434.85689)
			(xy 81.14919 -434.38064) (xy 81.145517 -434.372615) (xy 81.141534 -434.355427) (xy 81.141316 -434.346604)
			(xy 81.141316 -433.619148) (xy 81.141754 -433.607065) (xy 81.149211 -433.58408) (xy 81.16341 -433.564527)
			(xy 81.182959 -433.550322) (xy 81.205942 -433.542858) (xy 81.218024 -433.54244) (xy 82.157824 -433.54244)
			(xy 82.169913 -433.542793) (xy 82.192904 -433.550273) (xy 82.212458 -433.564493) (xy 82.22666 -433.58406)
			(xy 82.234118 -433.607059) (xy 82.234532 -433.619148) (xy 82.234532 -435.160674) (xy 83.141312 -435.160674)
			(xy 83.141312 -434.433726) (xy 83.141539 -434.424905) (xy 83.145521 -434.407717) (xy 83.149186 -434.39969)
			(xy 83.382612 -433.92344) (xy 83.387342 -433.912935) (xy 83.390822 -433.890169) (xy 83.387324 -433.867407)
			(xy 83.382612 -433.856892) (xy 83.149186 -433.380642) (xy 83.145514 -433.372616) (xy 83.14153 -433.355429)
			(xy 83.141312 -433.346606) (xy 83.141312 -432.61915) (xy 83.141849 -432.607066) (xy 83.149289 -432.584071)
			(xy 83.163458 -432.564493) (xy 83.182976 -432.55024) (xy 83.205938 -432.542702) (xy 83.21802 -432.542188)
			(xy 84.15782 -432.542188) (xy 84.169929 -432.542599) (xy 84.192955 -432.550103) (xy 84.207188 -432.560476)
			(xy 85.141308 -432.560476) (xy 85.141308 -430.018952) (xy 85.141723 -430.006873) (xy 85.149201 -429.983902)
			(xy 85.16341 -429.964364) (xy 85.182959 -429.950172) (xy 85.205937 -429.942713) (xy 85.218016 -429.942244)
			(xy 86.157816 -429.942244) (xy 86.169887 -429.94275) (xy 86.192846 -429.950211) (xy 86.212379 -429.964399)
			(xy 86.226574 -429.983925) (xy 86.234045 -430.006882) (xy 86.234524 -430.018952) (xy 86.234524 -431.560478)
			(xy 87.141304 -431.560478) (xy 87.141304 -429.018954) (xy 87.141767 -429.006866) (xy 87.149232 -428.98387)
			(xy 87.163421 -428.964293) (xy 87.182953 -428.950043) (xy 87.205925 -428.942506) (xy 87.218012 -428.941992)
			(xy 88.157812 -428.941992) (xy 88.169921 -428.942406) (xy 88.192947 -428.949908) (xy 88.207529 -428.960534)
			(xy 89.1413 -428.960534) (xy 89.1413 -426.41901) (xy 89.141815 -426.406925) (xy 89.149264 -426.383931)
			(xy 89.16344 -426.364355) (xy 89.182961 -426.350103) (xy 89.205925 -426.342563) (xy 89.218008 -426.342048)
			(xy 90.157808 -426.342048) (xy 90.169912 -426.342509) (xy 90.192931 -426.350004) (xy 90.212499 -426.364256)
			(xy 90.226696 -426.383865) (xy 90.234125 -426.406905) (xy 90.234516 -426.41901) (xy 90.234516 -428.960534)
			(xy 90.234121 -428.97263) (xy 90.226649 -428.995639) (xy 90.212446 -429.015222) (xy 90.192895 -429.02947)
			(xy 90.169903 -429.036993) (xy 90.157808 -429.037496) (xy 89.218008 -429.037496) (xy 89.205899 -429.037077)
			(xy 89.182871 -429.029579) (xy 89.163298 -429.015319) (xy 89.149103 -428.995697) (xy 89.141683 -428.972644)
			(xy 89.1413 -428.960534) (xy 88.207529 -428.960534) (xy 88.212519 -428.96417) (xy 88.226714 -428.983792)
			(xy 88.234136 -429.006844) (xy 88.23452 -429.018954) (xy 88.23452 -431.560478) (xy 88.234073 -431.57257)
			(xy 88.226618 -431.595577) (xy 88.212427 -431.615161) (xy 88.192887 -431.629411) (xy 88.169903 -431.636936)
			(xy 88.157812 -431.63744) (xy 87.218012 -431.63744) (xy 87.205908 -431.636974) (xy 87.182888 -431.629483)
			(xy 87.163318 -431.615232) (xy 87.149122 -431.595624) (xy 87.141693 -431.572583) (xy 87.141304 -431.560478)
			(xy 86.234524 -431.560478) (xy 86.234524 -432.560476) (xy 86.234067 -432.572556) (xy 86.226608 -432.595535)
			(xy 86.212413 -432.615084) (xy 86.192871 -432.62929) (xy 86.169896 -432.636761) (xy 86.157816 -432.637184)
			(xy 85.218016 -432.637184) (xy 85.205932 -432.636773) (xy 85.182946 -432.629307) (xy 85.163393 -432.615101)
			(xy 85.149189 -432.595547) (xy 85.141726 -432.57256) (xy 85.141308 -432.560476) (xy 84.207188 -432.560476)
			(xy 84.212526 -432.564366) (xy 84.226721 -432.583988) (xy 84.234143 -432.60704) (xy 84.234528 -432.61915)
			(xy 84.234528 -435.160674) (xy 84.23407 -435.172765) (xy 84.226616 -435.195771) (xy 84.212429 -435.215354)
			(xy 84.192891 -435.229604) (xy 84.16991 -435.237131) (xy 84.15782 -435.237636) (xy 83.21802 -435.237636)
			(xy 83.205916 -435.237167) (xy 83.182895 -435.229677) (xy 83.163325 -435.215428) (xy 83.149129 -435.19582)
			(xy 83.141701 -435.172779) (xy 83.141312 -435.160674) (xy 82.234532 -435.160674) (xy 82.234532 -436.160672)
			(xy 82.234064 -436.172751) (xy 82.226607 -436.195729) (xy 82.212414 -436.215277) (xy 82.192875 -436.229483)
			(xy 82.169903 -436.236956) (xy 82.157824 -436.23738) (xy 81.218024 -436.23738) (xy 81.20594 -436.236966)
			(xy 81.182953 -436.229502) (xy 81.1634 -436.215297) (xy 81.149196 -436.195743) (xy 81.141733 -436.172756)
			(xy 81.141316 -436.160672) (xy 80.207128 -436.160672) (xy 80.212406 -436.164508) (xy 80.2266 -436.184048)
			(xy 80.234063 -436.207017) (xy 80.234536 -436.219092) (xy 80.234536 -438.760616) (xy 80.23405 -438.772689)
			(xy 80.226586 -438.795651) (xy 80.212394 -438.815186) (xy 80.192862 -438.829381) (xy 80.169901 -438.836848)
			(xy 80.157828 -438.837324) (xy 79.218028 -438.837324) (xy 79.205948 -438.836864) (xy 79.182969 -438.829406)
			(xy 79.16342 -438.815211) (xy 79.149214 -438.79567) (xy 79.141743 -438.772695) (xy 79.14132 -438.760616)
			(xy 78.23454 -438.760616) (xy 78.23454 -439.760614) (xy 81.141316 -439.760614) (xy 81.141316 -439.033666)
			(xy 81.141556 -439.024845) (xy 81.145529 -439.007658) (xy 81.14919 -438.99963) (xy 81.382616 -438.52338)
			(xy 81.387319 -438.512864) (xy 81.390808 -438.490105) (xy 81.387322 -438.467346) (xy 81.382616 -438.456832)
			(xy 81.14919 -437.980582) (xy 81.145499 -437.972564) (xy 81.141528 -437.95537) (xy 81.141316 -437.946546)
			(xy 81.141316 -437.21909) (xy 81.141799 -437.207002) (xy 81.149255 -437.184006) (xy 81.163439 -437.164428)
			(xy 81.182967 -437.150177) (xy 81.205938 -437.142641) (xy 81.218024 -437.142128) (xy 82.157824 -437.142128)
			(xy 82.169937 -437.142496) (xy 82.19297 -437.150006) (xy 82.212545 -437.164279) (xy 82.226738 -437.183912)
			(xy 82.234153 -437.206975) (xy 82.234532 -437.21909) (xy 82.234532 -438.760616) (xy 83.141312 -438.760616)
			(xy 83.141312 -438.033668) (xy 83.141553 -438.024848) (xy 83.145525 -438.00766) (xy 83.149186 -437.999632)
			(xy 83.382612 -437.523382) (xy 83.387313 -437.512866) (xy 83.390803 -437.490107) (xy 83.387318 -437.467348)
			(xy 83.382612 -437.456834) (xy 83.149186 -436.980584) (xy 83.145496 -436.972566) (xy 83.141524 -436.955372)
			(xy 83.141312 -436.946548) (xy 83.141312 -436.219092) (xy 83.141706 -436.207007) (xy 83.149178 -436.18402)
			(xy 83.163388 -436.164469) (xy 83.182946 -436.150265) (xy 83.205935 -436.142802) (xy 83.21802 -436.142384)
			(xy 84.15782 -436.142384) (xy 84.169895 -436.142847) (xy 84.192861 -436.150314) (xy 84.207114 -436.160672)
			(xy 85.141308 -436.160672) (xy 85.141308 -435.433724) (xy 85.141535 -435.424903) (xy 85.145517 -435.407715)
			(xy 85.149182 -435.399688) (xy 85.382608 -434.923438) (xy 85.38734 -434.912933) (xy 85.390819 -434.890167)
			(xy 85.387321 -434.867404) (xy 85.382608 -434.85689) (xy 85.149182 -434.38064) (xy 85.145509 -434.372615)
			(xy 85.141526 -434.355427) (xy 85.141308 -434.346604) (xy 85.141308 -433.619148) (xy 85.141754 -433.607066)
			(xy 85.14921 -433.584082) (xy 85.163407 -433.56453) (xy 85.182954 -433.550325) (xy 85.205934 -433.542859)
			(xy 85.218016 -433.54244) (xy 86.157816 -433.54244) (xy 86.169904 -433.5428) (xy 86.192896 -433.550277)
			(xy 86.21245 -433.564496) (xy 86.226652 -433.584062) (xy 86.23411 -433.607059) (xy 86.234524 -433.619148)
			(xy 86.234524 -435.160674) (xy 87.141304 -435.160674) (xy 87.141304 -434.433726) (xy 87.141532 -434.424905)
			(xy 87.145513 -434.407717) (xy 87.149178 -434.39969) (xy 87.382604 -433.92344) (xy 87.387335 -433.912935)
			(xy 87.390814 -433.890169) (xy 87.387316 -433.867406) (xy 87.382604 -433.856892) (xy 87.149178 -433.380642)
			(xy 87.145505 -433.372617) (xy 87.141522 -433.355429) (xy 87.141304 -433.346606) (xy 87.141304 -432.61915)
			(xy 87.141849 -432.607067) (xy 87.149288 -432.584074) (xy 87.163455 -432.564496) (xy 87.182971 -432.550242)
			(xy 87.205931 -432.542703) (xy 87.218012 -432.542188) (xy 88.157812 -432.542188) (xy 88.16992 -432.542606)
			(xy 88.192946 -432.550107) (xy 88.207176 -432.560476) (xy 89.1413 -432.560476) (xy 89.1413 -430.018952)
			(xy 89.141723 -430.006874) (xy 89.1492 -429.983904) (xy 89.163407 -429.964367) (xy 89.182954 -429.950174)
			(xy 89.20593 -429.942714) (xy 89.218008 -429.942244) (xy 90.157808 -429.942244) (xy 90.169878 -429.942757)
			(xy 90.192837 -429.950216) (xy 90.21237 -429.964401) (xy 90.226566 -429.983927) (xy 90.234037 -430.006882)
			(xy 90.234516 -430.018952) (xy 90.234516 -431.360072) (xy 108.40466 -431.360072) (xy 108.405158 -431.275192)
			(xy 108.413115 -431.105619) (xy 108.429011 -430.936605) (xy 108.452812 -430.768522) (xy 108.484466 -430.601739)
			(xy 108.523902 -430.436623) (xy 108.571034 -430.273538) (xy 108.625758 -430.11284) (xy 108.687955 -429.954885)
			(xy 108.757487 -429.800018) (xy 108.834202 -429.648581) (xy 108.91793 -429.500905) (xy 109.008488 -429.357317)
			(xy 109.105677 -429.218131) (xy 109.209284 -429.083654) (xy 109.319079 -428.954181) (xy 109.434823 -428.829996)
			(xy 109.55626 -428.711373) (xy 109.683124 -428.598572) (xy 109.815135 -428.491842) (xy 109.952005 -428.391417)
			(xy 110.09343 -428.297518) (xy 110.239102 -428.21035) (xy 110.3887 -428.130107) (xy 110.541894 -428.056963)
			(xy 110.698348 -427.991081) (xy 110.857718 -427.932604) (xy 111.019654 -427.881662) (xy 111.1838 -427.838366)
			(xy 111.349795 -427.802811) (xy 111.517274 -427.775076) (xy 111.685869 -427.755222) (xy 111.855209 -427.743292)
			(xy 112.024922 -427.739313) (xy 112.194635 -427.743292) (xy 112.363975 -427.755222) (xy 112.53257 -427.775076)
			(xy 112.700049 -427.802811) (xy 112.866044 -427.838366) (xy 113.03019 -427.881662) (xy 113.192126 -427.932604)
			(xy 113.26825 -427.960536) (xy 125.241304 -427.960536) (xy 125.241304 -425.419012) (xy 125.241723 -425.406929)
			(xy 125.249189 -425.383944) (xy 125.263393 -425.364393) (xy 125.282944 -425.350189) (xy 125.305929 -425.342723)
			(xy 125.318012 -425.342304) (xy 126.257812 -425.342304) (xy 126.269888 -425.342754) (xy 126.292858 -425.350222)
			(xy 126.312396 -425.364421) (xy 126.326589 -425.383964) (xy 126.334049 -425.406935) (xy 126.33452 -425.419012)
			(xy 126.33452 -427.960536) (xy 126.334067 -427.972611) (xy 126.326596 -427.995578) (xy 126.312396 -428.015113)
			(xy 126.292856 -428.029307) (xy 126.269887 -428.036771) (xy 126.257812 -428.037244) (xy 125.318012 -428.037244)
			(xy 125.305942 -428.036726) (xy 125.282981 -428.029271) (xy 125.263447 -428.015087) (xy 125.249251 -427.995562)
			(xy 125.241781 -427.972606) (xy 125.241304 -427.960536) (xy 113.26825 -427.960536) (xy 113.351496 -427.991081)
			(xy 113.50795 -428.056963) (xy 113.661144 -428.130107) (xy 113.810742 -428.21035) (xy 113.956414 -428.297518)
			(xy 114.097839 -428.391417) (xy 114.234709 -428.491842) (xy 114.36672 -428.598572) (xy 114.493584 -428.711373)
			(xy 114.615021 -428.829996) (xy 114.730765 -428.954181) (xy 114.84056 -429.083654) (xy 114.944167 -429.218131)
			(xy 115.041356 -429.357317) (xy 115.131914 -429.500905) (xy 115.215642 -429.648581) (xy 115.292357 -429.800018)
			(xy 115.361889 -429.954885) (xy 115.424086 -430.11284) (xy 115.47881 -430.273538) (xy 115.525942 -430.436623)
			(xy 115.565378 -430.601739) (xy 115.597032 -430.768522) (xy 115.620833 -430.936605) (xy 115.636729 -431.105619)
			(xy 115.644686 -431.275192) (xy 115.645184 -431.360072) (xy 115.644698 -431.445674) (xy 115.639256 -431.560732)
			(xy 125.241304 -431.560732) (xy 125.241304 -429.019208) (xy 125.241719 -429.007124) (xy 125.249186 -428.98414)
			(xy 125.263391 -428.964588) (xy 125.282943 -428.950384) (xy 125.305928 -428.942919) (xy 125.318012 -428.9425)
			(xy 126.257812 -428.9425) (xy 126.269888 -428.942954) (xy 126.292857 -428.950421) (xy 126.306772 -428.960534)
			(xy 127.2413 -428.960534) (xy 127.2413 -426.41901) (xy 127.241815 -426.406925) (xy 127.249264 -426.383931)
			(xy 127.26344 -426.364355) (xy 127.282961 -426.350103) (xy 127.305925 -426.342563) (xy 127.318008 -426.342048)
			(xy 128.257808 -426.342048) (xy 128.269912 -426.342509) (xy 128.292931 -426.350004) (xy 128.312499 -426.364256)
			(xy 128.326696 -426.383865) (xy 128.334125 -426.406905) (xy 128.334516 -426.41901) (xy 128.334516 -427.960536)
			(xy 129.241296 -427.960536) (xy 129.241296 -425.419012) (xy 129.241723 -425.40693) (xy 129.249188 -425.383947)
			(xy 129.26339 -425.364396) (xy 129.282939 -425.350191) (xy 129.305922 -425.342724) (xy 129.318004 -425.342304)
			(xy 130.257804 -425.342304) (xy 130.269888 -425.342709) (xy 130.292873 -425.350179) (xy 130.312424 -425.364387)
			(xy 130.326628 -425.383941) (xy 130.334093 -425.406928) (xy 130.334512 -425.419012) (xy 130.334512 -427.960536)
			(xy 130.334067 -427.972612) (xy 130.326595 -427.99558) (xy 130.312393 -428.015116) (xy 130.292851 -428.029309)
			(xy 130.26988 -428.036772) (xy 130.257804 -428.037244) (xy 129.318004 -428.037244) (xy 129.305933 -428.036733)
			(xy 129.282972 -428.029276) (xy 129.263438 -428.01509) (xy 129.249242 -427.995564) (xy 129.241773 -427.972607)
			(xy 129.241296 -427.960536) (xy 128.334516 -427.960536) (xy 128.334516 -428.960534) (xy 128.334121 -428.97263)
			(xy 128.326649 -428.995639) (xy 128.312446 -429.015222) (xy 128.292895 -429.02947) (xy 128.269903 -429.036993)
			(xy 128.257808 -429.037496) (xy 127.318008 -429.037496) (xy 127.305899 -429.037077) (xy 127.282871 -429.029579)
			(xy 127.263298 -429.015319) (xy 127.249103 -428.995697) (xy 127.241683 -428.972644) (xy 127.2413 -428.960534)
			(xy 126.306772 -428.960534) (xy 126.312394 -428.96462) (xy 126.326588 -428.984161) (xy 126.334049 -429.007132)
			(xy 126.33452 -429.019208) (xy 126.33452 -431.560732) (xy 126.334063 -431.572807) (xy 126.326594 -431.595773)
			(xy 126.312395 -431.615309) (xy 126.292855 -431.629503) (xy 126.269887 -431.636967) (xy 126.257812 -431.63744)
			(xy 125.318012 -431.63744) (xy 125.305941 -431.636926) (xy 125.28298 -431.629471) (xy 125.263445 -431.615286)
			(xy 125.249249 -431.59576) (xy 125.241781 -431.572802) (xy 125.241304 -431.560732) (xy 115.639256 -431.560732)
			(xy 115.63661 -431.616688) (xy 115.620446 -431.787128) (xy 115.596243 -431.956613) (xy 115.564055 -432.124765)
			(xy 115.523953 -432.291207) (xy 115.476027 -432.455567) (xy 115.420385 -432.617477) (xy 115.35715 -432.776576)
			(xy 115.286464 -432.932508) (xy 115.208486 -433.084923) (xy 115.12339 -433.233482) (xy 115.031365 -433.377851)
			(xy 114.932619 -433.517709) (xy 114.82737 -433.652742) (xy 114.715856 -433.782648) (xy 114.598325 -433.907137)
			(xy 114.47504 -434.02593) (xy 114.346277 -434.138763) (xy 114.212324 -434.245381) (xy 114.07348 -434.345548)
			(xy 113.930056 -434.439039) (xy 113.782372 -434.525645) (xy 113.630759 -434.605172) (xy 113.475556 -434.677443)
			(xy 113.396522 -434.710332) (xy 113.388621 -434.713964) (xy 113.375731 -434.725623) (xy 113.367472 -434.740915)
			(xy 113.365788 -434.749448) (xy 113.35004 -434.849016) (xy 113.359438 -434.873654) (xy 113.369852 -434.88229)
			(xy 113.419298 -434.924299) (xy 113.513487 -435.013553) (xy 113.601975 -435.108462) (xy 113.644936 -435.160674)
			(xy 125.241304 -435.160674) (xy 125.241304 -434.433726) (xy 125.241532 -434.424905) (xy 125.245513 -434.407717)
			(xy 125.249178 -434.39969) (xy 125.482604 -433.92344) (xy 125.487335 -433.912935) (xy 125.490814 -433.890169)
			(xy 125.487316 -433.867406) (xy 125.482604 -433.856892) (xy 125.249178 -433.380642) (xy 125.245505 -433.372617)
			(xy 125.241522 -433.355429) (xy 125.241304 -433.346606) (xy 125.241304 -432.61915) (xy 125.241849 -432.607067)
			(xy 125.249288 -432.584074) (xy 125.263455 -432.564496) (xy 125.282971 -432.550242) (xy 125.305931 -432.542703)
			(xy 125.318012 -432.542188) (xy 126.257812 -432.542188) (xy 126.26992 -432.542606) (xy 126.292946 -432.550107)
			(xy 126.307524 -432.56073) (xy 127.2413 -432.56073) (xy 127.2413 -430.019206) (xy 127.241812 -430.007121)
			(xy 127.249262 -429.984127) (xy 127.263439 -429.964551) (xy 127.28296 -429.950298) (xy 127.305925 -429.942759)
			(xy 127.318008 -429.942244) (xy 128.257808 -429.942244) (xy 128.269912 -429.942709) (xy 128.29293 -429.950203)
			(xy 128.312498 -429.964455) (xy 128.326694 -429.984062) (xy 128.334125 -430.007101) (xy 128.334516 -430.019206)
			(xy 128.334516 -431.560732) (xy 129.241296 -431.560732) (xy 129.241296 -429.019208) (xy 129.241719 -429.007125)
			(xy 129.249185 -428.984142) (xy 129.263388 -428.964591) (xy 129.282938 -428.950387) (xy 129.305921 -428.94292)
			(xy 129.318004 -428.9425) (xy 130.257804 -428.9425) (xy 130.269888 -428.942909) (xy 130.292872 -428.950379)
			(xy 130.306847 -428.960534) (xy 131.241292 -428.960534) (xy 131.241292 -426.41901) (xy 131.241815 -426.406926)
			(xy 131.249263 -426.383934) (xy 131.263437 -426.364358) (xy 131.282956 -426.350105) (xy 131.305918 -426.342564)
			(xy 131.318 -426.342048) (xy 132.2578 -426.342048) (xy 132.269904 -426.342515) (xy 132.292922 -426.350009)
			(xy 132.312491 -426.364259) (xy 132.326687 -426.383866) (xy 132.334117 -426.406905) (xy 132.334508 -426.41901)
			(xy 132.334508 -427.960536) (xy 133.241288 -427.960536) (xy 133.241288 -425.419012) (xy 133.241723 -425.40693)
			(xy 133.249187 -425.383949) (xy 133.263387 -425.364399) (xy 133.282934 -425.350194) (xy 133.305914 -425.342726)
			(xy 133.317996 -425.342304) (xy 134.257796 -425.342304) (xy 134.26988 -425.342716) (xy 134.292864 -425.350184)
			(xy 134.312416 -425.36439) (xy 134.32662 -425.383943) (xy 134.334085 -425.406928) (xy 134.334504 -425.419012)
			(xy 134.334504 -427.960536) (xy 134.334067 -427.972613) (xy 134.326594 -427.995582) (xy 134.31239 -428.015119)
			(xy 134.292846 -428.029312) (xy 134.269873 -428.036773) (xy 134.257796 -428.037244) (xy 133.317996 -428.037244)
			(xy 133.305925 -428.03674) (xy 133.282964 -428.02928) (xy 133.26343 -428.015093) (xy 133.249234 -427.995565)
			(xy 133.241765 -427.972607) (xy 133.241288 -427.960536) (xy 132.334508 -427.960536) (xy 132.334508 -428.960534)
			(xy 132.334023 -428.972621) (xy 132.326562 -428.995614) (xy 132.312379 -429.01519) (xy 132.292853 -429.029441)
			(xy 132.269885 -429.03698) (xy 132.2578 -429.037496) (xy 131.318 -429.037496) (xy 131.305891 -429.037084)
			(xy 131.282863 -429.029584) (xy 131.263289 -429.015321) (xy 131.249095 -428.995699) (xy 131.241675 -428.972645)
			(xy 131.241292 -428.960534) (xy 130.306847 -428.960534) (xy 130.312423 -428.964586) (xy 130.326627 -428.984139)
			(xy 130.334093 -429.007124) (xy 130.334512 -429.019208) (xy 130.334512 -431.560732) (xy 130.334063 -431.572808)
			(xy 130.326592 -431.595775) (xy 130.312392 -431.615312) (xy 130.29285 -431.629505) (xy 130.26988 -431.636968)
			(xy 130.257804 -431.63744) (xy 129.318004 -431.63744) (xy 129.305933 -431.636933) (xy 129.282971 -431.629475)
			(xy 129.263437 -431.615289) (xy 129.249241 -431.595761) (xy 129.241773 -431.572803) (xy 129.241296 -431.560732)
			(xy 128.334516 -431.560732) (xy 128.334516 -432.56073) (xy 128.334117 -432.572826) (xy 128.326647 -432.595835)
			(xy 128.312444 -432.615418) (xy 128.292894 -432.629666) (xy 128.269902 -432.637189) (xy 128.257808 -432.637692)
			(xy 127.318008 -432.637692) (xy 127.305899 -432.637277) (xy 127.28287 -432.629779) (xy 127.263296 -432.615517)
			(xy 127.249102 -432.595895) (xy 127.241682 -432.572841) (xy 127.2413 -432.56073) (xy 126.307524 -432.56073)
			(xy 126.312518 -432.564369) (xy 126.326713 -432.583989) (xy 126.334135 -432.60704) (xy 126.33452 -432.61915)
			(xy 126.33452 -435.160674) (xy 126.33407 -435.172766) (xy 126.326615 -435.195773) (xy 126.312426 -435.215356)
			(xy 126.292886 -435.229606) (xy 126.269903 -435.237132) (xy 126.257812 -435.237636) (xy 125.318012 -435.237636)
			(xy 125.305907 -435.237174) (xy 125.282887 -435.229682) (xy 125.263317 -435.215431) (xy 125.24912 -435.195821)
			(xy 125.241693 -435.17278) (xy 125.241304 -435.160674) (xy 113.644936 -435.160674) (xy 113.684422 -435.208663)
			(xy 113.760513 -435.313772) (xy 113.829956 -435.423387) (xy 113.892486 -435.537087) (xy 113.947862 -435.654438)
			(xy 113.995874 -435.77499) (xy 114.036336 -435.89828) (xy 114.069094 -436.023838) (xy 114.094022 -436.151181)
			(xy 114.111025 -436.279823) (xy 114.120038 -436.40927) (xy 114.121027 -436.539027) (xy 114.113986 -436.668596)
			(xy 114.098945 -436.797482) (xy 114.075959 -436.92519) (xy 114.045118 -437.051232) (xy 114.006538 -437.175125)
			(xy 113.960369 -437.296394) (xy 113.906786 -437.414574) (xy 113.845996 -437.529214) (xy 113.77823 -437.639874)
			(xy 113.703749 -437.74613) (xy 113.622838 -437.847575) (xy 113.535806 -437.943821) (xy 113.442988 -438.034499)
			(xy 113.344738 -438.119261) (xy 113.241432 -438.197784) (xy 113.133467 -438.269766) (xy 113.021257 -438.334931)
			(xy 112.90523 -438.39303) (xy 112.785831 -438.443841) (xy 112.663518 -438.487169) (xy 112.538759 -438.522847)
			(xy 112.412032 -438.550739) (xy 112.283822 -438.570739) (xy 112.15462 -438.58277) (xy 112.024922 -438.586785)
			(xy 111.895224 -438.58277) (xy 111.766022 -438.570739) (xy 111.637812 -438.550739) (xy 111.511085 -438.522847)
			(xy 111.386326 -438.487169) (xy 111.264013 -438.443841) (xy 111.144614 -438.39303) (xy 111.028587 -438.334931)
			(xy 110.916377 -438.269766) (xy 110.808412 -438.197784) (xy 110.705106 -438.119261) (xy 110.606856 -438.034499)
			(xy 110.514038 -437.943821) (xy 110.427006 -437.847575) (xy 110.346095 -437.74613) (xy 110.271614 -437.639874)
			(xy 110.203848 -437.529214) (xy 110.143058 -437.414574) (xy 110.089475 -437.296394) (xy 110.043306 -437.175125)
			(xy 110.004726 -437.051232) (xy 109.973885 -436.92519) (xy 109.950899 -436.797482) (xy 109.935858 -436.668596)
			(xy 109.928817 -436.539027) (xy 109.929806 -436.40927) (xy 109.938819 -436.279823) (xy 109.955822 -436.151181)
			(xy 109.98075 -436.023838) (xy 110.013508 -435.89828) (xy 110.05397 -435.77499) (xy 110.101982 -435.654438)
			(xy 110.157358 -435.537087) (xy 110.219888 -435.423387) (xy 110.289331 -435.313772) (xy 110.365422 -435.208663)
			(xy 110.447869 -435.108462) (xy 110.536357 -435.013553) (xy 110.630546 -434.924299) (xy 110.679992 -434.88229)
			(xy 110.690406 -434.873654) (xy 110.699804 -434.849016) (xy 110.682024 -434.73624) (xy 110.665768 -434.715412)
			(xy 110.653322 -434.710332) (xy 110.574304 -434.677407) (xy 110.419107 -434.605131) (xy 110.267499 -434.5256)
			(xy 110.119821 -434.438991) (xy 109.976402 -434.345497) (xy 109.837562 -434.245328) (xy 109.703613 -434.138709)
			(xy 109.574854 -434.025876) (xy 109.451573 -433.907083) (xy 109.334045 -433.782595) (xy 109.222533 -433.65269)
			(xy 109.117287 -433.517659) (xy 109.018541 -433.377804) (xy 108.926517 -433.233438) (xy 108.84142 -433.084883)
			(xy 108.763441 -432.932471) (xy 108.692754 -432.776543) (xy 108.629516 -432.617449) (xy 108.57387 -432.455542)
			(xy 108.52594 -432.291187) (xy 108.485833 -432.124749) (xy 108.453638 -431.956601) (xy 108.429428 -431.78712)
			(xy 108.413257 -431.616683) (xy 108.405161 -431.445673) (xy 108.40466 -431.360072) (xy 90.234516 -431.360072)
			(xy 90.234516 -432.560476) (xy 90.234067 -432.572557) (xy 90.226607 -432.595537) (xy 90.21241 -432.615087)
			(xy 90.192866 -432.629292) (xy 90.169888 -432.636762) (xy 90.157808 -432.637184) (xy 89.218008 -432.637184)
			(xy 89.205923 -432.63678) (xy 89.182937 -432.629312) (xy 89.163384 -432.615105) (xy 89.149181 -432.595549)
			(xy 89.141717 -432.572561) (xy 89.1413 -432.560476) (xy 88.207176 -432.560476) (xy 88.212518 -432.564369)
			(xy 88.226713 -432.583989) (xy 88.234135 -432.60704) (xy 88.23452 -432.61915) (xy 88.23452 -435.160674)
			(xy 88.23407 -435.172766) (xy 88.226615 -435.195773) (xy 88.212426 -435.215356) (xy 88.192886 -435.229606)
			(xy 88.169903 -435.237132) (xy 88.157812 -435.237636) (xy 87.218012 -435.237636) (xy 87.205907 -435.237174)
			(xy 87.182887 -435.229682) (xy 87.163317 -435.215431) (xy 87.14912 -435.195821) (xy 87.141693 -435.17278)
			(xy 87.141304 -435.160674) (xy 86.234524 -435.160674) (xy 86.234524 -436.160672) (xy 86.234064 -436.172752)
			(xy 86.226606 -436.195731) (xy 86.212411 -436.21528) (xy 86.19287 -436.229486) (xy 86.169895 -436.236957)
			(xy 86.157816 -436.23738) (xy 85.218016 -436.23738) (xy 85.205931 -436.236973) (xy 85.182944 -436.229507)
			(xy 85.163392 -436.2153) (xy 85.149188 -436.195745) (xy 85.141725 -436.172757) (xy 85.141308 -436.160672)
			(xy 84.207114 -436.160672) (xy 84.212397 -436.164511) (xy 84.226591 -436.18405) (xy 84.234055 -436.207017)
			(xy 84.234528 -436.219092) (xy 84.234528 -438.760616) (xy 84.23405 -438.772689) (xy 84.226585 -438.795654)
			(xy 84.212391 -438.815189) (xy 84.192857 -438.829383) (xy 84.169893 -438.836849) (xy 84.15782 -438.837324)
			(xy 83.21802 -438.837324) (xy 83.20594 -438.83687) (xy 83.182961 -438.82941) (xy 83.163411 -438.815214)
			(xy 83.149206 -438.795672) (xy 83.141735 -438.772696) (xy 83.141312 -438.760616) (xy 82.234532 -438.760616)
			(xy 82.234532 -439.760614) (xy 85.141308 -439.760614) (xy 85.141308 -439.033666) (xy 85.141549 -439.024846)
			(xy 85.145521 -439.007658) (xy 85.149182 -438.99963) (xy 85.382608 -438.52338) (xy 85.387311 -438.512864)
			(xy 85.3908 -438.490105) (xy 85.387314 -438.467346) (xy 85.382608 -438.456832) (xy 85.149182 -437.980582)
			(xy 85.145491 -437.972564) (xy 85.141519 -437.95537) (xy 85.141308 -437.946546) (xy 85.141308 -437.21909)
			(xy 85.141798 -437.207003) (xy 85.149254 -437.184008) (xy 85.163436 -437.164431) (xy 85.182962 -437.150179)
			(xy 85.205931 -437.142642) (xy 85.218016 -437.142128) (xy 86.157816 -437.142128) (xy 86.169929 -437.142503)
			(xy 86.192961 -437.15001) (xy 86.212536 -437.164281) (xy 86.226729 -437.183914) (xy 86.234145 -437.206976)
			(xy 86.234524 -437.21909) (xy 86.234524 -438.760616) (xy 87.141304 -438.760616) (xy 87.141304 -438.033668)
			(xy 87.141546 -438.024848) (xy 87.145517 -438.00766) (xy 87.149178 -437.999632) (xy 87.382604 -437.523382)
			(xy 87.387305 -437.512865) (xy 87.390795 -437.490107) (xy 87.38731 -437.467348) (xy 87.382604 -437.456834)
			(xy 87.149178 -436.980584) (xy 87.145487 -436.972566) (xy 87.141516 -436.955372) (xy 87.141304 -436.946548)
			(xy 87.141304 -436.219092) (xy 87.141706 -436.207008) (xy 87.149177 -436.184023) (xy 87.163386 -436.164471)
			(xy 87.182941 -436.150268) (xy 87.205928 -436.142803) (xy 87.218012 -436.142384) (xy 88.157812 -436.142384)
			(xy 88.169886 -436.142854) (xy 88.192853 -436.150319) (xy 88.207101 -436.160672) (xy 89.1413 -436.160672)
			(xy 89.1413 -435.433724) (xy 89.141528 -435.424903) (xy 89.145509 -435.407715) (xy 89.149174 -435.399688)
			(xy 89.3826 -434.923438) (xy 89.387332 -434.912934) (xy 89.390812 -434.890167) (xy 89.387313 -434.867404)
			(xy 89.3826 -434.85689) (xy 89.149174 -434.38064) (xy 89.145501 -434.372615) (xy 89.141518 -434.355427)
			(xy 89.1413 -434.346604) (xy 89.1413 -433.619148) (xy 89.141754 -433.607067) (xy 89.149209 -433.584084)
			(xy 89.163404 -433.564533) (xy 89.182949 -433.550327) (xy 89.205927 -433.54286) (xy 89.218008 -433.54244)
			(xy 90.157808 -433.54244) (xy 90.169896 -433.542806) (xy 90.192887 -433.550282) (xy 90.212441 -433.564498)
			(xy 90.226644 -433.584063) (xy 90.234102 -433.60706) (xy 90.234516 -433.619148) (xy 90.234516 -436.160672)
			(xy 90.234064 -436.172752) (xy 90.226605 -436.195733) (xy 90.212409 -436.215283) (xy 90.192865 -436.229488)
			(xy 90.169888 -436.236958) (xy 90.157808 -436.23738) (xy 89.218008 -436.23738) (xy 89.205923 -436.23698)
			(xy 89.182936 -436.229512) (xy 89.163383 -436.215303) (xy 89.149179 -436.195746) (xy 89.141716 -436.172757)
			(xy 89.1413 -436.160672) (xy 88.207101 -436.160672) (xy 88.212389 -436.164514) (xy 88.226583 -436.184051)
			(xy 88.234047 -436.207018) (xy 88.23452 -436.219092) (xy 88.23452 -438.760616) (xy 88.234049 -438.77269)
			(xy 88.226584 -438.795656) (xy 88.212389 -438.815191) (xy 88.192852 -438.829386) (xy 88.169886 -438.83685)
			(xy 88.157812 -438.837324) (xy 87.218012 -438.837324) (xy 87.20594 -438.836826) (xy 87.182976 -438.829369)
			(xy 87.16344 -438.81518) (xy 87.149244 -438.79565) (xy 87.141779 -438.772688) (xy 87.141304 -438.760616)
			(xy 86.234524 -438.760616) (xy 86.234524 -439.760614) (xy 89.1413 -439.760614) (xy 89.1413 -439.033666)
			(xy 89.141541 -439.024846) (xy 89.145513 -439.007658) (xy 89.149174 -438.99963) (xy 89.3826 -438.52338)
			(xy 89.387303 -438.512864) (xy 89.390793 -438.490105) (xy 89.387306 -438.467346) (xy 89.3826 -438.456832)
			(xy 89.149174 -437.980582) (xy 89.145482 -437.972565) (xy 89.141511 -437.95537) (xy 89.1413 -437.946546)
			(xy 89.1413 -437.21909) (xy 89.141798 -437.207004) (xy 89.149253 -437.18401) (xy 89.163433 -437.164434)
			(xy 89.182957 -437.150182) (xy 89.205924 -437.142643) (xy 89.218008 -437.142128) (xy 90.157808 -437.142128)
			(xy 90.16992 -437.14251) (xy 90.192952 -437.150015) (xy 90.212528 -437.164284) (xy 90.226721 -437.183915)
			(xy 90.234137 -437.206976) (xy 90.234516 -437.21909) (xy 90.234516 -438.760616) (xy 125.241304 -438.760616)
			(xy 125.241304 -438.033668) (xy 125.241546 -438.024848) (xy 125.245517 -438.00766) (xy 125.249178 -437.999632)
			(xy 125.482604 -437.523382) (xy 125.487305 -437.512865) (xy 125.490795 -437.490107) (xy 125.48731 -437.467348)
			(xy 125.482604 -437.456834) (xy 125.249178 -436.980584) (xy 125.245487 -436.972566) (xy 125.241516 -436.955372)
			(xy 125.241304 -436.946548) (xy 125.241304 -436.219092) (xy 125.241706 -436.207008) (xy 125.249177 -436.184023)
			(xy 125.263386 -436.164471) (xy 125.282941 -436.150268) (xy 125.305928 -436.142803) (xy 125.318012 -436.142384)
			(xy 126.257812 -436.142384) (xy 126.269886 -436.142854) (xy 126.292853 -436.150319) (xy 126.307101 -436.160672)
			(xy 127.2413 -436.160672) (xy 127.2413 -435.433724) (xy 127.241528 -435.424903) (xy 127.245509 -435.407715)
			(xy 127.249174 -435.399688) (xy 127.4826 -434.923438) (xy 127.487332 -434.912934) (xy 127.490812 -434.890167)
			(xy 127.487313 -434.867404) (xy 127.4826 -434.85689) (xy 127.249174 -434.38064) (xy 127.245501 -434.372615)
			(xy 127.241518 -434.355427) (xy 127.2413 -434.346604) (xy 127.2413 -433.619148) (xy 127.241754 -433.607067)
			(xy 127.249209 -433.584084) (xy 127.263404 -433.564533) (xy 127.282949 -433.550327) (xy 127.305927 -433.54286)
			(xy 127.318008 -433.54244) (xy 128.257808 -433.54244) (xy 128.269896 -433.542806) (xy 128.292887 -433.550282)
			(xy 128.312441 -433.564498) (xy 128.326644 -433.584063) (xy 128.334102 -433.60706) (xy 128.334516 -433.619148)
			(xy 128.334516 -435.160674) (xy 129.241296 -435.160674) (xy 129.241296 -434.433726) (xy 129.241525 -434.424905)
			(xy 129.245505 -434.407717) (xy 129.24917 -434.39969) (xy 129.482596 -433.92344) (xy 129.487327 -433.912935)
			(xy 129.490807 -433.890169) (xy 129.487309 -433.867406) (xy 129.482596 -433.856892) (xy 129.24917 -433.380642)
			(xy 129.245497 -433.372617) (xy 129.241514 -433.355429) (xy 129.241296 -433.346606) (xy 129.241296 -432.61915)
			(xy 129.241849 -432.607067) (xy 129.249287 -432.584076) (xy 129.263453 -432.564499) (xy 129.282966 -432.550245)
			(xy 129.305924 -432.542704) (xy 129.318004 -432.542188) (xy 130.257804 -432.542188) (xy 130.269912 -432.542613)
			(xy 130.292937 -432.550112) (xy 130.30751 -432.56073) (xy 131.241292 -432.56073) (xy 131.241292 -430.019206)
			(xy 131.241812 -430.007122) (xy 131.249261 -429.984129) (xy 131.263436 -429.964553) (xy 131.282955 -429.950301)
			(xy 131.305917 -429.94276) (xy 131.318 -429.942244) (xy 132.2578 -429.942244) (xy 132.269903 -429.942715)
			(xy 132.292921 -429.950208) (xy 132.312489 -429.964457) (xy 132.326686 -429.984064) (xy 132.334117 -430.007102)
			(xy 132.334508 -430.019206) (xy 132.334508 -431.560732) (xy 133.241288 -431.560732) (xy 133.241288 -429.019208)
			(xy 133.241719 -429.007126) (xy 133.249184 -428.984144) (xy 133.263386 -428.964594) (xy 133.282933 -428.950389)
			(xy 133.305914 -428.942921) (xy 133.317996 -428.9425) (xy 134.257796 -428.9425) (xy 134.269879 -428.942916)
			(xy 134.292863 -428.950383) (xy 134.306834 -428.960534) (xy 135.241284 -428.960534) (xy 135.241284 -426.41901)
			(xy 135.241717 -426.406917) (xy 135.249176 -426.383909) (xy 135.26337 -426.364325) (xy 135.282914 -426.350076)
			(xy 135.3059 -426.342551) (xy 135.317992 -426.342048) (xy 136.257792 -426.342048) (xy 136.269895 -426.342522)
			(xy 136.292914 -426.350013) (xy 136.312482 -426.364262) (xy 136.326679 -426.383868) (xy 136.334109 -426.406906)
			(xy 136.3345 -426.41901) (xy 136.3345 -427.960536) (xy 137.24128 -427.960536) (xy 137.24128 -425.419012)
			(xy 137.241774 -425.406939) (xy 137.249232 -425.383974) (xy 137.263421 -425.364438) (xy 137.282953 -425.350243)
			(xy 137.305915 -425.342778) (xy 137.317988 -425.342304) (xy 138.257788 -425.342304) (xy 138.269871 -425.342723)
			(xy 138.292856 -425.350189) (xy 138.312407 -425.364393) (xy 138.326611 -425.383944) (xy 138.334077 -425.406929)
			(xy 138.334496 -425.419012) (xy 138.334496 -427.960536) (xy 138.334066 -427.972614) (xy 138.326593 -427.995584)
			(xy 138.312387 -428.015122) (xy 138.292841 -428.029315) (xy 138.269866 -428.036774) (xy 138.257788 -428.037244)
			(xy 137.317988 -428.037244) (xy 137.305916 -428.036746) (xy 137.282955 -428.029285) (xy 137.263421 -428.015096)
			(xy 137.249226 -427.995567) (xy 137.241757 -427.972607) (xy 137.24128 -427.960536) (xy 136.3345 -427.960536)
			(xy 136.3345 -428.960534) (xy 136.334022 -428.972621) (xy 136.326561 -428.995616) (xy 136.312376 -429.015192)
			(xy 136.292848 -429.029443) (xy 136.269878 -429.036981) (xy 136.257792 -429.037496) (xy 135.317992 -429.037496)
			(xy 135.305882 -429.037091) (xy 135.282854 -429.029588) (xy 135.263281 -429.015324) (xy 135.249086 -428.9957)
			(xy 135.241667 -428.972645) (xy 135.241284 -428.960534) (xy 134.306834 -428.960534) (xy 134.312414 -428.964588)
			(xy 134.326618 -428.98414) (xy 134.334085 -429.007125) (xy 134.334504 -429.019208) (xy 134.334504 -431.560732)
			(xy 134.334063 -431.572809) (xy 134.326591 -431.595778) (xy 134.312389 -431.615315) (xy 134.292845 -431.629508)
			(xy 134.269873 -431.636969) (xy 134.257796 -431.63744) (xy 133.317996 -431.63744) (xy 133.305924 -431.63694)
			(xy 133.282963 -431.62948) (xy 133.263428 -431.615292) (xy 133.249233 -431.595763) (xy 133.241765 -431.572803)
			(xy 133.241288 -431.560732) (xy 132.334508 -431.560732) (xy 132.334508 -432.56073) (xy 132.334019 -432.572816)
			(xy 132.32656 -432.59581) (xy 132.312377 -432.615385) (xy 132.292852 -432.629637) (xy 132.269885 -432.637176)
			(xy 132.2578 -432.637692) (xy 131.318 -432.637692) (xy 131.30589 -432.637284) (xy 131.282862 -432.629783)
			(xy 131.263288 -432.61552) (xy 131.249093 -432.595896) (xy 131.241674 -432.572841) (xy 131.241292 -432.56073)
			(xy 130.30751 -432.56073) (xy 130.312509 -432.564372) (xy 130.326704 -432.583991) (xy 130.334127 -432.607041)
			(xy 130.334512 -432.61915) (xy 130.334512 -435.160674) (xy 130.33407 -435.172767) (xy 130.326614 -435.195775)
			(xy 130.312423 -435.215359) (xy 130.292881 -435.229609) (xy 130.269896 -435.237133) (xy 130.257804 -435.237636)
			(xy 129.318004 -435.237636) (xy 129.305899 -435.237181) (xy 129.282878 -435.229687) (xy 129.263308 -435.215434)
			(xy 129.249112 -435.195823) (xy 129.241684 -435.17278) (xy 129.241296 -435.160674) (xy 128.334516 -435.160674)
			(xy 128.334516 -436.160672) (xy 128.334064 -436.172752) (xy 128.326605 -436.195733) (xy 128.312409 -436.215283)
			(xy 128.292865 -436.229488) (xy 128.269888 -436.236958) (xy 128.257808 -436.23738) (xy 127.318008 -436.23738)
			(xy 127.305923 -436.23698) (xy 127.282936 -436.229512) (xy 127.263383 -436.215303) (xy 127.249179 -436.195746)
			(xy 127.241716 -436.172757) (xy 127.2413 -436.160672) (xy 126.307101 -436.160672) (xy 126.312389 -436.164514)
			(xy 126.326583 -436.184051) (xy 126.334047 -436.207018) (xy 126.33452 -436.219092) (xy 126.33452 -438.760616)
			(xy 126.334049 -438.77269) (xy 126.326584 -438.795656) (xy 126.312389 -438.815191) (xy 126.292852 -438.829386)
			(xy 126.269886 -438.83685) (xy 126.257812 -438.837324) (xy 125.318012 -438.837324) (xy 125.30594 -438.836826)
			(xy 125.282976 -438.829369) (xy 125.26344 -438.81518) (xy 125.249244 -438.79565) (xy 125.241779 -438.772688)
			(xy 125.241304 -438.760616) (xy 90.234516 -438.760616) (xy 90.234516 -439.760614) (xy 127.2413 -439.760614)
			(xy 127.2413 -439.033666) (xy 127.241541 -439.024846) (xy 127.245513 -439.007658) (xy 127.249174 -438.99963)
			(xy 127.4826 -438.52338) (xy 127.487303 -438.512864) (xy 127.490793 -438.490105) (xy 127.487306 -438.467346)
			(xy 127.4826 -438.456832) (xy 127.249174 -437.980582) (xy 127.245482 -437.972565) (xy 127.241511 -437.95537)
			(xy 127.2413 -437.946546) (xy 127.2413 -437.21909) (xy 127.241798 -437.207004) (xy 127.249253 -437.18401)
			(xy 127.263433 -437.164434) (xy 127.282957 -437.150182) (xy 127.305924 -437.142643) (xy 127.318008 -437.142128)
			(xy 128.257808 -437.142128) (xy 128.26992 -437.14251) (xy 128.292952 -437.150015) (xy 128.312528 -437.164284)
			(xy 128.326721 -437.183915) (xy 128.334137 -437.206976) (xy 128.334516 -437.21909) (xy 128.334516 -438.760616)
			(xy 129.241296 -438.760616) (xy 129.241296 -438.033668) (xy 129.241539 -438.024848) (xy 129.24551 -438.00766)
			(xy 129.24917 -437.999632) (xy 129.482596 -437.523382) (xy 129.487298 -437.512866) (xy 129.490788 -437.490107)
			(xy 129.487302 -437.467348) (xy 129.482596 -437.456834) (xy 129.24917 -436.980584) (xy 129.245479 -436.972566)
			(xy 129.241508 -436.955372) (xy 129.241296 -436.946548) (xy 129.241296 -436.219092) (xy 129.241758 -436.207017)
			(xy 129.249223 -436.184049) (xy 129.26342 -436.164511) (xy 129.282959 -436.150317) (xy 129.305929 -436.142856)
			(xy 129.318004 -436.142384) (xy 130.257804 -436.142384) (xy 130.269878 -436.142861) (xy 130.292844 -436.150323)
			(xy 130.307088 -436.160672) (xy 131.241292 -436.160672) (xy 131.241292 -435.433724) (xy 131.241521 -435.424903)
			(xy 131.245501 -435.407715) (xy 131.249166 -435.399688) (xy 131.482592 -434.923438) (xy 131.487325 -434.912934)
			(xy 131.490805 -434.890167) (xy 131.487305 -434.867404) (xy 131.482592 -434.85689) (xy 131.249166 -434.38064)
			(xy 131.245492 -434.372615) (xy 131.24151 -434.355427) (xy 131.241292 -434.346604) (xy 131.241292 -433.619148)
			(xy 131.241754 -433.607068) (xy 131.249208 -433.584087) (xy 131.263401 -433.564536) (xy 131.282944 -433.55033)
			(xy 131.30592 -433.542861) (xy 131.318 -433.54244) (xy 132.2578 -433.54244) (xy 132.269888 -433.542813)
			(xy 132.292878 -433.550287) (xy 132.312433 -433.564501) (xy 132.326635 -433.584065) (xy 132.334094 -433.60706)
			(xy 132.334508 -433.619148) (xy 132.334508 -435.160674) (xy 133.241288 -435.160674) (xy 133.241288 -434.433726)
			(xy 133.241518 -434.424905) (xy 133.245498 -434.407718) (xy 133.249162 -434.39969) (xy 133.482588 -433.92344)
			(xy 133.487319 -433.912935) (xy 133.4908 -433.890169) (xy 133.487301 -433.867406) (xy 133.482588 -433.856892)
			(xy 133.249162 -433.380642) (xy 133.245489 -433.372617) (xy 133.241506 -433.355429) (xy 133.241288 -433.346606)
			(xy 133.241288 -432.61915) (xy 133.241751 -432.607058) (xy 133.2492 -432.584051) (xy 133.263385 -432.564466)
			(xy 133.282923 -432.550216) (xy 133.305906 -432.542691) (xy 133.317996 -432.542188) (xy 134.257796 -432.542188)
			(xy 134.269903 -432.542619) (xy 134.292929 -432.550116) (xy 134.307499 -432.56073) (xy 135.241284 -432.56073)
			(xy 135.241284 -430.019206) (xy 135.241713 -430.007112) (xy 135.249174 -429.984105) (xy 135.263369 -429.964521)
			(xy 135.282913 -429.950272) (xy 135.3059 -429.942747) (xy 135.317992 -429.942244) (xy 136.257792 -429.942244)
			(xy 136.269895 -429.942722) (xy 136.292912 -429.950213) (xy 136.312481 -429.96446) (xy 136.326678 -429.984065)
			(xy 136.334109 -430.007102) (xy 136.3345 -430.019206) (xy 136.3345 -431.560732) (xy 137.24128 -431.560732)
			(xy 137.24128 -429.019208) (xy 137.241771 -429.007135) (xy 137.24923 -428.98417) (xy 137.26342 -428.964634)
			(xy 137.282952 -428.950439) (xy 137.305915 -428.942974) (xy 137.317988 -428.9425) (xy 138.257788 -428.9425)
			(xy 138.269871 -428.942923) (xy 138.292854 -428.950388) (xy 138.30682 -428.960534) (xy 139.241276 -428.960534)
			(xy 139.241276 -426.41901) (xy 139.241717 -426.406917) (xy 139.249175 -426.383911) (xy 139.263367 -426.364328)
			(xy 139.282909 -426.350078) (xy 139.305893 -426.342553) (xy 139.317984 -426.342048) (xy 140.257784 -426.342048)
			(xy 140.269887 -426.342529) (xy 140.292905 -426.350018) (xy 140.312473 -426.364265) (xy 140.32667 -426.383869)
			(xy 140.334101 -426.406906) (xy 140.334492 -426.41901) (xy 140.334492 -427.960536) (xy 142.241016 -427.960536)
			(xy 142.241016 -425.419012) (xy 142.241427 -425.406902) (xy 142.248925 -425.383873) (xy 142.263187 -425.364298)
			(xy 142.282811 -425.350104) (xy 142.305867 -425.342685) (xy 142.317978 -425.342304) (xy 143.257778 -425.342304)
			(xy 143.269863 -425.342825) (xy 143.292857 -425.350272) (xy 143.312434 -425.364446) (xy 143.326686 -425.383966)
			(xy 143.334225 -425.406929) (xy 143.33474 -425.419012) (xy 143.33474 -427.960536) (xy 143.334315 -427.972643)
			(xy 143.32681 -427.995664) (xy 143.31255 -428.015233) (xy 143.292933 -428.029428) (xy 143.269886 -428.036855)
			(xy 143.257778 -428.037244) (xy 142.317978 -428.037244) (xy 142.305886 -428.036811) (xy 142.282882 -428.029347)
			(xy 142.263301 -428.015152) (xy 142.249051 -427.99561) (xy 142.241523 -427.972627) (xy 142.241016 -427.960536)
			(xy 140.334492 -427.960536) (xy 140.334492 -428.960534) (xy 140.334022 -428.972622) (xy 140.32656 -428.995619)
			(xy 140.312373 -429.015195) (xy 140.292843 -429.029446) (xy 140.269871 -429.036983) (xy 140.257784 -429.037496)
			(xy 139.317984 -429.037496) (xy 139.305874 -429.037097) (xy 139.282845 -429.029593) (xy 139.263272 -429.015327)
			(xy 139.249078 -428.995702) (xy 139.241659 -428.972646) (xy 139.241276 -428.960534) (xy 138.30682 -428.960534)
			(xy 138.312406 -428.964592) (xy 138.32661 -428.984142) (xy 138.334076 -429.007125) (xy 138.334496 -429.019208)
			(xy 138.334496 -431.560732) (xy 138.334063 -431.572809) (xy 138.32659 -431.59578) (xy 138.312386 -431.615317)
			(xy 138.29284 -431.62951) (xy 138.269866 -431.63697) (xy 138.257788 -431.63744) (xy 137.317988 -431.63744)
			(xy 137.305916 -431.636946) (xy 137.282954 -431.629484) (xy 137.26342 -431.615294) (xy 137.249225 -431.595764)
			(xy 137.241757 -431.572804) (xy 137.24128 -431.560732) (xy 136.3345 -431.560732) (xy 136.3345 -432.56073)
			(xy 136.334019 -432.572817) (xy 136.326559 -432.595812) (xy 136.312374 -432.615388) (xy 136.292847 -432.629639)
			(xy 136.269878 -432.637177) (xy 136.257792 -432.637692) (xy 135.317992 -432.637692) (xy 135.305882 -432.637291)
			(xy 135.282853 -432.629788) (xy 135.263279 -432.615523) (xy 135.249085 -432.595898) (xy 135.241666 -432.572842)
			(xy 135.241284 -432.56073) (xy 134.307499 -432.56073) (xy 134.312501 -432.564374) (xy 134.326696 -432.583992)
			(xy 134.334119 -432.607041) (xy 134.334504 -432.61915) (xy 134.334504 -435.160674) (xy 134.333971 -435.172758)
			(xy 134.326527 -435.19575) (xy 134.312356 -435.215327) (xy 134.292839 -435.22958) (xy 134.269878 -435.23712)
			(xy 134.257796 -435.237636) (xy 133.317996 -435.237636) (xy 133.305891 -435.237188) (xy 133.282869 -435.229692)
			(xy 133.263299 -435.215437) (xy 133.249103 -435.195824) (xy 133.241676 -435.172781) (xy 133.241288 -435.160674)
			(xy 132.334508 -435.160674) (xy 132.334508 -436.160672) (xy 132.334063 -436.172753) (xy 132.326604 -436.195735)
			(xy 132.312406 -436.215286) (xy 132.29286 -436.229491) (xy 132.269881 -436.236959) (xy 132.2578 -436.23738)
			(xy 131.318 -436.23738) (xy 131.305914 -436.236987) (xy 131.282927 -436.229516) (xy 131.263374 -436.215306)
			(xy 131.249171 -436.195748) (xy 131.241708 -436.172758) (xy 131.241292 -436.160672) (xy 130.307088 -436.160672)
			(xy 130.31238 -436.164517) (xy 130.326575 -436.184053) (xy 130.334039 -436.207018) (xy 130.334512 -436.219092)
			(xy 130.334512 -438.760616) (xy 130.334049 -438.772691) (xy 130.326583 -438.795658) (xy 130.312386 -438.815194)
			(xy 130.292847 -438.829388) (xy 130.269879 -438.836851) (xy 130.257804 -438.837324) (xy 129.318004 -438.837324)
			(xy 129.305931 -438.836833) (xy 129.282967 -438.829373) (xy 129.263431 -438.815183) (xy 129.249236 -438.795651)
			(xy 129.241771 -438.772689) (xy 129.241296 -438.760616) (xy 128.334516 -438.760616) (xy 128.334516 -439.760614)
			(xy 131.241292 -439.760614) (xy 131.241292 -439.033666) (xy 131.241534 -439.024846) (xy 131.245506 -439.007658)
			(xy 131.249166 -438.99963) (xy 131.482592 -438.52338) (xy 131.487295 -438.512864) (xy 131.490785 -438.490105)
			(xy 131.487299 -438.467346) (xy 131.482592 -438.456832) (xy 131.249166 -437.980582) (xy 131.245474 -437.972565)
			(xy 131.241503 -437.95537) (xy 131.241292 -437.946546) (xy 131.241292 -437.21909) (xy 131.241798 -437.207005)
			(xy 131.249252 -437.184012) (xy 131.26343 -437.164436) (xy 131.282952 -437.150184) (xy 131.305917 -437.142644)
			(xy 131.318 -437.142128) (xy 132.2578 -437.142128) (xy 132.269912 -437.142516) (xy 132.292944 -437.150019)
			(xy 132.312519 -437.164287) (xy 132.326713 -437.183916) (xy 132.334129 -437.206977) (xy 132.334508 -437.21909)
			(xy 132.334508 -438.760616) (xy 133.241288 -438.760616) (xy 133.241288 -438.033668) (xy 133.241531 -438.024848)
			(xy 133.245502 -438.00766) (xy 133.249162 -437.999632) (xy 133.482588 -437.523382) (xy 133.48729 -437.512866)
			(xy 133.490781 -437.490107) (xy 133.487295 -437.467348) (xy 133.482588 -437.456834) (xy 133.249162 -436.980584)
			(xy 133.24547 -436.972567) (xy 133.2415 -436.955372) (xy 133.241288 -436.946548) (xy 133.241288 -436.219092)
			(xy 133.241757 -436.207017) (xy 133.249222 -436.184051) (xy 133.263417 -436.164514) (xy 133.282954 -436.15032)
			(xy 133.305921 -436.142857) (xy 133.317996 -436.142384) (xy 134.257796 -436.142384) (xy 134.26987 -436.142868)
			(xy 134.292835 -436.150328) (xy 134.307075 -436.160672) (xy 135.241284 -436.160672) (xy 135.241284 -435.433724)
			(xy 135.241513 -435.424903) (xy 135.245494 -435.407716) (xy 135.249158 -435.399688) (xy 135.482584 -434.923438)
			(xy 135.487317 -434.912934) (xy 135.490797 -434.890167) (xy 135.487297 -434.867404) (xy 135.482584 -434.85689)
			(xy 135.249158 -434.38064) (xy 135.245484 -434.372615) (xy 135.241502 -434.355427) (xy 135.241284 -434.346604)
			(xy 135.241284 -433.619148) (xy 135.241753 -433.607069) (xy 135.249207 -433.584089) (xy 135.263399 -433.564538)
			(xy 135.282939 -433.550332) (xy 135.305913 -433.542862) (xy 135.317992 -433.54244) (xy 136.257792 -433.54244)
			(xy 136.269879 -433.54282) (xy 136.29287 -433.550291) (xy 136.312424 -433.564504) (xy 136.326627 -433.584066)
			(xy 136.334086 -433.607061) (xy 136.3345 -433.619148) (xy 136.3345 -435.160674) (xy 137.24128 -435.160674)
			(xy 137.24128 -434.433726) (xy 137.24151 -434.424905) (xy 137.24549 -434.407718) (xy 137.249154 -434.39969)
			(xy 137.48258 -433.92344) (xy 137.487312 -433.912935) (xy 137.490792 -433.890169) (xy 137.487293 -433.867406)
			(xy 137.48258 -433.856892) (xy 137.249154 -433.380642) (xy 137.24548 -433.372617) (xy 137.241498 -433.355429)
			(xy 137.24128 -433.346606) (xy 137.24128 -432.61915) (xy 137.241751 -432.607059) (xy 137.249198 -432.584053)
			(xy 137.263383 -432.564469) (xy 137.282918 -432.550218) (xy 137.305899 -432.542692) (xy 137.317988 -432.542188)
			(xy 138.257788 -432.542188) (xy 138.269895 -432.542627) (xy 138.29292 -432.550121) (xy 138.307485 -432.56073)
			(xy 139.241276 -432.56073) (xy 139.241276 -430.019206) (xy 139.241713 -430.007113) (xy 139.249173 -429.984107)
			(xy 139.263366 -429.964524) (xy 139.282908 -429.950274) (xy 139.305893 -429.942749) (xy 139.317984 -429.942244)
			(xy 140.257784 -429.942244) (xy 140.269886 -429.942729) (xy 140.292904 -429.950218) (xy 140.312472 -429.964463)
			(xy 140.326669 -429.984067) (xy 140.3341 -430.007103) (xy 140.334492 -430.019206) (xy 140.334492 -431.560732)
			(xy 142.241016 -431.560732) (xy 142.241016 -429.019208) (xy 142.241423 -429.007098) (xy 142.248922 -428.984068)
			(xy 142.263186 -428.964493) (xy 142.28281 -428.950299) (xy 142.305867 -428.942881) (xy 142.317978 -428.9425)
			(xy 143.257778 -428.9425) (xy 143.269862 -428.943025) (xy 143.292856 -428.950471) (xy 143.306755 -428.960534)
			(xy 144.241012 -428.960534) (xy 144.241012 -426.41901) (xy 144.24152 -426.406899) (xy 144.249001 -426.38386)
			(xy 144.263235 -426.36426) (xy 144.282828 -426.350018) (xy 144.305863 -426.342526) (xy 144.317974 -426.342048)
			(xy 145.257774 -426.342048) (xy 145.269896 -426.342482) (xy 145.292956 -426.349969) (xy 145.312572 -426.364216)
			(xy 145.326824 -426.38383) (xy 145.334315 -426.406888) (xy 145.334736 -426.41901) (xy 145.334736 -427.960536)
			(xy 146.241008 -427.960536) (xy 146.241008 -425.419012) (xy 146.241427 -425.406903) (xy 146.248924 -425.383875)
			(xy 146.263185 -425.364301) (xy 146.282806 -425.350106) (xy 146.30586 -425.342687) (xy 146.31797 -425.342304)
			(xy 147.25777 -425.342304) (xy 147.269854 -425.342832) (xy 147.292848 -425.350276) (xy 147.312425 -425.364448)
			(xy 147.326678 -425.383967) (xy 147.334217 -425.40693) (xy 147.334732 -425.419012) (xy 147.334732 -427.960536)
			(xy 147.334315 -427.972644) (xy 147.326809 -427.995667) (xy 147.312547 -428.015236) (xy 147.292928 -428.029431)
			(xy 147.269879 -428.036856) (xy 147.25777 -428.037244) (xy 146.31797 -428.037244) (xy 146.305877 -428.036818)
			(xy 146.282873 -428.029351) (xy 146.263292 -428.015154) (xy 146.249043 -427.995612) (xy 146.241515 -427.972627)
			(xy 146.241008 -427.960536) (xy 145.334736 -427.960536) (xy 145.334736 -428.960534) (xy 145.334317 -428.972653)
			(xy 145.326817 -428.995702) (xy 145.312562 -429.015305) (xy 145.292948 -429.029545) (xy 145.269893 -429.037026)
			(xy 145.257774 -429.037496) (xy 144.317974 -429.037496) (xy 144.305861 -429.037011) (xy 144.282823 -429.029521)
			(xy 144.263225 -429.015281) (xy 144.248983 -428.995684) (xy 144.24149 -428.972646) (xy 144.241012 -428.960534)
			(xy 143.306755 -428.960534) (xy 143.312432 -428.964644) (xy 143.326685 -428.984163) (xy 143.334225 -429.007126)
			(xy 143.33474 -429.019208) (xy 143.33474 -431.560732) (xy 143.334311 -431.572839) (xy 143.326808 -431.59586)
			(xy 143.312548 -431.615429) (xy 143.292932 -431.629624) (xy 143.269886 -431.637051) (xy 143.257778 -431.63744)
			(xy 142.317978 -431.63744) (xy 142.305885 -431.637011) (xy 142.282881 -431.629546) (xy 142.263299 -431.61535)
			(xy 142.24905 -431.595808) (xy 142.241522 -431.572823) (xy 142.241016 -431.560732) (xy 140.334492 -431.560732)
			(xy 140.334492 -432.56073) (xy 140.334019 -432.572818) (xy 140.326558 -432.595814) (xy 140.312372 -432.615391)
			(xy 140.292842 -432.629642) (xy 140.26987 -432.637179) (xy 140.257784 -432.637692) (xy 139.317984 -432.637692)
			(xy 139.305873 -432.637297) (xy 139.282844 -432.629792) (xy 139.263271 -432.615526) (xy 139.249077 -432.595899)
			(xy 139.241658 -432.572842) (xy 139.241276 -432.56073) (xy 138.307485 -432.56073) (xy 138.312492 -432.564377)
			(xy 138.326687 -432.583994) (xy 138.334111 -432.607042) (xy 138.334496 -432.61915) (xy 138.334496 -435.160674)
			(xy 138.333971 -435.172759) (xy 138.326526 -435.195752) (xy 138.312353 -435.21533) (xy 138.292834 -435.229582)
			(xy 138.269871 -435.237121) (xy 138.257788 -435.237636) (xy 137.317988 -435.237636) (xy 137.305882 -435.237194)
			(xy 137.282861 -435.229696) (xy 137.263291 -435.21544) (xy 137.249095 -435.195826) (xy 137.241668 -435.172781)
			(xy 137.24128 -435.160674) (xy 136.3345 -435.160674) (xy 136.3345 -436.160672) (xy 136.334063 -436.172754)
			(xy 136.326602 -436.195737) (xy 136.312403 -436.215289) (xy 136.292855 -436.229493) (xy 136.269874 -436.23696)
			(xy 136.257792 -436.23738) (xy 135.317992 -436.23738) (xy 135.305906 -436.236994) (xy 135.282918 -436.229521)
			(xy 135.263366 -436.215309) (xy 135.249163 -436.195749) (xy 135.2417 -436.172758) (xy 135.241284 -436.160672)
			(xy 134.307075 -436.160672) (xy 134.312372 -436.16452) (xy 134.326567 -436.184054) (xy 134.334031 -436.207019)
			(xy 134.334504 -436.219092) (xy 134.334504 -438.760616) (xy 134.334049 -438.772692) (xy 134.326582 -438.79566)
			(xy 134.312383 -438.815197) (xy 134.292842 -438.829391) (xy 134.269872 -438.836852) (xy 134.257796 -438.837324)
			(xy 133.317996 -438.837324) (xy 133.305923 -438.836839) (xy 133.282958 -438.829378) (xy 133.263423 -438.815186)
			(xy 133.249228 -438.795652) (xy 133.241763 -438.772689) (xy 133.241288 -438.760616) (xy 132.334508 -438.760616)
			(xy 132.334508 -439.760614) (xy 135.241284 -439.760614) (xy 135.241284 -439.033666) (xy 135.241527 -439.024846)
			(xy 135.245498 -439.007658) (xy 135.249158 -438.99963) (xy 135.482584 -438.52338) (xy 135.487288 -438.512864)
			(xy 135.490778 -438.490105) (xy 135.487291 -438.467346) (xy 135.482584 -438.456832) (xy 135.249158 -437.980582)
			(xy 135.245465 -437.972565) (xy 135.241495 -437.95537) (xy 135.241284 -437.946546) (xy 135.241284 -437.21909)
			(xy 135.2417 -437.206996) (xy 135.249165 -437.183987) (xy 135.263363 -437.164404) (xy 135.28291 -437.150155)
			(xy 135.305899 -437.142631) (xy 135.317992 -437.142128) (xy 136.257792 -437.142128) (xy 136.269903 -437.142523)
			(xy 136.292935 -437.150024) (xy 136.312511 -437.16429) (xy 136.326705 -437.183918) (xy 136.334121 -437.206977)
			(xy 136.3345 -437.21909) (xy 136.3345 -438.760616) (xy 137.24128 -438.760616) (xy 137.24128 -438.033668)
			(xy 137.241524 -438.024848) (xy 137.245494 -438.00766) (xy 137.249154 -437.999632) (xy 137.48258 -437.523382)
			(xy 137.487283 -437.512866) (xy 137.490774 -437.490107) (xy 137.487287 -437.467348) (xy 137.48258 -437.456834)
			(xy 137.249154 -436.980584) (xy 137.245462 -436.972567) (xy 137.241492 -436.955372) (xy 137.24128 -436.946548)
			(xy 137.24128 -436.219092) (xy 137.241757 -436.207018) (xy 137.249221 -436.184053) (xy 137.263414 -436.164517)
			(xy 137.282949 -436.150322) (xy 137.305914 -436.142858) (xy 137.317988 -436.142384) (xy 138.257788 -436.142384)
			(xy 138.269869 -436.142823) (xy 138.29285 -436.150286) (xy 138.307149 -436.160672) (xy 139.241276 -436.160672)
			(xy 139.241276 -435.433724) (xy 139.241506 -435.424903) (xy 139.245486 -435.407716) (xy 139.24915 -435.399688)
			(xy 139.482576 -434.923438) (xy 139.487309 -434.912934) (xy 139.49079 -434.890167) (xy 139.48729 -434.867404)
			(xy 139.482576 -434.85689) (xy 139.24915 -434.38064) (xy 139.245475 -434.372616) (xy 139.241494 -434.355427)
			(xy 139.241276 -434.346604) (xy 139.241276 -433.619148) (xy 139.241753 -433.607069) (xy 139.249206 -433.584091)
			(xy 139.263396 -433.564541) (xy 139.282934 -433.550335) (xy 139.305906 -433.542863) (xy 139.317984 -433.54244)
			(xy 140.257784 -433.54244) (xy 140.269871 -433.542827) (xy 140.292861 -433.550296) (xy 140.312416 -433.564507)
			(xy 140.326618 -433.584068) (xy 140.334078 -433.607061) (xy 140.334492 -433.619148) (xy 140.334492 -435.160674)
			(xy 142.241524 -435.160674) (xy 142.241524 -434.433726) (xy 142.24175 -434.424905) (xy 142.245732 -434.407717)
			(xy 142.249398 -434.39969) (xy 142.482824 -433.92344) (xy 142.487554 -433.912935) (xy 142.491032 -433.890169)
			(xy 142.487535 -433.867407) (xy 142.482824 -433.856892) (xy 142.249398 -433.380642) (xy 142.245727 -433.372616)
			(xy 142.241742 -433.355429) (xy 142.241524 -433.346606) (xy 142.241524 -432.61915) (xy 142.24205 -432.607065)
			(xy 142.249491 -432.584068) (xy 142.263663 -432.564489) (xy 142.283183 -432.550236) (xy 142.306149 -432.5427)
			(xy 142.318232 -432.542188) (xy 143.258032 -432.542188) (xy 143.270141 -432.542589) (xy 143.293168 -432.550096)
			(xy 143.307756 -432.56073) (xy 144.241012 -432.56073) (xy 144.241012 -430.019206) (xy 144.241517 -430.007094)
			(xy 144.248999 -429.984056) (xy 144.263233 -429.964456) (xy 144.282827 -429.950214) (xy 144.305863 -429.942722)
			(xy 144.317974 -429.942244) (xy 145.257774 -429.942244) (xy 145.269896 -429.942682) (xy 145.292955 -429.950168)
			(xy 145.312571 -429.964415) (xy 145.326823 -429.984027) (xy 145.334315 -430.007084) (xy 145.334736 -430.019206)
			(xy 145.334736 -431.560732) (xy 146.241008 -431.560732) (xy 146.241008 -429.019208) (xy 146.241423 -429.007099)
			(xy 146.248921 -428.98407) (xy 146.263183 -428.964496) (xy 146.282805 -428.950302) (xy 146.305859 -428.942882)
			(xy 146.31797 -428.9425) (xy 147.25777 -428.9425) (xy 147.269854 -428.943032) (xy 147.292847 -428.950476)
			(xy 147.306742 -428.960534) (xy 148.241004 -428.960534) (xy 148.241004 -426.41901) (xy 148.24152 -426.406899)
			(xy 148.249 -426.383862) (xy 148.263232 -426.364263) (xy 148.282823 -426.35002) (xy 148.305856 -426.342527)
			(xy 148.317966 -426.342048) (xy 149.257766 -426.342048) (xy 149.269888 -426.342489) (xy 149.292947 -426.349973)
			(xy 149.312564 -426.364219) (xy 149.326816 -426.383831) (xy 149.334307 -426.406888) (xy 149.334728 -426.41901)
			(xy 149.334728 -427.960536) (xy 150.241 -427.960536) (xy 150.241 -425.419012) (xy 150.241427 -425.406904)
			(xy 150.248923 -425.383877) (xy 150.263182 -425.364304) (xy 150.282801 -425.350109) (xy 150.305852 -425.342688)
			(xy 150.317962 -425.342304) (xy 151.257762 -425.342304) (xy 151.269846 -425.342839) (xy 151.292839 -425.350281)
			(xy 151.312417 -425.364451) (xy 151.32667 -425.383968) (xy 151.334209 -425.40693) (xy 151.334724 -425.419012)
			(xy 151.334724 -427.960536) (xy 151.334315 -427.972644) (xy 151.326808 -427.995669) (xy 151.312544 -428.015239)
			(xy 151.292923 -428.029433) (xy 151.269872 -428.036857) (xy 151.257762 -428.037244) (xy 150.317962 -428.037244)
			(xy 150.305869 -428.036825) (xy 150.282864 -428.029356) (xy 150.263284 -428.015157) (xy 150.249035 -427.995613)
			(xy 150.241507 -427.972628) (xy 150.241 -427.960536) (xy 149.334728 -427.960536) (xy 149.334728 -428.960534)
			(xy 149.334317 -428.972654) (xy 149.326816 -428.995704) (xy 149.31256 -429.015308) (xy 149.292943 -429.029547)
			(xy 149.269886 -429.037027) (xy 149.257766 -429.037496) (xy 148.317966 -429.037496) (xy 148.305853 -429.037018)
			(xy 148.282814 -429.029525) (xy 148.263216 -429.015284) (xy 148.248975 -428.995686) (xy 148.241482 -428.972647)
			(xy 148.241004 -428.960534) (xy 147.306742 -428.960534) (xy 147.312424 -428.964647) (xy 147.326677 -428.984164)
			(xy 147.334217 -429.007126) (xy 147.334732 -429.019208) (xy 147.334732 -431.560732) (xy 147.334311 -431.572839)
			(xy 147.326807 -431.595862) (xy 147.312545 -431.615432) (xy 147.292927 -431.629627) (xy 147.269879 -431.637052)
			(xy 147.25777 -431.63744) (xy 146.31797 -431.63744) (xy 146.305877 -431.637018) (xy 146.282872 -431.629551)
			(xy 146.263291 -431.615353) (xy 146.249042 -431.595809) (xy 146.241514 -431.572824) (xy 146.241008 -431.560732)
			(xy 145.334736 -431.560732) (xy 145.334736 -432.56073) (xy 145.334314 -432.572849) (xy 145.326815 -432.595897)
			(xy 145.312561 -432.615501) (xy 145.292947 -432.62974) (xy 145.269893 -432.637222) (xy 145.257774 -432.637692)
			(xy 144.317974 -432.637692) (xy 144.305861 -432.637211) (xy 144.282822 -432.62972) (xy 144.263223 -432.61548)
			(xy 144.248982 -432.595882) (xy 144.24149 -432.572843) (xy 144.241012 -432.56073) (xy 143.307756 -432.56073)
			(xy 143.312739 -432.564362) (xy 143.326933 -432.583985) (xy 143.334355 -432.607039) (xy 143.33474 -432.61915)
			(xy 143.33474 -435.160674) (xy 143.33427 -435.172764) (xy 143.326818 -435.195767) (xy 143.312633 -435.215349)
			(xy 143.293099 -435.2296) (xy 143.270121 -435.237129) (xy 143.258032 -435.237636) (xy 142.318232 -435.237636)
			(xy 142.306128 -435.237157) (xy 142.283108 -435.229671) (xy 142.263538 -435.215424) (xy 142.249341 -435.195818)
			(xy 142.241913 -435.172779) (xy 142.241524 -435.160674) (xy 140.334492 -435.160674) (xy 140.334492 -436.160672)
			(xy 140.334063 -436.172755) (xy 140.326601 -436.195739) (xy 140.3124 -436.215291) (xy 140.29285 -436.229496)
			(xy 140.269867 -436.236961) (xy 140.257784 -436.23738) (xy 139.317984 -436.23738) (xy 139.305898 -436.237001)
			(xy 139.28291 -436.229525) (xy 139.263357 -436.215312) (xy 139.249155 -436.195751) (xy 139.241692 -436.172759)
			(xy 139.241276 -436.160672) (xy 138.307149 -436.160672) (xy 138.3124 -436.164486) (xy 138.326605 -436.184032)
			(xy 138.334074 -436.207011) (xy 138.334496 -436.219092) (xy 138.334496 -438.760616) (xy 138.334049 -438.772693)
			(xy 138.326581 -438.795662) (xy 138.31238 -438.8152) (xy 138.292837 -438.829394) (xy 138.269865 -438.836853)
			(xy 138.257788 -438.837324) (xy 137.317988 -438.837324) (xy 137.305914 -438.836846) (xy 137.28295 -438.829382)
			(xy 137.263414 -438.815189) (xy 137.24922 -438.795654) (xy 137.241755 -438.77269) (xy 137.24128 -438.760616)
			(xy 136.3345 -438.760616) (xy 136.3345 -439.760614) (xy 139.241276 -439.760614) (xy 139.241276 -439.033666)
			(xy 139.24152 -439.024846) (xy 139.24549 -439.007658) (xy 139.24915 -438.99963) (xy 139.482576 -438.52338)
			(xy 139.48728 -438.512864) (xy 139.490771 -438.490105) (xy 139.487284 -438.467346) (xy 139.482576 -438.456832)
			(xy 139.24915 -437.980582) (xy 139.245457 -437.972565) (xy 139.241487 -437.955371) (xy 139.241276 -437.946546)
			(xy 139.241276 -437.21909) (xy 139.2417 -437.206996) (xy 139.249164 -437.183989) (xy 139.26336 -437.164407)
			(xy 139.282905 -437.150158) (xy 139.305892 -437.142632) (xy 139.317984 -437.142128) (xy 140.257784 -437.142128)
			(xy 140.269895 -437.14253) (xy 140.292926 -437.150029) (xy 140.312502 -437.164293) (xy 140.326696 -437.18392)
			(xy 140.334112 -437.206978) (xy 140.334492 -437.21909) (xy 140.334492 -438.760616) (xy 142.241016 -438.760616)
			(xy 142.241016 -438.033668) (xy 142.241323 -438.024835) (xy 142.24542 -438.007647) (xy 142.249144 -437.999632)
			(xy 142.48257 -437.523382) (xy 142.487273 -437.512866) (xy 142.490765 -437.490107) (xy 142.487278 -437.467348)
			(xy 142.48257 -437.456834) (xy 142.249144 -436.980584) (xy 142.245398 -436.972576) (xy 142.241289 -436.955385)
			(xy 142.241016 -436.946548) (xy 142.241016 -436.219092) (xy 142.24141 -436.206981) (xy 142.248913 -436.183951)
			(xy 142.26318 -436.164376) (xy 142.282807 -436.150183) (xy 142.305866 -436.142765) (xy 142.317978 -436.142384)
			(xy 143.257778 -436.142384) (xy 143.269871 -436.142827) (xy 143.292878 -436.150283) (xy 143.307215 -436.160672)
			(xy 144.24152 -436.160672) (xy 144.24152 -435.433724) (xy 144.241746 -435.424903) (xy 144.245728 -435.407715)
			(xy 144.249394 -435.399688) (xy 144.48282 -434.923438) (xy 144.487551 -434.912933) (xy 144.49103 -434.890167)
			(xy 144.487532 -434.867405) (xy 144.48282 -434.85689) (xy 144.249394 -434.38064) (xy 144.245722 -434.372615)
			(xy 144.241738 -434.355427) (xy 144.24152 -434.346604) (xy 144.24152 -433.619148) (xy 144.241954 -433.607065)
			(xy 144.249412 -433.584079) (xy 144.263611 -433.564526) (xy 144.283161 -433.550321) (xy 144.306145 -433.542857)
			(xy 144.318228 -433.54244) (xy 145.258028 -433.54244) (xy 145.270117 -433.542789) (xy 145.293109 -433.550271)
			(xy 145.312663 -433.564491) (xy 145.326864 -433.584059) (xy 145.334322 -433.607059) (xy 145.334736 -433.619148)
			(xy 145.334736 -435.160674) (xy 146.241516 -435.160674) (xy 146.241516 -434.433726) (xy 146.241743 -434.424905)
			(xy 146.245724 -434.407717) (xy 146.24939 -434.39969) (xy 146.482816 -433.92344) (xy 146.487546 -433.912935)
			(xy 146.491025 -433.890169) (xy 146.487528 -433.867407) (xy 146.482816 -433.856892) (xy 146.24939 -433.380642)
			(xy 146.245718 -433.372616) (xy 146.241734 -433.355429) (xy 146.241516 -433.346606) (xy 146.241516 -432.61915)
			(xy 146.242049 -432.607065) (xy 146.24949 -432.58407) (xy 146.26366 -432.564492) (xy 146.283178 -432.550239)
			(xy 146.306141 -432.542701) (xy 146.318224 -432.542188) (xy 147.258024 -432.542188) (xy 147.270133 -432.542596)
			(xy 147.293159 -432.5501) (xy 147.307744 -432.56073) (xy 148.241004 -432.56073) (xy 148.241004 -430.019206)
			(xy 148.241516 -430.007095) (xy 148.248998 -429.984058) (xy 148.263231 -429.964459) (xy 148.282822 -429.950216)
			(xy 148.305855 -429.942723) (xy 148.317966 -429.942244) (xy 149.257766 -429.942244) (xy 149.269888 -429.942689)
			(xy 149.292946 -429.950173) (xy 149.312563 -429.964418) (xy 149.326815 -429.984029) (xy 149.334307 -430.007085)
			(xy 149.334728 -430.019206) (xy 149.334728 -431.560732) (xy 150.241 -431.560732) (xy 150.241 -429.019208)
			(xy 150.241423 -429.0071) (xy 150.24892 -428.984072) (xy 150.26318 -428.964499) (xy 150.2828 -428.950304)
			(xy 150.305852 -428.942883) (xy 150.317962 -428.9425) (xy 151.257762 -428.9425) (xy 151.269846 -428.943039)
			(xy 151.292838 -428.95048) (xy 151.306728 -428.960534) (xy 152.240996 -428.960534) (xy 152.240996 -426.41901)
			(xy 152.24152 -426.4069) (xy 152.248999 -426.383864) (xy 152.263229 -426.364266) (xy 152.282818 -426.350023)
			(xy 152.305848 -426.342528) (xy 152.317958 -426.342048) (xy 153.257758 -426.342048) (xy 153.26988 -426.342496)
			(xy 153.292939 -426.349978) (xy 153.312555 -426.364222) (xy 153.326808 -426.383833) (xy 153.334299 -426.406889)
			(xy 153.33472 -426.41901) (xy 153.33472 -427.960536) (xy 154.240992 -427.960536) (xy 154.240992 -425.419012)
			(xy 154.241427 -425.406905) (xy 154.248922 -425.383879) (xy 154.263179 -425.364307) (xy 154.282796 -425.350111)
			(xy 154.305845 -425.342689) (xy 154.317954 -425.342304) (xy 155.257754 -425.342304) (xy 155.269838 -425.342846)
			(xy 155.292831 -425.350286) (xy 155.312408 -425.364454) (xy 155.326662 -425.38397) (xy 155.334201 -425.40693)
			(xy 155.334716 -425.419012) (xy 155.334716 -427.960536) (xy 155.334315 -427.972645) (xy 155.326807 -427.995671)
			(xy 155.312541 -428.015242) (xy 155.292918 -428.029436) (xy 155.269865 -428.036859) (xy 155.257754 -428.037244)
			(xy 154.317954 -428.037244) (xy 154.30586 -428.036832) (xy 154.282856 -428.02936) (xy 154.263275 -428.01516)
			(xy 154.249027 -427.995615) (xy 154.241499 -427.972628) (xy 154.240992 -427.960536) (xy 153.33472 -427.960536)
			(xy 153.33472 -428.960534) (xy 153.334369 -428.972663) (xy 153.326862 -428.99573) (xy 153.312594 -429.015348)
			(xy 153.292962 -429.029597) (xy 153.269887 -429.03708) (xy 153.257758 -429.037496) (xy 152.317958 -429.037496)
			(xy 152.305845 -429.037025) (xy 152.282806 -429.02953) (xy 152.263208 -429.015287) (xy 152.248966 -428.995687)
			(xy 152.241474 -428.972647) (xy 152.240996 -428.960534) (xy 151.306728 -428.960534) (xy 151.312415 -428.96465)
			(xy 151.326669 -428.984166) (xy 151.334209 -429.007126) (xy 151.334724 -429.019208) (xy 151.334724 -431.560732)
			(xy 151.334311 -431.57284) (xy 151.326806 -431.595864) (xy 151.312543 -431.615435) (xy 151.292922 -431.629629)
			(xy 151.269872 -431.637053) (xy 151.257762 -431.63744) (xy 150.317962 -431.63744) (xy 150.305868 -431.637025)
			(xy 150.282863 -431.629555) (xy 150.263282 -431.615356) (xy 150.249034 -431.595811) (xy 150.241506 -431.572824)
			(xy 150.241 -431.560732) (xy 149.334728 -431.560732) (xy 149.334728 -432.56073) (xy 149.334365 -432.572858)
			(xy 149.326861 -432.595923) (xy 149.312595 -432.615541) (xy 149.292966 -432.62979) (xy 149.269894 -432.637275)
			(xy 149.257766 -432.637692) (xy 148.317966 -432.637692) (xy 148.305853 -432.637218) (xy 148.282813 -432.629725)
			(xy 148.263215 -432.615482) (xy 148.248973 -432.595883) (xy 148.241482 -432.572843) (xy 148.241004 -432.56073)
			(xy 147.307744 -432.56073) (xy 147.312731 -432.564365) (xy 147.326925 -432.583987) (xy 147.334347 -432.60704)
			(xy 147.334732 -432.61915) (xy 147.334732 -435.160674) (xy 147.33427 -435.172765) (xy 147.326817 -435.195769)
			(xy 147.31263 -435.215352) (xy 147.293094 -435.229603) (xy 147.270113 -435.23713) (xy 147.258024 -435.237636)
			(xy 146.318224 -435.237636) (xy 146.30612 -435.237164) (xy 146.2831 -435.229675) (xy 146.263529 -435.215427)
			(xy 146.249333 -435.195819) (xy 146.241905 -435.172779) (xy 146.241516 -435.160674) (xy 145.334736 -435.160674)
			(xy 145.334736 -436.160672) (xy 145.334212 -436.172742) (xy 145.326761 -436.195704) (xy 145.312579 -436.215239)
			(xy 145.293054 -436.229435) (xy 145.270098 -436.236904) (xy 145.258028 -436.23738) (xy 144.318228 -436.23738)
			(xy 144.306144 -436.236963) (xy 144.283157 -436.2295) (xy 144.263604 -436.215296) (xy 144.2494 -436.195743)
			(xy 144.241937 -436.172756) (xy 144.24152 -436.160672) (xy 143.307215 -436.160672) (xy 143.312462 -436.164474)
			(xy 143.326712 -436.184016) (xy 143.334237 -436.207001) (xy 143.33474 -436.219092) (xy 143.33474 -438.760616)
			(xy 143.334298 -438.772722) (xy 143.326799 -438.795743) (xy 143.312543 -438.815312) (xy 143.292929 -438.829508)
			(xy 143.269885 -438.836935) (xy 143.257778 -438.837324) (xy 142.317978 -438.837324) (xy 142.305884 -438.836911)
			(xy 142.282876 -438.829444) (xy 142.263294 -438.815245) (xy 142.249045 -438.795698) (xy 142.24152 -438.772709)
			(xy 142.241016 -438.760616) (xy 140.334492 -438.760616) (xy 140.334492 -439.760614) (xy 144.241012 -439.760614)
			(xy 144.241012 -439.033666) (xy 144.241319 -439.024833) (xy 144.245416 -439.007645) (xy 144.24914 -438.99963)
			(xy 144.482566 -438.52338) (xy 144.487266 -438.512863) (xy 144.490752 -438.490105) (xy 144.487269 -438.467347)
			(xy 144.482566 -438.456832) (xy 144.24914 -437.980582) (xy 144.245393 -437.972574) (xy 144.241285 -437.955383)
			(xy 144.241012 -437.946546) (xy 144.241012 -437.21909) (xy 144.241503 -437.206978) (xy 144.24899 -437.183938)
			(xy 144.263228 -437.164339) (xy 144.282824 -437.150097) (xy 144.305862 -437.142606) (xy 144.317974 -437.142128)
			(xy 145.257774 -437.142128) (xy 145.269894 -437.142582) (xy 145.292951 -437.150066) (xy 145.312565 -437.164309)
			(xy 145.326818 -437.183917) (xy 145.334312 -437.20697) (xy 145.334736 -437.21909) (xy 145.334736 -438.760616)
			(xy 146.241008 -438.760616) (xy 146.241008 -438.033668) (xy 146.241316 -438.024835) (xy 146.245412 -438.007647)
			(xy 146.249136 -437.999632) (xy 146.482562 -437.523382) (xy 146.487261 -437.512865) (xy 146.490748 -437.490107)
			(xy 146.487265 -437.467349) (xy 146.482562 -437.456834) (xy 146.249136 -436.980584) (xy 146.245376 -436.97258)
			(xy 146.241262 -436.955387) (xy 146.241008 -436.946548) (xy 146.241008 -436.219092) (xy 146.241409 -436.206982)
			(xy 146.248912 -436.183953) (xy 146.263177 -436.164379) (xy 146.282802 -436.150185) (xy 146.305858 -436.142766)
			(xy 146.31797 -436.142384) (xy 147.25777 -436.142384) (xy 147.269862 -436.142834) (xy 147.292869 -436.150288)
			(xy 147.307202 -436.160672) (xy 148.241512 -436.160672) (xy 148.241512 -435.433724) (xy 148.241739 -435.424903)
			(xy 148.24572 -435.407715) (xy 148.249386 -435.399688) (xy 148.482812 -434.923438) (xy 148.487544 -434.912933)
			(xy 148.491022 -434.890167) (xy 148.487524 -434.867405) (xy 148.482812 -434.85689) (xy 148.249386 -434.38064)
			(xy 148.245713 -434.372615) (xy 148.24173 -434.355427) (xy 148.241512 -434.346604) (xy 148.241512 -433.619148)
			(xy 148.241954 -433.607066) (xy 148.249411 -433.584081) (xy 148.263608 -433.564528) (xy 148.283156 -433.550323)
			(xy 148.306138 -433.542858) (xy 148.31822 -433.54244) (xy 149.25802 -433.54244) (xy 149.270109 -433.542796)
			(xy 149.2931 -433.550275) (xy 149.312654 -433.564494) (xy 149.326856 -433.584061) (xy 149.334314 -433.607059)
			(xy 149.334728 -433.619148) (xy 149.334728 -435.160674) (xy 150.241508 -435.160674) (xy 150.241508 -434.433726)
			(xy 150.241736 -434.424905) (xy 150.245717 -434.407717) (xy 150.249382 -434.39969) (xy 150.482808 -433.92344)
			(xy 150.487539 -433.912935) (xy 150.491018 -433.890169) (xy 150.48752 -433.867406) (xy 150.482808 -433.856892)
			(xy 150.249382 -433.380642) (xy 150.24571 -433.372617) (xy 150.241726 -433.355429) (xy 150.241508 -433.346606)
			(xy 150.241508 -432.61915) (xy 150.242049 -432.607066) (xy 150.249488 -432.584073) (xy 150.263657 -432.564495)
			(xy 150.283173 -432.550241) (xy 150.306134 -432.542702) (xy 150.318216 -432.542188) (xy 151.258016 -432.542188)
			(xy 151.270125 -432.542602) (xy 151.29315 -432.550105) (xy 151.307731 -432.56073) (xy 152.240996 -432.56073)
			(xy 152.240996 -430.019206) (xy 152.241516 -430.007096) (xy 152.248997 -429.98406) (xy 152.263228 -429.964462)
			(xy 152.282817 -429.950219) (xy 152.305848 -429.942724) (xy 152.317958 -429.942244) (xy 153.257758 -429.942244)
			(xy 153.269879 -429.942696) (xy 153.292938 -429.950177) (xy 153.312554 -429.96442) (xy 153.326806 -429.98403)
			(xy 153.334299 -430.007085) (xy 153.33472 -430.019206) (xy 153.33472 -431.560732) (xy 154.240992 -431.560732)
			(xy 154.240992 -429.019208) (xy 154.241423 -429.0071) (xy 154.248919 -428.984075) (xy 154.263177 -428.964502)
			(xy 154.282795 -428.950307) (xy 154.305845 -428.942884) (xy 154.317954 -428.9425) (xy 155.257754 -428.9425)
			(xy 155.269837 -428.943046) (xy 155.29283 -428.950485) (xy 155.306715 -428.960534) (xy 156.240988 -428.960534)
			(xy 156.240988 -426.41901) (xy 156.24152 -426.406901) (xy 156.248998 -426.383867) (xy 156.263226 -426.364269)
			(xy 156.282813 -426.350025) (xy 156.305841 -426.342529) (xy 156.31795 -426.342048) (xy 157.25775 -426.342048)
			(xy 157.269868 -426.342469) (xy 157.292915 -426.349972) (xy 157.312516 -426.364226) (xy 157.326756 -426.383839)
			(xy 157.33424 -426.406891) (xy 157.334712 -426.41901) (xy 157.334712 -428.960534) (xy 157.334218 -428.972645)
			(xy 157.326728 -428.995681) (xy 157.31249 -429.015278) (xy 157.292896 -429.02952) (xy 157.269861 -429.037016)
			(xy 157.25775 -429.037496) (xy 156.31795 -429.037496) (xy 156.305836 -429.037031) (xy 156.282797 -429.029535)
			(xy 156.263199 -429.015289) (xy 156.248958 -428.995689) (xy 156.241466 -428.972648) (xy 156.240988 -428.960534)
			(xy 155.306715 -428.960534) (xy 155.312407 -428.964653) (xy 155.32666 -428.984167) (xy 155.334201 -429.007127)
			(xy 155.334716 -429.019208) (xy 155.334716 -431.560732) (xy 155.334311 -431.572841) (xy 155.326805 -431.595867)
			(xy 155.31254 -431.615438) (xy 155.292917 -431.629632) (xy 155.269864 -431.637055) (xy 155.257754 -431.63744)
			(xy 154.317954 -431.63744) (xy 154.30586 -431.637031) (xy 154.282855 -431.62956) (xy 154.263274 -431.615359)
			(xy 154.249025 -431.595812) (xy 154.241498 -431.572825) (xy 154.240992 -431.560732) (xy 153.33472 -431.560732)
			(xy 153.33472 -432.56073) (xy 153.334365 -432.572859) (xy 153.326859 -432.595926) (xy 153.312592 -432.615544)
			(xy 153.292961 -432.629792) (xy 153.269887 -432.637276) (xy 153.257758 -432.637692) (xy 152.317958 -432.637692)
			(xy 152.305844 -432.637225) (xy 152.282805 -432.629729) (xy 152.263206 -432.615485) (xy 152.248965 -432.595885)
			(xy 152.241474 -432.572844) (xy 152.240996 -432.56073) (xy 151.307731 -432.56073) (xy 151.312722 -432.564367)
			(xy 151.326917 -432.583988) (xy 151.334339 -432.60704) (xy 151.334724 -432.61915) (xy 151.334724 -435.160674)
			(xy 151.33427 -435.172766) (xy 151.326816 -435.195772) (xy 151.312627 -435.215355) (xy 151.293089 -435.229605)
			(xy 151.270106 -435.237131) (xy 151.258016 -435.237636) (xy 150.318216 -435.237636) (xy 150.306112 -435.23717)
			(xy 150.283091 -435.22968) (xy 150.263521 -435.21543) (xy 150.249324 -435.195821) (xy 150.241897 -435.172779)
			(xy 150.241508 -435.160674) (xy 149.334728 -435.160674) (xy 149.334728 -436.160672) (xy 149.334264 -436.172751)
			(xy 149.326806 -436.19573) (xy 149.312613 -436.215279) (xy 149.293073 -436.229484) (xy 149.270099 -436.236956)
			(xy 149.25802 -436.23738) (xy 148.31822 -436.23738) (xy 148.306136 -436.23697) (xy 148.283149 -436.229504)
			(xy 148.263596 -436.215299) (xy 148.249392 -436.195744) (xy 148.241929 -436.172756) (xy 148.241512 -436.160672)
			(xy 147.307202 -436.160672) (xy 147.312454 -436.164477) (xy 147.326704 -436.184017) (xy 147.334229 -436.207001)
			(xy 147.334732 -436.219092) (xy 147.334732 -438.760616) (xy 147.334298 -438.772723) (xy 147.326798 -438.795745)
			(xy 147.31254 -438.815315) (xy 147.292924 -438.82951) (xy 147.269878 -438.836936) (xy 147.25777 -438.837324)
			(xy 146.31797 -438.837324) (xy 146.305875 -438.836918) (xy 146.282868 -438.829448) (xy 146.263285 -438.815247)
			(xy 146.249037 -438.795699) (xy 146.241512 -438.77271) (xy 146.241008 -438.760616) (xy 145.334736 -438.760616)
			(xy 145.334736 -439.760614) (xy 148.241004 -439.760614) (xy 148.241004 -439.033666) (xy 148.241311 -439.024833)
			(xy 148.245408 -439.007645) (xy 148.249132 -438.99963) (xy 148.482558 -438.52338) (xy 148.487258 -438.512863)
			(xy 148.490745 -438.490105) (xy 148.487262 -438.467347) (xy 148.482558 -438.456832) (xy 148.249132 -437.980582)
			(xy 148.245371 -437.972578) (xy 148.241258 -437.955385) (xy 148.241004 -437.946546) (xy 148.241004 -437.21909)
			(xy 148.241503 -437.206978) (xy 148.248989 -437.183941) (xy 148.263225 -437.164342) (xy 148.282819 -437.1501)
			(xy 148.305854 -437.142607) (xy 148.317966 -437.142128) (xy 149.257766 -437.142128) (xy 149.269886 -437.142589)
			(xy 149.292942 -437.15007) (xy 149.312557 -437.164312) (xy 149.32681 -437.183918) (xy 149.334304 -437.20697)
			(xy 149.334728 -437.21909) (xy 149.334728 -438.760616) (xy 150.241 -438.760616) (xy 150.241 -438.033668)
			(xy 150.241309 -438.024835) (xy 150.245404 -438.007647) (xy 150.249128 -437.999632) (xy 150.482554 -437.523382)
			(xy 150.487253 -437.512865) (xy 150.490741 -437.490107) (xy 150.487257 -437.467349) (xy 150.482554 -437.456834)
			(xy 150.249128 -436.980584) (xy 150.245368 -436.97258) (xy 150.241254 -436.955387) (xy 150.241 -436.946548)
			(xy 150.241 -436.219092) (xy 150.241409 -436.206983) (xy 150.248911 -436.183955) (xy 150.263174 -436.164382)
			(xy 150.282797 -436.150188) (xy 150.305851 -436.142767) (xy 150.317962 -436.142384) (xy 151.257762 -436.142384)
			(xy 151.269854 -436.142841) (xy 151.292861 -436.150292) (xy 151.307189 -436.160672) (xy 152.241504 -436.160672)
			(xy 152.241504 -435.433724) (xy 152.241731 -435.424903) (xy 152.245713 -435.407715) (xy 152.249378 -435.399688)
			(xy 152.482804 -434.923438) (xy 152.487536 -434.912933) (xy 152.491015 -434.890167) (xy 152.487517 -434.867404)
			(xy 152.482804 -434.85689) (xy 152.249378 -434.38064) (xy 152.245705 -434.372615) (xy 152.241722 -434.355427)
			(xy 152.241504 -434.346604) (xy 152.241504 -433.619148) (xy 152.241954 -433.607067) (xy 152.24941 -433.584083)
			(xy 152.263606 -433.564531) (xy 152.283151 -433.550326) (xy 152.306131 -433.542859) (xy 152.318212 -433.54244)
			(xy 153.258012 -433.54244) (xy 153.2701 -433.542803) (xy 153.293091 -433.55028) (xy 153.312646 -433.564497)
			(xy 153.326848 -433.584062) (xy 153.334306 -433.60706) (xy 153.33472 -433.619148) (xy 153.33472 -435.160674)
			(xy 154.2415 -435.160674) (xy 154.2415 -434.433726) (xy 154.241728 -434.424905) (xy 154.245709 -434.407717)
			(xy 154.249374 -434.39969) (xy 154.4828 -433.92344) (xy 154.487531 -433.912935) (xy 154.491011 -433.890169)
			(xy 154.487513 -433.867406) (xy 154.4828 -433.856892) (xy 154.249374 -433.380642) (xy 154.245701 -433.372617)
			(xy 154.241718 -433.355429) (xy 154.2415 -433.346606) (xy 154.2415 -432.61915) (xy 154.242049 -432.607067)
			(xy 154.249487 -432.584075) (xy 154.263654 -432.564497) (xy 154.283168 -432.550244) (xy 154.306127 -432.542703)
			(xy 154.318208 -432.542188) (xy 155.258008 -432.542188) (xy 155.270116 -432.542609) (xy 155.293142 -432.550109)
			(xy 155.307718 -432.56073) (xy 156.240988 -432.56073) (xy 156.240988 -430.019206) (xy 156.241516 -430.007097)
			(xy 156.248996 -429.984062) (xy 156.263225 -429.964465) (xy 156.282812 -429.950221) (xy 156.305841 -429.942725)
			(xy 156.31795 -429.942244) (xy 157.25775 -429.942244) (xy 157.269868 -429.942669) (xy 157.292914 -429.950171)
			(xy 157.312515 -429.964425) (xy 157.326755 -429.984037) (xy 157.33424 -430.007088) (xy 157.334712 -430.019206)
			(xy 157.334712 -432.56073) (xy 157.334215 -432.572841) (xy 157.326725 -432.595877) (xy 157.312488 -432.615474)
			(xy 157.292895 -432.629716) (xy 157.269861 -432.637212) (xy 157.25775 -432.637692) (xy 156.31795 -432.637692)
			(xy 156.305836 -432.637231) (xy 156.282796 -432.629734) (xy 156.263198 -432.615488) (xy 156.248957 -432.595886)
			(xy 156.241466 -432.572844) (xy 156.240988 -432.56073) (xy 155.307718 -432.56073) (xy 155.312714 -432.56437)
			(xy 155.326908 -432.58399) (xy 155.334331 -432.607041) (xy 155.334716 -432.61915) (xy 155.334716 -435.160674)
			(xy 155.33427 -435.172767) (xy 155.326815 -435.195774) (xy 155.312624 -435.215358) (xy 155.293083 -435.229608)
			(xy 155.270099 -435.237133) (xy 155.258008 -435.237636) (xy 154.318208 -435.237636) (xy 154.306103 -435.237178)
			(xy 154.283082 -435.229685) (xy 154.263512 -435.215433) (xy 154.249316 -435.195822) (xy 154.241888 -435.17278)
			(xy 154.2415 -435.160674) (xy 153.33472 -435.160674) (xy 153.33472 -436.160672) (xy 153.334264 -436.172752)
			(xy 153.326805 -436.195732) (xy 153.31261 -436.215281) (xy 153.293068 -436.229487) (xy 153.270092 -436.236957)
			(xy 153.258012 -436.23738) (xy 152.318212 -436.23738) (xy 152.306127 -436.236976) (xy 152.28314 -436.229509)
			(xy 152.263587 -436.215301) (xy 152.249384 -436.195746) (xy 152.241921 -436.172757) (xy 152.241504 -436.160672)
			(xy 151.307189 -436.160672) (xy 151.312445 -436.16448) (xy 151.326695 -436.184019) (xy 151.334221 -436.207002)
			(xy 151.334724 -436.219092) (xy 151.334724 -438.760616) (xy 151.334298 -438.772723) (xy 151.326797 -438.795747)
			(xy 151.312537 -438.815318) (xy 151.292919 -438.829513) (xy 151.269871 -438.836937) (xy 151.257762 -438.837324)
			(xy 150.317962 -438.837324) (xy 150.305867 -438.836924) (xy 150.282859 -438.829453) (xy 150.263277 -438.81525)
			(xy 150.249029 -438.795701) (xy 150.241504 -438.77271) (xy 150.241 -438.760616) (xy 149.334728 -438.760616)
			(xy 149.334728 -439.760614) (xy 152.240996 -439.760614) (xy 152.240996 -439.033666) (xy 152.241304 -439.024833)
			(xy 152.2454 -439.007645) (xy 152.249124 -438.99963) (xy 152.48255 -438.52338) (xy 152.487251 -438.512864)
			(xy 152.490738 -438.490105) (xy 152.487254 -438.467347) (xy 152.48255 -438.456832) (xy 152.249124 -437.980582)
			(xy 152.245363 -437.972579) (xy 152.24125 -437.955385) (xy 152.240996 -437.946546) (xy 152.240996 -437.21909)
			(xy 152.241503 -437.206979) (xy 152.248988 -437.183943) (xy 152.263222 -437.164345) (xy 152.282814 -437.150102)
			(xy 152.305847 -437.142608) (xy 152.317958 -437.142128) (xy 153.257758 -437.142128) (xy 153.269878 -437.142595)
			(xy 153.292933 -437.150075) (xy 153.312548 -437.164315) (xy 153.326801 -437.18392) (xy 153.334296 -437.206971)
			(xy 153.33472 -437.21909) (xy 153.33472 -438.760616) (xy 154.240992 -438.760616) (xy 154.240992 -438.033668)
			(xy 154.241301 -438.024835) (xy 154.245397 -438.007647) (xy 154.24912 -437.999632) (xy 154.482546 -437.523382)
			(xy 154.487246 -437.512865) (xy 154.490734 -437.490107) (xy 154.48725 -437.467349) (xy 154.482546 -437.456834)
			(xy 154.24912 -436.980584) (xy 154.245359 -436.97258) (xy 154.241246 -436.955387) (xy 154.240992 -436.946548)
			(xy 154.240992 -436.219092) (xy 154.241409 -436.206983) (xy 154.24891 -436.183957) (xy 154.263172 -436.164385)
			(xy 154.282792 -436.15019) (xy 154.305844 -436.142768) (xy 154.317954 -436.142384) (xy 155.257754 -436.142384)
			(xy 155.269846 -436.142847) (xy 155.292852 -436.150297) (xy 155.307176 -436.160672) (xy 156.241496 -436.160672)
			(xy 156.241496 -435.433724) (xy 156.241724 -435.424903) (xy 156.245705 -435.407715) (xy 156.24937 -435.399688)
			(xy 156.482796 -434.923438) (xy 156.487529 -434.912934) (xy 156.491008 -434.890167) (xy 156.487509 -434.867404)
			(xy 156.482796 -434.85689) (xy 156.24937 -434.38064) (xy 156.245696 -434.372615) (xy 156.241714 -434.355427)
			(xy 156.241496 -434.346604) (xy 156.241496 -433.619148) (xy 156.241954 -433.607067) (xy 156.249408 -433.584086)
			(xy 156.263603 -433.564534) (xy 156.283146 -433.550329) (xy 156.306124 -433.542861) (xy 156.318204 -433.54244)
			(xy 157.258004 -433.54244) (xy 157.270092 -433.54281) (xy 157.293083 -433.550284) (xy 157.312637 -433.5645)
			(xy 157.326839 -433.584064) (xy 157.334298 -433.60706) (xy 157.334712 -433.619148) (xy 157.334712 -436.160672)
			(xy 157.334263 -436.172753) (xy 157.326804 -436.195734) (xy 157.312607 -436.215284) (xy 157.293063 -436.229489)
			(xy 157.270085 -436.236958) (xy 157.258004 -436.23738) (xy 156.318204 -436.23738) (xy 156.306119 -436.236984)
			(xy 156.283131 -436.229514) (xy 156.263578 -436.215304) (xy 156.249375 -436.195747) (xy 156.241912 -436.172757)
			(xy 156.241496 -436.160672) (xy 155.307176 -436.160672) (xy 155.312437 -436.164483) (xy 155.326687 -436.18402)
			(xy 155.334212 -436.207002) (xy 155.334716 -436.219092) (xy 155.334716 -438.760616) (xy 155.334298 -438.772724)
			(xy 155.326796 -438.795749) (xy 155.312534 -438.815321) (xy 155.292914 -438.829515) (xy 155.269863 -438.836939)
			(xy 155.257754 -438.837324) (xy 154.317954 -438.837324) (xy 154.305858 -438.836931) (xy 154.28285 -438.829457)
			(xy 154.263268 -438.815253) (xy 154.24902 -438.795702) (xy 154.241496 -438.77271) (xy 154.240992 -438.760616)
			(xy 153.33472 -438.760616) (xy 153.33472 -439.760614) (xy 156.240988 -439.760614) (xy 156.240988 -439.033666)
			(xy 156.241297 -439.024833) (xy 156.245393 -439.007645) (xy 156.249116 -438.99963) (xy 156.482542 -438.52338)
			(xy 156.487243 -438.512864) (xy 156.490731 -438.490105) (xy 156.487246 -438.467347) (xy 156.482542 -438.456832)
			(xy 156.249116 -437.980582) (xy 156.245355 -437.972579) (xy 156.241242 -437.955385) (xy 156.240988 -437.946546)
			(xy 156.240988 -437.21909) (xy 156.241503 -437.20698) (xy 156.248987 -437.183945) (xy 156.263219 -437.164348)
			(xy 156.282809 -437.150105) (xy 156.30584 -437.142609) (xy 156.31795 -437.142128) (xy 157.25775 -437.142128)
			(xy 157.269866 -437.142569) (xy 157.292909 -437.150069) (xy 157.312509 -437.164319) (xy 157.32675 -437.183927)
			(xy 157.334237 -437.206974) (xy 157.334712 -437.21909) (xy 157.334712 -438.760616) (xy 314.141104 -438.760616)
			(xy 314.141104 -438.033668) (xy 314.141412 -438.024835) (xy 314.145508 -438.007647) (xy 314.149232 -437.999632)
			(xy 314.382658 -437.523382) (xy 314.387357 -437.512865) (xy 314.390844 -437.490107) (xy 314.387361 -437.467349)
			(xy 314.382658 -437.456834) (xy 314.149232 -436.980584) (xy 314.145472 -436.97258) (xy 314.141358 -436.955387)
			(xy 314.141104 -436.946548) (xy 314.141104 -436.219092) (xy 314.141509 -436.206982) (xy 314.149012 -436.183954)
			(xy 314.163276 -436.164381) (xy 314.1829 -436.150186) (xy 314.205955 -436.142767) (xy 314.218066 -436.142384)
			(xy 315.157866 -436.142384) (xy 315.169958 -436.142837) (xy 315.192965 -436.15029) (xy 315.207295 -436.160672)
			(xy 316.1411 -436.160672) (xy 316.1411 -435.433724) (xy 316.141328 -435.424903) (xy 316.145309 -435.407715)
			(xy 316.148974 -435.399688) (xy 316.3824 -434.923438) (xy 316.387132 -434.912934) (xy 316.390612 -434.890167)
			(xy 316.387113 -434.867404) (xy 316.3824 -434.85689) (xy 316.148974 -434.38064) (xy 316.145301 -434.372615)
			(xy 316.141318 -434.355427) (xy 316.1411 -434.346604) (xy 316.1411 -433.619148) (xy 316.141554 -433.607067)
			(xy 316.149009 -433.584084) (xy 316.163204 -433.564533) (xy 316.182749 -433.550327) (xy 316.205727 -433.54286)
			(xy 316.217808 -433.54244) (xy 317.157608 -433.54244) (xy 317.169696 -433.542806) (xy 317.192687 -433.550282)
			(xy 317.212241 -433.564498) (xy 317.226444 -433.584063) (xy 317.233902 -433.60706) (xy 317.234316 -433.619148)
			(xy 317.234316 -435.160674) (xy 318.141096 -435.160674) (xy 318.141096 -434.433726) (xy 318.141325 -434.424905)
			(xy 318.145305 -434.407717) (xy 318.14897 -434.39969) (xy 318.382396 -433.92344) (xy 318.387127 -433.912935)
			(xy 318.390607 -433.890169) (xy 318.387109 -433.867406) (xy 318.382396 -433.856892) (xy 318.14897 -433.380642)
			(xy 318.145297 -433.372617) (xy 318.141314 -433.355429) (xy 318.141096 -433.346606) (xy 318.141096 -432.61915)
			(xy 318.141649 -432.607067) (xy 318.149087 -432.584076) (xy 318.163253 -432.564499) (xy 318.182766 -432.550245)
			(xy 318.205724 -432.542704) (xy 318.217804 -432.542188) (xy 319.157604 -432.542188) (xy 319.169712 -432.542613)
			(xy 319.192737 -432.550112) (xy 319.206962 -432.560476) (xy 320.141092 -432.560476) (xy 320.141092 -430.018952)
			(xy 320.141475 -430.006841) (xy 320.148987 -429.983814) (xy 320.163258 -429.964242) (xy 320.182885 -429.950049)
			(xy 320.205942 -429.942628) (xy 320.218054 -429.942244) (xy 321.157854 -429.942244) (xy 321.169942 -429.942747)
			(xy 321.192941 -429.950191) (xy 321.212522 -429.964368) (xy 321.226774 -429.983895) (xy 321.234307 -430.006866)
			(xy 321.234816 -430.018952) (xy 321.234816 -431.560478) (xy 322.141088 -431.560478) (xy 322.141088 -429.018954)
			(xy 322.141572 -429.006842) (xy 322.149066 -428.983806) (xy 322.163306 -428.964209) (xy 322.182902 -428.949967)
			(xy 322.205938 -428.942472) (xy 322.21805 -428.941992) (xy 323.15785 -428.941992) (xy 323.169963 -428.942468)
			(xy 323.193 -428.949964) (xy 323.207544 -428.960534) (xy 324.141084 -428.960534) (xy 324.141084 -426.41901)
			(xy 324.141469 -426.406883) (xy 324.148964 -426.383817) (xy 324.163223 -426.364198) (xy 324.182849 -426.349948)
			(xy 324.205919 -426.342464) (xy 324.218046 -426.342048) (xy 325.157846 -426.342048) (xy 325.169964 -426.342473)
			(xy 325.19301 -426.349974) (xy 325.212612 -426.364228) (xy 325.226852 -426.38384) (xy 325.234336 -426.406892)
			(xy 325.234808 -426.41901) (xy 325.234808 -427.960536) (xy 326.14108 -427.960536) (xy 326.14108 -425.419012)
			(xy 326.141527 -425.406906) (xy 326.14902 -425.383882) (xy 326.163275 -425.364311) (xy 326.182889 -425.350115)
			(xy 326.205935 -425.342691) (xy 326.218042 -425.342304) (xy 327.157842 -425.342304) (xy 327.16993 -425.342771)
			(xy 327.192926 -425.350235) (xy 327.212502 -425.364423) (xy 327.226753 -425.383953) (xy 327.23429 -425.406925)
			(xy 327.234804 -425.419012) (xy 327.234804 -427.960536) (xy 327.234414 -427.972646) (xy 327.226906 -427.995674)
			(xy 327.212637 -428.015246) (xy 327.19301 -428.02944) (xy 327.169954 -428.03686) (xy 327.157842 -428.037244)
			(xy 326.218042 -428.037244) (xy 326.205953 -428.036757) (xy 326.182951 -428.029309) (xy 326.163369 -428.015129)
			(xy 326.149118 -427.995598) (xy 326.141587 -427.972623) (xy 326.14108 -427.960536) (xy 325.234808 -427.960536)
			(xy 325.234808 -428.960534) (xy 325.234318 -428.972646) (xy 325.226827 -428.995682) (xy 325.212588 -429.01528)
			(xy 325.192993 -429.029522) (xy 325.169958 -429.037016) (xy 325.157846 -429.037496) (xy 324.218046 -429.037496)
			(xy 324.205929 -429.037002) (xy 324.182877 -429.029526) (xy 324.163264 -429.015292) (xy 324.149011 -428.995694)
			(xy 324.141511 -428.972651) (xy 324.141084 -428.960534) (xy 323.207544 -428.960534) (xy 323.212597 -428.964206)
			(xy 323.226838 -428.983804) (xy 323.234332 -429.006841) (xy 323.234812 -429.018954) (xy 323.234812 -431.560478)
			(xy 323.23427 -431.572586) (xy 323.226795 -431.59562) (xy 323.212569 -431.615218) (xy 323.192985 -431.629462)
			(xy 323.169958 -431.636959) (xy 323.15785 -431.63744) (xy 322.21805 -431.63744) (xy 322.205931 -431.63703)
			(xy 322.182882 -431.629527) (xy 322.163279 -431.615269) (xy 322.14904 -431.595653) (xy 322.141558 -431.572598)
			(xy 322.141088 -431.560478) (xy 321.234816 -431.560478) (xy 321.234816 -432.560476) (xy 321.234363 -432.572582)
			(xy 321.226872 -432.595606) (xy 321.21262 -432.615178) (xy 321.193006 -432.629374) (xy 321.169961 -432.636798)
			(xy 321.157854 -432.637184) (xy 320.218054 -432.637184) (xy 320.205964 -432.636732) (xy 320.182966 -432.629266)
			(xy 320.163389 -432.615074) (xy 320.149139 -432.59554) (xy 320.141604 -432.572564) (xy 320.141092 -432.560476)
			(xy 319.206962 -432.560476) (xy 319.212309 -432.564372) (xy 319.226504 -432.583991) (xy 319.233927 -432.607041)
			(xy 319.234312 -432.61915) (xy 319.234312 -435.160674) (xy 319.23387 -435.172767) (xy 319.226414 -435.195775)
			(xy 319.212223 -435.215359) (xy 319.192681 -435.229609) (xy 319.169696 -435.237133) (xy 319.157604 -435.237636)
			(xy 318.217804 -435.237636) (xy 318.205699 -435.237181) (xy 318.182678 -435.229687) (xy 318.163108 -435.215434)
			(xy 318.148912 -435.195823) (xy 318.141484 -435.17278) (xy 318.141096 -435.160674) (xy 317.234316 -435.160674)
			(xy 317.234316 -436.160672) (xy 317.233864 -436.172752) (xy 317.226405 -436.195733) (xy 317.212209 -436.215283)
			(xy 317.192665 -436.229488) (xy 317.169688 -436.236958) (xy 317.157608 -436.23738) (xy 316.217808 -436.23738)
			(xy 316.205723 -436.23698) (xy 316.182736 -436.229512) (xy 316.163183 -436.215303) (xy 316.148979 -436.195746)
			(xy 316.141516 -436.172757) (xy 316.1411 -436.160672) (xy 315.207295 -436.160672) (xy 315.212549 -436.164478)
			(xy 315.2268 -436.184018) (xy 315.234325 -436.207001) (xy 315.234828 -436.219092) (xy 315.234828 -438.760616)
			(xy 315.234398 -438.772723) (xy 315.226897 -438.795746) (xy 315.212638 -438.815316) (xy 315.193022 -438.829511)
			(xy 315.169974 -438.836937) (xy 315.157866 -438.837324) (xy 314.218066 -438.837324) (xy 314.205971 -438.836921)
			(xy 314.182963 -438.829451) (xy 314.163381 -438.815249) (xy 314.149133 -438.7957) (xy 314.141608 -438.77271)
			(xy 314.141104 -438.760616) (xy 157.334712 -438.760616) (xy 157.334712 -439.760614) (xy 316.1411 -439.760614)
			(xy 316.1411 -439.033666) (xy 316.141408 -439.024833) (xy 316.145504 -439.007645) (xy 316.149228 -438.99963)
			(xy 316.382654 -438.52338) (xy 316.387355 -438.512864) (xy 316.390842 -438.490105) (xy 316.387358 -438.467347)
			(xy 316.382654 -438.456832) (xy 316.149228 -437.980582) (xy 316.145467 -437.972579) (xy 316.141354 -437.955385)
			(xy 316.1411 -437.946546) (xy 316.1411 -437.21909) (xy 316.141603 -437.206979) (xy 316.149088 -437.183942)
			(xy 316.163324 -437.164343) (xy 316.182917 -437.150101) (xy 316.205951 -437.142607) (xy 316.218062 -437.142128)
			(xy 317.157862 -437.142128) (xy 317.169982 -437.142592) (xy 317.193038 -437.150073) (xy 317.212653 -437.164313)
			(xy 317.226905 -437.183919) (xy 317.2344 -437.20697) (xy 317.234824 -437.21909) (xy 317.234824 -438.760616)
			(xy 318.141096 -438.760616) (xy 318.141096 -438.033668) (xy 318.141405 -438.024835) (xy 318.145501 -438.007647)
			(xy 318.149224 -437.999632) (xy 318.38265 -437.523382) (xy 318.387349 -437.512865) (xy 318.390837 -437.490107)
			(xy 318.387354 -437.467349) (xy 318.38265 -437.456834) (xy 318.149224 -436.980584) (xy 318.145464 -436.97258)
			(xy 318.14135 -436.955387) (xy 318.141096 -436.946548) (xy 318.141096 -436.219092) (xy 318.141509 -436.206983)
			(xy 318.14901 -436.183956) (xy 318.163273 -436.164384) (xy 318.182895 -436.150189) (xy 318.205948 -436.142768)
			(xy 318.218058 -436.142384) (xy 319.157858 -436.142384) (xy 319.16995 -436.142844) (xy 319.192956 -436.150294)
			(xy 319.207283 -436.160672) (xy 320.141092 -436.160672) (xy 320.141092 -435.433724) (xy 320.141321 -435.424903)
			(xy 320.145301 -435.407715) (xy 320.148966 -435.399688) (xy 320.382392 -434.923438) (xy 320.387125 -434.912934)
			(xy 320.390605 -434.890167) (xy 320.387105 -434.867404) (xy 320.382392 -434.85689) (xy 320.148966 -434.38064)
			(xy 320.145292 -434.372615) (xy 320.14131 -434.355427) (xy 320.141092 -434.346604) (xy 320.141092 -433.619148)
			(xy 320.141554 -433.607068) (xy 320.149008 -433.584087) (xy 320.163201 -433.564536) (xy 320.182744 -433.55033)
			(xy 320.20572 -433.542861) (xy 320.2178 -433.54244) (xy 321.1576 -433.54244) (xy 321.169688 -433.542813)
			(xy 321.192678 -433.550287) (xy 321.212233 -433.564501) (xy 321.226435 -433.584065) (xy 321.233894 -433.60706)
			(xy 321.234308 -433.619148) (xy 321.234308 -435.160674) (xy 322.141088 -435.160674) (xy 322.141088 -434.433726)
			(xy 322.141318 -434.424905) (xy 322.145298 -434.407718) (xy 322.148962 -434.39969) (xy 322.382388 -433.92344)
			(xy 322.387119 -433.912935) (xy 322.3906 -433.890169) (xy 322.387101 -433.867406) (xy 322.382388 -433.856892)
			(xy 322.148962 -433.380642) (xy 322.145289 -433.372617) (xy 322.141306 -433.355429) (xy 322.141088 -433.346606)
			(xy 322.141088 -432.61915) (xy 322.141551 -432.607058) (xy 322.149 -432.584051) (xy 322.163185 -432.564466)
			(xy 322.182723 -432.550216) (xy 322.205706 -432.542691) (xy 322.217796 -432.542188) (xy 323.157596 -432.542188)
			(xy 323.169703 -432.542619) (xy 323.192729 -432.550116) (xy 323.20695 -432.560476) (xy 324.141084 -432.560476)
			(xy 324.141084 -430.018952) (xy 324.141475 -430.006842) (xy 324.148986 -429.983816) (xy 324.163255 -429.964245)
			(xy 324.18288 -429.950052) (xy 324.205935 -429.942629) (xy 324.218046 -429.942244) (xy 325.157846 -429.942244)
			(xy 325.169938 -429.942668) (xy 325.192941 -429.950138) (xy 325.212521 -429.964336) (xy 325.22677 -429.983878)
			(xy 325.2343 -430.006861) (xy 325.234808 -430.018952) (xy 325.234808 -431.560478) (xy 326.14108 -431.560478)
			(xy 326.14108 -429.018954) (xy 326.141473 -429.006833) (xy 326.148978 -428.983781) (xy 326.163239 -428.964176)
			(xy 326.18286 -428.949938) (xy 326.20592 -428.942459) (xy 326.218042 -428.941992) (xy 327.157842 -428.941992)
			(xy 327.169954 -428.942475) (xy 327.192991 -428.949968) (xy 327.207531 -428.960534) (xy 328.141076 -428.960534)
			(xy 328.141076 -426.41901) (xy 328.141469 -426.406884) (xy 328.148963 -426.383819) (xy 328.16322 -426.364201)
			(xy 328.182844 -426.34995) (xy 328.205912 -426.342465) (xy 328.218038 -426.342048) (xy 329.157838 -426.342048)
			(xy 329.169956 -426.342479) (xy 329.193002 -426.349978) (xy 329.212604 -426.36423) (xy 329.226844 -426.383841)
			(xy 329.234328 -426.406892) (xy 329.2348 -426.41901) (xy 329.2348 -427.960536) (xy 331.141324 -427.960536)
			(xy 331.141324 -425.419012) (xy 331.141724 -425.406927) (xy 331.149192 -425.383939) (xy 331.1634 -425.364386)
			(xy 331.182957 -425.350183) (xy 331.205947 -425.34272) (xy 331.218032 -425.342304) (xy 332.157832 -425.342304)
			(xy 332.169909 -425.342737) (xy 332.19288 -425.35021) (xy 332.212417 -425.364414) (xy 332.22661 -425.38396)
			(xy 332.23407 -425.406934) (xy 332.23454 -425.419012) (xy 332.23454 -427.960536) (xy 332.234067 -427.972609)
			(xy 332.226599 -427.995572) (xy 332.212403 -428.015106) (xy 332.192869 -428.0293) (xy 332.169905 -428.036768)
			(xy 332.157832 -428.037244) (xy 331.218032 -428.037244) (xy 331.205963 -428.036709) (xy 331.183003 -428.02926)
			(xy 331.163468 -428.01508) (xy 331.149271 -427.995558) (xy 331.141801 -427.972605) (xy 331.141324 -427.960536)
			(xy 329.2348 -427.960536) (xy 329.2348 -428.960534) (xy 329.234318 -428.972647) (xy 329.226826 -428.995684)
			(xy 329.212585 -429.015282) (xy 329.192988 -429.029524) (xy 329.169951 -429.037017) (xy 329.157838 -429.037496)
			(xy 328.218038 -429.037496) (xy 328.205921 -429.037008) (xy 328.182869 -429.029531) (xy 328.163256 -429.015295)
			(xy 328.149002 -428.995696) (xy 328.141503 -428.972651) (xy 328.141076 -428.960534) (xy 327.207531 -428.960534)
			(xy 327.212588 -428.964209) (xy 327.22683 -428.983805) (xy 327.234324 -429.006842) (xy 327.234804 -429.018954)
			(xy 327.234804 -431.560478) (xy 327.23427 -431.572587) (xy 327.226794 -431.595623) (xy 327.212567 -431.615221)
			(xy 327.19298 -431.629465) (xy 327.169951 -431.63696) (xy 327.157842 -431.63744) (xy 326.218042 -431.63744)
			(xy 326.205919 -431.637004) (xy 326.182858 -431.629521) (xy 326.16324 -431.615274) (xy 326.148988 -431.59566)
			(xy 326.141499 -431.572601) (xy 326.14108 -431.560478) (xy 325.234808 -431.560478) (xy 325.234808 -432.560476)
			(xy 325.234363 -432.572583) (xy 325.226871 -432.595608) (xy 325.212617 -432.615181) (xy 325.193001 -432.629376)
			(xy 325.169954 -432.636799) (xy 325.157846 -432.637184) (xy 324.218046 -432.637184) (xy 324.205961 -432.636654)
			(xy 324.182966 -432.629213) (xy 324.163387 -432.615042) (xy 324.149134 -432.595522) (xy 324.141597 -432.572559)
			(xy 324.141084 -432.560476) (xy 323.20695 -432.560476) (xy 323.212301 -432.564374) (xy 323.226496 -432.583992)
			(xy 323.233919 -432.607041) (xy 323.234304 -432.61915) (xy 323.234304 -435.160674) (xy 323.233771 -435.172758)
			(xy 323.226327 -435.19575) (xy 323.212156 -435.215327) (xy 323.192639 -435.22958) (xy 323.169678 -435.23712)
			(xy 323.157596 -435.237636) (xy 322.217796 -435.237636) (xy 322.205691 -435.237188) (xy 322.182669 -435.229692)
			(xy 322.163099 -435.215437) (xy 322.148903 -435.195824) (xy 322.141476 -435.172781) (xy 322.141088 -435.160674)
			(xy 321.234308 -435.160674) (xy 321.234308 -436.160672) (xy 321.233863 -436.172753) (xy 321.226404 -436.195735)
			(xy 321.212206 -436.215286) (xy 321.19266 -436.229491) (xy 321.169681 -436.236959) (xy 321.1576 -436.23738)
			(xy 320.2178 -436.23738) (xy 320.205714 -436.236987) (xy 320.182727 -436.229516) (xy 320.163174 -436.215306)
			(xy 320.148971 -436.195748) (xy 320.141508 -436.172758) (xy 320.141092 -436.160672) (xy 319.207283 -436.160672)
			(xy 319.212541 -436.164481) (xy 319.226791 -436.184019) (xy 319.234316 -436.207002) (xy 319.23482 -436.219092)
			(xy 319.23482 -438.760616) (xy 319.234398 -438.772724) (xy 319.226896 -438.795748) (xy 319.212636 -438.815319)
			(xy 319.193017 -438.829514) (xy 319.169967 -438.836938) (xy 319.157858 -438.837324) (xy 318.218058 -438.837324)
			(xy 318.205963 -438.836928) (xy 318.182955 -438.829455) (xy 318.163372 -438.815252) (xy 318.149124 -438.795701)
			(xy 318.1416 -438.77271) (xy 318.141096 -438.760616) (xy 317.234824 -438.760616) (xy 317.234824 -439.760614)
			(xy 320.141092 -439.760614) (xy 320.141092 -439.033666) (xy 320.141401 -439.024833) (xy 320.145496 -439.007645)
			(xy 320.14922 -438.99963) (xy 320.382646 -438.52338) (xy 320.387347 -438.512864) (xy 320.390834 -438.490105)
			(xy 320.38735 -438.467347) (xy 320.382646 -438.456832) (xy 320.14922 -437.980582) (xy 320.145459 -437.972579)
			(xy 320.141346 -437.955385) (xy 320.141092 -437.946546) (xy 320.141092 -437.21909) (xy 320.141603 -437.20698)
			(xy 320.149087 -437.183944) (xy 320.163321 -437.164346) (xy 320.182912 -437.150104) (xy 320.205944 -437.142608)
			(xy 320.218054 -437.142128) (xy 321.157854 -437.142128) (xy 321.169973 -437.142599) (xy 321.193029 -437.150077)
			(xy 321.212644 -437.164316) (xy 321.226897 -437.183921) (xy 321.234392 -437.206971) (xy 321.234816 -437.21909)
			(xy 321.234816 -438.760616) (xy 322.141088 -438.760616) (xy 322.141088 -438.033668) (xy 322.141398 -438.024835)
			(xy 322.145493 -438.007647) (xy 322.149216 -437.999632) (xy 322.382642 -437.523382) (xy 322.387342 -437.512865)
			(xy 322.39083 -437.490107) (xy 322.387346 -437.467349) (xy 322.382642 -437.456834) (xy 322.149216 -436.980584)
			(xy 322.145455 -436.972581) (xy 322.141342 -436.955387) (xy 322.141088 -436.946548) (xy 322.141088 -436.219092)
			(xy 322.141509 -436.206984) (xy 322.149009 -436.183958) (xy 322.16327 -436.164386) (xy 322.18289 -436.150192)
			(xy 322.205941 -436.142769) (xy 322.21805 -436.142384) (xy 323.15785 -436.142384) (xy 323.169941 -436.142851)
			(xy 323.192948 -436.150299) (xy 323.207269 -436.160672) (xy 324.141084 -436.160672) (xy 324.141084 -435.433724)
			(xy 324.141313 -435.424903) (xy 324.145294 -435.407716) (xy 324.148958 -435.399688) (xy 324.382384 -434.923438)
			(xy 324.387117 -434.912934) (xy 324.390597 -434.890167) (xy 324.387097 -434.867404) (xy 324.382384 -434.85689)
			(xy 324.148958 -434.38064) (xy 324.145284 -434.372615) (xy 324.141302 -434.355427) (xy 324.141084 -434.346604)
			(xy 324.141084 -433.619148) (xy 324.141553 -433.607069) (xy 324.149007 -433.584089) (xy 324.163199 -433.564538)
			(xy 324.182739 -433.550332) (xy 324.205713 -433.542862) (xy 324.217792 -433.54244) (xy 325.157592 -433.54244)
			(xy 325.169679 -433.54282) (xy 325.19267 -433.550291) (xy 325.212224 -433.564504) (xy 325.226427 -433.584066)
			(xy 325.233886 -433.607061) (xy 325.2343 -433.619148) (xy 325.2343 -435.160674) (xy 326.14108 -435.160674)
			(xy 326.14108 -434.433726) (xy 326.14131 -434.424905) (xy 326.14529 -434.407718) (xy 326.148954 -434.39969)
			(xy 326.38238 -433.92344) (xy 326.387112 -433.912935) (xy 326.390592 -433.890169) (xy 326.387093 -433.867406)
			(xy 326.38238 -433.856892) (xy 326.148954 -433.380642) (xy 326.14528 -433.372617) (xy 326.141298 -433.355429)
			(xy 326.14108 -433.346606) (xy 326.14108 -432.61915) (xy 326.141551 -432.607059) (xy 326.148998 -432.584053)
			(xy 326.163183 -432.564469) (xy 326.182718 -432.550218) (xy 326.205699 -432.542692) (xy 326.217788 -432.542188)
			(xy 327.157588 -432.542188) (xy 327.169695 -432.542627) (xy 327.19272 -432.550121) (xy 327.206936 -432.560476)
			(xy 328.141076 -432.560476) (xy 328.141076 -430.018952) (xy 328.141475 -430.006843) (xy 328.148985 -429.983818)
			(xy 328.163252 -429.964248) (xy 328.182875 -429.950054) (xy 328.205928 -429.94263) (xy 328.218038 -429.942244)
			(xy 329.157838 -429.942244) (xy 329.16993 -429.942675) (xy 329.192933 -429.950143) (xy 329.212512 -429.964338)
			(xy 329.226761 -429.983879) (xy 329.234292 -430.006861) (xy 329.2348 -430.018952) (xy 329.2348 -431.560478)
			(xy 331.141324 -431.560478) (xy 331.141324 -429.018954) (xy 331.141768 -429.006864) (xy 331.149235 -428.983864)
			(xy 331.163428 -428.964286) (xy 331.182965 -428.950037) (xy 331.205943 -428.942503) (xy 331.218032 -428.941992)
			(xy 332.157832 -428.941992) (xy 332.169942 -428.942389) (xy 332.192969 -428.949896) (xy 332.207563 -428.960534)
			(xy 333.14132 -428.960534) (xy 333.14132 -426.41901) (xy 333.141816 -426.406923) (xy 333.149267 -426.383926)
			(xy 333.163447 -426.364348) (xy 333.182973 -426.350096) (xy 333.205943 -426.34256) (xy 333.218028 -426.342048)
			(xy 334.157828 -426.342048) (xy 334.169933 -426.342492) (xy 334.192952 -426.349993) (xy 334.212521 -426.364249)
			(xy 334.226716 -426.383861) (xy 334.234145 -426.406904) (xy 334.234536 -426.41901) (xy 334.234536 -427.960536)
			(xy 335.141316 -427.960536) (xy 335.141316 -425.419012) (xy 335.141723 -425.406928) (xy 335.149191 -425.383941)
			(xy 335.163397 -425.364389) (xy 335.182952 -425.350185) (xy 335.205939 -425.342722) (xy 335.218024 -425.342304)
			(xy 336.157824 -425.342304) (xy 336.169901 -425.342744) (xy 336.192871 -425.350215) (xy 336.212409 -425.364417)
			(xy 336.226602 -425.383961) (xy 336.234061 -425.406935) (xy 336.234532 -425.419012) (xy 336.234532 -427.960536)
			(xy 336.234067 -427.97261) (xy 336.226598 -427.995574) (xy 336.2124 -428.015109) (xy 336.192864 -428.029303)
			(xy 336.169898 -428.036769) (xy 336.157824 -428.037244) (xy 335.218024 -428.037244) (xy 335.205954 -428.036716)
			(xy 335.182994 -428.029264) (xy 335.16346 -428.015083) (xy 335.149263 -427.99556) (xy 335.141793 -427.972605)
			(xy 335.141316 -427.960536) (xy 334.234536 -427.960536) (xy 334.234536 -428.960534) (xy 334.234121 -428.972628)
			(xy 334.226652 -428.995634) (xy 334.212453 -429.015215) (xy 334.192907 -429.029464) (xy 334.16992 -429.03699)
			(xy 334.157828 -429.037496) (xy 333.218028 -429.037496) (xy 333.20592 -429.03706) (xy 333.182893 -429.029567)
			(xy 333.163319 -429.015311) (xy 333.149124 -428.995693) (xy 333.141703 -428.972643) (xy 333.14132 -428.960534)
			(xy 332.207563 -428.960534) (xy 332.212541 -428.964163) (xy 332.226734 -428.983788) (xy 332.234156 -429.006843)
			(xy 332.23454 -429.018954) (xy 332.23454 -431.560478) (xy 332.234073 -431.572568) (xy 332.22662 -431.595572)
			(xy 332.212434 -431.615154) (xy 332.192899 -431.629404) (xy 332.169921 -431.636933) (xy 332.157832 -431.63744)
			(xy 331.218032 -431.63744) (xy 331.205929 -431.636957) (xy 331.182909 -431.629471) (xy 331.163339 -431.615225)
			(xy 331.149142 -431.59562) (xy 331.141713 -431.572582) (xy 331.141324 -431.560478) (xy 329.2348 -431.560478)
			(xy 329.2348 -432.560476) (xy 329.234363 -432.572584) (xy 329.22687 -432.59561) (xy 329.212614 -432.615184)
			(xy 329.192996 -432.629379) (xy 329.169947 -432.6368) (xy 329.157838 -432.637184) (xy 328.218038 -432.637184)
			(xy 328.205953 -432.636661) (xy 328.182957 -432.629217) (xy 328.163379 -432.615044) (xy 328.149126 -432.595524)
			(xy 328.141589 -432.572559) (xy 328.141076 -432.560476) (xy 327.206936 -432.560476) (xy 327.212292 -432.564377)
			(xy 327.226487 -432.583994) (xy 327.233911 -432.607042) (xy 327.234296 -432.61915) (xy 327.234296 -435.160674)
			(xy 327.233771 -435.172759) (xy 327.226326 -435.195752) (xy 327.212153 -435.21533) (xy 327.192634 -435.229582)
			(xy 327.169671 -435.237121) (xy 327.157588 -435.237636) (xy 326.217788 -435.237636) (xy 326.205682 -435.237194)
			(xy 326.182661 -435.229696) (xy 326.163091 -435.21544) (xy 326.148895 -435.195826) (xy 326.141468 -435.172781)
			(xy 326.14108 -435.160674) (xy 325.2343 -435.160674) (xy 325.2343 -436.160672) (xy 325.233863 -436.172754)
			(xy 325.226402 -436.195737) (xy 325.212203 -436.215289) (xy 325.192655 -436.229493) (xy 325.169674 -436.23696)
			(xy 325.157592 -436.23738) (xy 324.217792 -436.23738) (xy 324.205706 -436.236994) (xy 324.182718 -436.229521)
			(xy 324.163166 -436.215309) (xy 324.148963 -436.195749) (xy 324.1415 -436.172758) (xy 324.141084 -436.160672)
			(xy 323.207269 -436.160672) (xy 323.212532 -436.164484) (xy 323.226783 -436.184021) (xy 323.234308 -436.207002)
			(xy 323.234812 -436.219092) (xy 323.234812 -438.760616) (xy 323.234398 -438.772725) (xy 323.226895 -438.79575)
			(xy 323.212633 -438.815322) (xy 323.193012 -438.829517) (xy 323.16996 -438.836939) (xy 323.15785 -438.837324)
			(xy 322.21805 -438.837324) (xy 322.205959 -438.836849) (xy 322.182954 -438.829402) (xy 322.16337 -438.815219)
			(xy 322.149119 -438.795684) (xy 322.141593 -438.772705) (xy 322.141088 -438.760616) (xy 321.234816 -438.760616)
			(xy 321.234816 -439.760614) (xy 324.141084 -439.760614) (xy 324.141084 -439.033666) (xy 324.141393 -439.024833)
			(xy 324.145489 -439.007645) (xy 324.149212 -438.99963) (xy 324.382638 -438.52338) (xy 324.387339 -438.512864)
			(xy 324.390827 -438.490105) (xy 324.387343 -438.467347) (xy 324.382638 -438.456832) (xy 324.149212 -437.980582)
			(xy 324.14545 -437.972579) (xy 324.141338 -437.955385) (xy 324.141084 -437.946546) (xy 324.141084 -437.21909)
			(xy 324.141452 -437.206962) (xy 324.148953 -437.183895) (xy 324.163216 -437.164276) (xy 324.182845 -437.150027)
			(xy 324.205918 -437.142544) (xy 324.218046 -437.142128) (xy 325.157846 -437.142128) (xy 325.169962 -437.142572)
			(xy 325.193005 -437.150071) (xy 325.212605 -437.164321) (xy 325.226845 -437.183927) (xy 325.234333 -437.206974)
			(xy 325.234808 -437.21909) (xy 325.234808 -438.760616) (xy 326.14108 -438.760616) (xy 326.14108 -438.033668)
			(xy 326.14139 -438.024835) (xy 326.145485 -438.007647) (xy 326.149208 -437.999632) (xy 326.382634 -437.523382)
			(xy 326.387334 -437.512865) (xy 326.390823 -437.490107) (xy 326.387339 -437.467349) (xy 326.382634 -437.456834)
			(xy 326.149208 -436.980584) (xy 326.145447 -436.972581) (xy 326.141334 -436.955387) (xy 326.14108 -436.946548)
			(xy 326.14108 -436.219092) (xy 326.141509 -436.206985) (xy 326.149008 -436.183961) (xy 326.163267 -436.164389)
			(xy 326.182885 -436.150194) (xy 326.205933 -436.14277) (xy 326.218042 -436.142384) (xy 327.157842 -436.142384)
			(xy 327.169938 -436.142772) (xy 327.192948 -436.150246) (xy 327.207321 -436.160672) (xy 328.141076 -436.160672)
			(xy 328.141076 -435.433724) (xy 328.141306 -435.424903) (xy 328.145286 -435.407716) (xy 328.14895 -435.399688)
			(xy 328.382376 -434.923438) (xy 328.387109 -434.912934) (xy 328.39059 -434.890167) (xy 328.38709 -434.867404)
			(xy 328.382376 -434.85689) (xy 328.14895 -434.38064) (xy 328.145275 -434.372616) (xy 328.141294 -434.355427)
			(xy 328.141076 -434.346604) (xy 328.141076 -433.619148) (xy 328.141553 -433.607069) (xy 328.149006 -433.584091)
			(xy 328.163196 -433.564541) (xy 328.182734 -433.550335) (xy 328.205706 -433.542863) (xy 328.217784 -433.54244)
			(xy 329.157584 -433.54244) (xy 329.169671 -433.542827) (xy 329.192661 -433.550296) (xy 329.212216 -433.564507)
			(xy 329.226418 -433.584068) (xy 329.233878 -433.607061) (xy 329.234292 -433.619148) (xy 329.234292 -435.160674)
			(xy 331.141324 -435.160674) (xy 331.141324 -434.433726) (xy 331.14155 -434.424905) (xy 331.145532 -434.407717)
			(xy 331.149198 -434.39969) (xy 331.382624 -433.92344) (xy 331.387354 -433.912935) (xy 331.390832 -433.890169)
			(xy 331.387335 -433.867407) (xy 331.382624 -433.856892) (xy 331.149198 -433.380642) (xy 331.145527 -433.372616)
			(xy 331.141542 -433.355429) (xy 331.141324 -433.346606) (xy 331.141324 -432.61915) (xy 331.14185 -432.607065)
			(xy 331.149291 -432.584068) (xy 331.163463 -432.564489) (xy 331.182983 -432.550236) (xy 331.205949 -432.5427)
			(xy 331.218032 -432.542188) (xy 332.157832 -432.542188) (xy 332.169941 -432.542589) (xy 332.192968 -432.550096)
			(xy 332.207208 -432.560476) (xy 333.14132 -432.560476) (xy 333.14132 -430.018952) (xy 333.141724 -430.006872)
			(xy 333.149203 -429.983899) (xy 333.163414 -429.96436) (xy 333.182967 -429.950168) (xy 333.205948 -429.942712)
			(xy 333.218028 -429.942244) (xy 334.157828 -429.942244) (xy 334.169899 -429.942739) (xy 334.192859 -429.950204)
			(xy 334.212392 -429.964394) (xy 334.226587 -429.983923) (xy 334.234058 -430.006881) (xy 334.234536 -430.018952)
			(xy 334.234536 -431.560478) (xy 335.141316 -431.560478) (xy 335.141316 -429.018954) (xy 335.141768 -429.006864)
			(xy 335.149234 -428.983866) (xy 335.163426 -428.964289) (xy 335.18296 -428.950039) (xy 335.205936 -428.942504)
			(xy 335.218024 -428.941992) (xy 336.157824 -428.941992) (xy 336.169933 -428.942396) (xy 336.19296 -428.949901)
			(xy 336.207549 -428.960534) (xy 337.141312 -428.960534) (xy 337.141312 -426.41901) (xy 337.141815 -426.406924)
			(xy 337.149266 -426.383928) (xy 337.163444 -426.364351) (xy 337.182968 -426.350099) (xy 337.205936 -426.342562)
			(xy 337.21802 -426.342048) (xy 338.15782 -426.342048) (xy 338.169925 -426.342499) (xy 338.192944 -426.349997)
			(xy 338.212512 -426.364252) (xy 338.226708 -426.383863) (xy 338.234137 -426.406904) (xy 338.234528 -426.41901)
			(xy 338.234528 -427.960536) (xy 339.141308 -427.960536) (xy 339.141308 -425.419012) (xy 339.141723 -425.406928)
			(xy 339.149189 -425.383943) (xy 339.163394 -425.364392) (xy 339.182947 -425.350188) (xy 339.205932 -425.342723)
			(xy 339.218016 -425.342304) (xy 340.157816 -425.342304) (xy 340.169893 -425.342751) (xy 340.192862 -425.350219)
			(xy 340.2124 -425.36442) (xy 340.226594 -425.383963) (xy 340.234053 -425.406935) (xy 340.234524 -425.419012)
			(xy 340.234524 -427.960536) (xy 340.234067 -427.972611) (xy 340.226596 -427.995577) (xy 340.212397 -428.015112)
			(xy 340.192859 -428.029306) (xy 340.169891 -428.03677) (xy 340.157816 -428.037244) (xy 339.218016 -428.037244)
			(xy 339.205946 -428.036723) (xy 339.182985 -428.029269) (xy 339.163451 -428.015086) (xy 339.149255 -427.995561)
			(xy 339.141785 -427.972606) (xy 339.141308 -427.960536) (xy 338.234528 -427.960536) (xy 338.234528 -428.960534)
			(xy 338.234121 -428.972629) (xy 338.226651 -428.995636) (xy 338.21245 -429.015218) (xy 338.192902 -429.029466)
			(xy 338.169913 -429.036992) (xy 338.15782 -429.037496) (xy 337.21802 -429.037496) (xy 337.205912 -429.037066)
			(xy 337.182885 -429.029572) (xy 337.163311 -429.015314) (xy 337.149116 -428.995695) (xy 337.141695 -428.972643)
			(xy 337.141312 -428.960534) (xy 336.207549 -428.960534) (xy 336.212532 -428.964166) (xy 336.226726 -428.983789)
			(xy 336.234148 -429.006843) (xy 336.234532 -429.018954) (xy 336.234532 -431.560478) (xy 336.234073 -431.572569)
			(xy 336.226619 -431.595574) (xy 336.212432 -431.615156) (xy 336.192894 -431.629407) (xy 336.169914 -431.636934)
			(xy 336.157824 -431.63744) (xy 335.218024 -431.63744) (xy 335.20592 -431.636964) (xy 335.182901 -431.629476)
			(xy 335.163331 -431.615228) (xy 335.149134 -431.595622) (xy 335.141705 -431.572583) (xy 335.141316 -431.560478)
			(xy 334.234536 -431.560478) (xy 334.234536 -432.560476) (xy 334.234016 -432.572547) (xy 334.226563 -432.595508)
			(xy 334.21238 -432.615043) (xy 334.192855 -432.62924) (xy 334.169898 -432.636708) (xy 334.157828 -432.637184)
			(xy 333.218028 -432.637184) (xy 333.205944 -432.636763) (xy 333.182959 -432.6293) (xy 333.163406 -432.615097)
			(xy 333.149202 -432.595545) (xy 333.141738 -432.57256) (xy 333.14132 -432.560476) (xy 332.207208 -432.560476)
			(xy 332.212539 -432.564362) (xy 332.226733 -432.583985) (xy 332.234155 -432.607039) (xy 332.23454 -432.61915)
			(xy 332.23454 -435.160674) (xy 332.23407 -435.172764) (xy 332.226618 -435.195767) (xy 332.212433 -435.215349)
			(xy 332.192899 -435.2296) (xy 332.169921 -435.237129) (xy 332.157832 -435.237636) (xy 331.218032 -435.237636)
			(xy 331.205928 -435.237157) (xy 331.182908 -435.229671) (xy 331.163338 -435.215424) (xy 331.149141 -435.195818)
			(xy 331.141713 -435.172779) (xy 331.141324 -435.160674) (xy 329.234292 -435.160674) (xy 329.234292 -436.160672)
			(xy 329.233863 -436.172755) (xy 329.226401 -436.195739) (xy 329.2122 -436.215291) (xy 329.19265 -436.229496)
			(xy 329.169667 -436.236961) (xy 329.157584 -436.23738) (xy 328.217784 -436.23738) (xy 328.205698 -436.237001)
			(xy 328.18271 -436.229525) (xy 328.163157 -436.215312) (xy 328.148955 -436.195751) (xy 328.141492 -436.172759)
			(xy 328.141076 -436.160672) (xy 327.207321 -436.160672) (xy 327.212531 -436.164451) (xy 327.226778 -436.184004)
			(xy 327.234301 -436.206997) (xy 327.234804 -436.219092) (xy 327.234804 -438.760616) (xy 327.234397 -438.772725)
			(xy 327.226894 -438.795752) (xy 327.21263 -438.815325) (xy 327.193007 -438.829519) (xy 327.169953 -438.83694)
			(xy 327.157842 -438.837324) (xy 326.218042 -438.837324) (xy 326.205951 -438.836856) (xy 326.182946 -438.829407)
			(xy 326.163362 -438.815222) (xy 326.149111 -438.795686) (xy 326.141585 -438.772705) (xy 326.14108 -438.760616)
			(xy 325.234808 -438.760616) (xy 325.234808 -439.760614) (xy 328.141076 -439.760614) (xy 328.141076 -439.033666)
			(xy 328.141386 -439.024833) (xy 328.145481 -439.007645) (xy 328.149204 -438.99963) (xy 328.38263 -438.52338)
			(xy 328.387332 -438.512864) (xy 328.39082 -438.490105) (xy 328.387335 -438.467347) (xy 328.38263 -438.456832)
			(xy 328.149204 -437.980582) (xy 328.145442 -437.972579) (xy 328.14133 -437.955385) (xy 328.141076 -437.946546)
			(xy 328.141076 -437.21909) (xy 328.141452 -437.206963) (xy 328.148952 -437.183897) (xy 328.163213 -437.164279)
			(xy 328.18284 -437.15003) (xy 328.205911 -437.142545) (xy 328.218038 -437.142128) (xy 329.157838 -437.142128)
			(xy 329.169954 -437.142579) (xy 329.192996 -437.150076) (xy 329.212597 -437.164323) (xy 329.226837 -437.183929)
			(xy 329.234325 -437.206974) (xy 329.2348 -437.21909) (xy 329.2348 -438.760616) (xy 331.141324 -438.760616)
			(xy 331.141324 -438.033668) (xy 331.141564 -438.024847) (xy 331.145536 -438.00766) (xy 331.149198 -437.999632)
			(xy 331.382624 -437.523382) (xy 331.387325 -437.512865) (xy 331.390814 -437.490107) (xy 331.387329 -437.467348)
			(xy 331.382624 -437.456834) (xy 331.149198 -436.980584) (xy 331.145508 -436.972566) (xy 331.141536 -436.955372)
			(xy 331.141324 -436.946548) (xy 331.141324 -436.219092) (xy 331.141706 -436.207006) (xy 331.14918 -436.184017)
			(xy 331.163393 -436.164464) (xy 331.182953 -436.150262) (xy 331.205945 -436.1428) (xy 331.218032 -436.142384)
			(xy 332.157832 -436.142384) (xy 332.169907 -436.142837) (xy 332.192874 -436.150307) (xy 332.207134 -436.160672)
			(xy 333.14132 -436.160672) (xy 333.14132 -435.433724) (xy 333.141546 -435.424903) (xy 333.145528 -435.407715)
			(xy 333.149194 -435.399688) (xy 333.38262 -434.923438) (xy 333.387351 -434.912933) (xy 333.39083 -434.890167)
			(xy 333.387332 -434.867405) (xy 333.38262 -434.85689) (xy 333.149194 -434.38064) (xy 333.145522 -434.372615)
			(xy 333.141538 -434.355427) (xy 333.14132 -434.346604) (xy 333.14132 -433.619148) (xy 333.141754 -433.607065)
			(xy 333.149212 -433.584079) (xy 333.163411 -433.564526) (xy 333.182961 -433.550321) (xy 333.205945 -433.542857)
			(xy 333.218028 -433.54244) (xy 334.157828 -433.54244) (xy 334.169917 -433.542789) (xy 334.192909 -433.550271)
			(xy 334.212463 -433.564491) (xy 334.226664 -433.584059) (xy 334.234122 -433.607059) (xy 334.234536 -433.619148)
			(xy 334.234536 -435.160674) (xy 335.141316 -435.160674) (xy 335.141316 -434.433726) (xy 335.141543 -434.424905)
			(xy 335.145524 -434.407717) (xy 335.14919 -434.39969) (xy 335.382616 -433.92344) (xy 335.387346 -433.912935)
			(xy 335.390825 -433.890169) (xy 335.387328 -433.867407) (xy 335.382616 -433.856892) (xy 335.14919 -433.380642)
			(xy 335.145518 -433.372616) (xy 335.141534 -433.355429) (xy 335.141316 -433.346606) (xy 335.141316 -432.61915)
			(xy 335.141849 -432.607065) (xy 335.14929 -432.58407) (xy 335.16346 -432.564492) (xy 335.182978 -432.550239)
			(xy 335.205941 -432.542701) (xy 335.218024 -432.542188) (xy 336.157824 -432.542188) (xy 336.169933 -432.542596)
			(xy 336.192959 -432.5501) (xy 336.207195 -432.560476) (xy 337.141312 -432.560476) (xy 337.141312 -430.018952)
			(xy 337.141724 -430.006873) (xy 337.149202 -429.983901) (xy 337.163411 -429.964363) (xy 337.182962 -429.950171)
			(xy 337.205941 -429.942713) (xy 337.21802 -429.942244) (xy 338.15782 -429.942244) (xy 338.169891 -429.942747)
			(xy 338.19285 -429.950209) (xy 338.212383 -429.964397) (xy 338.226578 -429.983924) (xy 338.234049 -430.006881)
			(xy 338.234528 -430.018952) (xy 338.234528 -431.560478) (xy 339.141308 -431.560478) (xy 339.141308 -429.018954)
			(xy 339.141768 -429.006865) (xy 339.149233 -428.983868) (xy 339.163423 -428.964292) (xy 339.182955 -428.950042)
			(xy 339.205929 -428.942505) (xy 339.218016 -428.941992) (xy 340.157816 -428.941992) (xy 340.169925 -428.942402)
			(xy 340.192951 -428.949905) (xy 340.207536 -428.960534) (xy 341.141304 -428.960534) (xy 341.141304 -426.41901)
			(xy 341.141815 -426.406925) (xy 341.149265 -426.38393) (xy 341.163441 -426.364353) (xy 341.182963 -426.350101)
			(xy 341.205928 -426.342563) (xy 341.218012 -426.342048) (xy 342.157812 -426.342048) (xy 342.169916 -426.342505)
			(xy 342.192935 -426.350002) (xy 342.212504 -426.364255) (xy 342.2267 -426.383864) (xy 342.234129 -426.406905)
			(xy 342.23452 -426.41901) (xy 342.23452 -427.960536) (xy 343.1413 -427.960536) (xy 343.1413 -425.419012)
			(xy 343.141723 -425.406929) (xy 343.149188 -425.383946) (xy 343.163392 -425.364394) (xy 343.182942 -425.35019)
			(xy 343.205925 -425.342724) (xy 343.218008 -425.342304) (xy 344.157808 -425.342304) (xy 344.169892 -425.342706)
			(xy 344.192877 -425.350177) (xy 344.212429 -425.364386) (xy 344.226632 -425.383941) (xy 344.234097 -425.406928)
			(xy 344.234516 -425.419012) (xy 344.234516 -427.960536) (xy 344.234067 -427.972612) (xy 344.226595 -427.995579)
			(xy 344.212395 -428.015115) (xy 344.192854 -428.029308) (xy 344.169884 -428.036771) (xy 344.157808 -428.037244)
			(xy 343.218008 -428.037244) (xy 343.205937 -428.03673) (xy 343.182977 -428.029274) (xy 343.163443 -428.015089)
			(xy 343.149247 -427.995563) (xy 343.141777 -427.972606) (xy 343.1413 -427.960536) (xy 342.23452 -427.960536)
			(xy 342.23452 -428.960534) (xy 342.234121 -428.972629) (xy 342.22665 -428.995638) (xy 342.212447 -429.015221)
			(xy 342.192897 -429.029469) (xy 342.169906 -429.036993) (xy 342.157812 -429.037496) (xy 341.218012 -429.037496)
			(xy 341.205903 -429.037073) (xy 341.182876 -429.029577) (xy 341.163302 -429.015317) (xy 341.149107 -428.995696)
			(xy 341.141687 -428.972644) (xy 341.141304 -428.960534) (xy 340.207536 -428.960534) (xy 340.212524 -428.964169)
			(xy 340.226718 -428.983791) (xy 340.23414 -429.006844) (xy 340.234524 -429.018954) (xy 340.234524 -431.560478)
			(xy 340.234073 -431.57257) (xy 340.226618 -431.595576) (xy 340.212429 -431.615159) (xy 340.192889 -431.629409)
			(xy 340.169906 -431.636935) (xy 340.157816 -431.63744) (xy 339.218016 -431.63744) (xy 339.205912 -431.63697)
			(xy 339.182892 -431.62948) (xy 339.163322 -431.615231) (xy 339.149126 -431.595623) (xy 339.141697 -431.572583)
			(xy 339.141308 -431.560478) (xy 338.234528 -431.560478) (xy 338.234528 -432.560476) (xy 338.234067 -432.572555)
			(xy 338.226609 -432.595534) (xy 338.212414 -432.615083) (xy 338.192873 -432.629288) (xy 338.169899 -432.63676)
			(xy 338.15782 -432.637184) (xy 337.21802 -432.637184) (xy 337.205936 -432.63677) (xy 337.18295 -432.629305)
			(xy 337.163397 -432.6151) (xy 337.149193 -432.595547) (xy 337.14173 -432.57256) (xy 337.141312 -432.560476)
			(xy 336.207195 -432.560476) (xy 336.212531 -432.564365) (xy 336.226725 -432.583987) (xy 336.234147 -432.60704)
			(xy 336.234532 -432.61915) (xy 336.234532 -435.160674) (xy 336.23407 -435.172765) (xy 336.226617 -435.195769)
			(xy 336.21243 -435.215352) (xy 336.192894 -435.229603) (xy 336.169913 -435.23713) (xy 336.157824 -435.237636)
			(xy 335.218024 -435.237636) (xy 335.20592 -435.237164) (xy 335.1829 -435.229675) (xy 335.163329 -435.215427)
			(xy 335.149133 -435.195819) (xy 335.141705 -435.172779) (xy 335.141316 -435.160674) (xy 334.234536 -435.160674)
			(xy 334.234536 -436.160672) (xy 334.234012 -436.172742) (xy 334.226561 -436.195704) (xy 334.212379 -436.215239)
			(xy 334.192854 -436.229435) (xy 334.169898 -436.236904) (xy 334.157828 -436.23738) (xy 333.218028 -436.23738)
			(xy 333.205944 -436.236963) (xy 333.182957 -436.2295) (xy 333.163404 -436.215296) (xy 333.1492 -436.195743)
			(xy 333.141737 -436.172756) (xy 333.14132 -436.160672) (xy 332.207134 -436.160672) (xy 332.21241 -436.164507)
			(xy 332.226604 -436.184047) (xy 332.234067 -436.207016) (xy 332.23454 -436.219092) (xy 332.23454 -438.760616)
			(xy 332.23405 -438.772688) (xy 332.226587 -438.79565) (xy 332.212396 -438.815184) (xy 332.192865 -438.829379)
			(xy 332.169904 -438.836847) (xy 332.157832 -438.837324) (xy 331.218032 -438.837324) (xy 331.205953 -438.83686)
			(xy 331.182974 -438.829403) (xy 331.163424 -438.81521) (xy 331.149218 -438.795669) (xy 331.141747 -438.772695)
			(xy 331.141324 -438.760616) (xy 329.2348 -438.760616) (xy 329.2348 -439.760614) (xy 333.14132 -439.760614)
			(xy 333.14132 -439.033666) (xy 333.14156 -439.024845) (xy 333.145532 -439.007658) (xy 333.149194 -438.99963)
			(xy 333.38262 -438.52338) (xy 333.387322 -438.512864) (xy 333.390811 -438.490105) (xy 333.387326 -438.467346)
			(xy 333.38262 -438.456832) (xy 333.149194 -437.980582) (xy 333.145503 -437.972564) (xy 333.141532 -437.95537)
			(xy 333.14132 -437.946546) (xy 333.14132 -437.21909) (xy 333.141799 -437.207002) (xy 333.149256 -437.184004)
			(xy 333.16344 -437.164426) (xy 333.18297 -437.150176) (xy 333.205942 -437.14264) (xy 333.218028 -437.142128)
			(xy 334.157828 -437.142128) (xy 334.169941 -437.142493) (xy 334.192974 -437.150003) (xy 334.212549 -437.164277)
			(xy 334.226742 -437.183911) (xy 334.234157 -437.206975) (xy 334.234536 -437.21909) (xy 334.234536 -438.760616)
			(xy 335.141316 -438.760616) (xy 335.141316 -438.033668) (xy 335.141557 -438.024848) (xy 335.145529 -438.00766)
			(xy 335.14919 -437.999632) (xy 335.382616 -437.523382) (xy 335.387317 -437.512865) (xy 335.390807 -437.490107)
			(xy 335.387322 -437.467348) (xy 335.382616 -437.456834) (xy 335.14919 -436.980584) (xy 335.1455 -436.972566)
			(xy 335.141528 -436.955372) (xy 335.141316 -436.946548) (xy 335.141316 -436.219092) (xy 335.141706 -436.207006)
			(xy 335.149179 -436.184019) (xy 335.16339 -436.164467) (xy 335.182948 -436.150264) (xy 335.205938 -436.142801)
			(xy 335.218024 -436.142384) (xy 336.157824 -436.142384) (xy 336.169899 -436.142844) (xy 336.192866 -436.150312)
			(xy 336.20712 -436.160672) (xy 337.141312 -436.160672) (xy 337.141312 -435.433724) (xy 337.141539 -435.424903)
			(xy 337.14552 -435.407715) (xy 337.149186 -435.399688) (xy 337.382612 -434.923438) (xy 337.387344 -434.912933)
			(xy 337.390822 -434.890167) (xy 337.387324 -434.867405) (xy 337.382612 -434.85689) (xy 337.149186 -434.38064)
			(xy 337.145513 -434.372615) (xy 337.14153 -434.355427) (xy 337.141312 -434.346604) (xy 337.141312 -433.619148)
			(xy 337.141754 -433.607066) (xy 337.149211 -433.584081) (xy 337.163408 -433.564528) (xy 337.182956 -433.550323)
			(xy 337.205938 -433.542858) (xy 337.21802 -433.54244) (xy 338.15782 -433.54244) (xy 338.169909 -433.542796)
			(xy 338.1929 -433.550275) (xy 338.212454 -433.564494) (xy 338.226656 -433.584061) (xy 338.234114 -433.607059)
			(xy 338.234528 -433.619148) (xy 338.234528 -435.160674) (xy 339.141308 -435.160674) (xy 339.141308 -434.433726)
			(xy 339.141536 -434.424905) (xy 339.145517 -434.407717) (xy 339.149182 -434.39969) (xy 339.382608 -433.92344)
			(xy 339.387339 -433.912935) (xy 339.390818 -433.890169) (xy 339.38732 -433.867406) (xy 339.382608 -433.856892)
			(xy 339.149182 -433.380642) (xy 339.14551 -433.372617) (xy 339.141526 -433.355429) (xy 339.141308 -433.346606)
			(xy 339.141308 -432.61915) (xy 339.141849 -432.607066) (xy 339.149288 -432.584073) (xy 339.163457 -432.564495)
			(xy 339.182973 -432.550241) (xy 339.205934 -432.542702) (xy 339.218016 -432.542188) (xy 340.157816 -432.542188)
			(xy 340.169925 -432.542602) (xy 340.19295 -432.550105) (xy 340.207182 -432.560476) (xy 341.141304 -432.560476)
			(xy 341.141304 -430.018952) (xy 341.141723 -430.006874) (xy 341.149201 -429.983903) (xy 341.163408 -429.964366)
			(xy 341.182957 -429.950173) (xy 341.205933 -429.942714) (xy 341.218012 -429.942244) (xy 342.157812 -429.942244)
			(xy 342.169882 -429.942753) (xy 342.192842 -429.950213) (xy 342.212374 -429.9644) (xy 342.22657 -429.983926)
			(xy 342.234041 -430.006882) (xy 342.23452 -430.018952) (xy 342.23452 -431.560478) (xy 343.1413 -431.560478)
			(xy 343.1413 -429.018954) (xy 343.141767 -429.006866) (xy 343.149232 -428.983871) (xy 343.16342 -428.964295)
			(xy 343.18295 -428.950044) (xy 343.205922 -428.942507) (xy 343.218008 -428.941992) (xy 344.157808 -428.941992)
			(xy 344.169917 -428.942409) (xy 344.192943 -428.94991) (xy 344.207523 -428.960534) (xy 345.141296 -428.960534)
			(xy 345.141296 -426.41901) (xy 345.141815 -426.406925) (xy 345.149264 -426.383932) (xy 345.163439 -426.364356)
			(xy 345.182958 -426.350104) (xy 345.205921 -426.342564) (xy 345.218004 -426.342048) (xy 346.157804 -426.342048)
			(xy 346.169908 -426.342512) (xy 346.192927 -426.350006) (xy 346.212495 -426.364257) (xy 346.226691 -426.383866)
			(xy 346.234121 -426.406905) (xy 346.234512 -426.41901) (xy 346.234512 -428.960534) (xy 346.234121 -428.97263)
			(xy 346.226649 -428.99564) (xy 346.212444 -429.015223) (xy 346.192892 -429.029471) (xy 346.169899 -429.036994)
			(xy 346.157804 -429.037496) (xy 345.218004 -429.037496) (xy 345.205895 -429.03708) (xy 345.182867 -429.029582)
			(xy 345.163293 -429.01532) (xy 345.149099 -428.995698) (xy 345.141679 -428.972644) (xy 345.141296 -428.960534)
			(xy 344.207523 -428.960534) (xy 344.212515 -428.964172) (xy 344.22671 -428.983792) (xy 344.234132 -429.006844)
			(xy 344.234516 -429.018954) (xy 344.234516 -431.560478) (xy 344.234073 -431.572571) (xy 344.226617 -431.595578)
			(xy 344.212426 -431.615162) (xy 344.192884 -431.629412) (xy 344.169899 -431.636937) (xy 344.157808 -431.63744)
			(xy 343.218008 -431.63744) (xy 343.205904 -431.636978) (xy 343.182883 -431.629485) (xy 343.163313 -431.615234)
			(xy 343.149117 -431.595625) (xy 343.141689 -431.572584) (xy 343.1413 -431.560478) (xy 342.23452 -431.560478)
			(xy 342.23452 -432.560476) (xy 342.234067 -432.572556) (xy 342.226607 -432.595536) (xy 342.212411 -432.615086)
			(xy 342.192868 -432.629291) (xy 342.169892 -432.636761) (xy 342.157812 -432.637184) (xy 341.218012 -432.637184)
			(xy 341.205928 -432.636777) (xy 341.182941 -432.629309) (xy 341.163389 -432.615103) (xy 341.149185 -432.595548)
			(xy 341.141722 -432.572561) (xy 341.141304 -432.560476) (xy 340.207182 -432.560476) (xy 340.212522 -432.564367)
			(xy 340.226717 -432.583988) (xy 340.234139 -432.60704) (xy 340.234524 -432.61915) (xy 340.234524 -435.160674)
			(xy 340.23407 -435.172766) (xy 340.226616 -435.195772) (xy 340.212427 -435.215355) (xy 340.192889 -435.229605)
			(xy 340.169906 -435.237131) (xy 340.157816 -435.237636) (xy 339.218016 -435.237636) (xy 339.205912 -435.23717)
			(xy 339.182891 -435.22968) (xy 339.163321 -435.21543) (xy 339.149124 -435.195821) (xy 339.141697 -435.172779)
			(xy 339.141308 -435.160674) (xy 338.234528 -435.160674) (xy 338.234528 -436.160672) (xy 338.234064 -436.172751)
			(xy 338.226606 -436.19573) (xy 338.212413 -436.215279) (xy 338.192873 -436.229484) (xy 338.169899 -436.236956)
			(xy 338.15782 -436.23738) (xy 337.21802 -436.23738) (xy 337.205936 -436.23697) (xy 337.182949 -436.229504)
			(xy 337.163396 -436.215299) (xy 337.149192 -436.195744) (xy 337.141729 -436.172756) (xy 337.141312 -436.160672)
			(xy 336.20712 -436.160672) (xy 336.212401 -436.16451) (xy 336.226595 -436.184049) (xy 336.234059 -436.207017)
			(xy 336.234532 -436.219092) (xy 336.234532 -438.760616) (xy 336.23405 -438.772689) (xy 336.226586 -438.795653)
			(xy 336.212393 -438.815187) (xy 336.19286 -438.829382) (xy 336.169897 -438.836848) (xy 336.157824 -438.837324)
			(xy 335.218024 -438.837324) (xy 335.205944 -438.836867) (xy 335.182965 -438.829408) (xy 335.163416 -438.815213)
			(xy 335.14921 -438.795671) (xy 335.141739 -438.772696) (xy 335.141316 -438.760616) (xy 334.234536 -438.760616)
			(xy 334.234536 -439.760614) (xy 337.141312 -439.760614) (xy 337.141312 -439.033666) (xy 337.141552 -439.024846)
			(xy 337.145525 -439.007658) (xy 337.149186 -438.99963) (xy 337.382612 -438.52338) (xy 337.387315 -438.512864)
			(xy 337.390804 -438.490105) (xy 337.387318 -438.467346) (xy 337.382612 -438.456832) (xy 337.149186 -437.980582)
			(xy 337.145495 -437.972564) (xy 337.141524 -437.95537) (xy 337.141312 -437.946546) (xy 337.141312 -437.21909)
			(xy 337.141799 -437.207003) (xy 337.149255 -437.184007) (xy 337.163437 -437.164429) (xy 337.182965 -437.150178)
			(xy 337.205934 -437.142641) (xy 337.21802 -437.142128) (xy 338.15782 -437.142128) (xy 338.169933 -437.1425)
			(xy 338.192965 -437.150008) (xy 338.212541 -437.16428) (xy 338.226734 -437.183913) (xy 338.234149 -437.206976)
			(xy 338.234528 -437.21909) (xy 338.234528 -438.760616) (xy 339.141308 -438.760616) (xy 339.141308 -438.033668)
			(xy 339.141549 -438.024848) (xy 339.145521 -438.00766) (xy 339.149182 -437.999632) (xy 339.382608 -437.523382)
			(xy 339.387309 -437.512865) (xy 339.390799 -437.490107) (xy 339.387314 -437.467348) (xy 339.382608 -437.456834)
			(xy 339.149182 -436.980584) (xy 339.145491 -436.972566) (xy 339.14152 -436.955372) (xy 339.141308 -436.946548)
			(xy 339.141308 -436.219092) (xy 339.141706 -436.207007) (xy 339.149178 -436.184021) (xy 339.163387 -436.16447)
			(xy 339.182943 -436.150267) (xy 339.205931 -436.142802) (xy 339.218016 -436.142384) (xy 340.157816 -436.142384)
			(xy 340.169891 -436.142851) (xy 340.192857 -436.150317) (xy 340.207107 -436.160672) (xy 341.141304 -436.160672)
			(xy 341.141304 -435.433724) (xy 341.141531 -435.424903) (xy 341.145513 -435.407715) (xy 341.149178 -435.399688)
			(xy 341.382604 -434.923438) (xy 341.387336 -434.912933) (xy 341.390815 -434.890167) (xy 341.387317 -434.867404)
			(xy 341.382604 -434.85689) (xy 341.149178 -434.38064) (xy 341.145505 -434.372615) (xy 341.141522 -434.355427)
			(xy 341.141304 -434.346604) (xy 341.141304 -433.619148) (xy 341.141754 -433.607067) (xy 341.14921 -433.584083)
			(xy 341.163406 -433.564531) (xy 341.182951 -433.550326) (xy 341.205931 -433.542859) (xy 341.218012 -433.54244)
			(xy 342.157812 -433.54244) (xy 342.1699 -433.542803) (xy 342.192891 -433.55028) (xy 342.212446 -433.564497)
			(xy 342.226648 -433.584062) (xy 342.234106 -433.60706) (xy 342.23452 -433.619148) (xy 342.23452 -435.160674)
			(xy 343.1413 -435.160674) (xy 343.1413 -434.433726) (xy 343.141528 -434.424905) (xy 343.145509 -434.407717)
			(xy 343.149174 -434.39969) (xy 343.3826 -433.92344) (xy 343.387331 -433.912935) (xy 343.390811 -433.890169)
			(xy 343.387313 -433.867406) (xy 343.3826 -433.856892) (xy 343.149174 -433.380642) (xy 343.145501 -433.372617)
			(xy 343.141518 -433.355429) (xy 343.1413 -433.346606) (xy 343.1413 -432.61915) (xy 343.141849 -432.607067)
			(xy 343.149287 -432.584075) (xy 343.163454 -432.564497) (xy 343.182968 -432.550244) (xy 343.205927 -432.542703)
			(xy 343.218008 -432.542188) (xy 344.157808 -432.542188) (xy 344.169916 -432.542609) (xy 344.192942 -432.550109)
			(xy 344.20717 -432.560476) (xy 345.141296 -432.560476) (xy 345.141296 -430.018952) (xy 345.141723 -430.006875)
			(xy 345.149199 -429.983905) (xy 345.163405 -429.964368) (xy 345.182952 -429.950176) (xy 345.205926 -429.942715)
			(xy 345.218004 -429.942244) (xy 346.157804 -429.942244) (xy 346.169874 -429.94276) (xy 346.192833 -429.950218)
			(xy 346.212366 -429.964403) (xy 346.226562 -429.983927) (xy 346.234033 -430.006882) (xy 346.234512 -430.018952)
			(xy 346.234512 -431.360072) (xy 356.154736 -431.360072) (xy 356.155234 -431.275192) (xy 356.163191 -431.105619)
			(xy 356.179087 -430.936605) (xy 356.202888 -430.768522) (xy 356.234542 -430.601739) (xy 356.273978 -430.436623)
			(xy 356.32111 -430.273538) (xy 356.375834 -430.11284) (xy 356.438031 -429.954885) (xy 356.507563 -429.800018)
			(xy 356.584278 -429.648581) (xy 356.668006 -429.500905) (xy 356.758564 -429.357317) (xy 356.855753 -429.218131)
			(xy 356.95936 -429.083654) (xy 357.069155 -428.954181) (xy 357.184899 -428.829996) (xy 357.306336 -428.711373)
			(xy 357.4332 -428.598572) (xy 357.565211 -428.491842) (xy 357.702081 -428.391417) (xy 357.843506 -428.297518)
			(xy 357.989178 -428.21035) (xy 358.138776 -428.130107) (xy 358.29197 -428.056963) (xy 358.448424 -427.991081)
			(xy 358.607794 -427.932604) (xy 358.76973 -427.881662) (xy 358.933876 -427.838366) (xy 359.099871 -427.802811)
			(xy 359.26735 -427.775076) (xy 359.435945 -427.755222) (xy 359.605285 -427.743292) (xy 359.774998 -427.739313)
			(xy 359.944711 -427.743292) (xy 360.114051 -427.755222) (xy 360.282646 -427.775076) (xy 360.450125 -427.802811)
			(xy 360.61612 -427.838366) (xy 360.780266 -427.881662) (xy 360.942202 -427.932604) (xy 361.018326 -427.960536)
			(xy 381.2413 -427.960536) (xy 381.2413 -425.419012) (xy 381.241723 -425.406929) (xy 381.249188 -425.383946)
			(xy 381.263392 -425.364394) (xy 381.282942 -425.35019) (xy 381.305925 -425.342724) (xy 381.318008 -425.342304)
			(xy 382.257808 -425.342304) (xy 382.269892 -425.342706) (xy 382.292877 -425.350177) (xy 382.312429 -425.364386)
			(xy 382.326632 -425.383941) (xy 382.334097 -425.406928) (xy 382.334516 -425.419012) (xy 382.334516 -427.960536)
			(xy 382.334067 -427.972612) (xy 382.326595 -427.995579) (xy 382.312395 -428.015115) (xy 382.292854 -428.029308)
			(xy 382.269884 -428.036771) (xy 382.257808 -428.037244) (xy 381.318008 -428.037244) (xy 381.305937 -428.03673)
			(xy 381.282977 -428.029274) (xy 381.263443 -428.015089) (xy 381.249247 -427.995563) (xy 381.241777 -427.972606)
			(xy 381.2413 -427.960536) (xy 361.018326 -427.960536) (xy 361.101572 -427.991081) (xy 361.258026 -428.056963)
			(xy 361.41122 -428.130107) (xy 361.560818 -428.21035) (xy 361.70649 -428.297518) (xy 361.847915 -428.391417)
			(xy 361.984785 -428.491842) (xy 362.116796 -428.598572) (xy 362.24366 -428.711373) (xy 362.365097 -428.829996)
			(xy 362.480841 -428.954181) (xy 362.590636 -429.083654) (xy 362.694243 -429.218131) (xy 362.791432 -429.357317)
			(xy 362.88199 -429.500905) (xy 362.965718 -429.648581) (xy 363.042433 -429.800018) (xy 363.111965 -429.954885)
			(xy 363.174162 -430.11284) (xy 363.228886 -430.273538) (xy 363.276018 -430.436623) (xy 363.315454 -430.601739)
			(xy 363.347108 -430.768522) (xy 363.370909 -430.936605) (xy 363.386805 -431.105619) (xy 363.394762 -431.275192)
			(xy 363.39526 -431.360072) (xy 363.394788 -431.445675) (xy 363.389359 -431.560478) (xy 381.2413 -431.560478)
			(xy 381.2413 -429.018954) (xy 381.241767 -429.006866) (xy 381.249232 -428.983871) (xy 381.26342 -428.964295)
			(xy 381.28295 -428.950044) (xy 381.305922 -428.942507) (xy 381.318008 -428.941992) (xy 382.257808 -428.941992)
			(xy 382.269917 -428.942409) (xy 382.292943 -428.94991) (xy 382.307523 -428.960534) (xy 383.241296 -428.960534)
			(xy 383.241296 -426.41901) (xy 383.241815 -426.406925) (xy 383.249264 -426.383932) (xy 383.263439 -426.364356)
			(xy 383.282958 -426.350104) (xy 383.305921 -426.342564) (xy 383.318004 -426.342048) (xy 384.257804 -426.342048)
			(xy 384.269908 -426.342512) (xy 384.292927 -426.350006) (xy 384.312495 -426.364257) (xy 384.326691 -426.383866)
			(xy 384.334121 -426.406905) (xy 384.334512 -426.41901) (xy 384.334512 -427.960536) (xy 385.241292 -427.960536)
			(xy 385.241292 -425.419012) (xy 385.241723 -425.40693) (xy 385.249187 -425.383948) (xy 385.263389 -425.364397)
			(xy 385.282937 -425.350193) (xy 385.305918 -425.342725) (xy 385.318 -425.342304) (xy 386.2578 -425.342304)
			(xy 386.269884 -425.342713) (xy 386.292869 -425.350182) (xy 386.31242 -425.364388) (xy 386.326624 -425.383942)
			(xy 386.334089 -425.406928) (xy 386.334508 -425.419012) (xy 386.334508 -427.960536) (xy 386.334067 -427.972612)
			(xy 386.326594 -427.995581) (xy 386.312392 -428.015117) (xy 386.292849 -428.029311) (xy 386.269877 -428.036772)
			(xy 386.2578 -428.037244) (xy 385.318 -428.037244) (xy 385.305929 -428.036736) (xy 385.282968 -428.029278)
			(xy 385.263434 -428.015092) (xy 385.249238 -427.995564) (xy 385.241769 -427.972607) (xy 385.241292 -427.960536)
			(xy 384.334512 -427.960536) (xy 384.334512 -428.960534) (xy 384.334121 -428.97263) (xy 384.326649 -428.99564)
			(xy 384.312444 -429.015223) (xy 384.292892 -429.029471) (xy 384.269899 -429.036994) (xy 384.257804 -429.037496)
			(xy 383.318004 -429.037496) (xy 383.305895 -429.03708) (xy 383.282867 -429.029582) (xy 383.263293 -429.01532)
			(xy 383.249099 -428.995698) (xy 383.241679 -428.972644) (xy 383.241296 -428.960534) (xy 382.307523 -428.960534)
			(xy 382.312515 -428.964172) (xy 382.32671 -428.983792) (xy 382.334132 -429.006844) (xy 382.334516 -429.018954)
			(xy 382.334516 -431.560478) (xy 382.334073 -431.572571) (xy 382.326617 -431.595578) (xy 382.312426 -431.615162)
			(xy 382.292884 -431.629412) (xy 382.269899 -431.636937) (xy 382.257808 -431.63744) (xy 381.318008 -431.63744)
			(xy 381.305904 -431.636978) (xy 381.282883 -431.629485) (xy 381.263313 -431.615234) (xy 381.249117 -431.595625)
			(xy 381.241689 -431.572584) (xy 381.2413 -431.560478) (xy 363.389359 -431.560478) (xy 363.386701 -431.616689)
			(xy 363.370537 -431.787129) (xy 363.346334 -431.956615) (xy 363.314145 -432.124767) (xy 363.274043 -432.291209)
			(xy 363.226117 -432.455569) (xy 363.170474 -432.61748) (xy 363.107239 -432.776579) (xy 363.036553 -432.932511)
			(xy 362.958574 -433.084927) (xy 362.873477 -433.233486) (xy 362.781452 -433.377855) (xy 362.682704 -433.517713)
			(xy 362.577455 -433.652746) (xy 362.46594 -433.782652) (xy 362.348408 -433.907141) (xy 362.225123 -434.025934)
			(xy 362.096359 -434.138766) (xy 361.962404 -434.245385) (xy 361.82356 -434.345551) (xy 361.680135 -434.439042)
			(xy 361.53245 -434.525647) (xy 361.380836 -434.605174) (xy 361.225632 -434.677444) (xy 361.146598 -434.710332)
			(xy 361.138713 -434.713995) (xy 361.125816 -434.725637) (xy 361.117551 -434.740919) (xy 361.115864 -434.749448)
			(xy 361.100116 -434.849016) (xy 361.109514 -434.873654) (xy 361.119928 -434.88229) (xy 361.169374 -434.924299)
			(xy 361.263563 -435.013553) (xy 361.352051 -435.108462) (xy 361.395012 -435.160674) (xy 381.2413 -435.160674)
			(xy 381.2413 -434.433726) (xy 381.241528 -434.424905) (xy 381.245509 -434.407717) (xy 381.249174 -434.39969)
			(xy 381.4826 -433.92344) (xy 381.487331 -433.912935) (xy 381.490811 -433.890169) (xy 381.487313 -433.867406)
			(xy 381.4826 -433.856892) (xy 381.249174 -433.380642) (xy 381.245501 -433.372617) (xy 381.241518 -433.355429)
			(xy 381.2413 -433.346606) (xy 381.2413 -432.61915) (xy 381.241849 -432.607067) (xy 381.249287 -432.584075)
			(xy 381.263454 -432.564497) (xy 381.282968 -432.550244) (xy 381.305927 -432.542703) (xy 381.318008 -432.542188)
			(xy 382.257808 -432.542188) (xy 382.269916 -432.542609) (xy 382.292942 -432.550109) (xy 382.30717 -432.560476)
			(xy 383.241296 -432.560476) (xy 383.241296 -430.018952) (xy 383.241723 -430.006875) (xy 383.249199 -429.983905)
			(xy 383.263405 -429.964368) (xy 383.282952 -429.950176) (xy 383.305926 -429.942715) (xy 383.318004 -429.942244)
			(xy 384.257804 -429.942244) (xy 384.269874 -429.94276) (xy 384.292833 -429.950218) (xy 384.312366 -429.964403)
			(xy 384.326562 -429.983927) (xy 384.334033 -430.006882) (xy 384.334512 -430.018952) (xy 384.334512 -431.560478)
			(xy 385.241292 -431.560478) (xy 385.241292 -429.018954) (xy 385.241767 -429.006867) (xy 385.249231 -428.983873)
			(xy 385.263417 -428.964298) (xy 385.282945 -428.950047) (xy 385.305914 -428.942508) (xy 385.318 -428.941992)
			(xy 386.2578 -428.941992) (xy 386.269908 -428.942416) (xy 386.292934 -428.949914) (xy 386.307511 -428.960534)
			(xy 387.241288 -428.960534) (xy 387.241288 -426.41901) (xy 387.241717 -426.406916) (xy 387.249177 -426.383908)
			(xy 387.263371 -426.364324) (xy 387.282916 -426.350075) (xy 387.305904 -426.342551) (xy 387.317996 -426.342048)
			(xy 388.257796 -426.342048) (xy 388.269899 -426.342519) (xy 388.292918 -426.350011) (xy 388.312487 -426.36426)
			(xy 388.326683 -426.383867) (xy 388.334113 -426.406905) (xy 388.334504 -426.41901) (xy 388.334504 -427.960536)
			(xy 389.241284 -427.960536) (xy 389.241284 -425.419012) (xy 389.241723 -425.406931) (xy 389.249186 -425.38395)
			(xy 389.263386 -425.3644) (xy 389.282932 -425.350195) (xy 389.305911 -425.342726) (xy 389.317992 -425.342304)
			(xy 390.257792 -425.342304) (xy 390.269876 -425.342719) (xy 390.29286 -425.350186) (xy 390.312412 -425.364391)
			(xy 390.326616 -425.383943) (xy 390.334081 -425.406928) (xy 390.3345 -425.419012) (xy 390.3345 -427.960536)
			(xy 390.334067 -427.972613) (xy 390.326593 -427.995583) (xy 390.312389 -428.01512) (xy 390.292844 -428.029313)
			(xy 390.26987 -428.036773) (xy 390.257792 -428.037244) (xy 389.317992 -428.037244) (xy 389.305921 -428.036743)
			(xy 389.282959 -428.029283) (xy 389.263426 -428.015094) (xy 389.24923 -427.995566) (xy 389.241761 -427.972607)
			(xy 389.241284 -427.960536) (xy 388.334504 -427.960536) (xy 388.334504 -428.960534) (xy 388.334023 -428.972621)
			(xy 388.326562 -428.995615) (xy 388.312377 -429.015191) (xy 388.29285 -429.029442) (xy 388.269881 -429.036981)
			(xy 388.257796 -429.037496) (xy 387.317996 -429.037496) (xy 387.305887 -429.037087) (xy 387.282858 -429.029586)
			(xy 387.263285 -429.015323) (xy 387.249091 -428.995699) (xy 387.241671 -428.972645) (xy 387.241288 -428.960534)
			(xy 386.307511 -428.960534) (xy 386.312507 -428.964174) (xy 386.326701 -428.983794) (xy 386.334124 -429.006845)
			(xy 386.334508 -429.018954) (xy 386.334508 -431.560478) (xy 386.333975 -431.572562) (xy 386.32653 -431.595553)
			(xy 386.312359 -431.61513) (xy 386.292842 -431.629383) (xy 386.269882 -431.636924) (xy 386.2578 -431.63744)
			(xy 385.318 -431.63744) (xy 385.305895 -431.636984) (xy 385.282875 -431.62949) (xy 385.263305 -431.615237)
			(xy 385.249109 -431.595626) (xy 385.241681 -431.572584) (xy 385.241292 -431.560478) (xy 384.334512 -431.560478)
			(xy 384.334512 -432.560476) (xy 384.334067 -432.572557) (xy 384.326606 -432.595538) (xy 384.312409 -432.615089)
			(xy 384.292863 -432.629294) (xy 384.269885 -432.636762) (xy 384.257804 -432.637184) (xy 383.318004 -432.637184)
			(xy 383.305919 -432.636784) (xy 383.282932 -432.629314) (xy 383.26338 -432.615106) (xy 383.249176 -432.59555)
			(xy 383.241713 -432.572561) (xy 383.241296 -432.560476) (xy 382.30717 -432.560476) (xy 382.312514 -432.56437)
			(xy 382.326708 -432.58399) (xy 382.334131 -432.607041) (xy 382.334516 -432.61915) (xy 382.334516 -435.160674)
			(xy 382.33407 -435.172767) (xy 382.326615 -435.195774) (xy 382.312424 -435.215358) (xy 382.292883 -435.229608)
			(xy 382.269899 -435.237133) (xy 382.257808 -435.237636) (xy 381.318008 -435.237636) (xy 381.305903 -435.237178)
			(xy 381.282882 -435.229685) (xy 381.263312 -435.215433) (xy 381.249116 -435.195822) (xy 381.241688 -435.17278)
			(xy 381.2413 -435.160674) (xy 361.395012 -435.160674) (xy 361.434498 -435.208663) (xy 361.510589 -435.313772)
			(xy 361.580032 -435.423387) (xy 361.642562 -435.537087) (xy 361.697938 -435.654438) (xy 361.74595 -435.77499)
			(xy 361.786412 -435.89828) (xy 361.81917 -436.023838) (xy 361.844098 -436.151181) (xy 361.861101 -436.279823)
			(xy 361.870114 -436.40927) (xy 361.871103 -436.539027) (xy 361.864062 -436.668596) (xy 361.849021 -436.797482)
			(xy 361.826035 -436.92519) (xy 361.795194 -437.051232) (xy 361.756614 -437.175125) (xy 361.710445 -437.296394)
			(xy 361.656862 -437.414574) (xy 361.596072 -437.529214) (xy 361.528306 -437.639874) (xy 361.453825 -437.74613)
			(xy 361.372914 -437.847575) (xy 361.285882 -437.943821) (xy 361.193064 -438.034499) (xy 361.094814 -438.119261)
			(xy 360.991508 -438.197784) (xy 360.883543 -438.269766) (xy 360.771333 -438.334931) (xy 360.655306 -438.39303)
			(xy 360.535907 -438.443841) (xy 360.413594 -438.487169) (xy 360.288835 -438.522847) (xy 360.162108 -438.550739)
			(xy 360.033898 -438.570739) (xy 359.904696 -438.58277) (xy 359.774998 -438.586785) (xy 359.6453 -438.58277)
			(xy 359.516098 -438.570739) (xy 359.387888 -438.550739) (xy 359.261161 -438.522847) (xy 359.136402 -438.487169)
			(xy 359.014089 -438.443841) (xy 358.89469 -438.39303) (xy 358.778663 -438.334931) (xy 358.666453 -438.269766)
			(xy 358.558488 -438.197784) (xy 358.455182 -438.119261) (xy 358.356932 -438.034499) (xy 358.264114 -437.943821)
			(xy 358.177082 -437.847575) (xy 358.096171 -437.74613) (xy 358.02169 -437.639874) (xy 357.953924 -437.529214)
			(xy 357.893134 -437.414574) (xy 357.839551 -437.296394) (xy 357.793382 -437.175125) (xy 357.754802 -437.051232)
			(xy 357.723961 -436.92519) (xy 357.700975 -436.797482) (xy 357.685934 -436.668596) (xy 357.678893 -436.539027)
			(xy 357.679882 -436.40927) (xy 357.688895 -436.279823) (xy 357.705898 -436.151181) (xy 357.730826 -436.023838)
			(xy 357.763584 -435.89828) (xy 357.804046 -435.77499) (xy 357.852058 -435.654438) (xy 357.907434 -435.537087)
			(xy 357.969964 -435.423387) (xy 358.039407 -435.313772) (xy 358.115498 -435.208663) (xy 358.197945 -435.108462)
			(xy 358.286433 -435.013553) (xy 358.380622 -434.924299) (xy 358.430068 -434.88229) (xy 358.440228 -434.873908)
			(xy 358.449626 -434.849016) (xy 358.4321 -434.73624) (xy 358.415844 -434.715412) (xy 358.403398 -434.710332)
			(xy 358.325295 -434.677853) (xy 358.1719 -434.606515) (xy 358.022004 -434.52809) (xy 357.875935 -434.44275)
			(xy 357.734012 -434.350681) (xy 357.596544 -434.252083) (xy 357.463831 -434.147172) (xy 357.336162 -434.036176)
			(xy 357.213818 -433.919339) (xy 357.097064 -433.796915) (xy 356.986156 -433.669172) (xy 356.881335 -433.536387)
			(xy 356.782831 -433.398852) (xy 356.690858 -433.256866) (xy 356.605617 -433.110739) (xy 356.527295 -432.96079)
			(xy 356.456061 -432.807346) (xy 356.392073 -432.650743) (xy 356.335468 -432.491322) (xy 356.286372 -432.329431)
			(xy 356.244891 -432.165424) (xy 356.211115 -431.999658) (xy 356.185119 -431.832496) (xy 356.166958 -431.664301)
			(xy 356.156674 -431.495443) (xy 356.15499 -431.410872) (xy 356.155244 -431.410872) (xy 356.154736 -431.360072)
			(xy 346.234512 -431.360072) (xy 346.234512 -432.560476) (xy 346.234067 -432.572557) (xy 346.226606 -432.595538)
			(xy 346.212409 -432.615089) (xy 346.192863 -432.629294) (xy 346.169885 -432.636762) (xy 346.157804 -432.637184)
			(xy 345.218004 -432.637184) (xy 345.205919 -432.636784) (xy 345.182932 -432.629314) (xy 345.16338 -432.615106)
			(xy 345.149176 -432.59555) (xy 345.141713 -432.572561) (xy 345.141296 -432.560476) (xy 344.20717 -432.560476)
			(xy 344.212514 -432.56437) (xy 344.226708 -432.58399) (xy 344.234131 -432.607041) (xy 344.234516 -432.61915)
			(xy 344.234516 -435.160674) (xy 344.23407 -435.172767) (xy 344.226615 -435.195774) (xy 344.212424 -435.215358)
			(xy 344.192883 -435.229608) (xy 344.169899 -435.237133) (xy 344.157808 -435.237636) (xy 343.218008 -435.237636)
			(xy 343.205903 -435.237178) (xy 343.182882 -435.229685) (xy 343.163312 -435.215433) (xy 343.149116 -435.195822)
			(xy 343.141688 -435.17278) (xy 343.1413 -435.160674) (xy 342.23452 -435.160674) (xy 342.23452 -436.160672)
			(xy 342.234064 -436.172752) (xy 342.226605 -436.195732) (xy 342.21241 -436.215281) (xy 342.192868 -436.229487)
			(xy 342.169892 -436.236957) (xy 342.157812 -436.23738) (xy 341.218012 -436.23738) (xy 341.205927 -436.236976)
			(xy 341.18294 -436.229509) (xy 341.163387 -436.215301) (xy 341.149184 -436.195746) (xy 341.141721 -436.172757)
			(xy 341.141304 -436.160672) (xy 340.207107 -436.160672) (xy 340.212393 -436.164513) (xy 340.226587 -436.18405)
			(xy 340.234051 -436.207017) (xy 340.234524 -436.219092) (xy 340.234524 -438.760616) (xy 340.23405 -438.77269)
			(xy 340.226585 -438.795655) (xy 340.21239 -438.81519) (xy 340.192855 -438.829385) (xy 340.16989 -438.83685)
			(xy 340.157816 -438.837324) (xy 339.218016 -438.837324) (xy 339.205944 -438.836822) (xy 339.18298 -438.829366)
			(xy 339.163444 -438.815179) (xy 339.149248 -438.795649) (xy 339.141783 -438.772688) (xy 339.141308 -438.760616)
			(xy 338.234528 -438.760616) (xy 338.234528 -439.760614) (xy 341.141304 -439.760614) (xy 341.141304 -439.033666)
			(xy 341.141545 -439.024846) (xy 341.145517 -439.007658) (xy 341.149178 -438.99963) (xy 341.382604 -438.52338)
			(xy 341.387307 -438.512864) (xy 341.390796 -438.490105) (xy 341.38731 -438.467346) (xy 341.382604 -438.456832)
			(xy 341.149178 -437.980582) (xy 341.145487 -437.972564) (xy 341.141515 -437.95537) (xy 341.141304 -437.946546)
			(xy 341.141304 -437.21909) (xy 341.141798 -437.207004) (xy 341.149253 -437.184009) (xy 341.163434 -437.164432)
			(xy 341.18296 -437.150181) (xy 341.205927 -437.142643) (xy 341.218012 -437.142128) (xy 342.157812 -437.142128)
			(xy 342.169924 -437.142506) (xy 342.192957 -437.150012) (xy 342.212532 -437.164283) (xy 342.226725 -437.183914)
			(xy 342.234141 -437.206976) (xy 342.23452 -437.21909) (xy 342.23452 -438.760616) (xy 343.1413 -438.760616)
			(xy 343.1413 -438.033668) (xy 343.141542 -438.024848) (xy 343.145513 -438.00766) (xy 343.149174 -437.999632)
			(xy 343.3826 -437.523382) (xy 343.387302 -437.512866) (xy 343.390792 -437.490107) (xy 343.387306 -437.467348)
			(xy 343.3826 -437.456834) (xy 343.149174 -436.980584) (xy 343.145483 -436.972566) (xy 343.141512 -436.955372)
			(xy 343.1413 -436.946548) (xy 343.1413 -436.219092) (xy 343.141758 -436.207016) (xy 343.149223 -436.184047)
			(xy 343.163421 -436.16451) (xy 343.182962 -436.150316) (xy 343.205932 -436.142855) (xy 343.218008 -436.142384)
			(xy 344.157808 -436.142384) (xy 344.169882 -436.142857) (xy 344.192848 -436.150321) (xy 344.207094 -436.160672)
			(xy 345.141296 -436.160672) (xy 345.141296 -435.433724) (xy 345.141524 -435.424903) (xy 345.145505 -435.407715)
			(xy 345.14917 -435.399688) (xy 345.382596 -434.923438) (xy 345.387329 -434.912934) (xy 345.390808 -434.890167)
			(xy 345.387309 -434.867404) (xy 345.382596 -434.85689) (xy 345.14917 -434.38064) (xy 345.145496 -434.372615)
			(xy 345.141514 -434.355427) (xy 345.141296 -434.346604) (xy 345.141296 -433.619148) (xy 345.141754 -433.607067)
			(xy 345.149208 -433.584086) (xy 345.163403 -433.564534) (xy 345.182946 -433.550329) (xy 345.205924 -433.542861)
			(xy 345.218004 -433.54244) (xy 346.157804 -433.54244) (xy 346.169892 -433.54281) (xy 346.192883 -433.550284)
			(xy 346.212437 -433.5645) (xy 346.226639 -433.584064) (xy 346.234098 -433.60706) (xy 346.234512 -433.619148)
			(xy 346.234512 -436.160672) (xy 346.234063 -436.172753) (xy 346.226604 -436.195734) (xy 346.212407 -436.215284)
			(xy 346.192863 -436.229489) (xy 346.169885 -436.236958) (xy 346.157804 -436.23738) (xy 345.218004 -436.23738)
			(xy 345.205919 -436.236984) (xy 345.182931 -436.229514) (xy 345.163378 -436.215304) (xy 345.149175 -436.195747)
			(xy 345.141712 -436.172757) (xy 345.141296 -436.160672) (xy 344.207094 -436.160672) (xy 344.212384 -436.164516)
			(xy 344.226579 -436.184052) (xy 344.234043 -436.207018) (xy 344.234516 -436.219092) (xy 344.234516 -438.760616)
			(xy 344.234049 -438.772691) (xy 344.226583 -438.795657) (xy 344.212387 -438.815193) (xy 344.19285 -438.829387)
			(xy 344.169883 -438.836851) (xy 344.157808 -438.837324) (xy 343.218008 -438.837324) (xy 343.205935 -438.836829)
			(xy 343.182971 -438.829371) (xy 343.163435 -438.815182) (xy 343.14924 -438.79565) (xy 343.141775 -438.772688)
			(xy 343.1413 -438.760616) (xy 342.23452 -438.760616) (xy 342.23452 -439.760614) (xy 345.141296 -439.760614)
			(xy 345.141296 -439.033666) (xy 345.141538 -439.024846) (xy 345.145509 -439.007658) (xy 345.14917 -438.99963)
			(xy 345.382596 -438.52338) (xy 345.387299 -438.512864) (xy 345.390789 -438.490105) (xy 345.387302 -438.467346)
			(xy 345.382596 -438.456832) (xy 345.14917 -437.980582) (xy 345.145478 -437.972565) (xy 345.141507 -437.95537)
			(xy 345.141296 -437.946546) (xy 345.141296 -437.21909) (xy 345.141798 -437.207004) (xy 345.149252 -437.184011)
			(xy 345.163431 -437.164435) (xy 345.182955 -437.150183) (xy 345.20592 -437.142644) (xy 345.218004 -437.142128)
			(xy 346.157804 -437.142128) (xy 346.169916 -437.142513) (xy 346.192948 -437.150017) (xy 346.212524 -437.164286)
			(xy 346.226717 -437.183916) (xy 346.234133 -437.206977) (xy 346.234512 -437.21909) (xy 346.234512 -438.760616)
			(xy 381.2413 -438.760616) (xy 381.2413 -438.033668) (xy 381.241609 -438.024835) (xy 381.245704 -438.007647)
			(xy 381.249428 -437.999632) (xy 381.482854 -437.523382) (xy 381.487553 -437.512865) (xy 381.491041 -437.490107)
			(xy 381.487557 -437.467349) (xy 381.482854 -437.456834) (xy 381.249428 -436.980584) (xy 381.245668 -436.97258)
			(xy 381.241554 -436.955387) (xy 381.2413 -436.946548) (xy 381.2413 -436.219092) (xy 381.241709 -436.206983)
			(xy 381.249211 -436.183955) (xy 381.263474 -436.164382) (xy 381.283097 -436.150188) (xy 381.306151 -436.142767)
			(xy 381.318262 -436.142384) (xy 382.258062 -436.142384) (xy 382.270154 -436.142841) (xy 382.293161 -436.150292)
			(xy 382.307489 -436.160672) (xy 383.241296 -436.160672) (xy 383.241296 -435.433724) (xy 383.241524 -435.424903)
			(xy 383.245505 -435.407715) (xy 383.24917 -435.399688) (xy 383.482596 -434.923438) (xy 383.487329 -434.912934)
			(xy 383.490808 -434.890167) (xy 383.487309 -434.867404) (xy 383.482596 -434.85689) (xy 383.24917 -434.38064)
			(xy 383.245496 -434.372615) (xy 383.241514 -434.355427) (xy 383.241296 -434.346604) (xy 383.241296 -433.619148)
			(xy 383.241754 -433.607067) (xy 383.249208 -433.584086) (xy 383.263403 -433.564534) (xy 383.282946 -433.550329)
			(xy 383.305924 -433.542861) (xy 383.318004 -433.54244) (xy 384.257804 -433.54244) (xy 384.269892 -433.54281)
			(xy 384.292883 -433.550284) (xy 384.312437 -433.5645) (xy 384.326639 -433.584064) (xy 384.334098 -433.60706)
			(xy 384.334512 -433.619148) (xy 384.334512 -435.160674) (xy 385.241292 -435.160674) (xy 385.241292 -434.433726)
			(xy 385.241521 -434.424905) (xy 385.245501 -434.407717) (xy 385.249166 -434.39969) (xy 385.482592 -433.92344)
			(xy 385.487324 -433.912935) (xy 385.490804 -433.890169) (xy 385.487305 -433.867406) (xy 385.482592 -433.856892)
			(xy 385.249166 -433.380642) (xy 385.245493 -433.372617) (xy 385.24151 -433.355429) (xy 385.241292 -433.346606)
			(xy 385.241292 -432.61915) (xy 385.241849 -432.607068) (xy 385.249286 -432.584077) (xy 385.263451 -432.5645)
			(xy 385.282963 -432.550246) (xy 385.30592 -432.542705) (xy 385.318 -432.542188) (xy 386.2578 -432.542188)
			(xy 386.269908 -432.542616) (xy 386.292933 -432.550114) (xy 386.307156 -432.560476) (xy 387.241288 -432.560476)
			(xy 387.241288 -430.018952) (xy 387.241723 -430.006875) (xy 387.249198 -429.983907) (xy 387.263403 -429.964371)
			(xy 387.282947 -429.950178) (xy 387.305919 -429.942716) (xy 387.317996 -429.942244) (xy 388.257796 -429.942244)
			(xy 388.269866 -429.942767) (xy 388.292824 -429.950222) (xy 388.312357 -429.964406) (xy 388.326554 -429.983929)
			(xy 388.334025 -430.006883) (xy 388.334504 -430.018952) (xy 388.334504 -431.560478) (xy 389.241284 -431.560478)
			(xy 389.241284 -429.018954) (xy 389.241669 -429.006858) (xy 389.249144 -428.983848) (xy 389.26335 -428.964265)
			(xy 389.282903 -428.950018) (xy 389.305897 -428.942495) (xy 389.317992 -428.941992) (xy 390.257792 -428.941992)
			(xy 390.2699 -428.942423) (xy 390.292925 -428.949919) (xy 390.307497 -428.960534) (xy 391.24128 -428.960534)
			(xy 391.24128 -426.41901) (xy 391.241717 -426.406917) (xy 391.249176 -426.38391) (xy 391.263369 -426.364326)
			(xy 391.282911 -426.350077) (xy 391.305896 -426.342552) (xy 391.317988 -426.342048) (xy 392.257788 -426.342048)
			(xy 392.269891 -426.342526) (xy 392.292909 -426.350016) (xy 392.312478 -426.364263) (xy 392.326675 -426.383869)
			(xy 392.334105 -426.406906) (xy 392.334496 -426.41901) (xy 392.334496 -427.960536) (xy 393.241276 -427.960536)
			(xy 393.241276 -425.419012) (xy 393.241774 -425.40694) (xy 393.249231 -425.383976) (xy 393.26342 -425.36444)
			(xy 393.28295 -425.350244) (xy 393.305912 -425.342779) (xy 393.317984 -425.342304) (xy 394.257784 -425.342304)
			(xy 394.269867 -425.342727) (xy 394.292851 -425.350191) (xy 394.312403 -425.364394) (xy 394.326607 -425.383945)
			(xy 394.334073 -425.406929) (xy 394.334492 -425.419012) (xy 394.334492 -427.960536) (xy 394.334066 -427.972614)
			(xy 394.326592 -427.995585) (xy 394.312386 -428.015123) (xy 394.292839 -428.029316) (xy 394.269862 -428.036775)
			(xy 394.257784 -428.037244) (xy 393.317984 -428.037244) (xy 393.305912 -428.03675) (xy 393.282951 -428.029287)
			(xy 393.263417 -428.015097) (xy 393.249222 -427.995567) (xy 393.241753 -427.972608) (xy 393.241276 -427.960536)
			(xy 392.334496 -427.960536) (xy 392.334496 -428.960534) (xy 392.334022 -428.972622) (xy 392.326561 -428.995617)
			(xy 392.312374 -429.015194) (xy 392.292845 -429.029444) (xy 392.269874 -429.036982) (xy 392.257788 -429.037496)
			(xy 391.317988 -429.037496) (xy 391.305878 -429.037094) (xy 391.28285 -429.029591) (xy 391.263276 -429.015326)
			(xy 391.249082 -428.995701) (xy 391.241663 -428.972645) (xy 391.24128 -428.960534) (xy 390.307497 -428.960534)
			(xy 390.312498 -428.964177) (xy 390.326693 -428.983795) (xy 390.334116 -429.006845) (xy 390.3345 -429.018954)
			(xy 390.3345 -431.560478) (xy 390.333975 -431.572562) (xy 390.326529 -431.595556) (xy 390.312356 -431.615132)
			(xy 390.292837 -431.629385) (xy 390.269874 -431.636925) (xy 390.257792 -431.63744) (xy 389.317992 -431.63744)
			(xy 389.305887 -431.636991) (xy 389.282866 -431.629494) (xy 389.263296 -431.61524) (xy 389.249101 -431.595628)
			(xy 389.241673 -431.572585) (xy 389.241284 -431.560478) (xy 388.334504 -431.560478) (xy 388.334504 -432.560476)
			(xy 388.334067 -432.572558) (xy 388.326605 -432.59554) (xy 388.312406 -432.615091) (xy 388.292858 -432.629296)
			(xy 388.269878 -432.636764) (xy 388.257796 -432.637184) (xy 387.317996 -432.637184) (xy 387.305911 -432.636791)
			(xy 387.282924 -432.629319) (xy 387.263371 -432.615109) (xy 387.249168 -432.595551) (xy 387.241705 -432.572562)
			(xy 387.241288 -432.560476) (xy 386.307156 -432.560476) (xy 386.312505 -432.564373) (xy 386.3267 -432.583991)
			(xy 386.334123 -432.607041) (xy 386.334508 -432.61915) (xy 386.334508 -435.160674) (xy 386.333971 -435.172757)
			(xy 386.326528 -435.195749) (xy 386.312357 -435.215325) (xy 386.292841 -435.229578) (xy 386.269881 -435.23712)
			(xy 386.2578 -435.237636) (xy 385.318 -435.237636) (xy 385.305895 -435.237184) (xy 385.282873 -435.229689)
			(xy 385.263304 -435.215436) (xy 385.249108 -435.195824) (xy 385.24168 -435.17278) (xy 385.241292 -435.160674)
			(xy 384.334512 -435.160674) (xy 384.334512 -436.160672) (xy 384.334063 -436.172753) (xy 384.326604 -436.195734)
			(xy 384.312407 -436.215284) (xy 384.292863 -436.229489) (xy 384.269885 -436.236958) (xy 384.257804 -436.23738)
			(xy 383.318004 -436.23738) (xy 383.305919 -436.236984) (xy 383.282931 -436.229514) (xy 383.263378 -436.215304)
			(xy 383.249175 -436.195747) (xy 383.241712 -436.172757) (xy 383.241296 -436.160672) (xy 382.307489 -436.160672)
			(xy 382.312745 -436.16448) (xy 382.326995 -436.184019) (xy 382.334521 -436.207002) (xy 382.335024 -436.219092)
			(xy 382.335024 -438.760616) (xy 382.334598 -438.772723) (xy 382.327097 -438.795747) (xy 382.312837 -438.815318)
			(xy 382.293219 -438.829513) (xy 382.270171 -438.836937) (xy 382.258062 -438.837324) (xy 381.318262 -438.837324)
			(xy 381.306167 -438.836924) (xy 381.283159 -438.829453) (xy 381.263577 -438.81525) (xy 381.249329 -438.795701)
			(xy 381.241804 -438.77271) (xy 381.2413 -438.760616) (xy 346.234512 -438.760616) (xy 346.234512 -439.760614)
			(xy 383.241296 -439.760614) (xy 383.241296 -439.033666) (xy 383.241604 -439.024833) (xy 383.2457 -439.007645)
			(xy 383.249424 -438.99963) (xy 383.48285 -438.52338) (xy 383.487551 -438.512864) (xy 383.491038 -438.490105)
			(xy 383.487554 -438.467347) (xy 383.48285 -438.456832) (xy 383.249424 -437.980582) (xy 383.245663 -437.972579)
			(xy 383.24155 -437.955385) (xy 383.241296 -437.946546) (xy 383.241296 -437.21909) (xy 383.241803 -437.206979)
			(xy 383.249288 -437.183943) (xy 383.263522 -437.164345) (xy 383.283114 -437.150102) (xy 383.306147 -437.142608)
			(xy 383.318258 -437.142128) (xy 384.258058 -437.142128) (xy 384.270178 -437.142595) (xy 384.293233 -437.150075)
			(xy 384.312848 -437.164315) (xy 384.327101 -437.18392) (xy 384.334596 -437.206971) (xy 384.33502 -437.21909)
			(xy 384.33502 -438.760616) (xy 385.241292 -438.760616) (xy 385.241292 -438.033668) (xy 385.241601 -438.024835)
			(xy 385.245697 -438.007647) (xy 385.24942 -437.999632) (xy 385.482846 -437.523382) (xy 385.487546 -437.512865)
			(xy 385.491034 -437.490107) (xy 385.48755 -437.467349) (xy 385.482846 -437.456834) (xy 385.24942 -436.980584)
			(xy 385.245659 -436.97258) (xy 385.241546 -436.955387) (xy 385.241292 -436.946548) (xy 385.241292 -436.219092)
			(xy 385.241709 -436.206983) (xy 385.24921 -436.183957) (xy 385.263472 -436.164385) (xy 385.283092 -436.15019)
			(xy 385.306144 -436.142768) (xy 385.318254 -436.142384) (xy 386.258054 -436.142384) (xy 386.270146 -436.142847)
			(xy 386.293152 -436.150297) (xy 386.307476 -436.160672) (xy 387.241288 -436.160672) (xy 387.241288 -435.433724)
			(xy 387.241517 -435.424903) (xy 387.245497 -435.407715) (xy 387.249162 -435.399688) (xy 387.482588 -434.923438)
			(xy 387.487321 -434.912934) (xy 387.4908 -434.890167) (xy 387.487301 -434.867404) (xy 387.482588 -434.85689)
			(xy 387.249162 -434.38064) (xy 387.245488 -434.372615) (xy 387.241506 -434.355427) (xy 387.241288 -434.346604)
			(xy 387.241288 -433.619148) (xy 387.241753 -433.607068) (xy 387.249207 -433.584088) (xy 387.2634 -433.564537)
			(xy 387.282941 -433.550331) (xy 387.305916 -433.542862) (xy 387.317996 -433.54244) (xy 388.257796 -433.54244)
			(xy 388.269883 -433.542817) (xy 388.292874 -433.550289) (xy 388.312429 -433.564503) (xy 388.326631 -433.584065)
			(xy 388.33409 -433.60706) (xy 388.334504 -433.619148) (xy 388.334504 -435.160674) (xy 389.241284 -435.160674)
			(xy 389.241284 -434.433726) (xy 389.241514 -434.424905) (xy 389.245494 -434.407718) (xy 389.249158 -434.39969)
			(xy 389.482584 -433.92344) (xy 389.487316 -433.912935) (xy 389.490796 -433.890169) (xy 389.487297 -433.867406)
			(xy 389.482584 -433.856892) (xy 389.249158 -433.380642) (xy 389.245484 -433.372617) (xy 389.241502 -433.355429)
			(xy 389.241284 -433.346606) (xy 389.241284 -432.61915) (xy 389.241751 -432.607059) (xy 389.249199 -432.584052)
			(xy 389.263384 -432.564468) (xy 389.282921 -432.550217) (xy 389.305902 -432.542692) (xy 389.317992 -432.542188)
			(xy 390.257792 -432.542188) (xy 390.269899 -432.542623) (xy 390.292924 -432.550119) (xy 390.307143 -432.560476)
			(xy 391.24128 -432.560476) (xy 391.24128 -430.018952) (xy 391.241723 -430.006876) (xy 391.249197 -429.983909)
			(xy 391.2634 -429.964374) (xy 391.282942 -429.950181) (xy 391.305912 -429.942717) (xy 391.317988 -429.942244)
			(xy 392.257788 -429.942244) (xy 392.269857 -429.942774) (xy 392.292816 -429.950227) (xy 392.312349 -429.964408)
			(xy 392.326546 -429.98393) (xy 392.334017 -430.006883) (xy 392.334496 -430.018952) (xy 392.334496 -431.560478)
			(xy 393.241276 -431.560478) (xy 393.241276 -429.018954) (xy 393.241669 -429.006858) (xy 393.249143 -428.98385)
			(xy 393.263347 -428.964268) (xy 393.282898 -428.95002) (xy 393.30589 -428.942496) (xy 393.317984 -428.941992)
			(xy 394.257784 -428.941992) (xy 394.269891 -428.94243) (xy 394.292917 -428.949924) (xy 394.307483 -428.960534)
			(xy 395.241272 -428.960534) (xy 395.241272 -426.41901) (xy 395.241717 -426.406918) (xy 395.249174 -426.383912)
			(xy 395.263366 -426.364329) (xy 395.282906 -426.35008) (xy 395.305889 -426.342553) (xy 395.31798 -426.342048)
			(xy 396.25778 -426.342048) (xy 396.269883 -426.342533) (xy 396.2929 -426.35002) (xy 396.312469 -426.364266)
			(xy 396.326666 -426.38387) (xy 396.334097 -426.406906) (xy 396.334488 -426.41901) (xy 396.334488 -427.960536)
			(xy 398.241012 -427.960536) (xy 398.241012 -425.419012) (xy 398.241427 -425.406903) (xy 398.248924 -425.383874)
			(xy 398.263186 -425.364299) (xy 398.282809 -425.350105) (xy 398.305863 -425.342686) (xy 398.317974 -425.342304)
			(xy 399.257774 -425.342304) (xy 399.269859 -425.342829) (xy 399.292852 -425.350274) (xy 399.31243 -425.364447)
			(xy 399.326682 -425.383966) (xy 399.334221 -425.406929) (xy 399.334736 -425.419012) (xy 399.334736 -427.960536)
			(xy 399.334315 -427.972643) (xy 399.32681 -427.995665) (xy 399.312548 -428.015235) (xy 399.29293 -428.029429)
			(xy 399.269883 -428.036856) (xy 399.257774 -428.037244) (xy 398.317974 -428.037244) (xy 398.305881 -428.036815)
			(xy 398.282877 -428.029349) (xy 398.263296 -428.015153) (xy 398.249047 -427.995611) (xy 398.241519 -427.972627)
			(xy 398.241012 -427.960536) (xy 396.334488 -427.960536) (xy 396.334488 -428.960534) (xy 396.334022 -428.972623)
			(xy 396.32656 -428.99562) (xy 396.312372 -429.015197) (xy 396.29284 -429.029447) (xy 396.269867 -429.036983)
			(xy 396.25778 -429.037496) (xy 395.31798 -429.037496) (xy 395.30587 -429.037101) (xy 395.282841 -429.029595)
			(xy 395.263268 -429.015328) (xy 395.249074 -428.995702) (xy 395.241655 -428.972646) (xy 395.241272 -428.960534)
			(xy 394.307483 -428.960534) (xy 394.312489 -428.96418) (xy 394.326685 -428.983797) (xy 394.334107 -429.006846)
			(xy 394.334492 -429.018954) (xy 394.334492 -431.560478) (xy 394.333974 -431.572563) (xy 394.326528 -431.595558)
			(xy 394.312353 -431.615135) (xy 394.292832 -431.629388) (xy 394.269867 -431.636926) (xy 394.257784 -431.63744)
			(xy 393.317984 -431.63744) (xy 393.305878 -431.636998) (xy 393.282857 -431.629499) (xy 393.263288 -431.615243)
			(xy 393.249092 -431.595629) (xy 393.241665 -431.572585) (xy 393.241276 -431.560478) (xy 392.334496 -431.560478)
			(xy 392.334496 -432.560476) (xy 392.334067 -432.572559) (xy 392.326604 -432.595543) (xy 392.312403 -432.615094)
			(xy 392.292853 -432.629299) (xy 392.269871 -432.636765) (xy 392.257788 -432.637184) (xy 391.317988 -432.637184)
			(xy 391.305902 -432.636797) (xy 391.282915 -432.629324) (xy 391.263363 -432.615112) (xy 391.24916 -432.595553)
			(xy 391.241697 -432.572562) (xy 391.24128 -432.560476) (xy 390.307143 -432.560476) (xy 390.312497 -432.564376)
			(xy 390.326692 -432.583993) (xy 390.334115 -432.607041) (xy 390.3345 -432.61915) (xy 390.3345 -435.160674)
			(xy 390.333971 -435.172758) (xy 390.326526 -435.195751) (xy 390.312354 -435.215328) (xy 390.292836 -435.229581)
			(xy 390.269874 -435.237121) (xy 390.257792 -435.237636) (xy 389.317992 -435.237636) (xy 389.305886 -435.237191)
			(xy 389.282865 -435.229694) (xy 389.263295 -435.215438) (xy 389.249099 -435.195825) (xy 389.241672 -435.172781)
			(xy 389.241284 -435.160674) (xy 388.334504 -435.160674) (xy 388.334504 -436.160672) (xy 388.334063 -436.172754)
			(xy 388.326603 -436.195736) (xy 388.312404 -436.215287) (xy 388.292858 -436.229492) (xy 388.269878 -436.23696)
			(xy 388.257796 -436.23738) (xy 387.317996 -436.23738) (xy 387.30591 -436.236991) (xy 387.282923 -436.229518)
			(xy 387.26337 -436.215307) (xy 387.249167 -436.195749) (xy 387.241704 -436.172758) (xy 387.241288 -436.160672)
			(xy 386.307476 -436.160672) (xy 386.312737 -436.164483) (xy 386.326987 -436.18402) (xy 386.334512 -436.207002)
			(xy 386.335016 -436.219092) (xy 386.335016 -438.760616) (xy 386.334598 -438.772724) (xy 386.327096 -438.795749)
			(xy 386.312834 -438.815321) (xy 386.293214 -438.829515) (xy 386.270163 -438.836939) (xy 386.258054 -438.837324)
			(xy 385.318254 -438.837324) (xy 385.306158 -438.836931) (xy 385.28315 -438.829457) (xy 385.263568 -438.815253)
			(xy 385.24932 -438.795702) (xy 385.241796 -438.77271) (xy 385.241292 -438.760616) (xy 384.33502 -438.760616)
			(xy 384.33502 -439.760614) (xy 387.241288 -439.760614) (xy 387.241288 -439.033666) (xy 387.241597 -439.024833)
			(xy 387.245693 -439.007645) (xy 387.249416 -438.99963) (xy 387.482842 -438.52338) (xy 387.487543 -438.512864)
			(xy 387.491031 -438.490105) (xy 387.487546 -438.467347) (xy 387.482842 -438.456832) (xy 387.249416 -437.980582)
			(xy 387.245655 -437.972579) (xy 387.241542 -437.955385) (xy 387.241288 -437.946546) (xy 387.241288 -437.21909)
			(xy 387.241803 -437.20698) (xy 387.249287 -437.183945) (xy 387.263519 -437.164348) (xy 387.283109 -437.150105)
			(xy 387.30614 -437.142609) (xy 387.31825 -437.142128) (xy 388.25805 -437.142128) (xy 388.270166 -437.142569)
			(xy 388.293209 -437.150069) (xy 388.312809 -437.164319) (xy 388.32705 -437.183927) (xy 388.334537 -437.206974)
			(xy 388.335012 -437.21909) (xy 388.335012 -438.760616) (xy 389.241284 -438.760616) (xy 389.241284 -438.033668)
			(xy 389.241594 -438.024835) (xy 389.245689 -438.007647) (xy 389.249412 -437.999632) (xy 389.482838 -437.523382)
			(xy 389.487538 -437.512865) (xy 389.491026 -437.490107) (xy 389.487542 -437.467349) (xy 389.482838 -437.456834)
			(xy 389.249412 -436.980584) (xy 389.245651 -436.972581) (xy 389.241538 -436.955387) (xy 389.241284 -436.946548)
			(xy 389.241284 -436.219092) (xy 389.241709 -436.206984) (xy 389.249209 -436.183959) (xy 389.263469 -436.164388)
			(xy 389.283087 -436.150193) (xy 389.306137 -436.142769) (xy 389.318246 -436.142384) (xy 390.258046 -436.142384)
			(xy 390.270142 -436.142769) (xy 390.293152 -436.150244) (xy 390.307527 -436.160672) (xy 391.24128 -436.160672)
			(xy 391.24128 -435.433724) (xy 391.24151 -435.424903) (xy 391.24549 -435.407716) (xy 391.249154 -435.399688)
			(xy 391.48258 -434.923438) (xy 391.487313 -434.912934) (xy 391.490793 -434.890167) (xy 391.487294 -434.867404)
			(xy 391.48258 -434.85689) (xy 391.249154 -434.38064) (xy 391.24548 -434.372615) (xy 391.241498 -434.355427)
			(xy 391.24128 -434.346604) (xy 391.24128 -433.619148) (xy 391.241753 -433.607069) (xy 391.249206 -433.58409)
			(xy 391.263397 -433.56454) (xy 391.282936 -433.550334) (xy 391.305909 -433.542863) (xy 391.317988 -433.54244)
			(xy 392.257788 -433.54244) (xy 392.269875 -433.542824) (xy 392.292865 -433.550294) (xy 392.31242 -433.564506)
			(xy 392.326623 -433.584067) (xy 392.334082 -433.607061) (xy 392.334496 -433.619148) (xy 392.334496 -435.160674)
			(xy 393.241276 -435.160674) (xy 393.241276 -434.433726) (xy 393.241507 -434.424905) (xy 393.245486 -434.407718)
			(xy 393.24915 -434.39969) (xy 393.482576 -433.92344) (xy 393.487308 -433.912935) (xy 393.490789 -433.890169)
			(xy 393.48729 -433.867406) (xy 393.482576 -433.856892) (xy 393.24915 -433.380642) (xy 393.245476 -433.372617)
			(xy 393.241494 -433.355429) (xy 393.241276 -433.346606) (xy 393.241276 -432.61915) (xy 393.241751 -432.607059)
			(xy 393.249198 -432.584054) (xy 393.263381 -432.56447) (xy 393.282916 -432.550219) (xy 393.305895 -432.542693)
			(xy 393.317984 -432.542188) (xy 394.257784 -432.542188) (xy 394.269891 -432.54263) (xy 394.292915 -432.550124)
			(xy 394.307129 -432.560476) (xy 395.241272 -432.560476) (xy 395.241272 -430.018952) (xy 395.241723 -430.006877)
			(xy 395.249196 -429.983912) (xy 395.263397 -429.964377) (xy 395.282937 -429.950183) (xy 395.305905 -429.942718)
			(xy 395.31798 -429.942244) (xy 396.25778 -429.942244) (xy 396.269849 -429.94278) (xy 396.292807 -429.950232)
			(xy 396.31234 -429.964411) (xy 396.326537 -429.983932) (xy 396.334009 -430.006884) (xy 396.334488 -430.018952)
			(xy 396.334488 -431.560478) (xy 398.241012 -431.560478) (xy 398.241012 -429.018954) (xy 398.241472 -429.00684)
			(xy 398.248969 -428.983799) (xy 398.263215 -428.964201) (xy 398.282817 -428.94996) (xy 398.30586 -428.942469)
			(xy 398.317974 -428.941992) (xy 399.257774 -428.941992) (xy 399.269883 -428.942533) (xy 399.292917 -428.950008)
			(xy 399.307419 -428.960534) (xy 400.241008 -428.960534) (xy 400.241008 -426.41901) (xy 400.24152 -426.406899)
			(xy 400.249001 -426.383861) (xy 400.263233 -426.364262) (xy 400.282825 -426.350019) (xy 400.305859 -426.342526)
			(xy 400.31797 -426.342048) (xy 401.25777 -426.342048) (xy 401.269892 -426.342486) (xy 401.292952 -426.349971)
			(xy 401.312568 -426.364218) (xy 401.32682 -426.38383) (xy 401.334311 -426.406888) (xy 401.334732 -426.41901)
			(xy 401.334732 -427.960536) (xy 402.241004 -427.960536) (xy 402.241004 -425.419012) (xy 402.241427 -425.406903)
			(xy 402.248923 -425.383876) (xy 402.263183 -425.364302) (xy 402.282804 -425.350107) (xy 402.305856 -425.342687)
			(xy 402.317966 -425.342304) (xy 403.257766 -425.342304) (xy 403.26985 -425.342836) (xy 403.292844 -425.350279)
			(xy 403.312421 -425.36445) (xy 403.326674 -425.383968) (xy 403.334213 -425.40693) (xy 403.334728 -425.419012)
			(xy 403.334728 -427.960536) (xy 403.334315 -427.972644) (xy 403.326809 -427.995668) (xy 403.312545 -428.015238)
			(xy 403.292925 -428.029432) (xy 403.269875 -428.036857) (xy 403.257766 -428.037244) (xy 402.317966 -428.037244)
			(xy 402.305873 -428.036821) (xy 402.282869 -428.029353) (xy 402.263288 -428.015156) (xy 402.249039 -427.995612)
			(xy 402.241511 -427.972628) (xy 402.241004 -427.960536) (xy 401.334732 -427.960536) (xy 401.334732 -428.960534)
			(xy 401.334317 -428.972653) (xy 401.326817 -428.995703) (xy 401.312561 -429.015307) (xy 401.292945 -429.029546)
			(xy 401.26989 -429.037027) (xy 401.25777 -429.037496) (xy 400.31797 -429.037496) (xy 400.305857 -429.037014)
			(xy 400.282819 -429.029523) (xy 400.26322 -429.015282) (xy 400.248979 -428.995685) (xy 400.241486 -428.972647)
			(xy 400.241008 -428.960534) (xy 399.307419 -428.960534) (xy 399.312515 -428.964233) (xy 399.326759 -428.983818)
			(xy 399.334255 -429.006846) (xy 399.334736 -429.018954) (xy 399.334736 -431.560478) (xy 399.334321 -431.572602)
			(xy 399.326832 -431.595665) (xy 399.31258 -431.615282) (xy 399.292961 -431.629533) (xy 399.269898 -431.637022)
			(xy 399.257774 -431.63744) (xy 398.317974 -431.63744) (xy 398.305856 -431.63701) (xy 398.282808 -431.629513)
			(xy 398.263205 -431.615261) (xy 398.248965 -431.595649) (xy 398.241482 -431.572596) (xy 398.241012 -431.560478)
			(xy 396.334488 -431.560478) (xy 396.334488 -432.560476) (xy 396.334066 -432.572559) (xy 396.326603 -432.595545)
			(xy 396.3124 -432.615097) (xy 396.292848 -432.629301) (xy 396.269863 -432.636766) (xy 396.25778 -432.637184)
			(xy 395.31798 -432.637184) (xy 395.305894 -432.636804) (xy 395.282906 -432.629328) (xy 395.263354 -432.615114)
			(xy 395.249152 -432.595554) (xy 395.241689 -432.572562) (xy 395.241272 -432.560476) (xy 394.307129 -432.560476)
			(xy 394.312488 -432.564379) (xy 394.326683 -432.583995) (xy 394.334107 -432.607042) (xy 394.334492 -432.61915)
			(xy 394.334492 -435.160674) (xy 394.333971 -435.172759) (xy 394.326525 -435.195753) (xy 394.312352 -435.215331)
			(xy 394.292831 -435.229584) (xy 394.269867 -435.237122) (xy 394.257784 -435.237636) (xy 393.317984 -435.237636)
			(xy 393.305878 -435.237198) (xy 393.282856 -435.229698) (xy 393.263287 -435.215441) (xy 393.249091 -435.195827)
			(xy 393.241664 -435.172781) (xy 393.241276 -435.160674) (xy 392.334496 -435.160674) (xy 392.334496 -436.160672)
			(xy 392.334063 -436.172754) (xy 392.326602 -436.195738) (xy 392.312401 -436.21529) (xy 392.292853 -436.229495)
			(xy 392.26987 -436.236961) (xy 392.257788 -436.23738) (xy 391.317988 -436.23738) (xy 391.305902 -436.236997)
			(xy 391.282914 -436.229523) (xy 391.263361 -436.21531) (xy 391.249159 -436.19575) (xy 391.241696 -436.172758)
			(xy 391.24128 -436.160672) (xy 390.307527 -436.160672) (xy 390.312735 -436.16445) (xy 390.326982 -436.184003)
			(xy 390.334505 -436.206997) (xy 390.335008 -436.219092) (xy 390.335008 -438.760616) (xy 390.334598 -438.772725)
			(xy 390.327095 -438.795751) (xy 390.312831 -438.815324) (xy 390.293209 -438.829518) (xy 390.270156 -438.83694)
			(xy 390.258046 -438.837324) (xy 389.318246 -438.837324) (xy 389.306155 -438.836853) (xy 389.28315 -438.829404)
			(xy 389.263566 -438.81522) (xy 389.249315 -438.795685) (xy 389.241789 -438.772705) (xy 389.241284 -438.760616)
			(xy 388.335012 -438.760616) (xy 388.335012 -439.760614) (xy 391.24128 -439.760614) (xy 391.24128 -439.033666)
			(xy 391.24159 -439.024833) (xy 391.245685 -439.007645) (xy 391.249408 -438.99963) (xy 391.482834 -438.52338)
			(xy 391.487536 -438.512864) (xy 391.491024 -438.490105) (xy 391.487539 -438.467347) (xy 391.482834 -438.456832)
			(xy 391.249408 -437.980582) (xy 391.245646 -437.972579) (xy 391.241534 -437.955385) (xy 391.24128 -437.946546)
			(xy 391.24128 -437.21909) (xy 391.241652 -437.206963) (xy 391.249152 -437.183896) (xy 391.263415 -437.164278)
			(xy 391.283043 -437.150029) (xy 391.306114 -437.142544) (xy 391.318242 -437.142128) (xy 392.258042 -437.142128)
			(xy 392.270158 -437.142576) (xy 392.293201 -437.150073) (xy 392.312801 -437.164322) (xy 392.327041 -437.183928)
			(xy 392.334529 -437.206974) (xy 392.335004 -437.21909) (xy 392.335004 -438.760616) (xy 393.241276 -438.760616)
			(xy 393.241276 -438.033668) (xy 393.241587 -438.024835) (xy 393.245681 -438.007647) (xy 393.249404 -437.999632)
			(xy 393.48283 -437.523382) (xy 393.48753 -437.512865) (xy 393.491019 -437.490107) (xy 393.487535 -437.467349)
			(xy 393.48283 -437.456834) (xy 393.249404 -436.980584) (xy 393.245643 -436.972581) (xy 393.24153 -436.955387)
			(xy 393.241276 -436.946548) (xy 393.241276 -436.219092) (xy 393.241709 -436.206985) (xy 393.249208 -436.183962)
			(xy 393.263466 -436.164391) (xy 393.283082 -436.150195) (xy 393.30613 -436.142771) (xy 393.318238 -436.142384)
			(xy 394.258038 -436.142384) (xy 394.270134 -436.142776) (xy 394.293143 -436.150248) (xy 394.307514 -436.160672)
			(xy 395.241272 -436.160672) (xy 395.241272 -435.433724) (xy 395.241502 -435.424903) (xy 395.245482 -435.407716)
			(xy 395.249146 -435.399688) (xy 395.482572 -434.923438) (xy 395.487306 -434.912934) (xy 395.490786 -434.890167)
			(xy 395.487286 -434.867404) (xy 395.482572 -434.85689) (xy 395.249146 -434.38064) (xy 395.245471 -434.372616)
			(xy 395.24149 -434.355427) (xy 395.241272 -434.346604) (xy 395.241272 -433.619148) (xy 395.241753 -433.60707)
			(xy 395.249205 -433.584092) (xy 395.263394 -433.564543) (xy 395.282931 -433.550336) (xy 395.305902 -433.542864)
			(xy 395.31798 -433.54244) (xy 396.25778 -433.54244) (xy 396.269866 -433.542831) (xy 396.292857 -433.550298)
			(xy 396.312411 -433.564509) (xy 396.326614 -433.584069) (xy 396.334074 -433.607061) (xy 396.334488 -433.619148)
			(xy 396.334488 -435.160674) (xy 398.24152 -435.160674) (xy 398.24152 -434.433726) (xy 398.241747 -434.424905)
			(xy 398.245728 -434.407717) (xy 398.249394 -434.39969) (xy 398.48282 -433.92344) (xy 398.48755 -433.912935)
			(xy 398.491029 -433.890169) (xy 398.487532 -433.867407) (xy 398.48282 -433.856892) (xy 398.249394 -433.380642)
			(xy 398.245722 -433.372616) (xy 398.241738 -433.355429) (xy 398.24152 -433.346606) (xy 398.24152 -432.61915)
			(xy 398.24205 -432.607065) (xy 398.24949 -432.584069) (xy 398.263661 -432.56449) (xy 398.283181 -432.550237)
			(xy 398.306145 -432.542701) (xy 398.318228 -432.542188) (xy 399.258028 -432.542188) (xy 399.270137 -432.542592)
			(xy 399.293163 -432.550098) (xy 399.307402 -432.560476) (xy 400.241008 -432.560476) (xy 400.241008 -430.018952)
			(xy 400.241376 -430.00684) (xy 400.248889 -429.98381) (xy 400.263163 -429.964237) (xy 400.282795 -429.950044)
			(xy 400.305856 -429.942626) (xy 400.31797 -429.942244) (xy 401.25777 -429.942244) (xy 401.269858 -429.942733)
			(xy 401.292859 -429.950182) (xy 401.312439 -429.964363) (xy 401.326691 -429.983892) (xy 401.334223 -430.006865)
			(xy 401.334732 -430.018952) (xy 401.334732 -431.560478) (xy 402.241004 -431.560478) (xy 402.241004 -429.018954)
			(xy 402.241472 -429.00684) (xy 402.248968 -428.983801) (xy 402.263212 -428.964203) (xy 402.282812 -428.949962)
			(xy 402.305852 -428.94247) (xy 402.317966 -428.941992) (xy 403.257766 -428.941992) (xy 403.269874 -428.94254)
			(xy 403.292909 -428.950012) (xy 403.307406 -428.960534) (xy 404.241 -428.960534) (xy 404.241 -426.41901)
			(xy 404.24152 -426.4069) (xy 404.249 -426.383863) (xy 404.263231 -426.364265) (xy 404.28282 -426.350022)
			(xy 404.305852 -426.342527) (xy 404.317962 -426.342048) (xy 405.257762 -426.342048) (xy 405.269884 -426.342492)
			(xy 405.292943 -426.349975) (xy 405.31256 -426.36422) (xy 405.326812 -426.383832) (xy 405.334303 -426.406888)
			(xy 405.334724 -426.41901) (xy 405.334724 -427.960536) (xy 406.240996 -427.960536) (xy 406.240996 -425.419012)
			(xy 406.241427 -425.406904) (xy 406.248922 -425.383878) (xy 406.26318 -425.364305) (xy 406.282799 -425.35011)
			(xy 406.305849 -425.342688) (xy 406.317958 -425.342304) (xy 407.257758 -425.342304) (xy 407.269842 -425.342842)
			(xy 407.292835 -425.350283) (xy 407.312413 -425.364453) (xy 407.326666 -425.383969) (xy 407.334205 -425.40693)
			(xy 407.33472 -425.419012) (xy 407.33472 -427.960536) (xy 407.334315 -427.972645) (xy 407.326808 -427.99567)
			(xy 407.312543 -428.01524) (xy 407.29292 -428.029435) (xy 407.269868 -428.036858) (xy 407.257758 -428.037244)
			(xy 406.317958 -428.037244) (xy 406.305865 -428.036828) (xy 406.28286 -428.029358) (xy 406.263279 -428.015159)
			(xy 406.249031 -427.995614) (xy 406.241503 -427.972628) (xy 406.240996 -427.960536) (xy 405.334724 -427.960536)
			(xy 405.334724 -428.960534) (xy 405.334369 -428.972662) (xy 405.326862 -428.995729) (xy 405.312595 -429.015347)
			(xy 405.292964 -429.029595) (xy 405.269891 -429.03708) (xy 405.257762 -429.037496) (xy 404.317962 -429.037496)
			(xy 404.305849 -429.037021) (xy 404.28281 -429.029528) (xy 404.263212 -429.015285) (xy 404.24897 -428.995686)
			(xy 404.241478 -428.972647) (xy 404.241 -428.960534) (xy 403.307406 -428.960534) (xy 403.312507 -428.964236)
			(xy 403.326751 -428.98382) (xy 403.334247 -429.006846) (xy 403.334728 -429.018954) (xy 403.334728 -431.560478)
			(xy 403.334321 -431.572603) (xy 403.32683 -431.595667) (xy 403.312577 -431.615285) (xy 403.292956 -431.629536)
			(xy 403.269891 -431.637023) (xy 403.257766 -431.63744) (xy 402.317966 -431.63744) (xy 402.305847 -431.637017)
			(xy 402.282799 -431.629518) (xy 402.263196 -431.615264) (xy 402.248957 -431.59565) (xy 402.241474 -431.572597)
			(xy 402.241004 -431.560478) (xy 401.334732 -431.560478) (xy 401.334732 -432.560476) (xy 401.334263 -432.57258)
			(xy 401.326775 -432.595601) (xy 401.312525 -432.615172) (xy 401.292917 -432.629369) (xy 401.269875 -432.636796)
			(xy 401.25777 -432.637184) (xy 400.31797 -432.637184) (xy 400.305881 -432.636719) (xy 400.282884 -432.629257)
			(xy 400.263306 -432.615069) (xy 400.249056 -432.595537) (xy 400.24152 -432.572563) (xy 400.241008 -432.560476)
			(xy 399.307402 -432.560476) (xy 399.312735 -432.564363) (xy 399.326929 -432.583986) (xy 399.334351 -432.607039)
			(xy 399.334736 -432.61915) (xy 399.334736 -435.160674) (xy 399.33427 -435.172765) (xy 399.326818 -435.195768)
			(xy 399.312632 -435.215351) (xy 399.293096 -435.229601) (xy 399.270117 -435.23713) (xy 399.258028 -435.237636)
			(xy 398.318228 -435.237636) (xy 398.306124 -435.23716) (xy 398.283104 -435.229673) (xy 398.263534 -435.215425)
			(xy 398.249337 -435.195818) (xy 398.241909 -435.172779) (xy 398.24152 -435.160674) (xy 396.334488 -435.160674)
			(xy 396.334488 -436.160672) (xy 396.334063 -436.172755) (xy 396.326601 -436.19574) (xy 396.312399 -436.215293)
			(xy 396.292848 -436.229497) (xy 396.269863 -436.236962) (xy 396.25778 -436.23738) (xy 395.31798 -436.23738)
			(xy 395.305893 -436.237004) (xy 395.282905 -436.229528) (xy 395.263353 -436.215313) (xy 395.24915 -436.195752)
			(xy 395.241688 -436.172759) (xy 395.241272 -436.160672) (xy 394.307514 -436.160672) (xy 394.312726 -436.164453)
			(xy 394.326974 -436.184004) (xy 394.334497 -436.206997) (xy 394.335 -436.219092) (xy 394.335 -438.760616)
			(xy 394.334597 -438.772726) (xy 394.327094 -438.795754) (xy 394.312828 -438.815326) (xy 394.293204 -438.82952)
			(xy 394.270149 -438.836941) (xy 394.258038 -438.837324) (xy 393.318238 -438.837324) (xy 393.306147 -438.83686)
			(xy 393.283141 -438.829409) (xy 393.263558 -438.815223) (xy 393.249307 -438.795686) (xy 393.241781 -438.772706)
			(xy 393.241276 -438.760616) (xy 392.335004 -438.760616) (xy 392.335004 -439.760614) (xy 395.241272 -439.760614)
			(xy 395.241272 -439.033666) (xy 395.241583 -439.024833) (xy 395.245677 -439.007645) (xy 395.2494 -438.99963)
			(xy 395.482826 -438.52338) (xy 395.487528 -438.512864) (xy 395.491017 -438.490105) (xy 395.487531 -438.467346)
			(xy 395.482826 -438.456832) (xy 395.2494 -437.980582) (xy 395.245638 -437.972579) (xy 395.241526 -437.955385)
			(xy 395.241272 -437.946546) (xy 395.241272 -437.21909) (xy 395.241652 -437.206963) (xy 395.249151 -437.183898)
			(xy 395.263412 -437.164281) (xy 395.283038 -437.150031) (xy 395.306107 -437.142545) (xy 395.318234 -437.142128)
			(xy 396.258034 -437.142128) (xy 396.270149 -437.142583) (xy 396.293192 -437.150078) (xy 396.312792 -437.164325)
			(xy 396.327033 -437.18393) (xy 396.334521 -437.206975) (xy 396.334996 -437.21909) (xy 396.334996 -438.760616)
			(xy 398.24152 -438.760616) (xy 398.24152 -438.033668) (xy 398.24176 -438.024848) (xy 398.245733 -438.00766)
			(xy 398.249394 -437.999632) (xy 398.48282 -437.523382) (xy 398.487521 -437.512865) (xy 398.49101 -437.490107)
			(xy 398.487525 -437.467348) (xy 398.48282 -437.456834) (xy 398.249394 -436.980584) (xy 398.245704 -436.972566)
			(xy 398.241732 -436.955372) (xy 398.24152 -436.946548) (xy 398.24152 -436.219092) (xy 398.241906 -436.207006)
			(xy 398.249379 -436.184018) (xy 398.263591 -436.164466) (xy 398.283151 -436.150263) (xy 398.306142 -436.1428)
			(xy 398.318228 -436.142384) (xy 399.258028 -436.142384) (xy 399.270103 -436.14284) (xy 399.29307 -436.150309)
			(xy 399.307328 -436.160672) (xy 400.241516 -436.160672) (xy 400.241516 -435.433724) (xy 400.241742 -435.424903)
			(xy 400.245724 -435.407715) (xy 400.24939 -435.399688) (xy 400.482816 -434.923438) (xy 400.487548 -434.912933)
			(xy 400.491026 -434.890167) (xy 400.487528 -434.867405) (xy 400.482816 -434.85689) (xy 400.24939 -434.38064)
			(xy 400.245717 -434.372615) (xy 400.241734 -434.355427) (xy 400.241516 -434.346604) (xy 400.241516 -433.619148)
			(xy 400.241954 -433.607065) (xy 400.249411 -433.58408) (xy 400.26361 -433.564527) (xy 400.283159 -433.550322)
			(xy 400.306142 -433.542858) (xy 400.318224 -433.54244) (xy 401.258024 -433.54244) (xy 401.270113 -433.542793)
			(xy 401.293104 -433.550273) (xy 401.312658 -433.564493) (xy 401.32686 -433.58406) (xy 401.334318 -433.607059)
			(xy 401.334732 -433.619148) (xy 401.334732 -435.160674) (xy 402.241512 -435.160674) (xy 402.241512 -434.433726)
			(xy 402.241739 -434.424905) (xy 402.245721 -434.407717) (xy 402.249386 -434.39969) (xy 402.482812 -433.92344)
			(xy 402.487542 -433.912935) (xy 402.491022 -433.890169) (xy 402.487524 -433.867407) (xy 402.482812 -433.856892)
			(xy 402.249386 -433.380642) (xy 402.245714 -433.372616) (xy 402.24173 -433.355429) (xy 402.241512 -433.346606)
			(xy 402.241512 -432.61915) (xy 402.242049 -432.607066) (xy 402.249489 -432.584071) (xy 402.263658 -432.564493)
			(xy 402.283176 -432.55024) (xy 402.306138 -432.542702) (xy 402.31822 -432.542188) (xy 403.25802 -432.542188)
			(xy 403.270129 -432.542599) (xy 403.293155 -432.550103) (xy 403.307388 -432.560476) (xy 404.241 -432.560476)
			(xy 404.241 -430.018952) (xy 404.241376 -430.006841) (xy 404.248888 -429.983812) (xy 404.26316 -429.96424)
			(xy 404.28279 -429.950047) (xy 404.305849 -429.942627) (xy 404.317962 -429.942244) (xy 405.257762 -429.942244)
			(xy 405.26985 -429.94274) (xy 405.29285 -429.950187) (xy 405.312431 -429.964366) (xy 405.326683 -429.983894)
			(xy 405.334215 -430.006866) (xy 405.334724 -430.018952) (xy 405.334724 -431.560478) (xy 406.240996 -431.560478)
			(xy 406.240996 -429.018954) (xy 406.241472 -429.006841) (xy 406.248967 -428.983804) (xy 406.263209 -428.964206)
			(xy 406.282807 -428.949965) (xy 406.305845 -428.942471) (xy 406.317958 -428.941992) (xy 407.257758 -428.941992)
			(xy 407.269866 -428.942547) (xy 407.2929 -428.950017) (xy 407.307392 -428.960534) (xy 408.240992 -428.960534)
			(xy 408.240992 -426.41901) (xy 408.24152 -426.406901) (xy 408.248999 -426.383865) (xy 408.263228 -426.364268)
			(xy 408.282815 -426.350024) (xy 408.305845 -426.342528) (xy 408.317954 -426.342048) (xy 409.257754 -426.342048)
			(xy 409.269875 -426.342499) (xy 409.292934 -426.34998) (xy 409.312551 -426.364223) (xy 409.326804 -426.383833)
			(xy 409.334295 -426.406889) (xy 409.334716 -426.41901) (xy 409.334716 -427.960536) (xy 410.240988 -427.960536)
			(xy 410.240988 -425.419012) (xy 410.241427 -425.406905) (xy 410.248921 -425.38388) (xy 410.263177 -425.364308)
			(xy 410.282794 -425.350113) (xy 410.305842 -425.342689) (xy 410.31795 -425.342304) (xy 411.25775 -425.342304)
			(xy 411.269833 -425.342849) (xy 411.292826 -425.350288) (xy 411.312404 -425.364455) (xy 411.326658 -425.383971)
			(xy 411.334197 -425.406931) (xy 411.334712 -425.419012) (xy 411.334712 -427.960536) (xy 411.334314 -427.972646)
			(xy 411.326807 -427.995672) (xy 411.31254 -428.015243) (xy 411.292915 -428.029437) (xy 411.269861 -428.036859)
			(xy 411.25775 -428.037244) (xy 410.31795 -428.037244) (xy 410.305861 -428.03675) (xy 410.28286 -428.029305)
			(xy 410.263278 -428.015126) (xy 410.249026 -427.995597) (xy 410.241495 -427.972623) (xy 410.240988 -427.960536)
			(xy 409.334716 -427.960536) (xy 409.334716 -428.960534) (xy 409.334368 -428.972663) (xy 409.326861 -428.995731)
			(xy 409.312592 -429.015349) (xy 409.292959 -429.029598) (xy 409.269884 -429.037081) (xy 409.257754 -429.037496)
			(xy 408.317954 -429.037496) (xy 408.30584 -429.037028) (xy 408.282801 -429.029532) (xy 408.263203 -429.015288)
			(xy 408.248962 -428.995688) (xy 408.24147 -428.972648) (xy 408.240992 -428.960534) (xy 407.307392 -428.960534)
			(xy 407.312498 -428.964239) (xy 407.326743 -428.983821) (xy 407.334239 -429.006847) (xy 407.33472 -429.018954)
			(xy 407.33472 -431.560478) (xy 407.334321 -431.572604) (xy 407.326829 -431.595669) (xy 407.312574 -431.615288)
			(xy 407.292951 -431.629538) (xy 407.269884 -431.637024) (xy 407.257758 -431.63744) (xy 406.317958 -431.63744)
			(xy 406.305839 -431.637024) (xy 406.282791 -431.629522) (xy 406.263188 -431.615267) (xy 406.248948 -431.595652)
			(xy 406.241466 -431.572597) (xy 406.240996 -431.560478) (xy 405.334724 -431.560478) (xy 405.334724 -432.560476)
			(xy 405.334263 -432.572581) (xy 405.326774 -432.595604) (xy 405.312523 -432.615175) (xy 405.292912 -432.629371)
			(xy 405.269868 -432.636797) (xy 405.257762 -432.637184) (xy 404.317962 -432.637184) (xy 404.305873 -432.636726)
			(xy 404.282875 -432.629261) (xy 404.263298 -432.615072) (xy 404.249048 -432.595538) (xy 404.241512 -432.572564)
			(xy 404.241 -432.560476) (xy 403.307388 -432.560476) (xy 403.312726 -432.564366) (xy 403.326921 -432.583988)
			(xy 403.334343 -432.60704) (xy 403.334728 -432.61915) (xy 403.334728 -435.160674) (xy 403.33427 -435.172765)
			(xy 403.326816 -435.195771) (xy 403.312629 -435.215354) (xy 403.293091 -435.229604) (xy 403.27011 -435.237131)
			(xy 403.25802 -435.237636) (xy 402.31822 -435.237636) (xy 402.306116 -435.237167) (xy 402.283095 -435.229677)
			(xy 402.263525 -435.215428) (xy 402.249329 -435.19582) (xy 402.241901 -435.172779) (xy 402.241512 -435.160674)
			(xy 401.334732 -435.160674) (xy 401.334732 -436.160672) (xy 401.334264 -436.172751) (xy 401.326807 -436.195729)
			(xy 401.312614 -436.215277) (xy 401.293075 -436.229483) (xy 401.270103 -436.236956) (xy 401.258024 -436.23738)
			(xy 400.318224 -436.23738) (xy 400.30614 -436.236966) (xy 400.283153 -436.229502) (xy 400.2636 -436.215297)
			(xy 400.249396 -436.195743) (xy 400.241933 -436.172756) (xy 400.241516 -436.160672) (xy 399.307328 -436.160672)
			(xy 399.312606 -436.164508) (xy 399.3268 -436.184048) (xy 399.334263 -436.207017) (xy 399.334736 -436.219092)
			(xy 399.334736 -438.760616) (xy 399.33425 -438.772689) (xy 399.326786 -438.795651) (xy 399.312594 -438.815186)
			(xy 399.293062 -438.829381) (xy 399.270101 -438.836848) (xy 399.258028 -438.837324) (xy 398.318228 -438.837324)
			(xy 398.306148 -438.836864) (xy 398.283169 -438.829406) (xy 398.26362 -438.815211) (xy 398.249414 -438.79567)
			(xy 398.241943 -438.772695) (xy 398.24152 -438.760616) (xy 396.334996 -438.760616) (xy 396.334996 -439.760614)
			(xy 400.241516 -439.760614) (xy 400.241516 -439.033666) (xy 400.241756 -439.024845) (xy 400.245729 -439.007658)
			(xy 400.24939 -438.99963) (xy 400.482816 -438.52338) (xy 400.487519 -438.512864) (xy 400.491008 -438.490105)
			(xy 400.487522 -438.467346) (xy 400.482816 -438.456832) (xy 400.24939 -437.980582) (xy 400.245699 -437.972564)
			(xy 400.241728 -437.95537) (xy 400.241516 -437.946546) (xy 400.241516 -437.21909) (xy 400.241999 -437.207002)
			(xy 400.249455 -437.184006) (xy 400.263639 -437.164428) (xy 400.283167 -437.150177) (xy 400.306138 -437.142641)
			(xy 400.318224 -437.142128) (xy 401.258024 -437.142128) (xy 401.270137 -437.142496) (xy 401.29317 -437.150006)
			(xy 401.312745 -437.164279) (xy 401.326938 -437.183912) (xy 401.334353 -437.206975) (xy 401.334732 -437.21909)
			(xy 401.334732 -438.760616) (xy 402.241512 -438.760616) (xy 402.241512 -438.033668) (xy 402.241753 -438.024848)
			(xy 402.245725 -438.00766) (xy 402.249386 -437.999632) (xy 402.482812 -437.523382) (xy 402.487513 -437.512866)
			(xy 402.491003 -437.490107) (xy 402.487518 -437.467348) (xy 402.482812 -437.456834) (xy 402.249386 -436.980584)
			(xy 402.245696 -436.972566) (xy 402.241724 -436.955372) (xy 402.241512 -436.946548) (xy 402.241512 -436.219092)
			(xy 402.241906 -436.207007) (xy 402.249378 -436.18402) (xy 402.263588 -436.164469) (xy 402.283146 -436.150265)
			(xy 402.306135 -436.142802) (xy 402.31822 -436.142384) (xy 403.25802 -436.142384) (xy 403.270095 -436.142847)
			(xy 403.293061 -436.150314) (xy 403.307314 -436.160672) (xy 404.241508 -436.160672) (xy 404.241508 -435.433724)
			(xy 404.241735 -435.424903) (xy 404.245717 -435.407715) (xy 404.249382 -435.399688) (xy 404.482808 -434.923438)
			(xy 404.48754 -434.912933) (xy 404.491019 -434.890167) (xy 404.487521 -434.867404) (xy 404.482808 -434.85689)
			(xy 404.249382 -434.38064) (xy 404.245709 -434.372615) (xy 404.241726 -434.355427) (xy 404.241508 -434.346604)
			(xy 404.241508 -433.619148) (xy 404.241954 -433.607066) (xy 404.24941 -433.584082) (xy 404.263607 -433.56453)
			(xy 404.283154 -433.550325) (xy 404.306134 -433.542859) (xy 404.318216 -433.54244) (xy 405.258016 -433.54244)
			(xy 405.270104 -433.5428) (xy 405.293096 -433.550277) (xy 405.31265 -433.564496) (xy 405.326852 -433.584062)
			(xy 405.33431 -433.607059) (xy 405.334724 -433.619148) (xy 405.334724 -435.160674) (xy 406.241504 -435.160674)
			(xy 406.241504 -434.433726) (xy 406.241732 -434.424905) (xy 406.245713 -434.407717) (xy 406.249378 -434.39969)
			(xy 406.482804 -433.92344) (xy 406.487535 -433.912935) (xy 406.491014 -433.890169) (xy 406.487516 -433.867406)
			(xy 406.482804 -433.856892) (xy 406.249378 -433.380642) (xy 406.245705 -433.372617) (xy 406.241722 -433.355429)
			(xy 406.241504 -433.346606) (xy 406.241504 -432.61915) (xy 406.242049 -432.607067) (xy 406.249488 -432.584074)
			(xy 406.263655 -432.564496) (xy 406.283171 -432.550242) (xy 406.306131 -432.542703) (xy 406.318212 -432.542188)
			(xy 407.258012 -432.542188) (xy 407.27012 -432.542606) (xy 407.293146 -432.550107) (xy 407.307376 -432.560476)
			(xy 408.240992 -432.560476) (xy 408.240992 -430.018952) (xy 408.241375 -430.006841) (xy 408.248887 -429.983814)
			(xy 408.263158 -429.964242) (xy 408.282785 -429.950049) (xy 408.305842 -429.942628) (xy 408.317954 -429.942244)
			(xy 409.257754 -429.942244) (xy 409.269842 -429.942747) (xy 409.292841 -429.950191) (xy 409.312422 -429.964368)
			(xy 409.326674 -429.983895) (xy 409.334207 -430.006866) (xy 409.334716 -430.018952) (xy 409.334716 -431.560478)
			(xy 410.240988 -431.560478) (xy 410.240988 -429.018954) (xy 410.241472 -429.006842) (xy 410.248966 -428.983806)
			(xy 410.263206 -428.964209) (xy 410.282802 -428.949967) (xy 410.305838 -428.942472) (xy 410.31795 -428.941992)
			(xy 411.25775 -428.941992) (xy 411.269863 -428.942468) (xy 411.2929 -428.949964) (xy 411.307444 -428.960534)
			(xy 412.240984 -428.960534) (xy 412.240984 -426.41901) (xy 412.241369 -426.406883) (xy 412.248864 -426.383817)
			(xy 412.263123 -426.364198) (xy 412.282749 -426.349948) (xy 412.305819 -426.342464) (xy 412.317946 -426.342048)
			(xy 413.257746 -426.342048) (xy 413.269864 -426.342473) (xy 413.29291 -426.349974) (xy 413.312512 -426.364228)
			(xy 413.326752 -426.38384) (xy 413.334236 -426.406892) (xy 413.334708 -426.41901) (xy 413.334708 -428.960534)
			(xy 413.334218 -428.972646) (xy 413.326727 -428.995682) (xy 413.312488 -429.01528) (xy 413.292893 -429.029522)
			(xy 413.269858 -429.037016) (xy 413.257746 -429.037496) (xy 412.317946 -429.037496) (xy 412.305829 -429.037002)
			(xy 412.282777 -429.029526) (xy 412.263164 -429.015292) (xy 412.248911 -428.995694) (xy 412.241411 -428.972651)
			(xy 412.240984 -428.960534) (xy 411.307444 -428.960534) (xy 411.312497 -428.964206) (xy 411.326738 -428.983804)
			(xy 411.334232 -429.006841) (xy 411.334712 -429.018954) (xy 411.334712 -431.560478) (xy 411.33417 -431.572586)
			(xy 411.326695 -431.59562) (xy 411.312469 -431.615218) (xy 411.292885 -431.629462) (xy 411.269858 -431.636959)
			(xy 411.25775 -431.63744) (xy 410.31795 -431.63744) (xy 410.305831 -431.63703) (xy 410.282782 -431.629527)
			(xy 410.263179 -431.615269) (xy 410.24894 -431.595653) (xy 410.241458 -431.572598) (xy 410.240988 -431.560478)
			(xy 409.334716 -431.560478) (xy 409.334716 -432.560476) (xy 409.334263 -432.572582) (xy 409.326772 -432.595606)
			(xy 409.31252 -432.615178) (xy 409.292906 -432.629374) (xy 409.269861 -432.636798) (xy 409.257754 -432.637184)
			(xy 408.317954 -432.637184) (xy 408.305864 -432.636732) (xy 408.282866 -432.629266) (xy 408.263289 -432.615074)
			(xy 408.249039 -432.59554) (xy 408.241504 -432.572564) (xy 408.240992 -432.560476) (xy 407.307376 -432.560476)
			(xy 407.312718 -432.564369) (xy 407.326913 -432.583989) (xy 407.334335 -432.60704) (xy 407.33472 -432.61915)
			(xy 407.33472 -435.160674) (xy 407.33427 -435.172766) (xy 407.326815 -435.195773) (xy 407.312626 -435.215356)
			(xy 407.293086 -435.229606) (xy 407.270103 -435.237132) (xy 407.258012 -435.237636) (xy 406.318212 -435.237636)
			(xy 406.306107 -435.237174) (xy 406.283087 -435.229682) (xy 406.263517 -435.215431) (xy 406.24932 -435.195821)
			(xy 406.241893 -435.17278) (xy 406.241504 -435.160674) (xy 405.334724 -435.160674) (xy 405.334724 -436.160672)
			(xy 405.334264 -436.172752) (xy 405.326806 -436.195731) (xy 405.312611 -436.21528) (xy 405.29307 -436.229486)
			(xy 405.270095 -436.236957) (xy 405.258016 -436.23738) (xy 404.318216 -436.23738) (xy 404.306131 -436.236973)
			(xy 404.283144 -436.229507) (xy 404.263592 -436.2153) (xy 404.249388 -436.195745) (xy 404.241925 -436.172757)
			(xy 404.241508 -436.160672) (xy 403.307314 -436.160672) (xy 403.312597 -436.164511) (xy 403.326791 -436.18405)
			(xy 403.334255 -436.207017) (xy 403.334728 -436.219092) (xy 403.334728 -438.760616) (xy 403.33425 -438.772689)
			(xy 403.326785 -438.795654) (xy 403.312591 -438.815189) (xy 403.293057 -438.829383) (xy 403.270093 -438.836849)
			(xy 403.25802 -438.837324) (xy 402.31822 -438.837324) (xy 402.30614 -438.83687) (xy 402.283161 -438.82941)
			(xy 402.263611 -438.815214) (xy 402.249406 -438.795672) (xy 402.241935 -438.772696) (xy 402.241512 -438.760616)
			(xy 401.334732 -438.760616) (xy 401.334732 -439.760614) (xy 404.241508 -439.760614) (xy 404.241508 -439.033666)
			(xy 404.241749 -439.024846) (xy 404.245721 -439.007658) (xy 404.249382 -438.99963) (xy 404.482808 -438.52338)
			(xy 404.487511 -438.512864) (xy 404.491 -438.490105) (xy 404.487514 -438.467346) (xy 404.482808 -438.456832)
			(xy 404.249382 -437.980582) (xy 404.245691 -437.972564) (xy 404.241719 -437.95537) (xy 404.241508 -437.946546)
			(xy 404.241508 -437.21909) (xy 404.241998 -437.207003) (xy 404.249454 -437.184008) (xy 404.263636 -437.164431)
			(xy 404.283162 -437.150179) (xy 404.306131 -437.142642) (xy 404.318216 -437.142128) (xy 405.258016 -437.142128)
			(xy 405.270129 -437.142503) (xy 405.293161 -437.15001) (xy 405.312736 -437.164281) (xy 405.326929 -437.183914)
			(xy 405.334345 -437.206976) (xy 405.334724 -437.21909) (xy 405.334724 -438.760616) (xy 406.241504 -438.760616)
			(xy 406.241504 -438.033668) (xy 406.241746 -438.024848) (xy 406.245717 -438.00766) (xy 406.249378 -437.999632)
			(xy 406.482804 -437.523382) (xy 406.487505 -437.512865) (xy 406.490995 -437.490107) (xy 406.48751 -437.467348)
			(xy 406.482804 -437.456834) (xy 406.249378 -436.980584) (xy 406.245687 -436.972566) (xy 406.241716 -436.955372)
			(xy 406.241504 -436.946548) (xy 406.241504 -436.219092) (xy 406.241906 -436.207008) (xy 406.249377 -436.184023)
			(xy 406.263586 -436.164471) (xy 406.283141 -436.150268) (xy 406.306128 -436.142803) (xy 406.318212 -436.142384)
			(xy 407.258012 -436.142384) (xy 407.270086 -436.142854) (xy 407.293053 -436.150319) (xy 407.307301 -436.160672)
			(xy 408.2415 -436.160672) (xy 408.2415 -435.433724) (xy 408.241728 -435.424903) (xy 408.245709 -435.407715)
			(xy 408.249374 -435.399688) (xy 408.4828 -434.923438) (xy 408.487532 -434.912934) (xy 408.491012 -434.890167)
			(xy 408.487513 -434.867404) (xy 408.4828 -434.85689) (xy 408.249374 -434.38064) (xy 408.245701 -434.372615)
			(xy 408.241718 -434.355427) (xy 408.2415 -434.346604) (xy 408.2415 -433.619148) (xy 408.241954 -433.607067)
			(xy 408.249409 -433.584084) (xy 408.263604 -433.564533) (xy 408.283149 -433.550327) (xy 408.306127 -433.54286)
			(xy 408.318208 -433.54244) (xy 409.258008 -433.54244) (xy 409.270096 -433.542806) (xy 409.293087 -433.550282)
			(xy 409.312641 -433.564498) (xy 409.326844 -433.584063) (xy 409.334302 -433.60706) (xy 409.334716 -433.619148)
			(xy 409.334716 -435.160674) (xy 410.241496 -435.160674) (xy 410.241496 -434.433726) (xy 410.241725 -434.424905)
			(xy 410.245705 -434.407717) (xy 410.24937 -434.39969) (xy 410.482796 -433.92344) (xy 410.487527 -433.912935)
			(xy 410.491007 -433.890169) (xy 410.487509 -433.867406) (xy 410.482796 -433.856892) (xy 410.24937 -433.380642)
			(xy 410.245697 -433.372617) (xy 410.241714 -433.355429) (xy 410.241496 -433.346606) (xy 410.241496 -432.61915)
			(xy 410.242049 -432.607067) (xy 410.249487 -432.584076) (xy 410.263653 -432.564499) (xy 410.283166 -432.550245)
			(xy 410.306124 -432.542704) (xy 410.318204 -432.542188) (xy 411.258004 -432.542188) (xy 411.270112 -432.542613)
			(xy 411.293137 -432.550112) (xy 411.307362 -432.560476) (xy 412.240984 -432.560476) (xy 412.240984 -430.018952)
			(xy 412.241375 -430.006842) (xy 412.248886 -429.983816) (xy 412.263155 -429.964245) (xy 412.28278 -429.950052)
			(xy 412.305835 -429.942629) (xy 412.317946 -429.942244) (xy 413.257746 -429.942244) (xy 413.269838 -429.942668)
			(xy 413.292841 -429.950138) (xy 413.312421 -429.964336) (xy 413.32667 -429.983878) (xy 413.3342 -430.006861)
			(xy 413.334708 -430.018952) (xy 413.334708 -432.560476) (xy 413.334263 -432.572583) (xy 413.326771 -432.595608)
			(xy 413.312517 -432.615181) (xy 413.292901 -432.629376) (xy 413.269854 -432.636799) (xy 413.257746 -432.637184)
			(xy 412.317946 -432.637184) (xy 412.305861 -432.636654) (xy 412.282866 -432.629213) (xy 412.263287 -432.615042)
			(xy 412.249034 -432.595522) (xy 412.241497 -432.572559) (xy 412.240984 -432.560476) (xy 411.307362 -432.560476)
			(xy 411.312709 -432.564372) (xy 411.326904 -432.583991) (xy 411.334327 -432.607041) (xy 411.334712 -432.61915)
			(xy 411.334712 -435.160674) (xy 411.33427 -435.172767) (xy 411.326814 -435.195775) (xy 411.312623 -435.215359)
			(xy 411.293081 -435.229609) (xy 411.270096 -435.237133) (xy 411.258004 -435.237636) (xy 410.318204 -435.237636)
			(xy 410.306099 -435.237181) (xy 410.283078 -435.229687) (xy 410.263508 -435.215434) (xy 410.249312 -435.195823)
			(xy 410.241884 -435.17278) (xy 410.241496 -435.160674) (xy 409.334716 -435.160674) (xy 409.334716 -436.160672)
			(xy 409.334264 -436.172752) (xy 409.326805 -436.195733) (xy 409.312609 -436.215283) (xy 409.293065 -436.229488)
			(xy 409.270088 -436.236958) (xy 409.258008 -436.23738) (xy 408.318208 -436.23738) (xy 408.306123 -436.23698)
			(xy 408.283136 -436.229512) (xy 408.263583 -436.215303) (xy 408.249379 -436.195746) (xy 408.241916 -436.172757)
			(xy 408.2415 -436.160672) (xy 407.307301 -436.160672) (xy 407.312589 -436.164514) (xy 407.326783 -436.184051)
			(xy 407.334247 -436.207018) (xy 407.33472 -436.219092) (xy 407.33472 -438.760616) (xy 407.334249 -438.77269)
			(xy 407.326784 -438.795656) (xy 407.312589 -438.815191) (xy 407.293052 -438.829386) (xy 407.270086 -438.83685)
			(xy 407.258012 -438.837324) (xy 406.318212 -438.837324) (xy 406.30614 -438.836826) (xy 406.283176 -438.829369)
			(xy 406.26364 -438.81518) (xy 406.249444 -438.79565) (xy 406.241979 -438.772688) (xy 406.241504 -438.760616)
			(xy 405.334724 -438.760616) (xy 405.334724 -439.760614) (xy 408.2415 -439.760614) (xy 408.2415 -439.033666)
			(xy 408.241741 -439.024846) (xy 408.245713 -439.007658) (xy 408.249374 -438.99963) (xy 408.4828 -438.52338)
			(xy 408.487503 -438.512864) (xy 408.490993 -438.490105) (xy 408.487506 -438.467346) (xy 408.4828 -438.456832)
			(xy 408.249374 -437.980582) (xy 408.245682 -437.972565) (xy 408.241711 -437.95537) (xy 408.2415 -437.946546)
			(xy 408.2415 -437.21909) (xy 408.241998 -437.207004) (xy 408.249453 -437.18401) (xy 408.263633 -437.164434)
			(xy 408.283157 -437.150182) (xy 408.306124 -437.142643) (xy 408.318208 -437.142128) (xy 409.258008 -437.142128)
			(xy 409.27012 -437.14251) (xy 409.293152 -437.150015) (xy 409.312728 -437.164284) (xy 409.326921 -437.183915)
			(xy 409.334337 -437.206976) (xy 409.334716 -437.21909) (xy 409.334716 -438.760616) (xy 410.241496 -438.760616)
			(xy 410.241496 -438.033668) (xy 410.241739 -438.024848) (xy 410.24571 -438.00766) (xy 410.24937 -437.999632)
			(xy 410.482796 -437.523382) (xy 410.487498 -437.512866) (xy 410.490988 -437.490107) (xy 410.487502 -437.467348)
			(xy 410.482796 -437.456834) (xy 410.24937 -436.980584) (xy 410.245679 -436.972566) (xy 410.241708 -436.955372)
			(xy 410.241496 -436.946548) (xy 410.241496 -436.219092) (xy 410.241958 -436.207017) (xy 410.249423 -436.184049)
			(xy 410.26362 -436.164511) (xy 410.283159 -436.150317) (xy 410.306129 -436.142856) (xy 410.318204 -436.142384)
			(xy 411.258004 -436.142384) (xy 411.270078 -436.142861) (xy 411.293044 -436.150323) (xy 411.307288 -436.160672)
			(xy 412.241492 -436.160672) (xy 412.241492 -435.433724) (xy 412.241721 -435.424903) (xy 412.245701 -435.407715)
			(xy 412.249366 -435.399688) (xy 412.482792 -434.923438) (xy 412.487525 -434.912934) (xy 412.491005 -434.890167)
			(xy 412.487505 -434.867404) (xy 412.482792 -434.85689) (xy 412.249366 -434.38064) (xy 412.245692 -434.372615)
			(xy 412.24171 -434.355427) (xy 412.241492 -434.346604) (xy 412.241492 -433.619148) (xy 412.241954 -433.607068)
			(xy 412.249408 -433.584087) (xy 412.263601 -433.564536) (xy 412.283144 -433.55033) (xy 412.30612 -433.542861)
			(xy 412.3182 -433.54244) (xy 413.258 -433.54244) (xy 413.270088 -433.542813) (xy 413.293078 -433.550287)
			(xy 413.312633 -433.564501) (xy 413.326835 -433.584065) (xy 413.334294 -433.60706) (xy 413.334708 -433.619148)
			(xy 413.334708 -435.59984) (xy 446.741306 -435.59984) (xy 446.745288 -435.471854) (xy 446.75722 -435.344363)
			(xy 446.777054 -435.21786) (xy 446.804715 -435.092835) (xy 446.840095 -434.969772) (xy 446.883057 -434.849146)
			(xy 446.933435 -434.731425) (xy 446.991035 -434.617063) (xy 447.055633 -434.506504) (xy 447.12698 -434.400174)
			(xy 447.204799 -434.298486) (xy 447.288789 -434.201832) (xy 447.378626 -434.110587) (xy 447.473962 -434.025104)
			(xy 447.574427 -433.945713) (xy 447.679635 -433.872721) (xy 447.789176 -433.806412) (xy 447.902628 -433.747041)
			(xy 448.019552 -433.694837) (xy 448.139495 -433.650004) (xy 448.261993 -433.612715) (xy 448.386573 -433.583113)
			(xy 448.512751 -433.561314) (xy 448.640041 -433.547401) (xy 448.76795 -433.541429) (xy 448.895983 -433.54342)
			(xy 449.023644 -433.553368) (xy 449.15044 -433.571232) (xy 449.275879 -433.596945) (xy 449.399478 -433.630407)
			(xy 449.520757 -433.671488) (xy 449.639248 -433.72003) (xy 449.754492 -433.775844) (xy 449.866042 -433.838715)
			(xy 449.973469 -433.908399) (xy 450.076355 -433.984627) (xy 450.174303 -434.067104) (xy 450.266934 -434.155511)
			(xy 450.35389 -434.249506) (xy 450.434834 -434.348725) (xy 450.509453 -434.452784) (xy 450.577458 -434.561281)
			(xy 450.638586 -434.673796) (xy 450.692601 -434.789894) (xy 450.739294 -434.909125) (xy 450.778484 -435.031029)
			(xy 450.81002 -435.155133) (xy 450.833779 -435.280957) (xy 450.849669 -435.408016) (xy 450.85763 -435.535816)
			(xy 450.858128 -435.59984) (xy 450.85763 -435.663864) (xy 450.849669 -435.791664) (xy 450.833779 -435.918723)
			(xy 450.81002 -436.044547) (xy 450.778484 -436.168651) (xy 450.739294 -436.290555) (xy 450.692601 -436.409786)
			(xy 450.638586 -436.525884) (xy 450.577458 -436.638399) (xy 450.509453 -436.746896) (xy 450.434834 -436.850955)
			(xy 450.35389 -436.950174) (xy 450.266934 -437.044169) (xy 450.174303 -437.132576) (xy 450.076355 -437.215053)
			(xy 449.973469 -437.291281) (xy 449.866042 -437.360965) (xy 449.754492 -437.423836) (xy 449.639248 -437.47965)
			(xy 449.520757 -437.528192) (xy 449.399478 -437.569273) (xy 449.275879 -437.602735) (xy 449.15044 -437.628448)
			(xy 449.023644 -437.646312) (xy 448.895983 -437.65626) (xy 448.76795 -437.658251) (xy 448.640041 -437.652279)
			(xy 448.512751 -437.638366) (xy 448.386573 -437.616567) (xy 448.261993 -437.586965) (xy 448.139495 -437.549676)
			(xy 448.019552 -437.504843) (xy 447.902628 -437.452639) (xy 447.789176 -437.393268) (xy 447.679635 -437.326959)
			(xy 447.574427 -437.253967) (xy 447.473962 -437.174576) (xy 447.378626 -437.089093) (xy 447.288789 -436.997848)
			(xy 447.204799 -436.901194) (xy 447.12698 -436.799506) (xy 447.055633 -436.693176) (xy 446.991035 -436.582617)
			(xy 446.933435 -436.468255) (xy 446.883057 -436.350534) (xy 446.840095 -436.229908) (xy 446.804715 -436.106845)
			(xy 446.777054 -435.98182) (xy 446.75722 -435.855317) (xy 446.745288 -435.727826) (xy 446.741306 -435.59984)
			(xy 413.334708 -435.59984) (xy 413.334708 -436.160672) (xy 413.334263 -436.172753) (xy 413.326804 -436.195735)
			(xy 413.312606 -436.215286) (xy 413.29306 -436.229491) (xy 413.270081 -436.236959) (xy 413.258 -436.23738)
			(xy 412.3182 -436.23738) (xy 412.306114 -436.236987) (xy 412.283127 -436.229516) (xy 412.263574 -436.215306)
			(xy 412.249371 -436.195748) (xy 412.241908 -436.172758) (xy 412.241492 -436.160672) (xy 411.307288 -436.160672)
			(xy 411.31258 -436.164517) (xy 411.326775 -436.184053) (xy 411.334239 -436.207018) (xy 411.334712 -436.219092)
			(xy 411.334712 -438.760616) (xy 411.334249 -438.772691) (xy 411.326783 -438.795658) (xy 411.312586 -438.815194)
			(xy 411.293047 -438.829388) (xy 411.270079 -438.836851) (xy 411.258004 -438.837324) (xy 410.318204 -438.837324)
			(xy 410.306131 -438.836833) (xy 410.283167 -438.829373) (xy 410.263631 -438.815183) (xy 410.249436 -438.795651)
			(xy 410.241971 -438.772689) (xy 410.241496 -438.760616) (xy 409.334716 -438.760616) (xy 409.334716 -439.760614)
			(xy 412.241492 -439.760614) (xy 412.241492 -439.033666) (xy 412.241734 -439.024846) (xy 412.245706 -439.007658)
			(xy 412.249366 -438.99963) (xy 412.482792 -438.52338) (xy 412.487495 -438.512864) (xy 412.490985 -438.490105)
			(xy 412.487499 -438.467346) (xy 412.482792 -438.456832) (xy 412.249366 -437.980582) (xy 412.245674 -437.972565)
			(xy 412.241703 -437.95537) (xy 412.241492 -437.946546) (xy 412.241492 -437.21909) (xy 412.241998 -437.207005)
			(xy 412.249452 -437.184012) (xy 412.26363 -437.164436) (xy 412.283152 -437.150184) (xy 412.306117 -437.142644)
			(xy 412.3182 -437.142128) (xy 413.258 -437.142128) (xy 413.270112 -437.142516) (xy 413.293144 -437.150019)
			(xy 413.312719 -437.164287) (xy 413.326913 -437.183916) (xy 413.334329 -437.206977) (xy 413.334708 -437.21909)
			(xy 413.334708 -439.760614) (xy 413.334206 -439.7727) (xy 413.326751 -439.795693) (xy 413.312572 -439.815268)
			(xy 413.293049 -439.82952) (xy 413.270084 -439.83706) (xy 413.258 -439.837576) (xy 412.3182 -439.837576)
			(xy 412.306089 -439.837184) (xy 412.283057 -439.829681) (xy 412.263482 -439.815414) (xy 412.249288 -439.795786)
			(xy 412.241872 -439.772727) (xy 412.241492 -439.760614) (xy 409.334716 -439.760614) (xy 409.334304 -439.772709)
			(xy 409.326838 -439.795717) (xy 409.312639 -439.815301) (xy 409.293091 -439.829549) (xy 409.270101 -439.837073)
			(xy 409.258008 -439.837576) (xy 408.318208 -439.837576) (xy 408.306097 -439.837177) (xy 408.283066 -439.829677)
			(xy 408.263491 -439.815412) (xy 408.249296 -439.795785) (xy 408.24188 -439.772726) (xy 408.2415 -439.760614)
			(xy 405.334724 -439.760614) (xy 405.334304 -439.772708) (xy 405.326839 -439.795715) (xy 405.312642 -439.815298)
			(xy 405.293096 -439.829547) (xy 405.270109 -439.837072) (xy 405.258016 -439.837576) (xy 404.318216 -439.837576)
			(xy 404.306106 -439.83717) (xy 404.283075 -439.829672) (xy 404.263499 -439.815408) (xy 404.249305 -439.795783)
			(xy 404.241888 -439.772726) (xy 404.241508 -439.760614) (xy 401.334732 -439.760614) (xy 401.334304 -439.772707)
			(xy 401.32684 -439.795713) (xy 401.312645 -439.815295) (xy 401.293101 -439.829544) (xy 401.270116 -439.837071)
			(xy 401.258024 -439.837576) (xy 400.318224 -439.837576) (xy 400.306114 -439.837163) (xy 400.283083 -439.829667)
			(xy 400.263508 -439.815406) (xy 400.249313 -439.795781) (xy 400.241896 -439.772725) (xy 400.241516 -439.760614)
			(xy 396.334996 -439.760614) (xy 396.334501 -439.772726) (xy 396.327014 -439.795764) (xy 396.312777 -439.815363)
			(xy 396.293182 -439.829605) (xy 396.270146 -439.837098) (xy 396.258034 -439.837576) (xy 395.318234 -439.837576)
			(xy 395.306114 -439.837111) (xy 395.283059 -439.82963) (xy 395.263445 -439.81539) (xy 395.249192 -439.795784)
			(xy 395.241696 -439.772733) (xy 395.241272 -439.760614) (xy 392.335004 -439.760614) (xy 392.334501 -439.772725)
			(xy 392.327015 -439.795762) (xy 392.31278 -439.81536) (xy 392.293187 -439.829602) (xy 392.270153 -439.837097)
			(xy 392.258042 -439.837576) (xy 391.318242 -439.837576) (xy 391.306123 -439.837105) (xy 391.283068 -439.829626)
			(xy 391.263453 -439.815387) (xy 391.2492 -439.795783) (xy 391.241704 -439.772733) (xy 391.24128 -439.760614)
			(xy 388.335012 -439.760614) (xy 388.334501 -439.772724) (xy 388.327016 -439.79576) (xy 388.312782 -439.815357)
			(xy 388.293192 -439.8296) (xy 388.27016 -439.837096) (xy 388.25805 -439.837576) (xy 387.31825 -439.837576)
			(xy 387.306134 -439.837131) (xy 387.283092 -439.829632) (xy 387.263492 -439.815382) (xy 387.249252 -439.795776)
			(xy 387.241763 -439.77273) (xy 387.241288 -439.760614) (xy 384.33502 -439.760614) (xy 384.334651 -439.772742)
			(xy 384.32715 -439.795808) (xy 384.312886 -439.815426) (xy 384.293258 -439.829675) (xy 384.270186 -439.83716)
			(xy 384.258058 -439.837576) (xy 383.318258 -439.837576) (xy 383.306143 -439.837124) (xy 383.2831 -439.829627)
			(xy 383.263501 -439.815379) (xy 383.24926 -439.795774) (xy 383.241771 -439.77273) (xy 383.241296 -439.760614)
			(xy 346.234512 -439.760614) (xy 346.234104 -439.772709) (xy 346.226638 -439.795718) (xy 346.212437 -439.815302)
			(xy 346.192889 -439.829551) (xy 346.169898 -439.837074) (xy 346.157804 -439.837576) (xy 345.218004 -439.837576)
			(xy 345.205893 -439.83718) (xy 345.182862 -439.829679) (xy 345.163286 -439.815413) (xy 345.149092 -439.795785)
			(xy 345.141676 -439.772727) (xy 345.141296 -439.760614) (xy 342.23452 -439.760614) (xy 342.234104 -439.772708)
			(xy 342.226639 -439.795716) (xy 342.21244 -439.815299) (xy 342.192894 -439.829548) (xy 342.169905 -439.837073)
			(xy 342.157812 -439.837576) (xy 341.218012 -439.837576) (xy 341.205901 -439.837173) (xy 341.18287 -439.829674)
			(xy 341.163295 -439.81541) (xy 341.149101 -439.795784) (xy 341.141684 -439.772726) (xy 341.141304 -439.760614)
			(xy 338.234528 -439.760614) (xy 338.234104 -439.772708) (xy 338.22664 -439.795714) (xy 338.212443 -439.815297)
			(xy 338.192899 -439.829546) (xy 338.169912 -439.837072) (xy 338.15782 -439.837576) (xy 337.21802 -439.837576)
			(xy 337.20591 -439.837166) (xy 337.182879 -439.829669) (xy 337.163304 -439.815407) (xy 337.149109 -439.795782)
			(xy 337.141692 -439.772726) (xy 337.141312 -439.760614) (xy 334.234536 -439.760614) (xy 334.234104 -439.772707)
			(xy 334.226641 -439.795712) (xy 334.212446 -439.815294) (xy 334.192904 -439.829543) (xy 334.169919 -439.83707)
			(xy 334.157828 -439.837576) (xy 333.218028 -439.837576) (xy 333.205918 -439.837159) (xy 333.182888 -439.829665)
			(xy 333.163312 -439.815404) (xy 333.149117 -439.795781) (xy 333.1417 -439.772725) (xy 333.14132 -439.760614)
			(xy 329.2348 -439.760614) (xy 329.234301 -439.772726) (xy 329.226815 -439.795763) (xy 329.212578 -439.815361)
			(xy 329.192984 -439.829604) (xy 329.169949 -439.837097) (xy 329.157838 -439.837576) (xy 328.218038 -439.837576)
			(xy 328.205919 -439.837108) (xy 328.182863 -439.829628) (xy 328.163249 -439.815388) (xy 328.148996 -439.795783)
			(xy 328.1415 -439.772733) (xy 328.141076 -439.760614) (xy 325.234808 -439.760614) (xy 325.234301 -439.772725)
			(xy 325.226816 -439.795761) (xy 325.212581 -439.815358) (xy 325.192989 -439.829601) (xy 325.169957 -439.837096)
			(xy 325.157846 -439.837576) (xy 324.218046 -439.837576) (xy 324.205927 -439.837101) (xy 324.182872 -439.829623)
			(xy 324.163257 -439.815385) (xy 324.149004 -439.795782) (xy 324.141508 -439.772733) (xy 324.141084 -439.760614)
			(xy 321.234816 -439.760614) (xy 321.234451 -439.772742) (xy 321.226949 -439.795809) (xy 321.212685 -439.815428)
			(xy 321.193055 -439.829677) (xy 321.169982 -439.83716) (xy 321.157854 -439.837576) (xy 320.218054 -439.837576)
			(xy 320.205938 -439.837128) (xy 320.182896 -439.82963) (xy 320.163296 -439.815381) (xy 320.149056 -439.795775)
			(xy 320.141567 -439.77273) (xy 320.141092 -439.760614) (xy 317.234824 -439.760614) (xy 317.234451 -439.772741)
			(xy 317.22695 -439.795807) (xy 317.212688 -439.815425) (xy 317.19306 -439.829674) (xy 317.16999 -439.837159)
			(xy 317.157862 -439.837576) (xy 316.218062 -439.837576) (xy 316.205947 -439.837121) (xy 316.182905 -439.829625)
			(xy 316.163305 -439.815378) (xy 316.149064 -439.795774) (xy 316.141575 -439.772729) (xy 316.1411 -439.760614)
			(xy 157.334712 -439.760614) (xy 157.334201 -439.772724) (xy 157.326716 -439.79576) (xy 157.312482 -439.815357)
			(xy 157.292892 -439.8296) (xy 157.26986 -439.837096) (xy 157.25775 -439.837576) (xy 156.31795 -439.837576)
			(xy 156.305834 -439.837131) (xy 156.282792 -439.829632) (xy 156.263192 -439.815382) (xy 156.248952 -439.795776)
			(xy 156.241463 -439.77273) (xy 156.240988 -439.760614) (xy 153.33472 -439.760614) (xy 153.334351 -439.772742)
			(xy 153.32685 -439.795808) (xy 153.312586 -439.815426) (xy 153.292958 -439.829675) (xy 153.269886 -439.83716)
			(xy 153.257758 -439.837576) (xy 152.317958 -439.837576) (xy 152.305843 -439.837124) (xy 152.2828 -439.829627)
			(xy 152.263201 -439.815379) (xy 152.24896 -439.795774) (xy 152.241471 -439.77273) (xy 152.240996 -439.760614)
			(xy 149.334728 -439.760614) (xy 149.334351 -439.772741) (xy 149.326851 -439.795806) (xy 149.312589 -439.815424)
			(xy 149.292963 -439.829673) (xy 149.269893 -439.837159) (xy 149.257766 -439.837576) (xy 148.317966 -439.837576)
			(xy 148.305851 -439.837118) (xy 148.282809 -439.829623) (xy 148.263209 -439.815377) (xy 148.248968 -439.795773)
			(xy 148.241479 -439.772729) (xy 148.241004 -439.760614) (xy 145.334736 -439.760614) (xy 145.334351 -439.77274)
			(xy 145.326852 -439.795804) (xy 145.312592 -439.815421) (xy 145.292968 -439.82967) (xy 145.2699 -439.837158)
			(xy 145.257774 -439.837576) (xy 144.317974 -439.837576) (xy 144.305859 -439.837111) (xy 144.282818 -439.829618)
			(xy 144.263218 -439.815374) (xy 144.248976 -439.795772) (xy 144.241487 -439.772729) (xy 144.241012 -439.760614)
			(xy 140.334492 -439.760614) (xy 140.334005 -439.772701) (xy 140.326549 -439.795697) (xy 140.312366 -439.815274)
			(xy 140.292839 -439.829525) (xy 140.269869 -439.837062) (xy 140.257784 -439.837576) (xy 139.317984 -439.837576)
			(xy 139.305872 -439.837197) (xy 139.28284 -439.82969) (xy 139.263265 -439.81542) (xy 139.249072 -439.795789)
			(xy 139.241656 -439.772728) (xy 139.241276 -439.760614) (xy 136.3345 -439.760614) (xy 136.334006 -439.7727)
			(xy 136.32655 -439.795695) (xy 136.312369 -439.815271) (xy 136.292844 -439.829523) (xy 136.269877 -439.837061)
			(xy 136.257792 -439.837576) (xy 135.317992 -439.837576) (xy 135.30588 -439.83719) (xy 135.282849 -439.829686)
			(xy 135.263274 -439.815417) (xy 135.24908 -439.795788) (xy 135.241664 -439.772727) (xy 135.241284 -439.760614)
			(xy 132.334508 -439.760614) (xy 132.334006 -439.7727) (xy 132.326551 -439.795693) (xy 132.312372 -439.815268)
			(xy 132.292849 -439.82952) (xy 132.269884 -439.83706) (xy 132.2578 -439.837576) (xy 131.318 -439.837576)
			(xy 131.305889 -439.837184) (xy 131.282857 -439.829681) (xy 131.263282 -439.815414) (xy 131.249088 -439.795786)
			(xy 131.241672 -439.772727) (xy 131.241292 -439.760614) (xy 128.334516 -439.760614) (xy 128.334104 -439.772709)
			(xy 128.326638 -439.795717) (xy 128.312439 -439.815301) (xy 128.292891 -439.829549) (xy 128.269901 -439.837073)
			(xy 128.257808 -439.837576) (xy 127.318008 -439.837576) (xy 127.305897 -439.837177) (xy 127.282866 -439.829677)
			(xy 127.263291 -439.815412) (xy 127.249096 -439.795785) (xy 127.24168 -439.772726) (xy 127.2413 -439.760614)
			(xy 90.234516 -439.760614) (xy 90.234104 -439.772709) (xy 90.226638 -439.795717) (xy 90.212439 -439.815301)
			(xy 90.192891 -439.829549) (xy 90.169901 -439.837073) (xy 90.157808 -439.837576) (xy 89.218008 -439.837576)
			(xy 89.205897 -439.837177) (xy 89.182866 -439.829677) (xy 89.163291 -439.815412) (xy 89.149096 -439.795785)
			(xy 89.14168 -439.772726) (xy 89.1413 -439.760614) (xy 86.234524 -439.760614) (xy 86.234104 -439.772708)
			(xy 86.226639 -439.795715) (xy 86.212442 -439.815298) (xy 86.192896 -439.829547) (xy 86.169909 -439.837072)
			(xy 86.157816 -439.837576) (xy 85.218016 -439.837576) (xy 85.205906 -439.83717) (xy 85.182875 -439.829672)
			(xy 85.163299 -439.815408) (xy 85.149105 -439.795783) (xy 85.141688 -439.772726) (xy 85.141308 -439.760614)
			(xy 82.234532 -439.760614) (xy 82.234104 -439.772707) (xy 82.22664 -439.795713) (xy 82.212445 -439.815295)
			(xy 82.192901 -439.829544) (xy 82.169916 -439.837071) (xy 82.157824 -439.837576) (xy 81.218024 -439.837576)
			(xy 81.205914 -439.837163) (xy 81.182883 -439.829667) (xy 81.163308 -439.815406) (xy 81.149113 -439.795781)
			(xy 81.141696 -439.772725) (xy 81.141316 -439.760614) (xy 78.23454 -439.760614) (xy 78.234104 -439.772706)
			(xy 78.226641 -439.795711) (xy 78.212447 -439.815292) (xy 78.192906 -439.829542) (xy 78.169923 -439.83707)
			(xy 78.157832 -439.837576) (xy 77.218032 -439.837576) (xy 77.205922 -439.837156) (xy 77.182892 -439.829663)
			(xy 77.163316 -439.815403) (xy 77.149122 -439.79578) (xy 77.141704 -439.772725) (xy 77.141324 -439.760614)
			(xy 73.234804 -439.760614) (xy 73.234301 -439.772725) (xy 73.226815 -439.795762) (xy 73.21258 -439.81536)
			(xy 73.192987 -439.829602) (xy 73.169953 -439.837097) (xy 73.157842 -439.837576) (xy 72.218042 -439.837576)
			(xy 72.205923 -439.837105) (xy 72.182868 -439.829626) (xy 72.163253 -439.815387) (xy 72.149 -439.795783)
			(xy 72.141504 -439.772733) (xy 72.14108 -439.760614) (xy 69.234812 -439.760614) (xy 69.234301 -439.772724)
			(xy 69.226816 -439.79576) (xy 69.212582 -439.815357) (xy 69.192992 -439.8296) (xy 69.16996 -439.837096)
			(xy 69.15785 -439.837576) (xy 68.21805 -439.837576) (xy 68.205934 -439.837131) (xy 68.182892 -439.829632)
			(xy 68.163292 -439.815382) (xy 68.149052 -439.795776) (xy 68.141563 -439.77273) (xy 68.141088 -439.760614)
			(xy 65.23482 -439.760614) (xy 65.234451 -439.772742) (xy 65.22695 -439.795808) (xy 65.212686 -439.815426)
			(xy 65.193058 -439.829675) (xy 65.169986 -439.83716) (xy 65.157858 -439.837576) (xy 64.218058 -439.837576)
			(xy 64.205943 -439.837124) (xy 64.1829 -439.829627) (xy 64.163301 -439.815379) (xy 64.14906 -439.795774)
			(xy 64.141571 -439.77273) (xy 64.141096 -439.760614) (xy 61.234828 -439.760614) (xy 61.234451 -439.772741)
			(xy 61.226951 -439.795806) (xy 61.212689 -439.815424) (xy 61.193063 -439.829673) (xy 61.169993 -439.837159)
			(xy 61.157866 -439.837576) (xy 60.218066 -439.837576) (xy 60.205951 -439.837118) (xy 60.182909 -439.829623)
			(xy 60.163309 -439.815377) (xy 60.149068 -439.795773) (xy 60.141579 -439.772729) (xy 60.141104 -439.760614)
			(xy 7.00913 -439.760614) (xy 7.00913 -439.989976) (xy 7.009638 -440.045746) (xy 7.017973 -440.156973)
			(xy 7.034597 -440.267266) (xy 7.059417 -440.376009) (xy 7.092293 -440.482593) (xy 7.133043 -440.586422)
			(xy 7.181438 -440.686915) (xy 7.237207 -440.783511) (xy 7.300039 -440.87567) (xy 7.369583 -440.962874)
			(xy 7.445449 -441.044639) (xy 7.527212 -441.120505) (xy 7.614417 -441.190048) (xy 7.706575 -441.252881)
			(xy 7.803171 -441.30865) (xy 7.903664 -441.357045) (xy 8.007493 -441.397795) (xy 8.114077 -441.430672)
			(xy 8.22282 -441.455492) (xy 8.333113 -441.472116) (xy 8.44434 -441.480451) (xy 8.50011 -441.480956)
		)
		(stroke
			(width 0)
			(type solid)
		)
		(fill yes)
		(layer "In14.Cu")
		(net "GND")
	)
	(gr_arc
		(start 0.508 -77.67193)
		(mid 0.621601 -78.242658)
		(end 0.94488 -78.726538)
		(stroke
			(width 0.2)
			(type default)
		)
		(layer "In14.Cu")
	)
	(gr_line
		(start 0.508 -13.780008)
		(end 0.508 -77.67193)
		(stroke
			(width 0.2)
			(type default)
		)
		(layer "In14.Cu")
	)
	(gr_arc
		(start 0.508 -7.78002)
		(mid 0.944996 -8.83502)
		(end 1.999996 -9.272016)
		(stroke
			(width 0.2)
			(type default)
		)
		(layer "In14.Cu")
	)
	(gr_line
		(start 0.508 10.40003)
		(end 0.508 -7.78002)
		(stroke
			(width 0.2)
			(type default)
		)
		(layer "In14.Cu")
	)
	(gr_line
		(start 0.94488 -78.726538)
		(end 1.773428 -79.555086)
		(stroke
			(width 0.2)
			(type default)
		)
		(layer "In14.Cu")
	)
	(gr_line
		(start 1.414272 -79.914242)
		(end 0.585724 -79.085694)
		(stroke
			(width 1.016)
			(type default)
		)
		(layer "In14.Cu")
	)
	(gr_line
		(start 1.999996 -403.371558)
		(end 1.999996 -81.328514)
		(stroke
			(width 1.016)
			(type default)
		)
		(layer "In14.Cu")
	)
	(gr_arc
		(start 1.999996 -403.371558)
		(mid 2.152159 -404.136965)
		(end 2.58572 -404.78583)
		(stroke
			(width 1.016)
			(type default)
		)
		(layer "In14.Cu")
	)
	(gr_arc
		(start 1.999996 -81.328514)
		(mid 1.847755 -80.563149)
		(end 1.414272 -79.914242)
		(stroke
			(width 1.016)
			(type default)
		)
		(layer "In14.Cu")
	)
	(gr_arc
		(start 1.999996 -12.288012)
		(mid 0.944996 -12.725008)
		(end 0.508 -13.780008)
		(stroke
			(width 0.2)
			(type default)
		)
		(layer "In14.Cu")
	)
	(gr_arc
		(start 1.999996 -11.780012)
		(mid 0.585785 -12.365797)
		(end 0 -13.780008)
		(stroke
			(width 1.016)
			(type default)
		)
		(layer "In14.Cu")
	)
	(gr_line
		(start 1.999996 -11.780012)
		(end 11.102086 -11.780012)
		(stroke
			(width 1.016)
			(type default)
		)
		(layer "In14.Cu")
	)
	(gr_line
		(start 1.999996 -9.272016)
		(end 9.10209 -9.272016)
		(stroke
			(width 0.2)
			(type default)
		)
		(layer "In14.Cu")
	)
	(gr_arc
		(start 1.999996 11.892026)
		(mid 0.944996 11.45503)
		(end 0.508 10.40003)
		(stroke
			(width 0.2)
			(type default)
		)
		(layer "In14.Cu")
	)
	(gr_arc
		(start 2.507996 -403.371812)
		(mid 2.621533 -403.942691)
		(end 2.944876 -404.426674)
		(stroke
			(width 0.2)
			(type default)
		)
		(layer "In14.Cu")
	)
	(gr_arc
		(start 2.507996 -81.32826)
		(mid 2.317045 -80.368624)
		(end 1.773428 -79.555086)
		(stroke
			(width 0.2)
			(type default)
		)
		(layer "In14.Cu")
	)
	(gr_line
		(start 2.507996 -81.32826)
		(end 2.507996 -403.371812)
		(stroke
			(width 0.2)
			(type default)
		)
		(layer "In14.Cu")
	)
	(gr_line
		(start 2.944876 -404.426674)
		(end 6.273292 -407.75509)
		(stroke
			(width 0.2)
			(type default)
		)
		(layer "In14.Cu")
	)
	(gr_line
		(start 5.914136 -408.114246)
		(end 2.58572 -404.78583)
		(stroke
			(width 1.016)
			(type default)
		)
		(layer "In14.Cu")
	)
	(gr_line
		(start 6.500114 -439.989976)
		(end 6.500114 -409.528518)
		(stroke
			(width 1.016)
			(type default)
		)
		(layer "In14.Cu")
	)
	(gr_arc
		(start 6.500114 -439.989976)
		(mid 7.085891 -441.404199)
		(end 8.50011 -441.989972)
		(stroke
			(width 1.016)
			(type default)
		)
		(layer "In14.Cu")
	)
	(gr_arc
		(start 6.500114 -409.528518)
		(mid 6.347771 -408.763109)
		(end 5.914136 -408.114246)
		(stroke
			(width 1.016)
			(type default)
		)
		(layer "In14.Cu")
	)
	(gr_arc
		(start 7.008114 -439.989976)
		(mid 7.44511 -441.044976)
		(end 8.50011 -441.481972)
		(stroke
			(width 0.2)
			(type default)
		)
		(layer "In14.Cu")
	)
	(gr_arc
		(start 7.008114 -409.528518)
		(mid 6.817049 -408.568734)
		(end 6.273292 -407.75509)
		(stroke
			(width 0.2)
			(type default)
		)
		(layer "In14.Cu")
	)
	(gr_line
		(start 7.008114 -409.528518)
		(end 7.008114 -439.989976)
		(stroke
			(width 0.2)
			(type default)
		)
		(layer "In14.Cu")
	)
	(gr_line
		(start 8.50011 -441.481972)
		(end 194.496944 -441.481972)
		(stroke
			(width 0.2)
			(type default)
		)
		(layer "In14.Cu")
	)
	(gr_arc
		(start 9.10209 -9.272016)
		(mid 10.15709 -8.83502)
		(end 10.594086 -7.78002)
		(stroke
			(width 0.2)
			(type default)
		)
		(layer "In14.Cu")
	)
	(gr_line
		(start 10.594086 -7.78002)
		(end 10.594086 0.40005)
		(stroke
			(width 0.2)
			(type default)
		)
		(layer "In14.Cu")
	)
	(gr_line
		(start 11.102086 -12.288012)
		(end 1.999996 -12.288012)
		(stroke
			(width 0.2)
			(type default)
		)
		(layer "In14.Cu")
	)
	(gr_arc
		(start 11.102086 -12.288012)
		(mid 12.875508 -11.553438)
		(end 13.610082 -9.780016)
		(stroke
			(width 0.2)
			(type default)
		)
		(layer "In14.Cu")
	)
	(gr_arc
		(start 11.102086 -11.780012)
		(mid 12.516297 -11.194227)
		(end 13.102082 -9.780016)
		(stroke
			(width 1.016)
			(type default)
		)
		(layer "In14.Cu")
	)
	(gr_line
		(start 13.102082 -9.780016)
		(end 13.102082 -0.500126)
		(stroke
			(width 1.016)
			(type default)
		)
		(layer "In14.Cu")
	)
	(gr_arc
		(start 13.102082 2.908046)
		(mid 11.32866 2.173472)
		(end 10.594086 0.40005)
		(stroke
			(width 0.2)
			(type default)
		)
		(layer "In14.Cu")
	)
	(gr_line
		(start 13.102082 2.908046)
		(end 81.701894 2.908046)
		(stroke
			(width 0.2)
			(type default)
		)
		(layer "In14.Cu")
	)
	(gr_arc
		(start 13.601954 0)
		(mid 13.24848 -0.146572)
		(end 13.102082 -0.500126)
		(stroke
			(width 1.016)
			(type default)
		)
		(layer "In14.Cu")
	)
	(gr_line
		(start 13.601954 0)
		(end 81.202022 0)
		(stroke
			(width 1.016)
			(type default)
		)
		(layer "In14.Cu")
	)
	(gr_line
		(start 13.610082 -0.508)
		(end 13.610082 -9.780016)
		(stroke
			(width 0.2)
			(type default)
		)
		(layer "In14.Cu")
	)
	(gr_circle
		(center 25.82545 -40.816276)
		(end 26.71445 -40.816276)
		(stroke
			(width 0.2)
			(type default)
		)
		(fill no)
		(layer "In14.Cu")
	)
	(gr_circle
		(center 29.291534 -348.709488)
		(end 30.171644 -348.709488)
		(stroke
			(width 0.2)
			(type default)
		)
		(fill no)
		(layer "In14.Cu")
	)
	(gr_circle
		(center 29.908754 -348.709488)
		(end 30.788864 -348.709488)
		(stroke
			(width 0.2)
			(type default)
		)
		(fill no)
		(layer "In14.Cu")
	)
	(gr_circle
		(center 30.525974 -348.709488)
		(end 31.406084 -348.709488)
		(stroke
			(width 0.2)
			(type default)
		)
		(fill no)
		(layer "In14.Cu")
	)
	(gr_circle
		(center 30.795214 -347.966538)
		(end 31.684214 -347.966538)
		(stroke
			(width 0.2)
			(type default)
		)
		(fill no)
		(layer "In14.Cu")
	)
	(gr_circle
		(center 30.795214 -347.229938)
		(end 31.684214 -347.229938)
		(stroke
			(width 0.2)
			(type default)
		)
		(fill no)
		(layer "In14.Cu")
	)
	(gr_circle
		(center 31.22803 -350.318578)
		(end 32.11703 -350.318578)
		(stroke
			(width 0.2)
			(type default)
		)
		(fill no)
		(layer "In14.Cu")
	)
	(gr_circle
		(center 31.22803 -349.581978)
		(end 32.11703 -349.581978)
		(stroke
			(width 0.2)
			(type default)
		)
		(fill no)
		(layer "In14.Cu")
	)
	(gr_circle
		(center 31.752794 -349.142558)
		(end 32.641794 -349.142558)
		(stroke
			(width 0.2)
			(type default)
		)
		(fill no)
		(layer "In14.Cu")
	)
	(gr_circle
		(center 31.778194 -349.904558)
		(end 32.667194 -349.904558)
		(stroke
			(width 0.2)
			(type default)
		)
		(fill no)
		(layer "In14.Cu")
	)
	(gr_circle
		(center 32.311594 -350.260158)
		(end 33.200594 -350.260158)
		(stroke
			(width 0.2)
			(type default)
		)
		(fill no)
		(layer "In14.Cu")
	)
	(gr_circle
		(center 32.311594 -349.523558)
		(end 33.200594 -349.523558)
		(stroke
			(width 0.2)
			(type default)
		)
		(fill no)
		(layer "In14.Cu")
	)
	(gr_circle
		(center 32.311594 -348.786958)
		(end 33.200594 -348.786958)
		(stroke
			(width 0.2)
			(type default)
		)
		(fill no)
		(layer "In14.Cu")
	)
	(gr_circle
		(center 37.571934 -348.709488)
		(end 38.452044 -348.709488)
		(stroke
			(width 0.2)
			(type default)
		)
		(fill no)
		(layer "In14.Cu")
	)
	(gr_circle
		(center 38.189154 -348.709488)
		(end 39.069264 -348.709488)
		(stroke
			(width 0.2)
			(type default)
		)
		(fill no)
		(layer "In14.Cu")
	)
	(gr_circle
		(center 38.806374 -348.709488)
		(end 39.686484 -348.709488)
		(stroke
			(width 0.2)
			(type default)
		)
		(fill no)
		(layer "In14.Cu")
	)
	(gr_circle
		(center 39.050214 -347.974158)
		(end 39.939214 -347.974158)
		(stroke
			(width 0.2)
			(type default)
		)
		(fill no)
		(layer "In14.Cu")
	)
	(gr_circle
		(center 39.050214 -347.237558)
		(end 39.939214 -347.237558)
		(stroke
			(width 0.2)
			(type default)
		)
		(fill no)
		(layer "In14.Cu")
	)
	(gr_circle
		(center 39.50843 -350.318578)
		(end 40.39743 -350.318578)
		(stroke
			(width 0.2)
			(type default)
		)
		(fill no)
		(layer "In14.Cu")
	)
	(gr_circle
		(center 39.50843 -349.581978)
		(end 40.39743 -349.581978)
		(stroke
			(width 0.2)
			(type default)
		)
		(fill no)
		(layer "In14.Cu")
	)
	(gr_circle
		(center 40.033194 -349.142558)
		(end 40.922194 -349.142558)
		(stroke
			(width 0.2)
			(type default)
		)
		(fill no)
		(layer "In14.Cu")
	)
	(gr_circle
		(center 40.058594 -349.904558)
		(end 40.947594 -349.904558)
		(stroke
			(width 0.2)
			(type default)
		)
		(fill no)
		(layer "In14.Cu")
	)
	(gr_circle
		(center 40.591994 -350.260158)
		(end 41.480994 -350.260158)
		(stroke
			(width 0.2)
			(type default)
		)
		(fill no)
		(layer "In14.Cu")
	)
	(gr_circle
		(center 40.591994 -349.523558)
		(end 41.480994 -349.523558)
		(stroke
			(width 0.2)
			(type default)
		)
		(fill no)
		(layer "In14.Cu")
	)
	(gr_circle
		(center 40.591994 -348.786958)
		(end 41.480994 -348.786958)
		(stroke
			(width 0.2)
			(type default)
		)
		(fill no)
		(layer "In14.Cu")
	)
	(gr_circle
		(center 41.369742 -358.549194)
		(end 42.258742 -358.549194)
		(stroke
			(width 0.2)
			(type default)
		)
		(fill no)
		(layer "In14.Cu")
	)
	(gr_circle
		(center 41.417494 -357.898192)
		(end 42.306494 -357.898192)
		(stroke
			(width 0.2)
			(type default)
		)
		(fill no)
		(layer "In14.Cu")
	)
	(gr_circle
		(center 41.417494 -357.263192)
		(end 42.306494 -357.263192)
		(stroke
			(width 0.2)
			(type default)
		)
		(fill no)
		(layer "In14.Cu")
	)
	(gr_circle
		(center 41.427146 -359.2576)
		(end 42.316146 -359.2576)
		(stroke
			(width 0.2)
			(type default)
		)
		(fill no)
		(layer "In14.Cu")
	)
	(gr_circle
		(center 43.935904 -358.51084)
		(end 44.824904 -358.51084)
		(stroke
			(width 0.2)
			(type default)
		)
		(fill no)
		(layer "In14.Cu")
	)
	(gr_circle
		(center 43.983656 -357.859838)
		(end 44.872656 -357.859838)
		(stroke
			(width 0.2)
			(type default)
		)
		(fill no)
		(layer "In14.Cu")
	)
	(gr_circle
		(center 43.983656 -357.224838)
		(end 44.872656 -357.224838)
		(stroke
			(width 0.2)
			(type default)
		)
		(fill no)
		(layer "In14.Cu")
	)
	(gr_circle
		(center 43.993308 -359.219246)
		(end 44.882308 -359.219246)
		(stroke
			(width 0.2)
			(type default)
		)
		(fill no)
		(layer "In14.Cu")
	)
	(gr_circle
		(center 45.877734 -348.709488)
		(end 46.757844 -348.709488)
		(stroke
			(width 0.2)
			(type default)
		)
		(fill no)
		(layer "In14.Cu")
	)
	(gr_circle
		(center 46.494954 -348.709488)
		(end 47.375064 -348.709488)
		(stroke
			(width 0.2)
			(type default)
		)
		(fill no)
		(layer "In14.Cu")
	)
	(gr_circle
		(center 47.112174 -348.709488)
		(end 47.992284 -348.709488)
		(stroke
			(width 0.2)
			(type default)
		)
		(fill no)
		(layer "In14.Cu")
	)
	(gr_circle
		(center 47.366174 -348.017338)
		(end 48.255174 -348.017338)
		(stroke
			(width 0.2)
			(type default)
		)
		(fill no)
		(layer "In14.Cu")
	)
	(gr_circle
		(center 47.366174 -347.280738)
		(end 48.255174 -347.280738)
		(stroke
			(width 0.2)
			(type default)
		)
		(fill no)
		(layer "In14.Cu")
	)
	(gr_circle
		(center 47.81423 -350.318578)
		(end 48.70323 -350.318578)
		(stroke
			(width 0.2)
			(type default)
		)
		(fill no)
		(layer "In14.Cu")
	)
	(gr_circle
		(center 47.81423 -349.581978)
		(end 48.70323 -349.581978)
		(stroke
			(width 0.2)
			(type default)
		)
		(fill no)
		(layer "In14.Cu")
	)
	(gr_circle
		(center 47.880778 -358.108504)
		(end 48.769778 -358.108504)
		(stroke
			(width 0.2)
			(type default)
		)
		(fill no)
		(layer "In14.Cu")
	)
	(gr_circle
		(center 47.92853 -357.457502)
		(end 48.81753 -357.457502)
		(stroke
			(width 0.2)
			(type default)
		)
		(fill no)
		(layer "In14.Cu")
	)
	(gr_circle
		(center 47.92853 -356.822502)
		(end 48.81753 -356.822502)
		(stroke
			(width 0.2)
			(type default)
		)
		(fill no)
		(layer "In14.Cu")
	)
	(gr_circle
		(center 48.338994 -349.142558)
		(end 49.227994 -349.142558)
		(stroke
			(width 0.2)
			(type default)
		)
		(fill no)
		(layer "In14.Cu")
	)
	(gr_circle
		(center 48.364394 -349.904558)
		(end 49.253394 -349.904558)
		(stroke
			(width 0.2)
			(type default)
		)
		(fill no)
		(layer "In14.Cu")
	)
	(gr_circle
		(center 48.718978 -358.108504)
		(end 49.607978 -358.108504)
		(stroke
			(width 0.2)
			(type default)
		)
		(fill no)
		(layer "In14.Cu")
	)
	(gr_circle
		(center 48.76673 -357.457502)
		(end 49.65573 -357.457502)
		(stroke
			(width 0.2)
			(type default)
		)
		(fill no)
		(layer "In14.Cu")
	)
	(gr_circle
		(center 48.76673 -356.822502)
		(end 49.65573 -356.822502)
		(stroke
			(width 0.2)
			(type default)
		)
		(fill no)
		(layer "In14.Cu")
	)
	(gr_circle
		(center 48.897794 -350.260158)
		(end 49.786794 -350.260158)
		(stroke
			(width 0.2)
			(type default)
		)
		(fill no)
		(layer "In14.Cu")
	)
	(gr_circle
		(center 48.897794 -349.523558)
		(end 49.786794 -349.523558)
		(stroke
			(width 0.2)
			(type default)
		)
		(fill no)
		(layer "In14.Cu")
	)
	(gr_circle
		(center 48.897794 -348.786958)
		(end 49.786794 -348.786958)
		(stroke
			(width 0.2)
			(type default)
		)
		(fill no)
		(layer "In14.Cu")
	)
	(gr_circle
		(center 49.353978 -358.108504)
		(end 50.242978 -358.108504)
		(stroke
			(width 0.2)
			(type default)
		)
		(fill no)
		(layer "In14.Cu")
	)
	(gr_circle
		(center 49.40173 -357.457502)
		(end 50.29073 -357.457502)
		(stroke
			(width 0.2)
			(type default)
		)
		(fill no)
		(layer "In14.Cu")
	)
	(gr_circle
		(center 49.40173 -356.822502)
		(end 50.29073 -356.822502)
		(stroke
			(width 0.2)
			(type default)
		)
		(fill no)
		(layer "In14.Cu")
	)
	(gr_circle
		(center 49.988978 -358.108504)
		(end 50.877978 -358.108504)
		(stroke
			(width 0.2)
			(type default)
		)
		(fill no)
		(layer "In14.Cu")
	)
	(gr_circle
		(center 50.03673 -357.457502)
		(end 50.92573 -357.457502)
		(stroke
			(width 0.2)
			(type default)
		)
		(fill no)
		(layer "In14.Cu")
	)
	(gr_circle
		(center 50.03673 -356.822502)
		(end 50.92573 -356.822502)
		(stroke
			(width 0.2)
			(type default)
		)
		(fill no)
		(layer "In14.Cu")
	)
	(gr_circle
		(center 50.623978 -358.108504)
		(end 51.512978 -358.108504)
		(stroke
			(width 0.2)
			(type default)
		)
		(fill no)
		(layer "In14.Cu")
	)
	(gr_circle
		(center 50.67173 -357.457502)
		(end 51.56073 -357.457502)
		(stroke
			(width 0.2)
			(type default)
		)
		(fill no)
		(layer "In14.Cu")
	)
	(gr_circle
		(center 50.67173 -356.822502)
		(end 51.56073 -356.822502)
		(stroke
			(width 0.2)
			(type default)
		)
		(fill no)
		(layer "In14.Cu")
	)
	(gr_circle
		(center 54.234334 -348.709488)
		(end 55.114444 -348.709488)
		(stroke
			(width 0.2)
			(type default)
		)
		(fill no)
		(layer "In14.Cu")
	)
	(gr_circle
		(center 54.851554 -348.709488)
		(end 55.731664 -348.709488)
		(stroke
			(width 0.2)
			(type default)
		)
		(fill no)
		(layer "In14.Cu")
	)
	(gr_circle
		(center 55.468774 -348.709488)
		(end 56.348884 -348.709488)
		(stroke
			(width 0.2)
			(type default)
		)
		(fill no)
		(layer "In14.Cu")
	)
	(gr_circle
		(center 55.727854 -347.997018)
		(end 56.616854 -347.997018)
		(stroke
			(width 0.2)
			(type default)
		)
		(fill no)
		(layer "In14.Cu")
	)
	(gr_circle
		(center 55.727854 -347.260418)
		(end 56.616854 -347.260418)
		(stroke
			(width 0.2)
			(type default)
		)
		(fill no)
		(layer "In14.Cu")
	)
	(gr_circle
		(center 56.17083 -350.318578)
		(end 57.05983 -350.318578)
		(stroke
			(width 0.2)
			(type default)
		)
		(fill no)
		(layer "In14.Cu")
	)
	(gr_circle
		(center 56.17083 -349.581978)
		(end 57.05983 -349.581978)
		(stroke
			(width 0.2)
			(type default)
		)
		(fill no)
		(layer "In14.Cu")
	)
	(gr_circle
		(center 56.695594 -349.142558)
		(end 57.584594 -349.142558)
		(stroke
			(width 0.2)
			(type default)
		)
		(fill no)
		(layer "In14.Cu")
	)
	(gr_circle
		(center 56.720994 -349.904558)
		(end 57.609994 -349.904558)
		(stroke
			(width 0.2)
			(type default)
		)
		(fill no)
		(layer "In14.Cu")
	)
	(gr_circle
		(center 57.254394 -350.260158)
		(end 58.143394 -350.260158)
		(stroke
			(width 0.2)
			(type default)
		)
		(fill no)
		(layer "In14.Cu")
	)
	(gr_circle
		(center 57.254394 -349.523558)
		(end 58.143394 -349.523558)
		(stroke
			(width 0.2)
			(type default)
		)
		(fill no)
		(layer "In14.Cu")
	)
	(gr_circle
		(center 57.254394 -348.786958)
		(end 58.143394 -348.786958)
		(stroke
			(width 0.2)
			(type default)
		)
		(fill no)
		(layer "In14.Cu")
	)
	(gr_circle
		(center 61.93663 -166.86276)
		(end 62.82563 -166.86276)
		(stroke
			(width 0.2)
			(type default)
		)
		(fill no)
		(layer "In14.Cu")
	)
	(gr_circle
		(center 61.93663 -166.12616)
		(end 62.82563 -166.12616)
		(stroke
			(width 0.2)
			(type default)
		)
		(fill no)
		(layer "In14.Cu")
	)
	(gr_circle
		(center 61.93663 -165.38956)
		(end 62.82563 -165.38956)
		(stroke
			(width 0.2)
			(type default)
		)
		(fill no)
		(layer "In14.Cu")
	)
	(gr_circle
		(center 62.47003 -165.74516)
		(end 63.35903 -165.74516)
		(stroke
			(width 0.2)
			(type default)
		)
		(fill no)
		(layer "In14.Cu")
	)
	(gr_circle
		(center 62.49543 -166.50716)
		(end 63.38443 -166.50716)
		(stroke
			(width 0.2)
			(type default)
		)
		(fill no)
		(layer "In14.Cu")
	)
	(gr_circle
		(center 62.565534 -348.709488)
		(end 63.445644 -348.709488)
		(stroke
			(width 0.2)
			(type default)
		)
		(fill no)
		(layer "In14.Cu")
	)
	(gr_circle
		(center 63.020194 -166.06774)
		(end 63.909194 -166.06774)
		(stroke
			(width 0.2)
			(type default)
		)
		(fill no)
		(layer "In14.Cu")
	)
	(gr_circle
		(center 63.020194 -165.33114)
		(end 63.909194 -165.33114)
		(stroke
			(width 0.2)
			(type default)
		)
		(fill no)
		(layer "In14.Cu")
	)
	(gr_circle
		(center 63.182754 -348.709488)
		(end 64.062864 -348.709488)
		(stroke
			(width 0.2)
			(type default)
		)
		(fill no)
		(layer "In14.Cu")
	)
	(gr_circle
		(center 63.199264 -12.43711)
		(end 64.088264 -12.43711)
		(stroke
			(width 0.2)
			(type default)
		)
		(fill no)
		(layer "In14.Cu")
	)
	(gr_circle
		(center 63.579248 -168.42232)
		(end 64.468248 -168.42232)
		(stroke
			(width 0.2)
			(type default)
		)
		(fill no)
		(layer "In14.Cu")
	)
	(gr_circle
		(center 63.579248 -167.68572)
		(end 64.468248 -167.68572)
		(stroke
			(width 0.2)
			(type default)
		)
		(fill no)
		(layer "In14.Cu")
	)
	(gr_circle
		(center 63.631064 -13.09751)
		(end 64.520064 -13.09751)
		(stroke
			(width 0.2)
			(type default)
		)
		(fill no)
		(layer "In14.Cu")
	)
	(gr_circle
		(center 63.72225 -166.94023)
		(end 64.60236 -166.94023)
		(stroke
			(width 0.2)
			(type default)
		)
		(fill no)
		(layer "In14.Cu")
	)
	(gr_circle
		(center 63.799974 -348.709488)
		(end 64.680084 -348.709488)
		(stroke
			(width 0.2)
			(type default)
		)
		(fill no)
		(layer "In14.Cu")
	)
	(gr_circle
		(center 64.061594 -348.038928)
		(end 64.941704 -348.038928)
		(stroke
			(width 0.2)
			(type default)
		)
		(fill no)
		(layer "In14.Cu")
	)
	(gr_circle
		(center 64.061594 -347.302328)
		(end 64.941704 -347.302328)
		(stroke
			(width 0.2)
			(type default)
		)
		(fill no)
		(layer "In14.Cu")
	)
	(gr_circle
		(center 64.088264 -12.43711)
		(end 64.977264 -12.43711)
		(stroke
			(width 0.2)
			(type default)
		)
		(fill no)
		(layer "In14.Cu")
	)
	(gr_circle
		(center 64.33947 -166.94023)
		(end 65.21958 -166.94023)
		(stroke
			(width 0.2)
			(type default)
		)
		(fill no)
		(layer "In14.Cu")
	)
	(gr_circle
		(center 64.50203 -350.318578)
		(end 65.39103 -350.318578)
		(stroke
			(width 0.2)
			(type default)
		)
		(fill no)
		(layer "In14.Cu")
	)
	(gr_circle
		(center 64.50203 -349.581978)
		(end 65.39103 -349.581978)
		(stroke
			(width 0.2)
			(type default)
		)
		(fill no)
		(layer "In14.Cu")
	)
	(gr_circle
		(center 64.520064 -13.09751)
		(end 65.409064 -13.09751)
		(stroke
			(width 0.2)
			(type default)
		)
		(fill no)
		(layer "In14.Cu")
	)
	(gr_circle
		(center 64.95669 -166.94023)
		(end 65.8368 -166.94023)
		(stroke
			(width 0.2)
			(type default)
		)
		(fill no)
		(layer "In14.Cu")
	)
	(gr_circle
		(center 64.977264 -12.43711)
		(end 65.866264 -12.43711)
		(stroke
			(width 0.2)
			(type default)
		)
		(fill no)
		(layer "In14.Cu")
	)
	(gr_circle
		(center 65.026794 -349.142558)
		(end 65.915794 -349.142558)
		(stroke
			(width 0.2)
			(type default)
		)
		(fill no)
		(layer "In14.Cu")
	)
	(gr_circle
		(center 65.052194 -349.904558)
		(end 65.941194 -349.904558)
		(stroke
			(width 0.2)
			(type default)
		)
		(fill no)
		(layer "In14.Cu")
	)
	(gr_circle
		(center 65.409064 -13.09751)
		(end 66.298064 -13.09751)
		(stroke
			(width 0.2)
			(type default)
		)
		(fill no)
		(layer "In14.Cu")
	)
	(gr_circle
		(center 65.585594 -350.260158)
		(end 66.474594 -350.260158)
		(stroke
			(width 0.2)
			(type default)
		)
		(fill no)
		(layer "In14.Cu")
	)
	(gr_circle
		(center 65.585594 -349.523558)
		(end 66.474594 -349.523558)
		(stroke
			(width 0.2)
			(type default)
		)
		(fill no)
		(layer "In14.Cu")
	)
	(gr_circle
		(center 65.585594 -348.786958)
		(end 66.474594 -348.786958)
		(stroke
			(width 0.2)
			(type default)
		)
		(fill no)
		(layer "In14.Cu")
	)
	(gr_circle
		(center 65.866264 -12.43711)
		(end 66.755264 -12.43711)
		(stroke
			(width 0.2)
			(type default)
		)
		(fill no)
		(layer "In14.Cu")
	)
	(gr_circle
		(center 66.298064 -13.09751)
		(end 67.187064 -13.09751)
		(stroke
			(width 0.2)
			(type default)
		)
		(fill no)
		(layer "In14.Cu")
	)
	(gr_circle
		(center 66.399664 -25.56891)
		(end 67.288664 -25.56891)
		(stroke
			(width 0.2)
			(type default)
		)
		(fill no)
		(layer "In14.Cu")
	)
	(gr_circle
		(center 66.501264 -12.43711)
		(end 67.390264 -12.43711)
		(stroke
			(width 0.2)
			(type default)
		)
		(fill no)
		(layer "In14.Cu")
	)
	(gr_circle
		(center 66.774822 -20.327366)
		(end 67.663822 -20.327366)
		(stroke
			(width 0.2)
			(type default)
		)
		(fill no)
		(layer "In14.Cu")
	)
	(gr_circle
		(center 66.774822 -19.692366)
		(end 67.663822 -19.692366)
		(stroke
			(width 0.2)
			(type default)
		)
		(fill no)
		(layer "In14.Cu")
	)
	(gr_circle
		(center 66.780664 -24.88311)
		(end 67.669664 -24.88311)
		(stroke
			(width 0.2)
			(type default)
		)
		(fill no)
		(layer "In14.Cu")
	)
	(gr_circle
		(center 66.848228 -18.642584)
		(end 67.737228 -18.642584)
		(stroke
			(width 0.2)
			(type default)
		)
		(fill no)
		(layer "In14.Cu")
	)
	(gr_circle
		(center 66.882264 -22.26691)
		(end 67.771264 -22.26691)
		(stroke
			(width 0.2)
			(type default)
		)
		(fill no)
		(layer "In14.Cu")
	)
	(gr_circle
		(center 66.933064 -13.09751)
		(end 67.822064 -13.09751)
		(stroke
			(width 0.2)
			(type default)
		)
		(fill no)
		(layer "In14.Cu")
	)
	(gr_circle
		(center 67.288664 -25.56891)
		(end 68.177664 -25.56891)
		(stroke
			(width 0.2)
			(type default)
		)
		(fill no)
		(layer "In14.Cu")
	)
	(gr_circle
		(center 67.40271 -12.489434)
		(end 68.29171 -12.489434)
		(stroke
			(width 0.2)
			(type default)
		)
		(fill no)
		(layer "In14.Cu")
	)
	(gr_circle
		(center 67.669664 -24.88311)
		(end 68.558664 -24.88311)
		(stroke
			(width 0.2)
			(type default)
		)
		(fill no)
		(layer "In14.Cu")
	)
	(gr_circle
		(center 68.177664 -25.56891)
		(end 69.066664 -25.56891)
		(stroke
			(width 0.2)
			(type default)
		)
		(fill no)
		(layer "In14.Cu")
	)
	(gr_circle
		(center 68.54444 -18.476214)
		(end 69.43344 -18.476214)
		(stroke
			(width 0.2)
			(type default)
		)
		(fill no)
		(layer "In14.Cu")
	)
	(gr_circle
		(center 68.558664 -24.88311)
		(end 69.447664 -24.88311)
		(stroke
			(width 0.2)
			(type default)
		)
		(fill no)
		(layer "In14.Cu")
	)
	(gr_circle
		(center 69.498464 -24.55291)
		(end 70.387464 -24.55291)
		(stroke
			(width 0.2)
			(type default)
		)
		(fill no)
		(layer "In14.Cu")
	)
	(gr_circle
		(center 70.25005 -175.559974)
		(end 71.13905 -175.559974)
		(stroke
			(width 0.2)
			(type default)
		)
		(fill no)
		(layer "In14.Cu")
	)
	(gr_circle
		(center 70.25005 -174.823374)
		(end 71.13905 -174.823374)
		(stroke
			(width 0.2)
			(type default)
		)
		(fill no)
		(layer "In14.Cu")
	)
	(gr_circle
		(center 70.25005 -174.086774)
		(end 71.13905 -174.086774)
		(stroke
			(width 0.2)
			(type default)
		)
		(fill no)
		(layer "In14.Cu")
	)
	(gr_circle
		(center 70.78345 -174.442374)
		(end 71.67245 -174.442374)
		(stroke
			(width 0.2)
			(type default)
		)
		(fill no)
		(layer "In14.Cu")
	)
	(gr_circle
		(center 70.80885 -175.204374)
		(end 71.69785 -175.204374)
		(stroke
			(width 0.2)
			(type default)
		)
		(fill no)
		(layer "In14.Cu")
	)
	(gr_circle
		(center 71.099934 -336.988404)
		(end 71.980044 -336.988404)
		(stroke
			(width 0.2)
			(type default)
		)
		(fill no)
		(layer "In14.Cu")
	)
	(gr_circle
		(center 71.333614 -174.764954)
		(end 72.222614 -174.764954)
		(stroke
			(width 0.2)
			(type default)
		)
		(fill no)
		(layer "In14.Cu")
	)
	(gr_circle
		(center 71.333614 -174.028354)
		(end 72.222614 -174.028354)
		(stroke
			(width 0.2)
			(type default)
		)
		(fill no)
		(layer "In14.Cu")
	)
	(gr_circle
		(center 71.717154 -336.988404)
		(end 72.597264 -336.988404)
		(stroke
			(width 0.2)
			(type default)
		)
		(fill no)
		(layer "In14.Cu")
	)
	(gr_circle
		(center 71.892668 -177.10912)
		(end 72.781668 -177.10912)
		(stroke
			(width 0.2)
			(type default)
		)
		(fill no)
		(layer "In14.Cu")
	)
	(gr_circle
		(center 71.892668 -176.37252)
		(end 72.781668 -176.37252)
		(stroke
			(width 0.2)
			(type default)
		)
		(fill no)
		(layer "In14.Cu")
	)
	(gr_circle
		(center 72.03567 -175.639222)
		(end 72.91578 -175.639222)
		(stroke
			(width 0.2)
			(type default)
		)
		(fill no)
		(layer "In14.Cu")
	)
	(gr_circle
		(center 72.334374 -336.988404)
		(end 73.214484 -336.988404)
		(stroke
			(width 0.2)
			(type default)
		)
		(fill no)
		(layer "In14.Cu")
	)
	(gr_circle
		(center 72.616314 -336.255868)
		(end 73.496424 -336.255868)
		(stroke
			(width 0.2)
			(type default)
		)
		(fill no)
		(layer "In14.Cu")
	)
	(gr_circle
		(center 72.616314 -335.519268)
		(end 73.496424 -335.519268)
		(stroke
			(width 0.2)
			(type default)
		)
		(fill no)
		(layer "In14.Cu")
	)
	(gr_circle
		(center 72.65289 -175.639222)
		(end 73.533 -175.639222)
		(stroke
			(width 0.2)
			(type default)
		)
		(fill no)
		(layer "In14.Cu")
	)
	(gr_circle
		(center 73.03643 -338.597494)
		(end 73.92543 -338.597494)
		(stroke
			(width 0.2)
			(type default)
		)
		(fill no)
		(layer "In14.Cu")
	)
	(gr_circle
		(center 73.03643 -337.860894)
		(end 73.92543 -337.860894)
		(stroke
			(width 0.2)
			(type default)
		)
		(fill no)
		(layer "In14.Cu")
	)
	(gr_circle
		(center 73.27011 -175.639222)
		(end 74.15022 -175.639222)
		(stroke
			(width 0.2)
			(type default)
		)
		(fill no)
		(layer "In14.Cu")
	)
	(gr_circle
		(center 73.561194 -337.421474)
		(end 74.450194 -337.421474)
		(stroke
			(width 0.2)
			(type default)
		)
		(fill no)
		(layer "In14.Cu")
	)
	(gr_circle
		(center 73.586594 -338.183474)
		(end 74.475594 -338.183474)
		(stroke
			(width 0.2)
			(type default)
		)
		(fill no)
		(layer "In14.Cu")
	)
	(gr_circle
		(center 74.119994 -338.539074)
		(end 75.008994 -338.539074)
		(stroke
			(width 0.2)
			(type default)
		)
		(fill no)
		(layer "In14.Cu")
	)
	(gr_circle
		(center 74.119994 -337.802474)
		(end 75.008994 -337.802474)
		(stroke
			(width 0.2)
			(type default)
		)
		(fill no)
		(layer "In14.Cu")
	)
	(gr_circle
		(center 74.119994 -337.065874)
		(end 75.008994 -337.065874)
		(stroke
			(width 0.2)
			(type default)
		)
		(fill no)
		(layer "In14.Cu")
	)
	(gr_circle
		(center 74.811382 -351.637854)
		(end 75.700382 -351.637854)
		(stroke
			(width 0.2)
			(type default)
		)
		(fill no)
		(layer "In14.Cu")
	)
	(gr_circle
		(center 74.849482 -353.131374)
		(end 75.738482 -353.131374)
		(stroke
			(width 0.2)
			(type default)
		)
		(fill no)
		(layer "In14.Cu")
	)
	(gr_circle
		(center 74.849736 -352.30816)
		(end 75.738736 -352.30816)
		(stroke
			(width 0.2)
			(type default)
		)
		(fill no)
		(layer "In14.Cu")
	)
	(gr_circle
		(center 74.86015 -350.929448)
		(end 75.74915 -350.929448)
		(stroke
			(width 0.2)
			(type default)
		)
		(fill no)
		(layer "In14.Cu")
	)
	(gr_circle
		(center 77.178408 -16.520668)
		(end 78.067408 -16.520668)
		(stroke
			(width 0.2)
			(type default)
		)
		(fill no)
		(layer "In14.Cu")
	)
	(gr_circle
		(center 77.473048 -351.5995)
		(end 78.362048 -351.5995)
		(stroke
			(width 0.2)
			(type default)
		)
		(fill no)
		(layer "In14.Cu")
	)
	(gr_circle
		(center 77.511402 -352.978212)
		(end 78.400402 -352.978212)
		(stroke
			(width 0.2)
			(type default)
		)
		(fill no)
		(layer "In14.Cu")
	)
	(gr_circle
		(center 77.511402 -352.269806)
		(end 78.400402 -352.269806)
		(stroke
			(width 0.2)
			(type default)
		)
		(fill no)
		(layer "In14.Cu")
	)
	(gr_circle
		(center 77.521816 -350.891094)
		(end 78.410816 -350.891094)
		(stroke
			(width 0.2)
			(type default)
		)
		(fill no)
		(layer "In14.Cu")
	)
	(gr_circle
		(center 77.84338 -16.55064)
		(end 78.73238 -16.55064)
		(stroke
			(width 0.2)
			(type default)
		)
		(fill no)
		(layer "In14.Cu")
	)
	(gr_circle
		(center 78.85303 -178.798474)
		(end 79.74203 -178.798474)
		(stroke
			(width 0.2)
			(type default)
		)
		(fill no)
		(layer "In14.Cu")
	)
	(gr_circle
		(center 78.85303 -178.036474)
		(end 79.74203 -178.036474)
		(stroke
			(width 0.2)
			(type default)
		)
		(fill no)
		(layer "In14.Cu")
	)
	(gr_circle
		(center 79.10703 -179.560474)
		(end 79.99603 -179.560474)
		(stroke
			(width 0.2)
			(type default)
		)
		(fill no)
		(layer "In14.Cu")
	)
	(gr_circle
		(center 79.13243 -180.322474)
		(end 80.02143 -180.322474)
		(stroke
			(width 0.2)
			(type default)
		)
		(fill no)
		(layer "In14.Cu")
	)
	(gr_circle
		(center 79.403194 -178.384454)
		(end 80.292194 -178.384454)
		(stroke
			(width 0.2)
			(type default)
		)
		(fill no)
		(layer "In14.Cu")
	)
	(gr_circle
		(center 79.455518 -336.981292)
		(end 80.335628 -336.981292)
		(stroke
			(width 0.2)
			(type default)
		)
		(fill no)
		(layer "In14.Cu")
	)
	(gr_circle
		(center 79.657194 -179.883054)
		(end 80.546194 -179.883054)
		(stroke
			(width 0.2)
			(type default)
		)
		(fill no)
		(layer "In14.Cu")
	)
	(gr_circle
		(center 79.657194 -179.146454)
		(end 80.546194 -179.146454)
		(stroke
			(width 0.2)
			(type default)
		)
		(fill no)
		(layer "In14.Cu")
	)
	(gr_circle
		(center 79.921862 -18.238724)
		(end 80.810862 -18.238724)
		(stroke
			(width 0.2)
			(type default)
		)
		(fill no)
		(layer "In14.Cu")
	)
	(gr_circle
		(center 79.921862 -17.502124)
		(end 80.810862 -17.502124)
		(stroke
			(width 0.2)
			(type default)
		)
		(fill no)
		(layer "In14.Cu")
	)
	(gr_circle
		(center 80.072738 -336.981292)
		(end 80.952848 -336.981292)
		(stroke
			(width 0.2)
			(type default)
		)
		(fill no)
		(layer "In14.Cu")
	)
	(gr_circle
		(center 80.241648 -182.2196)
		(end 81.130648 -182.2196)
		(stroke
			(width 0.2)
			(type default)
		)
		(fill no)
		(layer "In14.Cu")
	)
	(gr_circle
		(center 80.241648 -181.483)
		(end 81.130648 -181.483)
		(stroke
			(width 0.2)
			(type default)
		)
		(fill no)
		(layer "In14.Cu")
	)
	(gr_circle
		(center 80.35925 -180.755544)
		(end 81.23936 -180.755544)
		(stroke
			(width 0.2)
			(type default)
		)
		(fill no)
		(layer "In14.Cu")
	)
	(gr_circle
		(center 80.689958 -336.981292)
		(end 81.570068 -336.981292)
		(stroke
			(width 0.2)
			(type default)
		)
		(fill no)
		(layer "In14.Cu")
	)
	(gr_circle
		(center 80.97647 -180.755544)
		(end 81.85658 -180.755544)
		(stroke
			(width 0.2)
			(type default)
		)
		(fill no)
		(layer "In14.Cu")
	)
	(gr_circle
		(center 80.977994 -336.245708)
		(end 81.858104 -336.245708)
		(stroke
			(width 0.2)
			(type default)
		)
		(fill no)
		(layer "In14.Cu")
	)
	(gr_circle
		(center 80.977994 -335.509108)
		(end 81.858104 -335.509108)
		(stroke
			(width 0.2)
			(type default)
		)
		(fill no)
		(layer "In14.Cu")
	)
	(gr_line
		(start 81.193894 -9.780016)
		(end 81.193894 -0.508)
		(stroke
			(width 0.2)
			(type default)
		)
		(layer "In14.Cu")
	)
	(gr_arc
		(start 81.193894 -9.780016)
		(mid 81.928474 -11.55343)
		(end 83.70189 -12.288012)
		(stroke
			(width 0.2)
			(type default)
		)
		(layer "In14.Cu")
	)
	(gr_line
		(start 81.193894 -0.508)
		(end 13.610082 -0.508)
		(stroke
			(width 0.2)
			(type default)
		)
		(layer "In14.Cu")
	)
	(gr_circle
		(center 81.392014 -338.590382)
		(end 82.281014 -338.590382)
		(stroke
			(width 0.2)
			(type default)
		)
		(fill no)
		(layer "In14.Cu")
	)
	(gr_circle
		(center 81.392014 -337.853782)
		(end 82.281014 -337.853782)
		(stroke
			(width 0.2)
			(type default)
		)
		(fill no)
		(layer "In14.Cu")
	)
	(gr_circle
		(center 81.59369 -180.755544)
		(end 82.4738 -180.755544)
		(stroke
			(width 0.2)
			(type default)
		)
		(fill no)
		(layer "In14.Cu")
	)
	(gr_arc
		(start 81.701894 -9.780016)
		(mid 82.287679 -11.194227)
		(end 83.70189 -11.780012)
		(stroke
			(width 1.016)
			(type default)
		)
		(layer "In14.Cu")
	)
	(gr_arc
		(start 81.701894 -0.500126)
		(mid 81.555625 -0.146451)
		(end 81.202022 0)
		(stroke
			(width 1.016)
			(type default)
		)
		(layer "In14.Cu")
	)
	(gr_line
		(start 81.701894 -0.500126)
		(end 81.701894 -9.780016)
		(stroke
			(width 1.016)
			(type default)
		)
		(layer "In14.Cu")
	)
	(gr_circle
		(center 81.916778 -337.414362)
		(end 82.805778 -337.414362)
		(stroke
			(width 0.2)
			(type default)
		)
		(fill no)
		(layer "In14.Cu")
	)
	(gr_circle
		(center 81.942178 -338.176362)
		(end 82.831178 -338.176362)
		(stroke
			(width 0.2)
			(type default)
		)
		(fill no)
		(layer "In14.Cu")
	)
	(gr_circle
		(center 82.183986 -348.89948)
		(end 83.072986 -348.89948)
		(stroke
			(width 0.2)
			(type default)
		)
		(fill no)
		(layer "In14.Cu")
	)
	(gr_circle
		(center 82.222086 -350.393)
		(end 83.111086 -350.393)
		(stroke
			(width 0.2)
			(type default)
		)
		(fill no)
		(layer "In14.Cu")
	)
	(gr_circle
		(center 82.22234 -349.569786)
		(end 83.11134 -349.569786)
		(stroke
			(width 0.2)
			(type default)
		)
		(fill no)
		(layer "In14.Cu")
	)
	(gr_circle
		(center 82.232754 -348.191074)
		(end 83.121754 -348.191074)
		(stroke
			(width 0.2)
			(type default)
		)
		(fill no)
		(layer "In14.Cu")
	)
	(gr_circle
		(center 82.475578 -338.531962)
		(end 83.364578 -338.531962)
		(stroke
			(width 0.2)
			(type default)
		)
		(fill no)
		(layer "In14.Cu")
	)
	(gr_circle
		(center 82.475578 -337.795362)
		(end 83.364578 -337.795362)
		(stroke
			(width 0.2)
			(type default)
		)
		(fill no)
		(layer "In14.Cu")
	)
	(gr_circle
		(center 82.475578 -337.058762)
		(end 83.364578 -337.058762)
		(stroke
			(width 0.2)
			(type default)
		)
		(fill no)
		(layer "In14.Cu")
	)
	(gr_circle
		(center 82.989674 -165.962076)
		(end 84.386674 -165.962076)
		(stroke
			(width 0.2)
			(type default)
		)
		(fill no)
		(layer "In14.Cu")
	)
	(gr_line
		(start 83.70189 -11.780012)
		(end 124.102114 -11.780012)
		(stroke
			(width 1.016)
			(type default)
		)
		(layer "In14.Cu")
	)
	(gr_arc
		(start 84.20989 -7.78002)
		(mid 84.646886 -8.83502)
		(end 85.701886 -9.272016)
		(stroke
			(width 0.2)
			(type default)
		)
		(layer "In14.Cu")
	)
	(gr_arc
		(start 84.20989 0.40005)
		(mid 83.475332 2.173501)
		(end 81.701894 2.908046)
		(stroke
			(width 0.2)
			(type default)
		)
		(layer "In14.Cu")
	)
	(gr_line
		(start 84.20989 0.40005)
		(end 84.20989 -7.78002)
		(stroke
			(width 0.2)
			(type default)
		)
		(layer "In14.Cu")
	)
	(gr_circle
		(center 84.845652 -348.861126)
		(end 85.734652 -348.861126)
		(stroke
			(width 0.2)
			(type default)
		)
		(fill no)
		(layer "In14.Cu")
	)
	(gr_circle
		(center 84.884006 -350.239838)
		(end 85.773006 -350.239838)
		(stroke
			(width 0.2)
			(type default)
		)
		(fill no)
		(layer "In14.Cu")
	)
	(gr_circle
		(center 84.884006 -349.531432)
		(end 85.773006 -349.531432)
		(stroke
			(width 0.2)
			(type default)
		)
		(fill no)
		(layer "In14.Cu")
	)
	(gr_circle
		(center 84.89442 -348.15272)
		(end 85.78342 -348.15272)
		(stroke
			(width 0.2)
			(type default)
		)
		(fill no)
		(layer "In14.Cu")
	)
	(gr_line
		(start 85.701886 -9.272016)
		(end 122.102118 -9.272016)
		(stroke
			(width 0.2)
			(type default)
		)
		(layer "In14.Cu")
	)
	(gr_circle
		(center 86.97087 -180.610002)
		(end 87.85987 -180.610002)
		(stroke
			(width 0.2)
			(type default)
		)
		(fill no)
		(layer "In14.Cu")
	)
	(gr_circle
		(center 86.97087 -179.873402)
		(end 87.85987 -179.873402)
		(stroke
			(width 0.2)
			(type default)
		)
		(fill no)
		(layer "In14.Cu")
	)
	(gr_circle
		(center 86.97087 -179.136802)
		(end 87.85987 -179.136802)
		(stroke
			(width 0.2)
			(type default)
		)
		(fill no)
		(layer "In14.Cu")
	)
	(gr_circle
		(center 87.01913 -164.097716)
		(end 87.90813 -164.097716)
		(stroke
			(width 0.2)
			(type default)
		)
		(fill no)
		(layer "In14.Cu")
	)
	(gr_circle
		(center 87.03945 -163.447476)
		(end 87.92845 -163.447476)
		(stroke
			(width 0.2)
			(type default)
		)
		(fill no)
		(layer "In14.Cu")
	)
	(gr_circle
		(center 87.03945 -162.812476)
		(end 87.92845 -162.812476)
		(stroke
			(width 0.2)
			(type default)
		)
		(fill no)
		(layer "In14.Cu")
	)
	(gr_circle
		(center 87.50427 -179.492402)
		(end 88.39327 -179.492402)
		(stroke
			(width 0.2)
			(type default)
		)
		(fill no)
		(layer "In14.Cu")
	)
	(gr_circle
		(center 87.52967 -180.254402)
		(end 88.41867 -180.254402)
		(stroke
			(width 0.2)
			(type default)
		)
		(fill no)
		(layer "In14.Cu")
	)
	(gr_circle
		(center 87.65413 -164.097716)
		(end 88.54313 -164.097716)
		(stroke
			(width 0.2)
			(type default)
		)
		(fill no)
		(layer "In14.Cu")
	)
	(gr_circle
		(center 87.67445 -163.447476)
		(end 88.56345 -163.447476)
		(stroke
			(width 0.2)
			(type default)
		)
		(fill no)
		(layer "In14.Cu")
	)
	(gr_circle
		(center 87.67445 -162.812476)
		(end 88.56345 -162.812476)
		(stroke
			(width 0.2)
			(type default)
		)
		(fill no)
		(layer "In14.Cu")
	)
	(gr_circle
		(center 87.813134 -336.966814)
		(end 88.693244 -336.966814)
		(stroke
			(width 0.2)
			(type default)
		)
		(fill no)
		(layer "In14.Cu")
	)
	(gr_circle
		(center 88.054434 -179.814982)
		(end 88.943434 -179.814982)
		(stroke
			(width 0.2)
			(type default)
		)
		(fill no)
		(layer "In14.Cu")
	)
	(gr_circle
		(center 88.054434 -179.078382)
		(end 88.943434 -179.078382)
		(stroke
			(width 0.2)
			(type default)
		)
		(fill no)
		(layer "In14.Cu")
	)
	(gr_circle
		(center 88.28913 -164.097716)
		(end 89.17813 -164.097716)
		(stroke
			(width 0.2)
			(type default)
		)
		(fill no)
		(layer "In14.Cu")
	)
	(gr_circle
		(center 88.30945 -163.447476)
		(end 89.19845 -163.447476)
		(stroke
			(width 0.2)
			(type default)
		)
		(fill no)
		(layer "In14.Cu")
	)
	(gr_circle
		(center 88.30945 -162.812476)
		(end 89.19845 -162.812476)
		(stroke
			(width 0.2)
			(type default)
		)
		(fill no)
		(layer "In14.Cu")
	)
	(gr_circle
		(center 88.430354 -336.966814)
		(end 89.310464 -336.966814)
		(stroke
			(width 0.2)
			(type default)
		)
		(fill no)
		(layer "In14.Cu")
	)
	(gr_circle
		(center 88.49233 -182.13324)
		(end 89.38133 -182.13324)
		(stroke
			(width 0.2)
			(type default)
		)
		(fill no)
		(layer "In14.Cu")
	)
	(gr_circle
		(center 88.49233 -181.39664)
		(end 89.38133 -181.39664)
		(stroke
			(width 0.2)
			(type default)
		)
		(fill no)
		(layer "In14.Cu")
	)
	(gr_circle
		(center 88.75649 -180.687472)
		(end 89.6366 -180.687472)
		(stroke
			(width 0.2)
			(type default)
		)
		(fill no)
		(layer "In14.Cu")
	)
	(gr_circle
		(center 88.92413 -164.097716)
		(end 89.81313 -164.097716)
		(stroke
			(width 0.2)
			(type default)
		)
		(fill no)
		(layer "In14.Cu")
	)
	(gr_circle
		(center 88.94445 -163.447476)
		(end 89.83345 -163.447476)
		(stroke
			(width 0.2)
			(type default)
		)
		(fill no)
		(layer "In14.Cu")
	)
	(gr_circle
		(center 88.94445 -162.812476)
		(end 89.83345 -162.812476)
		(stroke
			(width 0.2)
			(type default)
		)
		(fill no)
		(layer "In14.Cu")
	)
	(gr_circle
		(center 89.047574 -336.966814)
		(end 89.927684 -336.966814)
		(stroke
			(width 0.2)
			(type default)
		)
		(fill no)
		(layer "In14.Cu")
	)
	(gr_circle
		(center 89.314528 -345.237562)
		(end 90.203528 -345.237562)
		(stroke
			(width 0.2)
			(type default)
		)
		(fill no)
		(layer "In14.Cu")
	)
	(gr_circle
		(center 89.319354 -336.255868)
		(end 90.199464 -336.255868)
		(stroke
			(width 0.2)
			(type default)
		)
		(fill no)
		(layer "In14.Cu")
	)
	(gr_circle
		(center 89.319354 -335.519268)
		(end 90.199464 -335.519268)
		(stroke
			(width 0.2)
			(type default)
		)
		(fill no)
		(layer "In14.Cu")
	)
	(gr_circle
		(center 89.350088 -345.96959)
		(end 90.239088 -345.96959)
		(stroke
			(width 0.2)
			(type default)
		)
		(fill no)
		(layer "In14.Cu")
	)
	(gr_circle
		(center 89.37371 -180.687472)
		(end 90.25382 -180.687472)
		(stroke
			(width 0.2)
			(type default)
		)
		(fill no)
		(layer "In14.Cu")
	)
	(gr_circle
		(center 89.388442 -346.639896)
		(end 90.277442 -346.639896)
		(stroke
			(width 0.2)
			(type default)
		)
		(fill no)
		(layer "In14.Cu")
	)
	(gr_circle
		(center 89.55913 -164.097716)
		(end 90.44813 -164.097716)
		(stroke
			(width 0.2)
			(type default)
		)
		(fill no)
		(layer "In14.Cu")
	)
	(gr_circle
		(center 89.57945 -163.447476)
		(end 90.46845 -163.447476)
		(stroke
			(width 0.2)
			(type default)
		)
		(fill no)
		(layer "In14.Cu")
	)
	(gr_circle
		(center 89.57945 -162.812476)
		(end 90.46845 -162.812476)
		(stroke
			(width 0.2)
			(type default)
		)
		(fill no)
		(layer "In14.Cu")
	)
	(gr_circle
		(center 89.74963 -338.575904)
		(end 90.63863 -338.575904)
		(stroke
			(width 0.2)
			(type default)
		)
		(fill no)
		(layer "In14.Cu")
	)
	(gr_circle
		(center 89.74963 -337.839304)
		(end 90.63863 -337.839304)
		(stroke
			(width 0.2)
			(type default)
		)
		(fill no)
		(layer "In14.Cu")
	)
	(gr_circle
		(center 89.983056 -345.261184)
		(end 90.872056 -345.261184)
		(stroke
			(width 0.2)
			(type default)
		)
		(fill no)
		(layer "In14.Cu")
	)
	(gr_circle
		(center 89.985088 -345.96959)
		(end 90.874088 -345.96959)
		(stroke
			(width 0.2)
			(type default)
		)
		(fill no)
		(layer "In14.Cu")
	)
	(gr_circle
		(center 89.99093 -180.687472)
		(end 90.87104 -180.687472)
		(stroke
			(width 0.2)
			(type default)
		)
		(fill no)
		(layer "In14.Cu")
	)
	(gr_circle
		(center 90.023442 -346.639896)
		(end 90.912442 -346.639896)
		(stroke
			(width 0.2)
			(type default)
		)
		(fill no)
		(layer "In14.Cu")
	)
	(gr_circle
		(center 90.21953 -164.107876)
		(end 91.10853 -164.107876)
		(stroke
			(width 0.2)
			(type default)
		)
		(fill no)
		(layer "In14.Cu")
	)
	(gr_circle
		(center 90.23985 -163.457636)
		(end 91.12885 -163.457636)
		(stroke
			(width 0.2)
			(type default)
		)
		(fill no)
		(layer "In14.Cu")
	)
	(gr_circle
		(center 90.23985 -162.822636)
		(end 91.12885 -162.822636)
		(stroke
			(width 0.2)
			(type default)
		)
		(fill no)
		(layer "In14.Cu")
	)
	(gr_circle
		(center 90.274394 -337.399884)
		(end 91.163394 -337.399884)
		(stroke
			(width 0.2)
			(type default)
		)
		(fill no)
		(layer "In14.Cu")
	)
	(gr_circle
		(center 90.299794 -338.161884)
		(end 91.188794 -338.161884)
		(stroke
			(width 0.2)
			(type default)
		)
		(fill no)
		(layer "In14.Cu")
	)
	(gr_circle
		(center 90.618056 -345.261184)
		(end 91.507056 -345.261184)
		(stroke
			(width 0.2)
			(type default)
		)
		(fill no)
		(layer "In14.Cu")
	)
	(gr_circle
		(center 90.620088 -345.96959)
		(end 91.509088 -345.96959)
		(stroke
			(width 0.2)
			(type default)
		)
		(fill no)
		(layer "In14.Cu")
	)
	(gr_circle
		(center 90.658442 -346.639896)
		(end 91.547442 -346.639896)
		(stroke
			(width 0.2)
			(type default)
		)
		(fill no)
		(layer "In14.Cu")
	)
	(gr_circle
		(center 90.833194 -338.517484)
		(end 91.722194 -338.517484)
		(stroke
			(width 0.2)
			(type default)
		)
		(fill no)
		(layer "In14.Cu")
	)
	(gr_circle
		(center 90.833194 -337.780884)
		(end 91.722194 -337.780884)
		(stroke
			(width 0.2)
			(type default)
		)
		(fill no)
		(layer "In14.Cu")
	)
	(gr_circle
		(center 90.833194 -337.044284)
		(end 91.722194 -337.044284)
		(stroke
			(width 0.2)
			(type default)
		)
		(fill no)
		(layer "In14.Cu")
	)
	(gr_circle
		(center 91.255088 -345.96959)
		(end 92.144088 -345.96959)
		(stroke
			(width 0.2)
			(type default)
		)
		(fill no)
		(layer "In14.Cu")
	)
	(gr_circle
		(center 91.293442 -346.639896)
		(end 92.182442 -346.639896)
		(stroke
			(width 0.2)
			(type default)
		)
		(fill no)
		(layer "In14.Cu")
	)
	(gr_circle
		(center 91.380056 -345.261184)
		(end 92.269056 -345.261184)
		(stroke
			(width 0.2)
			(type default)
		)
		(fill no)
		(layer "In14.Cu")
	)
	(gr_circle
		(center 91.966288 -345.96959)
		(end 92.855288 -345.96959)
		(stroke
			(width 0.2)
			(type default)
		)
		(fill no)
		(layer "In14.Cu")
	)
	(gr_circle
		(center 92.004642 -346.639896)
		(end 92.893642 -346.639896)
		(stroke
			(width 0.2)
			(type default)
		)
		(fill no)
		(layer "In14.Cu")
	)
	(gr_circle
		(center 92.015056 -345.261184)
		(end 92.904056 -345.261184)
		(stroke
			(width 0.2)
			(type default)
		)
		(fill no)
		(layer "In14.Cu")
	)
	(gr_circle
		(center 92.387674 -165.962076)
		(end 93.784674 -165.962076)
		(stroke
			(width 0.2)
			(type default)
		)
		(fill no)
		(layer "In14.Cu")
	)
	(gr_circle
		(center 92.601288 -345.96959)
		(end 93.490288 -345.96959)
		(stroke
			(width 0.2)
			(type default)
		)
		(fill no)
		(layer "In14.Cu")
	)
	(gr_circle
		(center 92.639642 -346.639896)
		(end 93.528642 -346.639896)
		(stroke
			(width 0.2)
			(type default)
		)
		(fill no)
		(layer "In14.Cu")
	)
	(gr_circle
		(center 92.650056 -345.261184)
		(end 93.539056 -345.261184)
		(stroke
			(width 0.2)
			(type default)
		)
		(fill no)
		(layer "In14.Cu")
	)
	(gr_circle
		(center 95.36303 -180.627274)
		(end 96.25203 -180.627274)
		(stroke
			(width 0.2)
			(type default)
		)
		(fill no)
		(layer "In14.Cu")
	)
	(gr_circle
		(center 95.36303 -179.890674)
		(end 96.25203 -179.890674)
		(stroke
			(width 0.2)
			(type default)
		)
		(fill no)
		(layer "In14.Cu")
	)
	(gr_circle
		(center 95.36303 -179.154074)
		(end 96.25203 -179.154074)
		(stroke
			(width 0.2)
			(type default)
		)
		(fill no)
		(layer "In14.Cu")
	)
	(gr_circle
		(center 95.89643 -179.509674)
		(end 96.78543 -179.509674)
		(stroke
			(width 0.2)
			(type default)
		)
		(fill no)
		(layer "In14.Cu")
	)
	(gr_circle
		(center 95.92183 -180.271674)
		(end 96.81083 -180.271674)
		(stroke
			(width 0.2)
			(type default)
		)
		(fill no)
		(layer "In14.Cu")
	)
	(gr_circle
		(center 96.144334 -337.017614)
		(end 97.024444 -337.017614)
		(stroke
			(width 0.2)
			(type default)
		)
		(fill no)
		(layer "In14.Cu")
	)
	(gr_circle
		(center 96.446594 -179.832254)
		(end 97.335594 -179.832254)
		(stroke
			(width 0.2)
			(type default)
		)
		(fill no)
		(layer "In14.Cu")
	)
	(gr_circle
		(center 96.446594 -179.095654)
		(end 97.335594 -179.095654)
		(stroke
			(width 0.2)
			(type default)
		)
		(fill no)
		(layer "In14.Cu")
	)
	(gr_circle
		(center 96.761554 -337.017614)
		(end 97.641664 -337.017614)
		(stroke
			(width 0.2)
			(type default)
		)
		(fill no)
		(layer "In14.Cu")
	)
	(gr_circle
		(center 96.980248 -182.13324)
		(end 97.869248 -182.13324)
		(stroke
			(width 0.2)
			(type default)
		)
		(fill no)
		(layer "In14.Cu")
	)
	(gr_circle
		(center 96.980248 -181.39664)
		(end 97.869248 -181.39664)
		(stroke
			(width 0.2)
			(type default)
		)
		(fill no)
		(layer "In14.Cu")
	)
	(gr_circle
		(center 97.14865 -180.704744)
		(end 98.02876 -180.704744)
		(stroke
			(width 0.2)
			(type default)
		)
		(fill no)
		(layer "In14.Cu")
	)
	(gr_circle
		(center 97.378774 -337.017614)
		(end 98.258884 -337.017614)
		(stroke
			(width 0.2)
			(type default)
		)
		(fill no)
		(layer "In14.Cu")
	)
	(gr_circle
		(center 97.658174 -336.319368)
		(end 98.538284 -336.319368)
		(stroke
			(width 0.2)
			(type default)
		)
		(fill no)
		(layer "In14.Cu")
	)
	(gr_circle
		(center 97.658174 -335.582768)
		(end 98.538284 -335.582768)
		(stroke
			(width 0.2)
			(type default)
		)
		(fill no)
		(layer "In14.Cu")
	)
	(gr_circle
		(center 97.76587 -180.704744)
		(end 98.64598 -180.704744)
		(stroke
			(width 0.2)
			(type default)
		)
		(fill no)
		(layer "In14.Cu")
	)
	(gr_circle
		(center 98.08083 -338.626704)
		(end 98.96983 -338.626704)
		(stroke
			(width 0.2)
			(type default)
		)
		(fill no)
		(layer "In14.Cu")
	)
	(gr_circle
		(center 98.08083 -337.890104)
		(end 98.96983 -337.890104)
		(stroke
			(width 0.2)
			(type default)
		)
		(fill no)
		(layer "In14.Cu")
	)
	(gr_circle
		(center 98.199194 -339.358224)
		(end 99.088194 -339.358224)
		(stroke
			(width 0.2)
			(type default)
		)
		(fill no)
		(layer "In14.Cu")
	)
	(gr_circle
		(center 98.38309 -180.704744)
		(end 99.2632 -180.704744)
		(stroke
			(width 0.2)
			(type default)
		)
		(fill no)
		(layer "In14.Cu")
	)
	(gr_circle
		(center 98.605594 -337.450684)
		(end 99.494594 -337.450684)
		(stroke
			(width 0.2)
			(type default)
		)
		(fill no)
		(layer "In14.Cu")
	)
	(gr_circle
		(center 98.630994 -338.212684)
		(end 99.519994 -338.212684)
		(stroke
			(width 0.2)
			(type default)
		)
		(fill no)
		(layer "In14.Cu")
	)
	(gr_circle
		(center 98.747834 -339.736684)
		(end 99.636834 -339.736684)
		(stroke
			(width 0.2)
			(type default)
		)
		(fill no)
		(layer "In14.Cu")
	)
	(gr_circle
		(center 98.747834 -338.974684)
		(end 99.636834 -338.974684)
		(stroke
			(width 0.2)
			(type default)
		)
		(fill no)
		(layer "In14.Cu")
	)
	(gr_circle
		(center 103.74503 -176.106074)
		(end 104.63403 -176.106074)
		(stroke
			(width 0.2)
			(type default)
		)
		(fill no)
		(layer "In14.Cu")
	)
	(gr_circle
		(center 103.74503 -175.369474)
		(end 104.63403 -175.369474)
		(stroke
			(width 0.2)
			(type default)
		)
		(fill no)
		(layer "In14.Cu")
	)
	(gr_circle
		(center 103.74503 -174.632874)
		(end 104.63403 -174.632874)
		(stroke
			(width 0.2)
			(type default)
		)
		(fill no)
		(layer "In14.Cu")
	)
	(gr_circle
		(center 104.27843 -174.988474)
		(end 105.16743 -174.988474)
		(stroke
			(width 0.2)
			(type default)
		)
		(fill no)
		(layer "In14.Cu")
	)
	(gr_circle
		(center 104.30383 -175.750474)
		(end 105.19283 -175.750474)
		(stroke
			(width 0.2)
			(type default)
		)
		(fill no)
		(layer "In14.Cu")
	)
	(gr_circle
		(center 104.420162 -341.927688)
		(end 105.300272 -341.927688)
		(stroke
			(width 0.2)
			(type default)
		)
		(fill no)
		(layer "In14.Cu")
	)
	(gr_circle
		(center 104.828594 -175.311054)
		(end 105.717594 -175.311054)
		(stroke
			(width 0.2)
			(type default)
		)
		(fill no)
		(layer "In14.Cu")
	)
	(gr_circle
		(center 104.828594 -174.574454)
		(end 105.717594 -174.574454)
		(stroke
			(width 0.2)
			(type default)
		)
		(fill no)
		(layer "In14.Cu")
	)
	(gr_circle
		(center 105.037382 -341.927688)
		(end 105.917492 -341.927688)
		(stroke
			(width 0.2)
			(type default)
		)
		(fill no)
		(layer "In14.Cu")
	)
	(gr_circle
		(center 105.336848 -177.65776)
		(end 106.225848 -177.65776)
		(stroke
			(width 0.2)
			(type default)
		)
		(fill no)
		(layer "In14.Cu")
	)
	(gr_circle
		(center 105.336848 -176.92116)
		(end 106.225848 -176.92116)
		(stroke
			(width 0.2)
			(type default)
		)
		(fill no)
		(layer "In14.Cu")
	)
	(gr_circle
		(center 105.53065 -176.183544)
		(end 106.41076 -176.183544)
		(stroke
			(width 0.2)
			(type default)
		)
		(fill no)
		(layer "In14.Cu")
	)
	(gr_circle
		(center 105.654602 -341.927688)
		(end 106.534712 -341.927688)
		(stroke
			(width 0.2)
			(type default)
		)
		(fill no)
		(layer "In14.Cu")
	)
	(gr_circle
		(center 105.934002 -341.229442)
		(end 106.814112 -341.229442)
		(stroke
			(width 0.2)
			(type default)
		)
		(fill no)
		(layer "In14.Cu")
	)
	(gr_circle
		(center 105.934002 -340.492842)
		(end 106.814112 -340.492842)
		(stroke
			(width 0.2)
			(type default)
		)
		(fill no)
		(layer "In14.Cu")
	)
	(gr_circle
		(center 106.14787 -176.183544)
		(end 107.02798 -176.183544)
		(stroke
			(width 0.2)
			(type default)
		)
		(fill no)
		(layer "In14.Cu")
	)
	(gr_circle
		(center 106.34345 -343.450164)
		(end 107.23245 -343.450164)
		(stroke
			(width 0.2)
			(type default)
		)
		(fill no)
		(layer "In14.Cu")
	)
	(gr_circle
		(center 106.34345 -342.713564)
		(end 107.23245 -342.713564)
		(stroke
			(width 0.2)
			(type default)
		)
		(fill no)
		(layer "In14.Cu")
	)
	(gr_circle
		(center 106.76509 -176.183544)
		(end 107.6452 -176.183544)
		(stroke
			(width 0.2)
			(type default)
		)
		(fill no)
		(layer "In14.Cu")
	)
	(gr_circle
		(center 106.98607 -342.540844)
		(end 107.87507 -342.540844)
		(stroke
			(width 0.2)
			(type default)
		)
		(fill no)
		(layer "In14.Cu")
	)
	(gr_circle
		(center 106.98607 -341.804244)
		(end 107.87507 -341.804244)
		(stroke
			(width 0.2)
			(type default)
		)
		(fill no)
		(layer "In14.Cu")
	)
	(gr_circle
		(center 107.01401 -343.986104)
		(end 107.90301 -343.986104)
		(stroke
			(width 0.2)
			(type default)
		)
		(fill no)
		(layer "In14.Cu")
	)
	(gr_circle
		(center 107.01401 -343.249504)
		(end 107.90301 -343.249504)
		(stroke
			(width 0.2)
			(type default)
		)
		(fill no)
		(layer "In14.Cu")
	)
	(gr_circle
		(center 110.140496 -150.941786)
		(end 111.537496 -150.941786)
		(stroke
			(width 0.2)
			(type default)
		)
		(fill no)
		(layer "In14.Cu")
	)
	(gr_circle
		(center 111.97463 -169.857674)
		(end 112.86363 -169.857674)
		(stroke
			(width 0.2)
			(type default)
		)
		(fill no)
		(layer "In14.Cu")
	)
	(gr_circle
		(center 111.97463 -169.121074)
		(end 112.86363 -169.121074)
		(stroke
			(width 0.2)
			(type default)
		)
		(fill no)
		(layer "In14.Cu")
	)
	(gr_circle
		(center 111.97463 -168.384474)
		(end 112.86363 -168.384474)
		(stroke
			(width 0.2)
			(type default)
		)
		(fill no)
		(layer "In14.Cu")
	)
	(gr_circle
		(center 112.50803 -168.740074)
		(end 113.39703 -168.740074)
		(stroke
			(width 0.2)
			(type default)
		)
		(fill no)
		(layer "In14.Cu")
	)
	(gr_circle
		(center 112.53343 -169.502074)
		(end 113.42243 -169.502074)
		(stroke
			(width 0.2)
			(type default)
		)
		(fill no)
		(layer "In14.Cu")
	)
	(gr_circle
		(center 113.058194 -169.062654)
		(end 113.947194 -169.062654)
		(stroke
			(width 0.2)
			(type default)
		)
		(fill no)
		(layer "In14.Cu")
	)
	(gr_circle
		(center 113.058194 -168.326054)
		(end 113.947194 -168.326054)
		(stroke
			(width 0.2)
			(type default)
		)
		(fill no)
		(layer "In14.Cu")
	)
	(gr_circle
		(center 113.591848 -171.33316)
		(end 114.480848 -171.33316)
		(stroke
			(width 0.2)
			(type default)
		)
		(fill no)
		(layer "In14.Cu")
	)
	(gr_circle
		(center 113.591848 -170.59656)
		(end 114.480848 -170.59656)
		(stroke
			(width 0.2)
			(type default)
		)
		(fill no)
		(layer "In14.Cu")
	)
	(gr_circle
		(center 113.76025 -169.935144)
		(end 114.64036 -169.935144)
		(stroke
			(width 0.2)
			(type default)
		)
		(fill no)
		(layer "In14.Cu")
	)
	(gr_circle
		(center 114.37747 -169.935144)
		(end 115.25758 -169.935144)
		(stroke
			(width 0.2)
			(type default)
		)
		(fill no)
		(layer "In14.Cu")
	)
	(gr_circle
		(center 114.99469 -169.935144)
		(end 115.8748 -169.935144)
		(stroke
			(width 0.2)
			(type default)
		)
		(fill no)
		(layer "In14.Cu")
	)
	(gr_circle
		(center 116.258594 -152.657556)
		(end 117.147594 -152.657556)
		(stroke
			(width 0.2)
			(type default)
		)
		(fill no)
		(layer "In14.Cu")
	)
	(gr_circle
		(center 116.258594 -152.022556)
		(end 117.147594 -152.022556)
		(stroke
			(width 0.2)
			(type default)
		)
		(fill no)
		(layer "In14.Cu")
	)
	(gr_circle
		(center 116.893594 -152.657556)
		(end 117.782594 -152.657556)
		(stroke
			(width 0.2)
			(type default)
		)
		(fill no)
		(layer "In14.Cu")
	)
	(gr_circle
		(center 116.893594 -152.022556)
		(end 117.782594 -152.022556)
		(stroke
			(width 0.2)
			(type default)
		)
		(fill no)
		(layer "In14.Cu")
	)
	(gr_circle
		(center 117.559074 -152.657556)
		(end 118.448074 -152.657556)
		(stroke
			(width 0.2)
			(type default)
		)
		(fill no)
		(layer "In14.Cu")
	)
	(gr_circle
		(center 117.559074 -152.022556)
		(end 118.448074 -152.022556)
		(stroke
			(width 0.2)
			(type default)
		)
		(fill no)
		(layer "In14.Cu")
	)
	(gr_circle
		(center 118.194074 -152.657556)
		(end 119.083074 -152.657556)
		(stroke
			(width 0.2)
			(type default)
		)
		(fill no)
		(layer "In14.Cu")
	)
	(gr_circle
		(center 118.194074 -152.022556)
		(end 119.083074 -152.022556)
		(stroke
			(width 0.2)
			(type default)
		)
		(fill no)
		(layer "In14.Cu")
	)
	(gr_circle
		(center 118.829074 -152.657556)
		(end 119.718074 -152.657556)
		(stroke
			(width 0.2)
			(type default)
		)
		(fill no)
		(layer "In14.Cu")
	)
	(gr_circle
		(center 118.829074 -152.022556)
		(end 119.718074 -152.022556)
		(stroke
			(width 0.2)
			(type default)
		)
		(fill no)
		(layer "In14.Cu")
	)
	(gr_circle
		(center 119.464074 -152.657556)
		(end 120.353074 -152.657556)
		(stroke
			(width 0.2)
			(type default)
		)
		(fill no)
		(layer "In14.Cu")
	)
	(gr_circle
		(center 119.464074 -152.022556)
		(end 120.353074 -152.022556)
		(stroke
			(width 0.2)
			(type default)
		)
		(fill no)
		(layer "In14.Cu")
	)
	(gr_circle
		(center 120.25503 -163.126674)
		(end 121.14403 -163.126674)
		(stroke
			(width 0.2)
			(type default)
		)
		(fill no)
		(layer "In14.Cu")
	)
	(gr_circle
		(center 120.25503 -162.390074)
		(end 121.14403 -162.390074)
		(stroke
			(width 0.2)
			(type default)
		)
		(fill no)
		(layer "In14.Cu")
	)
	(gr_circle
		(center 120.25503 -161.653474)
		(end 121.14403 -161.653474)
		(stroke
			(width 0.2)
			(type default)
		)
		(fill no)
		(layer "In14.Cu")
	)
	(gr_circle
		(center 120.78843 -162.009074)
		(end 121.67743 -162.009074)
		(stroke
			(width 0.2)
			(type default)
		)
		(fill no)
		(layer "In14.Cu")
	)
	(gr_circle
		(center 120.81383 -162.771074)
		(end 121.70283 -162.771074)
		(stroke
			(width 0.2)
			(type default)
		)
		(fill no)
		(layer "In14.Cu")
	)
	(gr_circle
		(center 121.338594 -162.331654)
		(end 122.227594 -162.331654)
		(stroke
			(width 0.2)
			(type default)
		)
		(fill no)
		(layer "In14.Cu")
	)
	(gr_circle
		(center 121.338594 -161.595054)
		(end 122.227594 -161.595054)
		(stroke
			(width 0.2)
			(type default)
		)
		(fill no)
		(layer "In14.Cu")
	)
	(gr_circle
		(center 121.872248 -164.62756)
		(end 122.761248 -164.62756)
		(stroke
			(width 0.2)
			(type default)
		)
		(fill no)
		(layer "In14.Cu")
	)
	(gr_circle
		(center 121.872248 -163.89096)
		(end 122.761248 -163.89096)
		(stroke
			(width 0.2)
			(type default)
		)
		(fill no)
		(layer "In14.Cu")
	)
	(gr_circle
		(center 122.04065 -163.204144)
		(end 122.92076 -163.204144)
		(stroke
			(width 0.2)
			(type default)
		)
		(fill no)
		(layer "In14.Cu")
	)
	(gr_arc
		(start 122.102118 -9.272016)
		(mid 123.157118 -8.83502)
		(end 123.594114 -7.78002)
		(stroke
			(width 0.2)
			(type default)
		)
		(layer "In14.Cu")
	)
	(gr_circle
		(center 122.65787 -163.204144)
		(end 123.53798 -163.204144)
		(stroke
			(width 0.2)
			(type default)
		)
		(fill no)
		(layer "In14.Cu")
	)
	(gr_circle
		(center 123.27509 -163.204144)
		(end 124.1552 -163.204144)
		(stroke
			(width 0.2)
			(type default)
		)
		(fill no)
		(layer "In14.Cu")
	)
	(gr_line
		(start 123.594114 -7.78002)
		(end 123.594114 -4.879848)
		(stroke
			(width 0.2)
			(type default)
		)
		(layer "In14.Cu")
	)
	(gr_line
		(start 124.102114 -12.288012)
		(end 83.70189 -12.288012)
		(stroke
			(width 0.2)
			(type default)
		)
		(layer "In14.Cu")
	)
	(gr_arc
		(start 124.102114 -12.288012)
		(mid 125.875532 -11.553433)
		(end 126.61011 -9.780016)
		(stroke
			(width 0.2)
			(type default)
		)
		(layer "In14.Cu")
	)
	(gr_arc
		(start 124.102114 -11.780012)
		(mid 125.516325 -11.194227)
		(end 126.10211 -9.780016)
		(stroke
			(width 1.016)
			(type default)
		)
		(layer "In14.Cu")
	)
	(gr_line
		(start 126.10211 -9.780016)
		(end 126.10211 -5.780024)
		(stroke
			(width 1.016)
			(type default)
		)
		(layer "In14.Cu")
	)
	(gr_arc
		(start 126.10211 -2.371852)
		(mid 124.3287 -3.106426)
		(end 123.594114 -4.879848)
		(stroke
			(width 0.2)
			(type default)
		)
		(layer "In14.Cu")
	)
	(gr_line
		(start 126.10211 -2.371852)
		(end 194.701922 -2.371852)
		(stroke
			(width 0.2)
			(type default)
		)
		(layer "In14.Cu")
	)
	(gr_arc
		(start 126.601982 -5.279898)
		(mid 126.248489 -5.42646)
		(end 126.10211 -5.780024)
		(stroke
			(width 1.016)
			(type default)
		)
		(layer "In14.Cu")
	)
	(gr_line
		(start 126.601982 -5.279898)
		(end 194.20205 -5.279898)
		(stroke
			(width 1.016)
			(type default)
		)
		(layer "In14.Cu")
	)
	(gr_line
		(start 126.61011 -5.787898)
		(end 126.61011 -9.780016)
		(stroke
			(width 0.2)
			(type default)
		)
		(layer "In14.Cu")
	)
	(gr_circle
		(center 128.71323 -154.465274)
		(end 129.60223 -154.465274)
		(stroke
			(width 0.2)
			(type default)
		)
		(fill no)
		(layer "In14.Cu")
	)
	(gr_circle
		(center 128.71323 -153.728674)
		(end 129.60223 -153.728674)
		(stroke
			(width 0.2)
			(type default)
		)
		(fill no)
		(layer "In14.Cu")
	)
	(gr_circle
		(center 128.71323 -152.992074)
		(end 129.60223 -152.992074)
		(stroke
			(width 0.2)
			(type default)
		)
		(fill no)
		(layer "In14.Cu")
	)
	(gr_circle
		(center 129.24663 -153.347674)
		(end 130.13563 -153.347674)
		(stroke
			(width 0.2)
			(type default)
		)
		(fill no)
		(layer "In14.Cu")
	)
	(gr_circle
		(center 129.27203 -154.109674)
		(end 130.16103 -154.109674)
		(stroke
			(width 0.2)
			(type default)
		)
		(fill no)
		(layer "In14.Cu")
	)
	(gr_circle
		(center 129.796794 -153.670254)
		(end 130.685794 -153.670254)
		(stroke
			(width 0.2)
			(type default)
		)
		(fill no)
		(layer "In14.Cu")
	)
	(gr_circle
		(center 129.796794 -152.933654)
		(end 130.685794 -152.933654)
		(stroke
			(width 0.2)
			(type default)
		)
		(fill no)
		(layer "In14.Cu")
	)
	(gr_circle
		(center 130.305048 -155.94076)
		(end 131.194048 -155.94076)
		(stroke
			(width 0.2)
			(type default)
		)
		(fill no)
		(layer "In14.Cu")
	)
	(gr_circle
		(center 130.305048 -155.20416)
		(end 131.194048 -155.20416)
		(stroke
			(width 0.2)
			(type default)
		)
		(fill no)
		(layer "In14.Cu")
	)
	(gr_circle
		(center 130.49885 -154.542744)
		(end 131.37896 -154.542744)
		(stroke
			(width 0.2)
			(type default)
		)
		(fill no)
		(layer "In14.Cu")
	)
	(gr_circle
		(center 131.11607 -154.542744)
		(end 131.99618 -154.542744)
		(stroke
			(width 0.2)
			(type default)
		)
		(fill no)
		(layer "In14.Cu")
	)
	(gr_circle
		(center 131.73329 -154.542744)
		(end 132.6134 -154.542744)
		(stroke
			(width 0.2)
			(type default)
		)
		(fill no)
		(layer "In14.Cu")
	)
	(gr_circle
		(center 176.332134 -26.634948)
		(end 177.221134 -26.634948)
		(stroke
			(width 0.2)
			(type default)
		)
		(fill no)
		(layer "In14.Cu")
	)
	(gr_circle
		(center 176.713134 -25.949148)
		(end 177.602134 -25.949148)
		(stroke
			(width 0.2)
			(type default)
		)
		(fill no)
		(layer "In14.Cu")
	)
	(gr_circle
		(center 176.878234 -19.942048)
		(end 177.767234 -19.942048)
		(stroke
			(width 0.2)
			(type default)
		)
		(fill no)
		(layer "In14.Cu")
	)
	(gr_circle
		(center 176.968912 -21.349208)
		(end 177.857912 -21.349208)
		(stroke
			(width 0.2)
			(type default)
		)
		(fill no)
		(layer "In14.Cu")
	)
	(gr_circle
		(center 176.968912 -20.714208)
		(end 177.857912 -20.714208)
		(stroke
			(width 0.2)
			(type default)
		)
		(fill no)
		(layer "In14.Cu")
	)
	(gr_circle
		(center 177.221134 -26.634948)
		(end 178.110134 -26.634948)
		(stroke
			(width 0.2)
			(type default)
		)
		(fill no)
		(layer "In14.Cu")
	)
	(gr_circle
		(center 177.472594 -21.85289)
		(end 178.361594 -21.85289)
		(stroke
			(width 0.2)
			(type default)
		)
		(fill no)
		(layer "In14.Cu")
	)
	(gr_circle
		(center 177.602134 -25.949148)
		(end 178.491134 -25.949148)
		(stroke
			(width 0.2)
			(type default)
		)
		(fill no)
		(layer "In14.Cu")
	)
	(gr_circle
		(center 178.110134 -26.634948)
		(end 178.999134 -26.634948)
		(stroke
			(width 0.2)
			(type default)
		)
		(fill no)
		(layer "In14.Cu")
	)
	(gr_circle
		(center 178.491134 -25.949148)
		(end 179.380134 -25.949148)
		(stroke
			(width 0.2)
			(type default)
		)
		(fill no)
		(layer "In14.Cu")
	)
	(gr_circle
		(center 179.507134 -25.517348)
		(end 180.396134 -25.517348)
		(stroke
			(width 0.2)
			(type default)
		)
		(fill no)
		(layer "In14.Cu")
	)
	(gr_circle
		(center 180.921914 -27.107388)
		(end 181.810914 -27.107388)
		(stroke
			(width 0.2)
			(type default)
		)
		(fill no)
		(layer "In14.Cu")
	)
	(gr_circle
		(center 183.610758 -353.283774)
		(end 184.490868 -353.283774)
		(stroke
			(width 0.2)
			(type default)
		)
		(fill no)
		(layer "In14.Cu")
	)
	(gr_circle
		(center 184.227978 -353.283774)
		(end 185.108088 -353.283774)
		(stroke
			(width 0.2)
			(type default)
		)
		(fill no)
		(layer "In14.Cu")
	)
	(gr_circle
		(center 184.845198 -353.283774)
		(end 185.725308 -353.283774)
		(stroke
			(width 0.2)
			(type default)
		)
		(fill no)
		(layer "In14.Cu")
	)
	(gr_circle
		(center 184.85612 -403.222714)
		(end 185.74512 -403.222714)
		(stroke
			(width 0.2)
			(type default)
		)
		(fill no)
		(layer "In14.Cu")
	)
	(gr_circle
		(center 184.85612 -401.919694)
		(end 185.74512 -401.919694)
		(stroke
			(width 0.2)
			(type default)
		)
		(fill no)
		(layer "In14.Cu")
	)
	(gr_circle
		(center 184.85612 -400.616674)
		(end 185.74512 -400.616674)
		(stroke
			(width 0.2)
			(type default)
		)
		(fill no)
		(layer "In14.Cu")
	)
	(gr_circle
		(center 184.962292 -352.558604)
		(end 185.851292 -352.558604)
		(stroke
			(width 0.2)
			(type default)
		)
		(fill no)
		(layer "In14.Cu")
	)
	(gr_circle
		(center 184.962292 -351.822004)
		(end 185.851292 -351.822004)
		(stroke
			(width 0.2)
			(type default)
		)
		(fill no)
		(layer "In14.Cu")
	)
	(gr_circle
		(center 185.547254 -354.892864)
		(end 186.436254 -354.892864)
		(stroke
			(width 0.2)
			(type default)
		)
		(fill no)
		(layer "In14.Cu")
	)
	(gr_circle
		(center 185.547254 -354.156264)
		(end 186.436254 -354.156264)
		(stroke
			(width 0.2)
			(type default)
		)
		(fill no)
		(layer "In14.Cu")
	)
	(gr_circle
		(center 185.673492 -408.092402)
		(end 186.562492 -408.092402)
		(stroke
			(width 0.2)
			(type default)
		)
		(fill no)
		(layer "In14.Cu")
	)
	(gr_circle
		(center 185.673492 -407.330402)
		(end 186.562492 -407.330402)
		(stroke
			(width 0.2)
			(type default)
		)
		(fill no)
		(layer "In14.Cu")
	)
	(gr_circle
		(center 185.673492 -406.517602)
		(end 186.562492 -406.517602)
		(stroke
			(width 0.2)
			(type default)
		)
		(fill no)
		(layer "In14.Cu")
	)
	(gr_circle
		(center 185.673492 -405.755602)
		(end 186.562492 -405.755602)
		(stroke
			(width 0.2)
			(type default)
		)
		(fill no)
		(layer "In14.Cu")
	)
	(gr_circle
		(center 185.673492 -404.993602)
		(end 186.562492 -404.993602)
		(stroke
			(width 0.2)
			(type default)
		)
		(fill no)
		(layer "In14.Cu")
	)
	(gr_circle
		(center 186.034172 -362.234988)
		(end 186.923172 -362.234988)
		(stroke
			(width 0.2)
			(type default)
		)
		(fill no)
		(layer "In14.Cu")
	)
	(gr_circle
		(center 186.034172 -361.472988)
		(end 186.923172 -361.472988)
		(stroke
			(width 0.2)
			(type default)
		)
		(fill no)
		(layer "In14.Cu")
	)
	(gr_circle
		(center 186.034172 -360.710988)
		(end 186.923172 -360.710988)
		(stroke
			(width 0.2)
			(type default)
		)
		(fill no)
		(layer "In14.Cu")
	)
	(gr_circle
		(center 186.072018 -353.716844)
		(end 186.961018 -353.716844)
		(stroke
			(width 0.2)
			(type default)
		)
		(fill no)
		(layer "In14.Cu")
	)
	(gr_circle
		(center 186.097418 -354.478844)
		(end 186.986418 -354.478844)
		(stroke
			(width 0.2)
			(type default)
		)
		(fill no)
		(layer "In14.Cu")
	)
	(gr_circle
		(center 186.27852 -403.222714)
		(end 187.16752 -403.222714)
		(stroke
			(width 0.2)
			(type default)
		)
		(fill no)
		(layer "In14.Cu")
	)
	(gr_circle
		(center 186.27852 -400.616674)
		(end 187.16752 -400.616674)
		(stroke
			(width 0.2)
			(type default)
		)
		(fill no)
		(layer "In14.Cu")
	)
	(gr_circle
		(center 186.435492 -408.092402)
		(end 187.324492 -408.092402)
		(stroke
			(width 0.2)
			(type default)
		)
		(fill no)
		(layer "In14.Cu")
	)
	(gr_circle
		(center 186.435492 -407.330402)
		(end 187.324492 -407.330402)
		(stroke
			(width 0.2)
			(type default)
		)
		(fill no)
		(layer "In14.Cu")
	)
	(gr_circle
		(center 186.435492 -406.517602)
		(end 187.324492 -406.517602)
		(stroke
			(width 0.2)
			(type default)
		)
		(fill no)
		(layer "In14.Cu")
	)
	(gr_circle
		(center 186.435492 -405.755602)
		(end 187.324492 -405.755602)
		(stroke
			(width 0.2)
			(type default)
		)
		(fill no)
		(layer "In14.Cu")
	)
	(gr_circle
		(center 186.435492 -404.993602)
		(end 187.324492 -404.993602)
		(stroke
			(width 0.2)
			(type default)
		)
		(fill no)
		(layer "In14.Cu")
	)
	(gr_circle
		(center 186.630818 -354.834444)
		(end 187.519818 -354.834444)
		(stroke
			(width 0.2)
			(type default)
		)
		(fill no)
		(layer "In14.Cu")
	)
	(gr_circle
		(center 186.630818 -354.097844)
		(end 187.519818 -354.097844)
		(stroke
			(width 0.2)
			(type default)
		)
		(fill no)
		(layer "In14.Cu")
	)
	(gr_circle
		(center 186.630818 -353.361244)
		(end 187.519818 -353.361244)
		(stroke
			(width 0.2)
			(type default)
		)
		(fill no)
		(layer "In14.Cu")
	)
	(gr_circle
		(center 186.796172 -362.234988)
		(end 187.685172 -362.234988)
		(stroke
			(width 0.2)
			(type default)
		)
		(fill no)
		(layer "In14.Cu")
	)
	(gr_circle
		(center 186.796172 -361.472988)
		(end 187.685172 -361.472988)
		(stroke
			(width 0.2)
			(type default)
		)
		(fill no)
		(layer "In14.Cu")
	)
	(gr_circle
		(center 186.796172 -360.710988)
		(end 187.685172 -360.710988)
		(stroke
			(width 0.2)
			(type default)
		)
		(fill no)
		(layer "In14.Cu")
	)
	(gr_circle
		(center 187.197492 -408.092402)
		(end 188.086492 -408.092402)
		(stroke
			(width 0.2)
			(type default)
		)
		(fill no)
		(layer "In14.Cu")
	)
	(gr_circle
		(center 187.197492 -407.330402)
		(end 188.086492 -407.330402)
		(stroke
			(width 0.2)
			(type default)
		)
		(fill no)
		(layer "In14.Cu")
	)
	(gr_circle
		(center 187.197492 -406.517602)
		(end 188.086492 -406.517602)
		(stroke
			(width 0.2)
			(type default)
		)
		(fill no)
		(layer "In14.Cu")
	)
	(gr_circle
		(center 187.197492 -405.755602)
		(end 188.086492 -405.755602)
		(stroke
			(width 0.2)
			(type default)
		)
		(fill no)
		(layer "In14.Cu")
	)
	(gr_circle
		(center 187.197492 -404.993602)
		(end 188.086492 -404.993602)
		(stroke
			(width 0.2)
			(type default)
		)
		(fill no)
		(layer "In14.Cu")
	)
	(gr_circle
		(center 187.67552 -403.222714)
		(end 188.56452 -403.222714)
		(stroke
			(width 0.2)
			(type default)
		)
		(fill no)
		(layer "In14.Cu")
	)
	(gr_circle
		(center 187.67552 -401.919694)
		(end 188.56452 -401.919694)
		(stroke
			(width 0.2)
			(type default)
		)
		(fill no)
		(layer "In14.Cu")
	)
	(gr_circle
		(center 187.67552 -400.616674)
		(end 188.56452 -400.616674)
		(stroke
			(width 0.2)
			(type default)
		)
		(fill no)
		(layer "In14.Cu")
	)
	(gr_circle
		(center 187.959492 -408.092402)
		(end 188.848492 -408.092402)
		(stroke
			(width 0.2)
			(type default)
		)
		(fill no)
		(layer "In14.Cu")
	)
	(gr_circle
		(center 187.959492 -407.330402)
		(end 188.848492 -407.330402)
		(stroke
			(width 0.2)
			(type default)
		)
		(fill no)
		(layer "In14.Cu")
	)
	(gr_circle
		(center 187.959492 -406.517602)
		(end 188.848492 -406.517602)
		(stroke
			(width 0.2)
			(type default)
		)
		(fill no)
		(layer "In14.Cu")
	)
	(gr_circle
		(center 187.959492 -405.755602)
		(end 188.848492 -405.755602)
		(stroke
			(width 0.2)
			(type default)
		)
		(fill no)
		(layer "In14.Cu")
	)
	(gr_circle
		(center 187.959492 -404.993602)
		(end 188.848492 -404.993602)
		(stroke
			(width 0.2)
			(type default)
		)
		(fill no)
		(layer "In14.Cu")
	)
	(gr_circle
		(center 188.721492 -408.092402)
		(end 189.610492 -408.092402)
		(stroke
			(width 0.2)
			(type default)
		)
		(fill no)
		(layer "In14.Cu")
	)
	(gr_circle
		(center 188.721492 -407.330402)
		(end 189.610492 -407.330402)
		(stroke
			(width 0.2)
			(type default)
		)
		(fill no)
		(layer "In14.Cu")
	)
	(gr_circle
		(center 188.721492 -406.517602)
		(end 189.610492 -406.517602)
		(stroke
			(width 0.2)
			(type default)
		)
		(fill no)
		(layer "In14.Cu")
	)
	(gr_circle
		(center 188.721492 -405.755602)
		(end 189.610492 -405.755602)
		(stroke
			(width 0.2)
			(type default)
		)
		(fill no)
		(layer "In14.Cu")
	)
	(gr_circle
		(center 188.721492 -404.993602)
		(end 189.610492 -404.993602)
		(stroke
			(width 0.2)
			(type default)
		)
		(fill no)
		(layer "In14.Cu")
	)
	(gr_circle
		(center 189.483492 -408.092402)
		(end 190.372492 -408.092402)
		(stroke
			(width 0.2)
			(type default)
		)
		(fill no)
		(layer "In14.Cu")
	)
	(gr_circle
		(center 189.483492 -407.330402)
		(end 190.372492 -407.330402)
		(stroke
			(width 0.2)
			(type default)
		)
		(fill no)
		(layer "In14.Cu")
	)
	(gr_circle
		(center 189.483492 -406.517602)
		(end 190.372492 -406.517602)
		(stroke
			(width 0.2)
			(type default)
		)
		(fill no)
		(layer "In14.Cu")
	)
	(gr_circle
		(center 189.483492 -405.755602)
		(end 190.372492 -405.755602)
		(stroke
			(width 0.2)
			(type default)
		)
		(fill no)
		(layer "In14.Cu")
	)
	(gr_circle
		(center 189.483492 -404.993602)
		(end 190.372492 -404.993602)
		(stroke
			(width 0.2)
			(type default)
		)
		(fill no)
		(layer "In14.Cu")
	)
	(gr_circle
		(center 190.508636 -23.593552)
		(end 191.397636 -23.593552)
		(stroke
			(width 0.2)
			(type default)
		)
		(fill no)
		(layer "In14.Cu")
	)
	(gr_circle
		(center 190.508636 -22.856952)
		(end 191.397636 -22.856952)
		(stroke
			(width 0.2)
			(type default)
		)
		(fill no)
		(layer "In14.Cu")
	)
	(gr_circle
		(center 191.67983 -362.430568)
		(end 193.07683 -362.430568)
		(stroke
			(width 0.2)
			(type default)
		)
		(fill no)
		(layer "In14.Cu")
	)
	(gr_circle
		(center 191.927734 -13.106908)
		(end 192.816734 -13.106908)
		(stroke
			(width 0.2)
			(type default)
		)
		(fill no)
		(layer "In14.Cu")
	)
	(gr_circle
		(center 191.937386 -353.309174)
		(end 192.817496 -353.309174)
		(stroke
			(width 0.2)
			(type default)
		)
		(fill no)
		(layer "In14.Cu")
	)
	(gr_circle
		(center 192.461134 -16.416528)
		(end 193.350134 -16.416528)
		(stroke
			(width 0.2)
			(type default)
		)
		(fill no)
		(layer "In14.Cu")
	)
	(gr_circle
		(center 192.461134 -15.781528)
		(end 193.350134 -15.781528)
		(stroke
			(width 0.2)
			(type default)
		)
		(fill no)
		(layer "In14.Cu")
	)
	(gr_circle
		(center 192.554606 -353.309174)
		(end 193.434716 -353.309174)
		(stroke
			(width 0.2)
			(type default)
		)
		(fill no)
		(layer "In14.Cu")
	)
	(gr_circle
		(center 192.689734 -13.106908)
		(end 193.578734 -13.106908)
		(stroke
			(width 0.2)
			(type default)
		)
		(fill no)
		(layer "In14.Cu")
	)
	(gr_circle
		(center 193.096134 -16.416528)
		(end 193.985134 -16.416528)
		(stroke
			(width 0.2)
			(type default)
		)
		(fill no)
		(layer "In14.Cu")
	)
	(gr_circle
		(center 193.096134 -15.781528)
		(end 193.985134 -15.781528)
		(stroke
			(width 0.2)
			(type default)
		)
		(fill no)
		(layer "In14.Cu")
	)
	(gr_circle
		(center 193.171826 -353.309174)
		(end 194.051936 -353.309174)
		(stroke
			(width 0.2)
			(type default)
		)
		(fill no)
		(layer "In14.Cu")
	)
	(gr_circle
		(center 193.28892 -352.563684)
		(end 194.17792 -352.563684)
		(stroke
			(width 0.2)
			(type default)
		)
		(fill no)
		(layer "In14.Cu")
	)
	(gr_circle
		(center 193.28892 -351.827084)
		(end 194.17792 -351.827084)
		(stroke
			(width 0.2)
			(type default)
		)
		(fill no)
		(layer "In14.Cu")
	)
	(gr_circle
		(center 193.731134 -15.781528)
		(end 194.620134 -15.781528)
		(stroke
			(width 0.2)
			(type default)
		)
		(fill no)
		(layer "In14.Cu")
	)
	(gr_circle
		(center 193.858134 -16.543528)
		(end 194.747134 -16.543528)
		(stroke
			(width 0.2)
			(type default)
		)
		(fill no)
		(layer "In14.Cu")
	)
	(gr_circle
		(center 193.873882 -354.918264)
		(end 194.762882 -354.918264)
		(stroke
			(width 0.2)
			(type default)
		)
		(fill no)
		(layer "In14.Cu")
	)
	(gr_circle
		(center 193.873882 -354.181664)
		(end 194.762882 -354.181664)
		(stroke
			(width 0.2)
			(type default)
		)
		(fill no)
		(layer "In14.Cu")
	)
	(gr_line
		(start 194.193922 -9.780016)
		(end 194.193922 -5.787898)
		(stroke
			(width 0.2)
			(type default)
		)
		(layer "In14.Cu")
	)
	(gr_arc
		(start 194.193922 -9.780016)
		(mid 194.928504 -11.55342)
		(end 196.701918 -12.288012)
		(stroke
			(width 0.2)
			(type default)
		)
		(layer "In14.Cu")
	)
	(gr_line
		(start 194.193922 -5.787898)
		(end 126.61011 -5.787898)
		(stroke
			(width 0.2)
			(type default)
		)
		(layer "In14.Cu")
	)
	(gr_circle
		(center 194.398646 -353.742244)
		(end 195.287646 -353.742244)
		(stroke
			(width 0.2)
			(type default)
		)
		(fill no)
		(layer "In14.Cu")
	)
	(gr_circle
		(center 194.424046 -354.504244)
		(end 195.313046 -354.504244)
		(stroke
			(width 0.2)
			(type default)
		)
		(fill no)
		(layer "In14.Cu")
	)
	(gr_line
		(start 194.496944 -441.481972)
		(end 194.496944 -441.17006)
		(stroke
			(width 0.2)
			(type default)
		)
		(layer "In14.Cu")
	)
	(gr_line
		(start 194.505072 -441.989972)
		(end 8.50011 -441.989972)
		(stroke
			(width 1.016)
			(type default)
		)
		(layer "In14.Cu")
	)
	(gr_arc
		(start 194.505072 -441.989972)
		(mid 194.858553 -441.843573)
		(end 195.004944 -441.4901)
		(stroke
			(width 1.016)
			(type default)
		)
		(layer "In14.Cu")
	)
	(gr_arc
		(start 194.701922 -9.780016)
		(mid 195.287707 -11.194227)
		(end 196.701918 -11.780012)
		(stroke
			(width 1.016)
			(type default)
		)
		(layer "In14.Cu")
	)
	(gr_arc
		(start 194.701922 -5.780024)
		(mid 194.555654 -5.42634)
		(end 194.20205 -5.279898)
		(stroke
			(width 1.016)
			(type default)
		)
		(layer "In14.Cu")
	)
	(gr_line
		(start 194.701922 -5.780024)
		(end 194.701922 -9.780016)
		(stroke
			(width 1.016)
			(type default)
		)
		(layer "In14.Cu")
	)
	(gr_line
		(start 194.9069 -420.700454)
		(end 194.9069 -413.816038)
		(stroke
			(width 0.635)
			(type default)
		)
		(layer "In14.Cu")
	)
	(gr_arc
		(start 194.9069 -420.700454)
		(mid 194.935087 -420.841508)
		(end 195.015104 -420.961058)
		(stroke
			(width 0.635)
			(type default)
		)
		(layer "In14.Cu")
	)
	(gr_line
		(start 194.9069 -413.816038)
		(end 195.7959 -412.927038)
		(stroke
			(width 0.635)
			(type default)
		)
		(layer "In14.Cu")
	)
	(gr_circle
		(center 194.957446 -354.859844)
		(end 195.846446 -354.859844)
		(stroke
			(width 0.2)
			(type default)
		)
		(fill no)
		(layer "In14.Cu")
	)
	(gr_circle
		(center 194.957446 -354.123244)
		(end 195.846446 -354.123244)
		(stroke
			(width 0.2)
			(type default)
		)
		(fill no)
		(layer "In14.Cu")
	)
	(gr_circle
		(center 194.957446 -353.386644)
		(end 195.846446 -353.386644)
		(stroke
			(width 0.2)
			(type default)
		)
		(fill no)
		(layer "In14.Cu")
	)
	(gr_line
		(start 195.004944 -441.17006)
		(end 195.004944 -441.4901)
		(stroke
			(width 1.016)
			(type default)
		)
		(layer "In14.Cu")
	)
	(gr_line
		(start 195.015104 -420.961058)
		(end 205.73746 -431.683414)
		(stroke
			(width 0.635)
			(type default)
		)
		(layer "In14.Cu")
	)
	(gr_arc
		(start 195.50507 -440.669934)
		(mid 195.151428 -440.816418)
		(end 195.004944 -441.17006)
		(stroke
			(width 1.016)
			(type default)
		)
		(layer "In14.Cu")
	)
	(gr_arc
		(start 195.50507 -440.161934)
		(mid 194.792223 -440.457215)
		(end 194.496944 -441.17006)
		(stroke
			(width 0.2)
			(type default)
		)
		(layer "In14.Cu")
	)
	(gr_line
		(start 195.50507 -440.161934)
		(end 276.314916 -440.161934)
		(stroke
			(width 0.2)
			(type default)
		)
		(layer "In14.Cu")
	)
	(gr_line
		(start 195.7959 -412.927038)
		(end 226.929188 -412.927038)
		(stroke
			(width 0.635)
			(type default)
		)
		(layer "In14.Cu")
	)
	(gr_line
		(start 196.701918 -11.780012)
		(end 221.30004 -11.780012)
		(stroke
			(width 1.016)
			(type default)
		)
		(layer "In14.Cu")
	)
	(gr_arc
		(start 197.209918 -7.78002)
		(mid 197.646914 -8.83502)
		(end 198.701914 -9.272016)
		(stroke
			(width 0.2)
			(type default)
		)
		(layer "In14.Cu")
	)
	(gr_arc
		(start 197.209918 -4.879848)
		(mid 196.475361 -3.106388)
		(end 194.701922 -2.371852)
		(stroke
			(width 0.2)
			(type default)
		)
		(layer "In14.Cu")
	)
	(gr_line
		(start 197.209918 -4.879848)
		(end 197.209918 -7.78002)
		(stroke
			(width 0.2)
			(type default)
		)
		(layer "In14.Cu")
	)
	(gr_circle
		(center 197.2437 -408.059382)
		(end 198.1327 -408.059382)
		(stroke
			(width 0.2)
			(type default)
		)
		(fill no)
		(layer "In14.Cu")
	)
	(gr_circle
		(center 197.2437 -407.297382)
		(end 198.1327 -407.297382)
		(stroke
			(width 0.2)
			(type default)
		)
		(fill no)
		(layer "In14.Cu")
	)
	(gr_circle
		(center 197.2437 -406.535382)
		(end 198.1327 -406.535382)
		(stroke
			(width 0.2)
			(type default)
		)
		(fill no)
		(layer "In14.Cu")
	)
	(gr_circle
		(center 197.2437 -405.773382)
		(end 198.1327 -405.773382)
		(stroke
			(width 0.2)
			(type default)
		)
		(fill no)
		(layer "In14.Cu")
	)
	(gr_circle
		(center 197.2437 -405.011382)
		(end 198.1327 -405.011382)
		(stroke
			(width 0.2)
			(type default)
		)
		(fill no)
		(layer "In14.Cu")
	)
	(gr_circle
		(center 198.0057 -408.059382)
		(end 198.8947 -408.059382)
		(stroke
			(width 0.2)
			(type default)
		)
		(fill no)
		(layer "In14.Cu")
	)
	(gr_circle
		(center 198.0057 -407.297382)
		(end 198.8947 -407.297382)
		(stroke
			(width 0.2)
			(type default)
		)
		(fill no)
		(layer "In14.Cu")
	)
	(gr_circle
		(center 198.0057 -406.535382)
		(end 198.8947 -406.535382)
		(stroke
			(width 0.2)
			(type default)
		)
		(fill no)
		(layer "In14.Cu")
	)
	(gr_circle
		(center 198.0057 -405.773382)
		(end 198.8947 -405.773382)
		(stroke
			(width 0.2)
			(type default)
		)
		(fill no)
		(layer "In14.Cu")
	)
	(gr_circle
		(center 198.0057 -405.011382)
		(end 198.8947 -405.011382)
		(stroke
			(width 0.2)
			(type default)
		)
		(fill no)
		(layer "In14.Cu")
	)
	(gr_circle
		(center 198.114158 -403.223222)
		(end 199.003158 -403.223222)
		(stroke
			(width 0.2)
			(type default)
		)
		(fill no)
		(layer "In14.Cu")
	)
	(gr_circle
		(center 198.114158 -401.920202)
		(end 199.003158 -401.920202)
		(stroke
			(width 0.2)
			(type default)
		)
		(fill no)
		(layer "In14.Cu")
	)
	(gr_circle
		(center 198.114158 -400.617182)
		(end 199.003158 -400.617182)
		(stroke
			(width 0.2)
			(type default)
		)
		(fill no)
		(layer "In14.Cu")
	)
	(gr_circle
		(center 198.160386 -37.328094)
		(end 199.049386 -37.328094)
		(stroke
			(width 0.2)
			(type default)
		)
		(fill no)
		(layer "In14.Cu")
	)
	(gr_circle
		(center 198.486014 -30.133798)
		(end 199.375014 -30.133798)
		(stroke
			(width 0.2)
			(type default)
		)
		(fill no)
		(layer "In14.Cu")
	)
	(gr_line
		(start 198.701914 -9.272016)
		(end 223.300036 -9.272016)
		(stroke
			(width 0.2)
			(type default)
		)
		(layer "In14.Cu")
	)
	(gr_circle
		(center 198.7677 -408.059382)
		(end 199.6567 -408.059382)
		(stroke
			(width 0.2)
			(type default)
		)
		(fill no)
		(layer "In14.Cu")
	)
	(gr_circle
		(center 198.7677 -407.297382)
		(end 199.6567 -407.297382)
		(stroke
			(width 0.2)
			(type default)
		)
		(fill no)
		(layer "In14.Cu")
	)
	(gr_circle
		(center 198.7677 -406.535382)
		(end 199.6567 -406.535382)
		(stroke
			(width 0.2)
			(type default)
		)
		(fill no)
		(layer "In14.Cu")
	)
	(gr_circle
		(center 198.7677 -405.773382)
		(end 199.6567 -405.773382)
		(stroke
			(width 0.2)
			(type default)
		)
		(fill no)
		(layer "In14.Cu")
	)
	(gr_circle
		(center 198.7677 -405.011382)
		(end 199.6567 -405.011382)
		(stroke
			(width 0.2)
			(type default)
		)
		(fill no)
		(layer "In14.Cu")
	)
	(gr_circle
		(center 198.836026 -37.965634)
		(end 199.725026 -37.965634)
		(stroke
			(width 0.2)
			(type default)
		)
		(fill no)
		(layer "In14.Cu")
	)
	(gr_circle
		(center 199.121014 -30.133798)
		(end 200.010014 -30.133798)
		(stroke
			(width 0.2)
			(type default)
		)
		(fill no)
		(layer "In14.Cu")
	)
	(gr_circle
		(center 199.435974 -30.720538)
		(end 200.324974 -30.720538)
		(stroke
			(width 0.2)
			(type default)
		)
		(fill no)
		(layer "In14.Cu")
	)
	(gr_circle
		(center 199.5297 -408.059382)
		(end 200.4187 -408.059382)
		(stroke
			(width 0.2)
			(type default)
		)
		(fill no)
		(layer "In14.Cu")
	)
	(gr_circle
		(center 199.5297 -407.297382)
		(end 200.4187 -407.297382)
		(stroke
			(width 0.2)
			(type default)
		)
		(fill no)
		(layer "In14.Cu")
	)
	(gr_circle
		(center 199.5297 -406.535382)
		(end 200.4187 -406.535382)
		(stroke
			(width 0.2)
			(type default)
		)
		(fill no)
		(layer "In14.Cu")
	)
	(gr_circle
		(center 199.5297 -405.773382)
		(end 200.4187 -405.773382)
		(stroke
			(width 0.2)
			(type default)
		)
		(fill no)
		(layer "In14.Cu")
	)
	(gr_circle
		(center 199.5297 -405.011382)
		(end 200.4187 -405.011382)
		(stroke
			(width 0.2)
			(type default)
		)
		(fill no)
		(layer "In14.Cu")
	)
	(gr_circle
		(center 199.536558 -403.223222)
		(end 200.425558 -403.223222)
		(stroke
			(width 0.2)
			(type default)
		)
		(fill no)
		(layer "In14.Cu")
	)
	(gr_circle
		(center 199.536558 -400.617182)
		(end 200.425558 -400.617182)
		(stroke
			(width 0.2)
			(type default)
		)
		(fill no)
		(layer "In14.Cu")
	)
	(gr_circle
		(center 199.756014 -30.133798)
		(end 200.645014 -30.133798)
		(stroke
			(width 0.2)
			(type default)
		)
		(fill no)
		(layer "In14.Cu")
	)
	(gr_circle
		(center 200.070974 -30.720538)
		(end 200.959974 -30.720538)
		(stroke
			(width 0.2)
			(type default)
		)
		(fill no)
		(layer "In14.Cu")
	)
	(gr_circle
		(center 200.2917 -408.059382)
		(end 201.1807 -408.059382)
		(stroke
			(width 0.2)
			(type default)
		)
		(fill no)
		(layer "In14.Cu")
	)
	(gr_circle
		(center 200.2917 -407.297382)
		(end 201.1807 -407.297382)
		(stroke
			(width 0.2)
			(type default)
		)
		(fill no)
		(layer "In14.Cu")
	)
	(gr_circle
		(center 200.2917 -406.535382)
		(end 201.1807 -406.535382)
		(stroke
			(width 0.2)
			(type default)
		)
		(fill no)
		(layer "In14.Cu")
	)
	(gr_circle
		(center 200.2917 -405.773382)
		(end 201.1807 -405.773382)
		(stroke
			(width 0.2)
			(type default)
		)
		(fill no)
		(layer "In14.Cu")
	)
	(gr_circle
		(center 200.2917 -405.011382)
		(end 201.1807 -405.011382)
		(stroke
			(width 0.2)
			(type default)
		)
		(fill no)
		(layer "In14.Cu")
	)
	(gr_circle
		(center 200.33234 -378.160534)
		(end 201.22134 -378.160534)
		(stroke
			(width 0.2)
			(type default)
		)
		(fill no)
		(layer "In14.Cu")
	)
	(gr_circle
		(center 200.391014 -30.133798)
		(end 201.280014 -30.133798)
		(stroke
			(width 0.2)
			(type default)
		)
		(fill no)
		(layer "In14.Cu")
	)
	(gr_circle
		(center 200.705974 -30.720538)
		(end 201.594974 -30.720538)
		(stroke
			(width 0.2)
			(type default)
		)
		(fill no)
		(layer "In14.Cu")
	)
	(gr_circle
		(center 200.933558 -403.223222)
		(end 201.822558 -403.223222)
		(stroke
			(width 0.2)
			(type default)
		)
		(fill no)
		(layer "In14.Cu")
	)
	(gr_circle
		(center 200.933558 -401.920202)
		(end 201.822558 -401.920202)
		(stroke
			(width 0.2)
			(type default)
		)
		(fill no)
		(layer "In14.Cu")
	)
	(gr_circle
		(center 200.933558 -400.617182)
		(end 201.822558 -400.617182)
		(stroke
			(width 0.2)
			(type default)
		)
		(fill no)
		(layer "In14.Cu")
	)
	(gr_circle
		(center 201.0537 -408.059382)
		(end 201.9427 -408.059382)
		(stroke
			(width 0.2)
			(type default)
		)
		(fill no)
		(layer "In14.Cu")
	)
	(gr_circle
		(center 201.0537 -407.297382)
		(end 201.9427 -407.297382)
		(stroke
			(width 0.2)
			(type default)
		)
		(fill no)
		(layer "In14.Cu")
	)
	(gr_circle
		(center 201.0537 -406.535382)
		(end 201.9427 -406.535382)
		(stroke
			(width 0.2)
			(type default)
		)
		(fill no)
		(layer "In14.Cu")
	)
	(gr_circle
		(center 201.0537 -405.773382)
		(end 201.9427 -405.773382)
		(stroke
			(width 0.2)
			(type default)
		)
		(fill no)
		(layer "In14.Cu")
	)
	(gr_circle
		(center 201.0537 -405.011382)
		(end 201.9427 -405.011382)
		(stroke
			(width 0.2)
			(type default)
		)
		(fill no)
		(layer "In14.Cu")
	)
	(gr_circle
		(center 201.340974 -30.720538)
		(end 202.229974 -30.720538)
		(stroke
			(width 0.2)
			(type default)
		)
		(fill no)
		(layer "In14.Cu")
	)
	(gr_circle
		(center 201.745342 -346.583)
		(end 202.634342 -346.583)
		(stroke
			(width 0.2)
			(type default)
		)
		(fill no)
		(layer "In14.Cu")
	)
	(gr_circle
		(center 201.745342 -345.821)
		(end 202.634342 -345.821)
		(stroke
			(width 0.2)
			(type default)
		)
		(fill no)
		(layer "In14.Cu")
	)
	(gr_circle
		(center 201.745342 -344.8304)
		(end 202.634342 -344.8304)
		(stroke
			(width 0.2)
			(type default)
		)
		(fill no)
		(layer "In14.Cu")
	)
	(gr_circle
		(center 201.745342 -344.0684)
		(end 202.634342 -344.0684)
		(stroke
			(width 0.2)
			(type default)
		)
		(fill no)
		(layer "In14.Cu")
	)
	(gr_line
		(start 205.73746 -435.231032)
		(end 207.302608 -436.79618)
		(stroke
			(width 0.635)
			(type default)
		)
		(layer "In14.Cu")
	)
	(gr_line
		(start 205.73746 -431.683414)
		(end 205.73746 -435.231032)
		(stroke
			(width 0.635)
			(type default)
		)
		(layer "In14.Cu")
	)
	(gr_circle
		(center 207.1497 -408.059382)
		(end 208.0387 -408.059382)
		(stroke
			(width 0.2)
			(type default)
		)
		(fill no)
		(layer "In14.Cu")
	)
	(gr_line
		(start 207.302608 -436.79618)
		(end 229.074472 -436.79618)
		(stroke
			(width 0.635)
			(type default)
		)
		(layer "In14.Cu")
	)
	(gr_circle
		(center 207.9117 -408.059382)
		(end 208.8007 -408.059382)
		(stroke
			(width 0.2)
			(type default)
		)
		(fill no)
		(layer "In14.Cu")
	)
	(gr_circle
		(center 207.9117 -407.297382)
		(end 208.8007 -407.297382)
		(stroke
			(width 0.2)
			(type default)
		)
		(fill no)
		(layer "In14.Cu")
	)
	(gr_circle
		(center 208.508854 -37.366448)
		(end 209.397854 -37.366448)
		(stroke
			(width 0.2)
			(type default)
		)
		(fill no)
		(layer "In14.Cu")
	)
	(gr_circle
		(center 208.6737 -408.059382)
		(end 209.5627 -408.059382)
		(stroke
			(width 0.2)
			(type default)
		)
		(fill no)
		(layer "In14.Cu")
	)
	(gr_circle
		(center 208.6737 -407.297382)
		(end 209.5627 -407.297382)
		(stroke
			(width 0.2)
			(type default)
		)
		(fill no)
		(layer "In14.Cu")
	)
	(gr_circle
		(center 208.6737 -406.535382)
		(end 209.5627 -406.535382)
		(stroke
			(width 0.2)
			(type default)
		)
		(fill no)
		(layer "In14.Cu")
	)
	(gr_circle
		(center 208.6737 -405.773382)
		(end 209.5627 -405.773382)
		(stroke
			(width 0.2)
			(type default)
		)
		(fill no)
		(layer "In14.Cu")
	)
	(gr_circle
		(center 208.6737 -405.011382)
		(end 209.5627 -405.011382)
		(stroke
			(width 0.2)
			(type default)
		)
		(fill no)
		(layer "In14.Cu")
	)
	(gr_circle
		(center 208.782158 -403.223222)
		(end 209.671158 -403.223222)
		(stroke
			(width 0.2)
			(type default)
		)
		(fill no)
		(layer "In14.Cu")
	)
	(gr_circle
		(center 208.782158 -401.920202)
		(end 209.671158 -401.920202)
		(stroke
			(width 0.2)
			(type default)
		)
		(fill no)
		(layer "In14.Cu")
	)
	(gr_circle
		(center 208.782158 -400.617182)
		(end 209.671158 -400.617182)
		(stroke
			(width 0.2)
			(type default)
		)
		(fill no)
		(layer "In14.Cu")
	)
	(gr_circle
		(center 209.4357 -408.059382)
		(end 210.3247 -408.059382)
		(stroke
			(width 0.2)
			(type default)
		)
		(fill no)
		(layer "In14.Cu")
	)
	(gr_circle
		(center 209.4357 -407.297382)
		(end 210.3247 -407.297382)
		(stroke
			(width 0.2)
			(type default)
		)
		(fill no)
		(layer "In14.Cu")
	)
	(gr_circle
		(center 209.4357 -406.535382)
		(end 210.3247 -406.535382)
		(stroke
			(width 0.2)
			(type default)
		)
		(fill no)
		(layer "In14.Cu")
	)
	(gr_circle
		(center 209.4357 -405.773382)
		(end 210.3247 -405.773382)
		(stroke
			(width 0.2)
			(type default)
		)
		(fill no)
		(layer "In14.Cu")
	)
	(gr_circle
		(center 209.4357 -405.011382)
		(end 210.3247 -405.011382)
		(stroke
			(width 0.2)
			(type default)
		)
		(fill no)
		(layer "In14.Cu")
	)
	(gr_circle
		(center 210.1977 -408.059382)
		(end 211.0867 -408.059382)
		(stroke
			(width 0.2)
			(type default)
		)
		(fill no)
		(layer "In14.Cu")
	)
	(gr_circle
		(center 210.1977 -407.297382)
		(end 211.0867 -407.297382)
		(stroke
			(width 0.2)
			(type default)
		)
		(fill no)
		(layer "In14.Cu")
	)
	(gr_circle
		(center 210.1977 -406.535382)
		(end 211.0867 -406.535382)
		(stroke
			(width 0.2)
			(type default)
		)
		(fill no)
		(layer "In14.Cu")
	)
	(gr_circle
		(center 210.1977 -405.773382)
		(end 211.0867 -405.773382)
		(stroke
			(width 0.2)
			(type default)
		)
		(fill no)
		(layer "In14.Cu")
	)
	(gr_circle
		(center 210.1977 -405.011382)
		(end 211.0867 -405.011382)
		(stroke
			(width 0.2)
			(type default)
		)
		(fill no)
		(layer "In14.Cu")
	)
	(gr_circle
		(center 210.204558 -403.223222)
		(end 211.093558 -403.223222)
		(stroke
			(width 0.2)
			(type default)
		)
		(fill no)
		(layer "In14.Cu")
	)
	(gr_circle
		(center 210.204558 -400.617182)
		(end 211.093558 -400.617182)
		(stroke
			(width 0.2)
			(type default)
		)
		(fill no)
		(layer "In14.Cu")
	)
	(gr_circle
		(center 210.9597 -408.059382)
		(end 211.8487 -408.059382)
		(stroke
			(width 0.2)
			(type default)
		)
		(fill no)
		(layer "In14.Cu")
	)
	(gr_circle
		(center 210.9597 -407.297382)
		(end 211.8487 -407.297382)
		(stroke
			(width 0.2)
			(type default)
		)
		(fill no)
		(layer "In14.Cu")
	)
	(gr_circle
		(center 210.9597 -406.535382)
		(end 211.8487 -406.535382)
		(stroke
			(width 0.2)
			(type default)
		)
		(fill no)
		(layer "In14.Cu")
	)
	(gr_circle
		(center 210.9597 -405.773382)
		(end 211.8487 -405.773382)
		(stroke
			(width 0.2)
			(type default)
		)
		(fill no)
		(layer "In14.Cu")
	)
	(gr_circle
		(center 210.9597 -405.011382)
		(end 211.8487 -405.011382)
		(stroke
			(width 0.2)
			(type default)
		)
		(fill no)
		(layer "In14.Cu")
	)
	(gr_circle
		(center 211.601558 -403.223222)
		(end 212.490558 -403.223222)
		(stroke
			(width 0.2)
			(type default)
		)
		(fill no)
		(layer "In14.Cu")
	)
	(gr_circle
		(center 211.601558 -401.920202)
		(end 212.490558 -401.920202)
		(stroke
			(width 0.2)
			(type default)
		)
		(fill no)
		(layer "In14.Cu")
	)
	(gr_circle
		(center 211.601558 -400.617182)
		(end 212.490558 -400.617182)
		(stroke
			(width 0.2)
			(type default)
		)
		(fill no)
		(layer "In14.Cu")
	)
	(gr_circle
		(center 211.7217 -408.059382)
		(end 212.6107 -408.059382)
		(stroke
			(width 0.2)
			(type default)
		)
		(fill no)
		(layer "In14.Cu")
	)
	(gr_circle
		(center 211.7217 -407.297382)
		(end 212.6107 -407.297382)
		(stroke
			(width 0.2)
			(type default)
		)
		(fill no)
		(layer "In14.Cu")
	)
	(gr_circle
		(center 211.7217 -406.535382)
		(end 212.6107 -406.535382)
		(stroke
			(width 0.2)
			(type default)
		)
		(fill no)
		(layer "In14.Cu")
	)
	(gr_circle
		(center 211.7217 -405.773382)
		(end 212.6107 -405.773382)
		(stroke
			(width 0.2)
			(type default)
		)
		(fill no)
		(layer "In14.Cu")
	)
	(gr_circle
		(center 211.7217 -405.011382)
		(end 212.6107 -405.011382)
		(stroke
			(width 0.2)
			(type default)
		)
		(fill no)
		(layer "In14.Cu")
	)
	(gr_circle
		(center 212.4837 -408.059382)
		(end 213.3727 -408.059382)
		(stroke
			(width 0.2)
			(type default)
		)
		(fill no)
		(layer "In14.Cu")
	)
	(gr_circle
		(center 212.4837 -407.297382)
		(end 213.3727 -407.297382)
		(stroke
			(width 0.2)
			(type default)
		)
		(fill no)
		(layer "In14.Cu")
	)
	(gr_circle
		(center 217.8177 -408.059382)
		(end 218.7067 -408.059382)
		(stroke
			(width 0.2)
			(type default)
		)
		(fill no)
		(layer "In14.Cu")
	)
	(gr_circle
		(center 218.5797 -408.059382)
		(end 219.4687 -408.059382)
		(stroke
			(width 0.2)
			(type default)
		)
		(fill no)
		(layer "In14.Cu")
	)
	(gr_circle
		(center 218.5797 -407.297382)
		(end 219.4687 -407.297382)
		(stroke
			(width 0.2)
			(type default)
		)
		(fill no)
		(layer "In14.Cu")
	)
	(gr_circle
		(center 219.3417 -408.059382)
		(end 220.2307 -408.059382)
		(stroke
			(width 0.2)
			(type default)
		)
		(fill no)
		(layer "In14.Cu")
	)
	(gr_circle
		(center 219.3417 -407.297382)
		(end 220.2307 -407.297382)
		(stroke
			(width 0.2)
			(type default)
		)
		(fill no)
		(layer "In14.Cu")
	)
	(gr_circle
		(center 219.3417 -406.535382)
		(end 220.2307 -406.535382)
		(stroke
			(width 0.2)
			(type default)
		)
		(fill no)
		(layer "In14.Cu")
	)
	(gr_circle
		(center 219.3417 -405.773382)
		(end 220.2307 -405.773382)
		(stroke
			(width 0.2)
			(type default)
		)
		(fill no)
		(layer "In14.Cu")
	)
	(gr_circle
		(center 219.3417 -405.011382)
		(end 220.2307 -405.011382)
		(stroke
			(width 0.2)
			(type default)
		)
		(fill no)
		(layer "In14.Cu")
	)
	(gr_circle
		(center 219.450158 -403.223222)
		(end 220.339158 -403.223222)
		(stroke
			(width 0.2)
			(type default)
		)
		(fill no)
		(layer "In14.Cu")
	)
	(gr_circle
		(center 219.450158 -401.920202)
		(end 220.339158 -401.920202)
		(stroke
			(width 0.2)
			(type default)
		)
		(fill no)
		(layer "In14.Cu")
	)
	(gr_circle
		(center 219.450158 -400.617182)
		(end 220.339158 -400.617182)
		(stroke
			(width 0.2)
			(type default)
		)
		(fill no)
		(layer "In14.Cu")
	)
	(gr_circle
		(center 220.1037 -408.059382)
		(end 220.9927 -408.059382)
		(stroke
			(width 0.2)
			(type default)
		)
		(fill no)
		(layer "In14.Cu")
	)
	(gr_circle
		(center 220.1037 -407.297382)
		(end 220.9927 -407.297382)
		(stroke
			(width 0.2)
			(type default)
		)
		(fill no)
		(layer "In14.Cu")
	)
	(gr_circle
		(center 220.1037 -406.535382)
		(end 220.9927 -406.535382)
		(stroke
			(width 0.2)
			(type default)
		)
		(fill no)
		(layer "In14.Cu")
	)
	(gr_circle
		(center 220.1037 -405.773382)
		(end 220.9927 -405.773382)
		(stroke
			(width 0.2)
			(type default)
		)
		(fill no)
		(layer "In14.Cu")
	)
	(gr_circle
		(center 220.1037 -405.011382)
		(end 220.9927 -405.011382)
		(stroke
			(width 0.2)
			(type default)
		)
		(fill no)
		(layer "In14.Cu")
	)
	(gr_circle
		(center 220.8657 -408.059382)
		(end 221.7547 -408.059382)
		(stroke
			(width 0.2)
			(type default)
		)
		(fill no)
		(layer "In14.Cu")
	)
	(gr_circle
		(center 220.8657 -407.297382)
		(end 221.7547 -407.297382)
		(stroke
			(width 0.2)
			(type default)
		)
		(fill no)
		(layer "In14.Cu")
	)
	(gr_circle
		(center 220.8657 -406.535382)
		(end 221.7547 -406.535382)
		(stroke
			(width 0.2)
			(type default)
		)
		(fill no)
		(layer "In14.Cu")
	)
	(gr_circle
		(center 220.8657 -405.773382)
		(end 221.7547 -405.773382)
		(stroke
			(width 0.2)
			(type default)
		)
		(fill no)
		(layer "In14.Cu")
	)
	(gr_circle
		(center 220.8657 -405.011382)
		(end 221.7547 -405.011382)
		(stroke
			(width 0.2)
			(type default)
		)
		(fill no)
		(layer "In14.Cu")
	)
	(gr_circle
		(center 220.872558 -403.223222)
		(end 221.761558 -403.223222)
		(stroke
			(width 0.2)
			(type default)
		)
		(fill no)
		(layer "In14.Cu")
	)
	(gr_circle
		(center 220.872558 -400.617182)
		(end 221.761558 -400.617182)
		(stroke
			(width 0.2)
			(type default)
		)
		(fill no)
		(layer "In14.Cu")
	)
	(gr_line
		(start 221.30004 -12.288012)
		(end 196.701918 -12.288012)
		(stroke
			(width 0.2)
			(type default)
		)
		(layer "In14.Cu")
	)
	(gr_circle
		(center 221.6277 -408.059382)
		(end 222.5167 -408.059382)
		(stroke
			(width 0.2)
			(type default)
		)
		(fill no)
		(layer "In14.Cu")
	)
	(gr_circle
		(center 221.6277 -407.297382)
		(end 222.5167 -407.297382)
		(stroke
			(width 0.2)
			(type default)
		)
		(fill no)
		(layer "In14.Cu")
	)
	(gr_circle
		(center 221.6277 -406.535382)
		(end 222.5167 -406.535382)
		(stroke
			(width 0.2)
			(type default)
		)
		(fill no)
		(layer "In14.Cu")
	)
	(gr_circle
		(center 221.6277 -405.773382)
		(end 222.5167 -405.773382)
		(stroke
			(width 0.2)
			(type default)
		)
		(fill no)
		(layer "In14.Cu")
	)
	(gr_circle
		(center 221.6277 -405.011382)
		(end 222.5167 -405.011382)
		(stroke
			(width 0.2)
			(type default)
		)
		(fill no)
		(layer "In14.Cu")
	)
	(gr_circle
		(center 222.269558 -403.223222)
		(end 223.158558 -403.223222)
		(stroke
			(width 0.2)
			(type default)
		)
		(fill no)
		(layer "In14.Cu")
	)
	(gr_circle
		(center 222.269558 -401.920202)
		(end 223.158558 -401.920202)
		(stroke
			(width 0.2)
			(type default)
		)
		(fill no)
		(layer "In14.Cu")
	)
	(gr_circle
		(center 222.269558 -400.617182)
		(end 223.158558 -400.617182)
		(stroke
			(width 0.2)
			(type default)
		)
		(fill no)
		(layer "In14.Cu")
	)
	(gr_circle
		(center 222.3897 -408.059382)
		(end 223.2787 -408.059382)
		(stroke
			(width 0.2)
			(type default)
		)
		(fill no)
		(layer "In14.Cu")
	)
	(gr_circle
		(center 222.3897 -407.297382)
		(end 223.2787 -407.297382)
		(stroke
			(width 0.2)
			(type default)
		)
		(fill no)
		(layer "In14.Cu")
	)
	(gr_circle
		(center 222.3897 -406.535382)
		(end 223.2787 -406.535382)
		(stroke
			(width 0.2)
			(type default)
		)
		(fill no)
		(layer "In14.Cu")
	)
	(gr_circle
		(center 222.3897 -405.773382)
		(end 223.2787 -405.773382)
		(stroke
			(width 0.2)
			(type default)
		)
		(fill no)
		(layer "In14.Cu")
	)
	(gr_circle
		(center 222.3897 -405.011382)
		(end 223.2787 -405.011382)
		(stroke
			(width 0.2)
			(type default)
		)
		(fill no)
		(layer "In14.Cu")
	)
	(gr_line
		(start 222.792036 -34.120074)
		(end 222.792036 -13.780008)
		(stroke
			(width 0.2)
			(type default)
		)
		(layer "In14.Cu")
	)
	(gr_arc
		(start 222.792036 -34.120074)
		(mid 223.526604 -35.8935)
		(end 225.300032 -36.62807)
		(stroke
			(width 0.2)
			(type default)
		)
		(layer "In14.Cu")
	)
	(gr_arc
		(start 222.792036 -13.780008)
		(mid 222.35504 -12.725008)
		(end 221.30004 -12.288012)
		(stroke
			(width 0.2)
			(type default)
		)
		(layer "In14.Cu")
	)
	(gr_circle
		(center 223.1517 -408.059382)
		(end 224.0407 -408.059382)
		(stroke
			(width 0.2)
			(type default)
		)
		(fill no)
		(layer "In14.Cu")
	)
	(gr_circle
		(center 223.1517 -407.297382)
		(end 224.0407 -407.297382)
		(stroke
			(width 0.2)
			(type default)
		)
		(fill no)
		(layer "In14.Cu")
	)
	(gr_arc
		(start 223.300036 -34.120074)
		(mid 223.885821 -35.534285)
		(end 225.300032 -36.12007)
		(stroke
			(width 1.016)
			(type default)
		)
		(layer "In14.Cu")
	)
	(gr_arc
		(start 223.300036 -13.780008)
		(mid 222.714256 -12.365778)
		(end 221.30004 -11.780012)
		(stroke
			(width 1.016)
			(type default)
		)
		(layer "In14.Cu")
	)
	(gr_line
		(start 223.300036 -13.780008)
		(end 223.300036 -34.120074)
		(stroke
			(width 1.016)
			(type default)
		)
		(layer "In14.Cu")
	)
	(gr_line
		(start 225.300032 -36.12007)
		(end 256.800096 -36.12007)
		(stroke
			(width 1.016)
			(type default)
		)
		(layer "In14.Cu")
	)
	(gr_arc
		(start 225.808032 -33.120076)
		(mid 225.952135 -33.467971)
		(end 226.30003 -33.612074)
		(stroke
			(width 0.2)
			(type default)
		)
		(layer "In14.Cu")
	)
	(gr_arc
		(start 225.808032 -11.780012)
		(mid 225.073463 -10.006571)
		(end 223.300036 -9.272016)
		(stroke
			(width 0.2)
			(type default)
		)
		(layer "In14.Cu")
	)
	(gr_line
		(start 225.808032 -11.780012)
		(end 225.808032 -33.120076)
		(stroke
			(width 0.2)
			(type default)
		)
		(layer "In14.Cu")
	)
	(gr_line
		(start 226.30003 -33.612074)
		(end 255.800098 -33.612074)
		(stroke
			(width 0.2)
			(type default)
		)
		(layer "In14.Cu")
	)
	(gr_line
		(start 226.929188 -412.927038)
		(end 229.543102 -410.313124)
		(stroke
			(width 0.635)
			(type default)
		)
		(layer "In14.Cu")
	)
	(gr_circle
		(center 228.4857 -408.059382)
		(end 229.3747 -408.059382)
		(stroke
			(width 0.2)
			(type default)
		)
		(fill no)
		(layer "In14.Cu")
	)
	(gr_line
		(start 229.074472 -436.79618)
		(end 229.997 -435.873652)
		(stroke
			(width 0.635)
			(type default)
		)
		(layer "In14.Cu")
	)
	(gr_circle
		(center 229.2477 -408.059382)
		(end 230.1367 -408.059382)
		(stroke
			(width 0.2)
			(type default)
		)
		(fill no)
		(layer "In14.Cu")
	)
	(gr_circle
		(center 229.2477 -407.297382)
		(end 230.1367 -407.297382)
		(stroke
			(width 0.2)
			(type default)
		)
		(fill no)
		(layer "In14.Cu")
	)
	(gr_line
		(start 229.543102 -410.313124)
		(end 234.719114 -410.313124)
		(stroke
			(width 0.635)
			(type default)
		)
		(layer "In14.Cu")
	)
	(gr_line
		(start 229.997 -435.873652)
		(end 229.997 -422.180766)
		(stroke
			(width 0.635)
			(type default)
		)
		(layer "In14.Cu")
	)
	(gr_circle
		(center 230.0097 -408.059382)
		(end 230.8987 -408.059382)
		(stroke
			(width 0.2)
			(type default)
		)
		(fill no)
		(layer "In14.Cu")
	)
	(gr_circle
		(center 230.0097 -407.297382)
		(end 230.8987 -407.297382)
		(stroke
			(width 0.2)
			(type default)
		)
		(fill no)
		(layer "In14.Cu")
	)
	(gr_circle
		(center 230.0097 -406.535382)
		(end 230.8987 -406.535382)
		(stroke
			(width 0.2)
			(type default)
		)
		(fill no)
		(layer "In14.Cu")
	)
	(gr_circle
		(center 230.0097 -405.773382)
		(end 230.8987 -405.773382)
		(stroke
			(width 0.2)
			(type default)
		)
		(fill no)
		(layer "In14.Cu")
	)
	(gr_circle
		(center 230.0097 -405.011382)
		(end 230.8987 -405.011382)
		(stroke
			(width 0.2)
			(type default)
		)
		(fill no)
		(layer "In14.Cu")
	)
	(gr_circle
		(center 230.118158 -403.223222)
		(end 231.007158 -403.223222)
		(stroke
			(width 0.2)
			(type default)
		)
		(fill no)
		(layer "In14.Cu")
	)
	(gr_circle
		(center 230.118158 -401.920202)
		(end 231.007158 -401.920202)
		(stroke
			(width 0.2)
			(type default)
		)
		(fill no)
		(layer "In14.Cu")
	)
	(gr_circle
		(center 230.118158 -400.617182)
		(end 231.007158 -400.617182)
		(stroke
			(width 0.2)
			(type default)
		)
		(fill no)
		(layer "In14.Cu")
	)
	(gr_circle
		(center 230.7717 -408.059382)
		(end 231.6607 -408.059382)
		(stroke
			(width 0.2)
			(type default)
		)
		(fill no)
		(layer "In14.Cu")
	)
	(gr_circle
		(center 230.7717 -407.297382)
		(end 231.6607 -407.297382)
		(stroke
			(width 0.2)
			(type default)
		)
		(fill no)
		(layer "In14.Cu")
	)
	(gr_circle
		(center 230.7717 -406.535382)
		(end 231.6607 -406.535382)
		(stroke
			(width 0.2)
			(type default)
		)
		(fill no)
		(layer "In14.Cu")
	)
	(gr_circle
		(center 230.7717 -405.773382)
		(end 231.6607 -405.773382)
		(stroke
			(width 0.2)
			(type default)
		)
		(fill no)
		(layer "In14.Cu")
	)
	(gr_circle
		(center 230.7717 -405.011382)
		(end 231.6607 -405.011382)
		(stroke
			(width 0.2)
			(type default)
		)
		(fill no)
		(layer "In14.Cu")
	)
	(gr_circle
		(center 231.5337 -408.059382)
		(end 232.4227 -408.059382)
		(stroke
			(width 0.2)
			(type default)
		)
		(fill no)
		(layer "In14.Cu")
	)
	(gr_circle
		(center 231.5337 -407.297382)
		(end 232.4227 -407.297382)
		(stroke
			(width 0.2)
			(type default)
		)
		(fill no)
		(layer "In14.Cu")
	)
	(gr_circle
		(center 231.5337 -406.535382)
		(end 232.4227 -406.535382)
		(stroke
			(width 0.2)
			(type default)
		)
		(fill no)
		(layer "In14.Cu")
	)
	(gr_circle
		(center 231.5337 -405.773382)
		(end 232.4227 -405.773382)
		(stroke
			(width 0.2)
			(type default)
		)
		(fill no)
		(layer "In14.Cu")
	)
	(gr_circle
		(center 231.5337 -405.011382)
		(end 232.4227 -405.011382)
		(stroke
			(width 0.2)
			(type default)
		)
		(fill no)
		(layer "In14.Cu")
	)
	(gr_circle
		(center 231.540558 -403.223222)
		(end 232.429558 -403.223222)
		(stroke
			(width 0.2)
			(type default)
		)
		(fill no)
		(layer "In14.Cu")
	)
	(gr_circle
		(center 231.540558 -400.617182)
		(end 232.429558 -400.617182)
		(stroke
			(width 0.2)
			(type default)
		)
		(fill no)
		(layer "In14.Cu")
	)
	(gr_circle
		(center 232.2957 -408.059382)
		(end 233.1847 -408.059382)
		(stroke
			(width 0.2)
			(type default)
		)
		(fill no)
		(layer "In14.Cu")
	)
	(gr_circle
		(center 232.2957 -407.297382)
		(end 233.1847 -407.297382)
		(stroke
			(width 0.2)
			(type default)
		)
		(fill no)
		(layer "In14.Cu")
	)
	(gr_circle
		(center 232.2957 -406.535382)
		(end 233.1847 -406.535382)
		(stroke
			(width 0.2)
			(type default)
		)
		(fill no)
		(layer "In14.Cu")
	)
	(gr_circle
		(center 232.2957 -405.773382)
		(end 233.1847 -405.773382)
		(stroke
			(width 0.2)
			(type default)
		)
		(fill no)
		(layer "In14.Cu")
	)
	(gr_circle
		(center 232.2957 -405.011382)
		(end 233.1847 -405.011382)
		(stroke
			(width 0.2)
			(type default)
		)
		(fill no)
		(layer "In14.Cu")
	)
	(gr_circle
		(center 232.937558 -403.223222)
		(end 233.826558 -403.223222)
		(stroke
			(width 0.2)
			(type default)
		)
		(fill no)
		(layer "In14.Cu")
	)
	(gr_circle
		(center 232.937558 -401.920202)
		(end 233.826558 -401.920202)
		(stroke
			(width 0.2)
			(type default)
		)
		(fill no)
		(layer "In14.Cu")
	)
	(gr_circle
		(center 232.937558 -400.617182)
		(end 233.826558 -400.617182)
		(stroke
			(width 0.2)
			(type default)
		)
		(fill no)
		(layer "In14.Cu")
	)
	(gr_circle
		(center 233.0577 -408.059382)
		(end 233.9467 -408.059382)
		(stroke
			(width 0.2)
			(type default)
		)
		(fill no)
		(layer "In14.Cu")
	)
	(gr_circle
		(center 233.0577 -407.297382)
		(end 233.9467 -407.297382)
		(stroke
			(width 0.2)
			(type default)
		)
		(fill no)
		(layer "In14.Cu")
	)
	(gr_circle
		(center 233.0577 -406.535382)
		(end 233.9467 -406.535382)
		(stroke
			(width 0.2)
			(type default)
		)
		(fill no)
		(layer "In14.Cu")
	)
	(gr_circle
		(center 233.0577 -405.773382)
		(end 233.9467 -405.773382)
		(stroke
			(width 0.2)
			(type default)
		)
		(fill no)
		(layer "In14.Cu")
	)
	(gr_circle
		(center 233.0577 -405.011382)
		(end 233.9467 -405.011382)
		(stroke
			(width 0.2)
			(type default)
		)
		(fill no)
		(layer "In14.Cu")
	)
	(gr_circle
		(center 233.8197 -408.059382)
		(end 234.7087 -408.059382)
		(stroke
			(width 0.2)
			(type default)
		)
		(fill no)
		(layer "In14.Cu")
	)
	(gr_circle
		(center 233.8197 -407.297382)
		(end 234.7087 -407.297382)
		(stroke
			(width 0.2)
			(type default)
		)
		(fill no)
		(layer "In14.Cu")
	)
	(gr_line
		(start 234.719114 -410.313124)
		(end 238.882682 -406.149556)
		(stroke
			(width 0.635)
			(type default)
		)
		(layer "In14.Cu")
	)
	(gr_line
		(start 234.897676 -417.28009)
		(end 229.997 -422.180766)
		(stroke
			(width 0.635)
			(type default)
		)
		(layer "In14.Cu")
	)
	(gr_circle
		(center 237.629954 -44.025566)
		(end 238.518954 -44.025566)
		(stroke
			(width 0.2)
			(type default)
		)
		(fill no)
		(layer "In14.Cu")
	)
	(gr_circle
		(center 237.640114 -44.716446)
		(end 238.529114 -44.716446)
		(stroke
			(width 0.2)
			(type default)
		)
		(fill no)
		(layer "In14.Cu")
	)
	(gr_circle
		(center 238.292894 -44.802806)
		(end 239.181894 -44.802806)
		(stroke
			(width 0.2)
			(type default)
		)
		(fill no)
		(layer "In14.Cu")
	)
	(gr_circle
		(center 238.292894 -44.040806)
		(end 239.181894 -44.040806)
		(stroke
			(width 0.2)
			(type default)
		)
		(fill no)
		(layer "In14.Cu")
	)
	(gr_arc
		(start 238.695992 -393.003532)
		(mid 238.724179 -393.144586)
		(end 238.804196 -393.264136)
		(stroke
			(width 0.635)
			(type default)
		)
		(layer "In14.Cu")
	)
	(gr_line
		(start 238.695992 -384.337306)
		(end 238.695992 -393.003532)
		(stroke
			(width 0.635)
			(type default)
		)
		(layer "In14.Cu")
	)
	(gr_line
		(start 238.752126 -384.198876)
		(end 238.695992 -384.337306)
		(stroke
			(width 0.635)
			(type default)
		)
		(layer "In14.Cu")
	)
	(gr_line
		(start 238.804196 -393.264136)
		(end 239.027716 -393.487656)
		(stroke
			(width 0.635)
			(type default)
		)
		(layer "In14.Cu")
	)
	(gr_line
		(start 238.805974 -384.146806)
		(end 238.752126 -384.198876)
		(stroke
			(width 0.635)
			(type default)
		)
		(layer "In14.Cu")
	)
	(gr_line
		(start 238.882682 -406.149556)
		(end 238.882682 -394.001498)
		(stroke
			(width 0.635)
			(type default)
		)
		(layer "In14.Cu")
	)
	(gr_line
		(start 238.882682 -394.210794)
		(end 238.882682 -394.001498)
		(stroke
			(width 0.635)
			(type default)
		)
		(layer "In14.Cu")
	)
	(gr_line
		(start 238.882682 -394.210794)
		(end 279.615392 -394.210794)
		(stroke
			(width 0.635)
			(type default)
		)
		(layer "In14.Cu")
	)
	(gr_line
		(start 238.882682 -394.001498)
		(end 239.28832 -393.59586)
		(stroke
			(width 0.635)
			(type default)
		)
		(layer "In14.Cu")
	)
	(gr_circle
		(center 238.943134 -44.802806)
		(end 239.832134 -44.802806)
		(stroke
			(width 0.2)
			(type default)
		)
		(fill no)
		(layer "In14.Cu")
	)
	(gr_circle
		(center 238.943134 -44.040806)
		(end 239.832134 -44.040806)
		(stroke
			(width 0.2)
			(type default)
		)
		(fill no)
		(layer "In14.Cu")
	)
	(gr_arc
		(start 239.027716 -393.487656)
		(mid 239.147257 -393.567682)
		(end 239.28832 -393.59586)
		(stroke
			(width 0.635)
			(type default)
		)
		(layer "In14.Cu")
	)
	(gr_line
		(start 239.281716 -383.671064)
		(end 238.805974 -384.146806)
		(stroke
			(width 0.635)
			(type default)
		)
		(layer "In14.Cu")
	)
	(gr_line
		(start 239.28832 -393.59586)
		(end 273.155664 -393.59586)
		(stroke
			(width 0.635)
			(type default)
		)
		(layer "In14.Cu")
	)
	(gr_arc
		(start 239.54232 -383.56286)
		(mid 239.401266 -383.591047)
		(end 239.281716 -383.671064)
		(stroke
			(width 0.635)
			(type default)
		)
		(layer "In14.Cu")
	)
	(gr_circle
		(center 239.578134 -44.802806)
		(end 240.467134 -44.802806)
		(stroke
			(width 0.2)
			(type default)
		)
		(fill no)
		(layer "In14.Cu")
	)
	(gr_circle
		(center 239.578134 -44.040806)
		(end 240.467134 -44.040806)
		(stroke
			(width 0.2)
			(type default)
		)
		(fill no)
		(layer "In14.Cu")
	)
	(gr_circle
		(center 240.213134 -44.802806)
		(end 241.102134 -44.802806)
		(stroke
			(width 0.2)
			(type default)
		)
		(fill no)
		(layer "In14.Cu")
	)
	(gr_circle
		(center 240.213134 -44.040806)
		(end 241.102134 -44.040806)
		(stroke
			(width 0.2)
			(type default)
		)
		(fill no)
		(layer "In14.Cu")
	)
	(gr_circle
		(center 240.893854 -44.830746)
		(end 241.782854 -44.830746)
		(stroke
			(width 0.2)
			(type default)
		)
		(fill no)
		(layer "In14.Cu")
	)
	(gr_circle
		(center 244.518942 -43.246802)
		(end 245.407942 -43.246802)
		(stroke
			(width 0.2)
			(type default)
		)
		(fill no)
		(layer "In14.Cu")
	)
	(gr_circle
		(center 244.518942 -42.611802)
		(end 245.407942 -42.611802)
		(stroke
			(width 0.2)
			(type default)
		)
		(fill no)
		(layer "In14.Cu")
	)
	(gr_circle
		(center 245.857522 -52.022502)
		(end 246.746522 -52.022502)
		(stroke
			(width 0.2)
			(type default)
		)
		(fill no)
		(layer "In14.Cu")
	)
	(gr_circle
		(center 246.873522 -52.022502)
		(end 247.762522 -52.022502)
		(stroke
			(width 0.2)
			(type default)
		)
		(fill no)
		(layer "In14.Cu")
	)
	(gr_circle
		(center 247.825514 -40.94988)
		(end 248.714514 -40.94988)
		(stroke
			(width 0.2)
			(type default)
		)
		(fill no)
		(layer "In14.Cu")
	)
	(gr_circle
		(center 247.840246 -51.320446)
		(end 248.729246 -51.320446)
		(stroke
			(width 0.2)
			(type default)
		)
		(fill no)
		(layer "In14.Cu")
	)
	(gr_circle
		(center 248.214134 -52.171346)
		(end 249.103134 -52.171346)
		(stroke
			(width 0.2)
			(type default)
		)
		(fill no)
		(layer "In14.Cu")
	)
	(gr_circle
		(center 248.881646 -51.320446)
		(end 249.770646 -51.320446)
		(stroke
			(width 0.2)
			(type default)
		)
		(fill no)
		(layer "In14.Cu")
	)
	(gr_circle
		(center 249.202448 -40.945816)
		(end 250.091448 -40.945816)
		(stroke
			(width 0.2)
			(type default)
		)
		(fill no)
		(layer "In14.Cu")
	)
	(gr_circle
		(center 249.905266 -51.349148)
		(end 250.794266 -51.349148)
		(stroke
			(width 0.2)
			(type default)
		)
		(fill no)
		(layer "In14.Cu")
	)
	(gr_circle
		(center 250.449334 -49.555146)
		(end 251.338334 -49.555146)
		(stroke
			(width 0.2)
			(type default)
		)
		(fill no)
		(layer "In14.Cu")
	)
	(gr_circle
		(center 250.779534 -52.222146)
		(end 251.668534 -52.222146)
		(stroke
			(width 0.2)
			(type default)
		)
		(fill no)
		(layer "In14.Cu")
	)
	(gr_circle
		(center 250.779534 -51.333146)
		(end 251.668534 -51.333146)
		(stroke
			(width 0.2)
			(type default)
		)
		(fill no)
		(layer "In14.Cu")
	)
	(gr_circle
		(center 250.779534 -50.444146)
		(end 251.668534 -50.444146)
		(stroke
			(width 0.2)
			(type default)
		)
		(fill no)
		(layer "In14.Cu")
	)
	(gr_circle
		(center 251.516134 -52.501546)
		(end 252.405134 -52.501546)
		(stroke
			(width 0.2)
			(type default)
		)
		(fill no)
		(layer "In14.Cu")
	)
	(gr_circle
		(center 251.516134 -51.612546)
		(end 252.405134 -51.612546)
		(stroke
			(width 0.2)
			(type default)
		)
		(fill no)
		(layer "In14.Cu")
	)
	(gr_circle
		(center 251.516134 -50.723546)
		(end 252.405134 -50.723546)
		(stroke
			(width 0.2)
			(type default)
		)
		(fill no)
		(layer "In14.Cu")
	)
	(gr_circle
		(center 255.347978 -39.380922)
		(end 256.236978 -39.380922)
		(stroke
			(width 0.2)
			(type default)
		)
		(fill no)
		(layer "In14.Cu")
	)
	(gr_arc
		(start 255.800098 -33.612074)
		(mid 256.147993 -33.467971)
		(end 256.292096 -33.120076)
		(stroke
			(width 0.2)
			(type default)
		)
		(layer "In14.Cu")
	)
	(gr_line
		(start 256.292096 -33.120076)
		(end 256.292096 -11.780012)
		(stroke
			(width 0.2)
			(type default)
		)
		(layer "In14.Cu")
	)
	(gr_line
		(start 256.800096 -36.62807)
		(end 225.300032 -36.62807)
		(stroke
			(width 0.2)
			(type default)
		)
		(layer "In14.Cu")
	)
	(gr_arc
		(start 256.800096 -36.62807)
		(mid 258.57351 -35.893495)
		(end 259.308092 -34.120074)
		(stroke
			(width 0.2)
			(type default)
		)
		(layer "In14.Cu")
	)
	(gr_arc
		(start 256.800096 -36.12007)
		(mid 258.214307 -35.534285)
		(end 258.800092 -34.120074)
		(stroke
			(width 1.016)
			(type default)
		)
		(layer "In14.Cu")
	)
	(gr_line
		(start 258.800092 -34.120074)
		(end 258.800092 -13.780008)
		(stroke
			(width 1.016)
			(type default)
		)
		(layer "In14.Cu")
	)
	(gr_arc
		(start 258.800092 -9.272016)
		(mid 257.02668 -10.006595)
		(end 256.292096 -11.780012)
		(stroke
			(width 0.2)
			(type default)
		)
		(layer "In14.Cu")
	)
	(gr_line
		(start 258.800092 -9.272016)
		(end 383.601976 -9.272016)
		(stroke
			(width 0.2)
			(type default)
		)
		(layer "In14.Cu")
	)
	(gr_line
		(start 259.308092 -13.780008)
		(end 259.308092 -34.120074)
		(stroke
			(width 0.2)
			(type default)
		)
		(layer "In14.Cu")
	)
	(gr_arc
		(start 260.800088 -12.288012)
		(mid 259.745088 -12.725008)
		(end 259.308092 -13.780008)
		(stroke
			(width 0.2)
			(type default)
		)
		(layer "In14.Cu")
	)
	(gr_arc
		(start 260.800088 -11.780012)
		(mid 259.385888 -12.365802)
		(end 258.800092 -13.780008)
		(stroke
			(width 1.016)
			(type default)
		)
		(layer "In14.Cu")
	)
	(gr_line
		(start 260.800088 -11.780012)
		(end 385.601972 -11.780012)
		(stroke
			(width 1.016)
			(type default)
		)
		(layer "In14.Cu")
	)
	(gr_line
		(start 272.19021 -417.28009)
		(end 234.897676 -417.28009)
		(stroke
			(width 0.635)
			(type default)
		)
		(layer "In14.Cu")
	)
	(gr_arc
		(start 273.155664 -393.59586)
		(mid 273.296718 -393.567673)
		(end 273.416268 -393.487656)
		(stroke
			(width 0.635)
			(type default)
		)
		(layer "In14.Cu")
	)
	(gr_line
		(start 273.33067 -394.041884)
		(end 279.547066 -394.041884)
		(stroke
			(width 0.635)
			(type default)
		)
		(layer "In14.Cu")
	)
	(gr_line
		(start 273.416268 -393.487656)
		(end 273.893788 -393.010136)
		(stroke
			(width 0.635)
			(type default)
		)
		(layer "In14.Cu")
	)
	(gr_line
		(start 273.481546 -383.56286)
		(end 239.54232 -383.56286)
		(stroke
			(width 0.635)
			(type default)
		)
		(layer "In14.Cu")
	)
	(gr_line
		(start 273.619976 -383.618994)
		(end 273.481546 -383.56286)
		(stroke
			(width 0.635)
			(type default)
		)
		(layer "In14.Cu")
	)
	(gr_line
		(start 273.672046 -383.672842)
		(end 273.619976 -383.618994)
		(stroke
			(width 0.635)
			(type default)
		)
		(layer "In14.Cu")
	)
	(gr_arc
		(start 273.893788 -393.010136)
		(mid 273.97387 -392.890613)
		(end 274.001992 -392.749532)
		(stroke
			(width 0.635)
			(type default)
		)
		(layer "In14.Cu")
	)
	(gr_line
		(start 273.893788 -383.894584)
		(end 273.672046 -383.672842)
		(stroke
			(width 0.635)
			(type default)
		)
		(layer "In14.Cu")
	)
	(gr_line
		(start 274.001992 -392.749532)
		(end 274.001992 -384.155188)
		(stroke
			(width 0.635)
			(type default)
		)
		(layer "In14.Cu")
	)
	(gr_arc
		(start 274.001992 -384.155188)
		(mid 273.973805 -384.014134)
		(end 273.893788 -383.894584)
		(stroke
			(width 0.635)
			(type default)
		)
		(layer "In14.Cu")
	)
	(gr_line
		(start 274.123404 -393.697206)
		(end 279.133554 -393.697206)
		(stroke
			(width 0.635)
			(type default)
		)
		(layer "In14.Cu")
	)
	(gr_line
		(start 274.433792 -392.938762)
		(end 273.33067 -394.041884)
		(stroke
			(width 0.635)
			(type default)
		)
		(layer "In14.Cu")
	)
	(gr_line
		(start 274.433792 -392.938762)
		(end 274.50288 -392.869674)
		(stroke
			(width 0.635)
			(type default)
		)
		(layer "In14.Cu")
	)
	(gr_line
		(start 274.433792 -392.317732)
		(end 274.67052 -392.55446)
		(stroke
			(width 0.635)
			(type default)
		)
		(layer "In14.Cu")
	)
	(gr_line
		(start 274.433792 -384.002788)
		(end 274.433792 -392.938762)
		(stroke
			(width 0.635)
			(type default)
		)
		(layer "In14.Cu")
	)
	(gr_line
		(start 274.433792 -384.002788)
		(end 274.433792 -392.317732)
		(stroke
			(width 0.635)
			(type default)
		)
		(layer "In14.Cu")
	)
	(gr_line
		(start 274.50288 -392.869674)
		(end 279.110694 -392.869674)
		(stroke
			(width 0.635)
			(type default)
		)
		(layer "In14.Cu")
	)
	(gr_line
		(start 274.732496 -393.237466)
		(end 274.433792 -392.938762)
		(stroke
			(width 0.635)
			(type default)
		)
		(layer "In14.Cu")
	)
	(gr_line
		(start 274.778724 -392.605514)
		(end 274.192746 -392.019536)
		(stroke
			(width 0.635)
			(type default)
		)
		(layer "In14.Cu")
	)
	(gr_line
		(start 274.87372 -383.56286)
		(end 274.433792 -384.002788)
		(stroke
			(width 0.635)
			(type default)
		)
		(layer "In14.Cu")
	)
	(gr_circle
		(center 276.112986 -348.704662)
		(end 276.993096 -348.704662)
		(stroke
			(width 0.2)
			(type default)
		)
		(fill no)
		(layer "In14.Cu")
	)
	(gr_line
		(start 276.314916 -440.669934)
		(end 195.50507 -440.669934)
		(stroke
			(width 1.016)
			(type default)
		)
		(layer "In14.Cu")
	)
	(gr_circle
		(center 276.730206 -348.704662)
		(end 277.610316 -348.704662)
		(stroke
			(width 0.2)
			(type default)
		)
		(fill no)
		(layer "In14.Cu")
	)
	(gr_line
		(start 276.815042 -441.4901)
		(end 276.815042 -441.17006)
		(stroke
			(width 1.016)
			(type default)
		)
		(layer "In14.Cu")
	)
	(gr_arc
		(start 276.815042 -441.4901)
		(mid 276.961452 -441.843558)
		(end 277.314914 -441.989972)
		(stroke
			(width 1.016)
			(type default)
		)
		(layer "In14.Cu")
	)
	(gr_arc
		(start 276.815042 -441.17006)
		(mid 276.668558 -440.816418)
		(end 276.314916 -440.669934)
		(stroke
			(width 1.016)
			(type default)
		)
		(layer "In14.Cu")
	)
	(gr_line
		(start 277.323042 -441.481972)
		(end 463.300064 -441.481972)
		(stroke
			(width 0.2)
			(type default)
		)
		(layer "In14.Cu")
	)
	(gr_arc
		(start 277.323042 -441.17006)
		(mid 277.027756 -440.457227)
		(end 276.314916 -440.161934)
		(stroke
			(width 0.2)
			(type default)
		)
		(layer "In14.Cu")
	)
	(gr_line
		(start 277.323042 -441.17006)
		(end 277.323042 -441.481972)
		(stroke
			(width 0.2)
			(type default)
		)
		(layer "In14.Cu")
	)
	(gr_circle
		(center 277.347426 -348.704662)
		(end 278.227536 -348.704662)
		(stroke
			(width 0.2)
			(type default)
		)
		(fill no)
		(layer "In14.Cu")
	)
	(gr_circle
		(center 277.593806 -348.025212)
		(end 278.482806 -348.025212)
		(stroke
			(width 0.2)
			(type default)
		)
		(fill no)
		(layer "In14.Cu")
	)
	(gr_circle
		(center 277.593806 -347.288612)
		(end 278.482806 -347.288612)
		(stroke
			(width 0.2)
			(type default)
		)
		(fill no)
		(layer "In14.Cu")
	)
	(gr_circle
		(center 278.049482 -350.313752)
		(end 278.938482 -350.313752)
		(stroke
			(width 0.2)
			(type default)
		)
		(fill no)
		(layer "In14.Cu")
	)
	(gr_circle
		(center 278.049482 -349.577152)
		(end 278.938482 -349.577152)
		(stroke
			(width 0.2)
			(type default)
		)
		(fill no)
		(layer "In14.Cu")
	)
	(gr_circle
		(center 278.574246 -349.137732)
		(end 279.463246 -349.137732)
		(stroke
			(width 0.2)
			(type default)
		)
		(fill no)
		(layer "In14.Cu")
	)
	(gr_circle
		(center 278.599646 -349.899732)
		(end 279.488646 -349.899732)
		(stroke
			(width 0.2)
			(type default)
		)
		(fill no)
		(layer "In14.Cu")
	)
	(gr_line
		(start 278.892508 -393.237466)
		(end 274.732496 -393.237466)
		(stroke
			(width 0.635)
			(type default)
		)
		(layer "In14.Cu")
	)
	(gr_line
		(start 279.110694 -392.869674)
		(end 279.351994 -392.628374)
		(stroke
			(width 0.635)
			(type default)
		)
		(layer "In14.Cu")
	)
	(gr_circle
		(center 279.133046 -350.255332)
		(end 280.022046 -350.255332)
		(stroke
			(width 0.2)
			(type default)
		)
		(fill no)
		(layer "In14.Cu")
	)
	(gr_circle
		(center 279.133046 -349.518732)
		(end 280.022046 -349.518732)
		(stroke
			(width 0.2)
			(type default)
		)
		(fill no)
		(layer "In14.Cu")
	)
	(gr_circle
		(center 279.133046 -348.782132)
		(end 280.022046 -348.782132)
		(stroke
			(width 0.2)
			(type default)
		)
		(fill no)
		(layer "In14.Cu")
	)
	(gr_line
		(start 279.133554 -393.697206)
		(end 279.983946 -392.846814)
		(stroke
			(width 0.635)
			(type default)
		)
		(layer "In14.Cu")
	)
	(gr_line
		(start 279.329134 -392.605514)
		(end 274.778724 -392.605514)
		(stroke
			(width 0.635)
			(type default)
		)
		(layer "In14.Cu")
	)
	(gr_line
		(start 279.351994 -392.628374)
		(end 279.329134 -392.605514)
		(stroke
			(width 0.635)
			(type default)
		)
		(layer "In14.Cu")
	)
	(gr_line
		(start 279.547066 -394.041884)
		(end 280.477976 -393.110974)
		(stroke
			(width 0.635)
			(type default)
		)
		(layer "In14.Cu")
	)
	(gr_line
		(start 279.616408 -392.513566)
		(end 278.892508 -393.237466)
		(stroke
			(width 0.635)
			(type default)
		)
		(layer "In14.Cu")
	)
	(gr_line
		(start 279.616408 -383.780538)
		(end 279.616408 -392.513566)
		(stroke
			(width 0.635)
			(type default)
		)
		(layer "In14.Cu")
	)
	(gr_line
		(start 279.834086 -383.56286)
		(end 279.616408 -383.780538)
		(stroke
			(width 0.635)
			(type default)
		)
		(layer "In14.Cu")
	)
	(gr_arc
		(start 279.875996 -394.318998)
		(mid 279.756473 -394.238916)
		(end 279.615392 -394.210794)
		(stroke
			(width 0.635)
			(type default)
		)
		(layer "In14.Cu")
	)
	(gr_line
		(start 279.983946 -392.846814)
		(end 279.983946 -383.781046)
		(stroke
			(width 0.635)
			(type default)
		)
		(layer "In14.Cu")
	)
	(gr_line
		(start 279.983946 -383.781046)
		(end 280.202132 -383.56286)
		(stroke
			(width 0.635)
			(type default)
		)
		(layer "In14.Cu")
	)
	(gr_line
		(start 280.202132 -383.56286)
		(end 274.87372 -383.56286)
		(stroke
			(width 0.635)
			(type default)
		)
		(layer "In14.Cu")
	)
	(gr_line
		(start 280.202132 -383.56286)
		(end 279.834086 -383.56286)
		(stroke
			(width 0.635)
			(type default)
		)
		(layer "In14.Cu")
	)
	(gr_line
		(start 280.259536 -394.702538)
		(end 279.875996 -394.318998)
		(stroke
			(width 0.635)
			(type default)
		)
		(layer "In14.Cu")
	)
	(gr_line
		(start 280.36774 -409.10256)
		(end 272.19021 -417.28009)
		(stroke
			(width 0.635)
			(type default)
		)
		(layer "In14.Cu")
	)
	(gr_arc
		(start 280.36774 -394.963142)
		(mid 280.339553 -394.822088)
		(end 280.259536 -394.702538)
		(stroke
			(width 0.635)
			(type default)
		)
		(layer "In14.Cu")
	)
	(gr_line
		(start 280.36774 -394.963142)
		(end 280.36774 -409.10256)
		(stroke
			(width 0.635)
			(type default)
		)
		(layer "In14.Cu")
	)
	(gr_line
		(start 280.477976 -393.110974)
		(end 280.477976 -383.838704)
		(stroke
			(width 0.635)
			(type default)
		)
		(layer "In14.Cu")
	)
	(gr_line
		(start 280.477976 -383.838704)
		(end 280.202132 -383.56286)
		(stroke
			(width 0.635)
			(type default)
		)
		(layer "In14.Cu")
	)
	(gr_line
		(start 280.537412 -392.55446)
		(end 274.67052 -392.55446)
		(stroke
			(width 0.635)
			(type default)
		)
		(layer "In14.Cu")
	)
	(gr_line
		(start 280.537412 -392.55446)
		(end 280.9113 -392.180572)
		(stroke
			(width 0.635)
			(type default)
		)
		(layer "In14.Cu")
	)
	(gr_line
		(start 280.9113 -392.180572)
		(end 280.9113 -384.272028)
		(stroke
			(width 0.635)
			(type default)
		)
		(layer "In14.Cu")
	)
	(gr_line
		(start 280.9113 -384.272028)
		(end 280.202132 -383.56286)
		(stroke
			(width 0.635)
			(type default)
		)
		(layer "In14.Cu")
	)
	(gr_circle
		(center 284.393386 -348.704662)
		(end 285.273496 -348.704662)
		(stroke
			(width 0.2)
			(type default)
		)
		(fill no)
		(layer "In14.Cu")
	)
	(gr_circle
		(center 285.010606 -348.704662)
		(end 285.890716 -348.704662)
		(stroke
			(width 0.2)
			(type default)
		)
		(fill no)
		(layer "In14.Cu")
	)
	(gr_circle
		(center 285.627826 -348.704662)
		(end 286.507936 -348.704662)
		(stroke
			(width 0.2)
			(type default)
		)
		(fill no)
		(layer "In14.Cu")
	)
	(gr_circle
		(center 285.869126 -347.982032)
		(end 286.758126 -347.982032)
		(stroke
			(width 0.2)
			(type default)
		)
		(fill no)
		(layer "In14.Cu")
	)
	(gr_circle
		(center 285.869126 -347.245432)
		(end 286.758126 -347.245432)
		(stroke
			(width 0.2)
			(type default)
		)
		(fill no)
		(layer "In14.Cu")
	)
	(gr_circle
		(center 286.329882 -350.313752)
		(end 287.218882 -350.313752)
		(stroke
			(width 0.2)
			(type default)
		)
		(fill no)
		(layer "In14.Cu")
	)
	(gr_circle
		(center 286.329882 -349.577152)
		(end 287.218882 -349.577152)
		(stroke
			(width 0.2)
			(type default)
		)
		(fill no)
		(layer "In14.Cu")
	)
	(gr_circle
		(center 286.36595 -355.279198)
		(end 287.25495 -355.279198)
		(stroke
			(width 0.2)
			(type default)
		)
		(fill no)
		(layer "In14.Cu")
	)
	(gr_circle
		(center 286.37611 -356.584758)
		(end 287.26511 -356.584758)
		(stroke
			(width 0.2)
			(type default)
		)
		(fill no)
		(layer "In14.Cu")
	)
	(gr_circle
		(center 286.37611 -355.949758)
		(end 287.26511 -355.949758)
		(stroke
			(width 0.2)
			(type default)
		)
		(fill no)
		(layer "In14.Cu")
	)
	(gr_circle
		(center 286.854646 -349.137732)
		(end 287.743646 -349.137732)
		(stroke
			(width 0.2)
			(type default)
		)
		(fill no)
		(layer "In14.Cu")
	)
	(gr_circle
		(center 286.880046 -349.899732)
		(end 287.769046 -349.899732)
		(stroke
			(width 0.2)
			(type default)
		)
		(fill no)
		(layer "In14.Cu")
	)
	(gr_circle
		(center 287.00095 -355.279198)
		(end 287.88995 -355.279198)
		(stroke
			(width 0.2)
			(type default)
		)
		(fill no)
		(layer "In14.Cu")
	)
	(gr_circle
		(center 287.01111 -356.584758)
		(end 287.90011 -356.584758)
		(stroke
			(width 0.2)
			(type default)
		)
		(fill no)
		(layer "In14.Cu")
	)
	(gr_circle
		(center 287.01111 -355.949758)
		(end 287.90011 -355.949758)
		(stroke
			(width 0.2)
			(type default)
		)
		(fill no)
		(layer "In14.Cu")
	)
	(gr_circle
		(center 287.413446 -350.255332)
		(end 288.302446 -350.255332)
		(stroke
			(width 0.2)
			(type default)
		)
		(fill no)
		(layer "In14.Cu")
	)
	(gr_circle
		(center 287.413446 -349.518732)
		(end 288.302446 -349.518732)
		(stroke
			(width 0.2)
			(type default)
		)
		(fill no)
		(layer "In14.Cu")
	)
	(gr_circle
		(center 287.413446 -348.782132)
		(end 288.302446 -348.782132)
		(stroke
			(width 0.2)
			(type default)
		)
		(fill no)
		(layer "In14.Cu")
	)
	(gr_circle
		(center 287.63595 -355.279198)
		(end 288.52495 -355.279198)
		(stroke
			(width 0.2)
			(type default)
		)
		(fill no)
		(layer "In14.Cu")
	)
	(gr_circle
		(center 287.64611 -356.584758)
		(end 288.53511 -356.584758)
		(stroke
			(width 0.2)
			(type default)
		)
		(fill no)
		(layer "In14.Cu")
	)
	(gr_circle
		(center 287.64611 -355.949758)
		(end 288.53511 -355.949758)
		(stroke
			(width 0.2)
			(type default)
		)
		(fill no)
		(layer "In14.Cu")
	)
	(gr_circle
		(center 288.27095 -355.279198)
		(end 289.15995 -355.279198)
		(stroke
			(width 0.2)
			(type default)
		)
		(fill no)
		(layer "In14.Cu")
	)
	(gr_circle
		(center 288.28111 -356.584758)
		(end 289.17011 -356.584758)
		(stroke
			(width 0.2)
			(type default)
		)
		(fill no)
		(layer "In14.Cu")
	)
	(gr_circle
		(center 288.28111 -355.949758)
		(end 289.17011 -355.949758)
		(stroke
			(width 0.2)
			(type default)
		)
		(fill no)
		(layer "In14.Cu")
	)
	(gr_circle
		(center 288.90595 -355.279198)
		(end 289.79495 -355.279198)
		(stroke
			(width 0.2)
			(type default)
		)
		(fill no)
		(layer "In14.Cu")
	)
	(gr_circle
		(center 288.91611 -356.584758)
		(end 289.80511 -356.584758)
		(stroke
			(width 0.2)
			(type default)
		)
		(fill no)
		(layer "In14.Cu")
	)
	(gr_circle
		(center 288.91611 -355.949758)
		(end 289.80511 -355.949758)
		(stroke
			(width 0.2)
			(type default)
		)
		(fill no)
		(layer "In14.Cu")
	)
	(gr_circle
		(center 292.699186 -348.704662)
		(end 293.579296 -348.704662)
		(stroke
			(width 0.2)
			(type default)
		)
		(fill no)
		(layer "In14.Cu")
	)
	(gr_circle
		(center 293.316406 -348.704662)
		(end 294.196516 -348.704662)
		(stroke
			(width 0.2)
			(type default)
		)
		(fill no)
		(layer "In14.Cu")
	)
	(gr_circle
		(center 293.933626 -348.704662)
		(end 294.813736 -348.704662)
		(stroke
			(width 0.2)
			(type default)
		)
		(fill no)
		(layer "In14.Cu")
	)
	(gr_circle
		(center 294.146986 -347.959172)
		(end 295.035986 -347.959172)
		(stroke
			(width 0.2)
			(type default)
		)
		(fill no)
		(layer "In14.Cu")
	)
	(gr_circle
		(center 294.146986 -347.222572)
		(end 295.035986 -347.222572)
		(stroke
			(width 0.2)
			(type default)
		)
		(fill no)
		(layer "In14.Cu")
	)
	(gr_circle
		(center 294.635682 -350.313752)
		(end 295.524682 -350.313752)
		(stroke
			(width 0.2)
			(type default)
		)
		(fill no)
		(layer "In14.Cu")
	)
	(gr_circle
		(center 294.635682 -349.577152)
		(end 295.524682 -349.577152)
		(stroke
			(width 0.2)
			(type default)
		)
		(fill no)
		(layer "In14.Cu")
	)
	(gr_circle
		(center 295.160446 -349.137732)
		(end 296.049446 -349.137732)
		(stroke
			(width 0.2)
			(type default)
		)
		(fill no)
		(layer "In14.Cu")
	)
	(gr_circle
		(center 295.185846 -349.899732)
		(end 296.074846 -349.899732)
		(stroke
			(width 0.2)
			(type default)
		)
		(fill no)
		(layer "In14.Cu")
	)
	(gr_circle
		(center 295.719246 -350.255332)
		(end 296.608246 -350.255332)
		(stroke
			(width 0.2)
			(type default)
		)
		(fill no)
		(layer "In14.Cu")
	)
	(gr_circle
		(center 295.719246 -349.518732)
		(end 296.608246 -349.518732)
		(stroke
			(width 0.2)
			(type default)
		)
		(fill no)
		(layer "In14.Cu")
	)
	(gr_circle
		(center 295.719246 -348.782132)
		(end 296.608246 -348.782132)
		(stroke
			(width 0.2)
			(type default)
		)
		(fill no)
		(layer "In14.Cu")
	)
	(gr_circle
		(center 296.29989 -358.769666)
		(end 297.69689 -358.769666)
		(stroke
			(width 0.2)
			(type default)
		)
		(fill no)
		(layer "In14.Cu")
	)
	(gr_circle
		(center 301.055786 -348.704662)
		(end 301.935896 -348.704662)
		(stroke
			(width 0.2)
			(type default)
		)
		(fill no)
		(layer "In14.Cu")
	)
	(gr_circle
		(center 301.673006 -348.704662)
		(end 302.553116 -348.704662)
		(stroke
			(width 0.2)
			(type default)
		)
		(fill no)
		(layer "In14.Cu")
	)
	(gr_circle
		(center 302.290226 -348.704662)
		(end 303.170336 -348.704662)
		(stroke
			(width 0.2)
			(type default)
		)
		(fill no)
		(layer "In14.Cu")
	)
	(gr_circle
		(center 302.526446 -348.002352)
		(end 303.415446 -348.002352)
		(stroke
			(width 0.2)
			(type default)
		)
		(fill no)
		(layer "In14.Cu")
	)
	(gr_circle
		(center 302.526446 -347.265752)
		(end 303.415446 -347.265752)
		(stroke
			(width 0.2)
			(type default)
		)
		(fill no)
		(layer "In14.Cu")
	)
	(gr_circle
		(center 302.992282 -350.313752)
		(end 303.881282 -350.313752)
		(stroke
			(width 0.2)
			(type default)
		)
		(fill no)
		(layer "In14.Cu")
	)
	(gr_circle
		(center 302.992282 -349.577152)
		(end 303.881282 -349.577152)
		(stroke
			(width 0.2)
			(type default)
		)
		(fill no)
		(layer "In14.Cu")
	)
	(gr_circle
		(center 303.517046 -349.137732)
		(end 304.406046 -349.137732)
		(stroke
			(width 0.2)
			(type default)
		)
		(fill no)
		(layer "In14.Cu")
	)
	(gr_circle
		(center 303.542446 -349.899732)
		(end 304.431446 -349.899732)
		(stroke
			(width 0.2)
			(type default)
		)
		(fill no)
		(layer "In14.Cu")
	)
	(gr_circle
		(center 304.075846 -350.255332)
		(end 304.964846 -350.255332)
		(stroke
			(width 0.2)
			(type default)
		)
		(fill no)
		(layer "In14.Cu")
	)
	(gr_circle
		(center 304.075846 -349.518732)
		(end 304.964846 -349.518732)
		(stroke
			(width 0.2)
			(type default)
		)
		(fill no)
		(layer "In14.Cu")
	)
	(gr_circle
		(center 304.075846 -348.782132)
		(end 304.964846 -348.782132)
		(stroke
			(width 0.2)
			(type default)
		)
		(fill no)
		(layer "In14.Cu")
	)
	(gr_circle
		(center 309.386986 -348.704662)
		(end 310.267096 -348.704662)
		(stroke
			(width 0.2)
			(type default)
		)
		(fill no)
		(layer "In14.Cu")
	)
	(gr_circle
		(center 310.004206 -348.704662)
		(end 310.884316 -348.704662)
		(stroke
			(width 0.2)
			(type default)
		)
		(fill no)
		(layer "In14.Cu")
	)
	(gr_circle
		(center 310.621426 -348.704662)
		(end 311.501536 -348.704662)
		(stroke
			(width 0.2)
			(type default)
		)
		(fill no)
		(layer "In14.Cu")
	)
	(gr_circle
		(center 310.867806 -348.002352)
		(end 311.756806 -348.002352)
		(stroke
			(width 0.2)
			(type default)
		)
		(fill no)
		(layer "In14.Cu")
	)
	(gr_circle
		(center 310.867806 -347.265752)
		(end 311.756806 -347.265752)
		(stroke
			(width 0.2)
			(type default)
		)
		(fill no)
		(layer "In14.Cu")
	)
	(gr_circle
		(center 311.323482 -350.313752)
		(end 312.212482 -350.313752)
		(stroke
			(width 0.2)
			(type default)
		)
		(fill no)
		(layer "In14.Cu")
	)
	(gr_circle
		(center 311.323482 -349.577152)
		(end 312.212482 -349.577152)
		(stroke
			(width 0.2)
			(type default)
		)
		(fill no)
		(layer "In14.Cu")
	)
	(gr_circle
		(center 311.848246 -349.137732)
		(end 312.737246 -349.137732)
		(stroke
			(width 0.2)
			(type default)
		)
		(fill no)
		(layer "In14.Cu")
	)
	(gr_circle
		(center 311.873646 -349.899732)
		(end 312.762646 -349.899732)
		(stroke
			(width 0.2)
			(type default)
		)
		(fill no)
		(layer "In14.Cu")
	)
	(gr_circle
		(center 312.407046 -350.255332)
		(end 313.296046 -350.255332)
		(stroke
			(width 0.2)
			(type default)
		)
		(fill no)
		(layer "In14.Cu")
	)
	(gr_circle
		(center 312.407046 -349.518732)
		(end 313.296046 -349.518732)
		(stroke
			(width 0.2)
			(type default)
		)
		(fill no)
		(layer "In14.Cu")
	)
	(gr_circle
		(center 312.407046 -348.782132)
		(end 313.296046 -348.782132)
		(stroke
			(width 0.2)
			(type default)
		)
		(fill no)
		(layer "In14.Cu")
	)
	(gr_circle
		(center 319.0367 -336.983578)
		(end 319.91681 -336.983578)
		(stroke
			(width 0.2)
			(type default)
		)
		(fill no)
		(layer "In14.Cu")
	)
	(gr_circle
		(center 319.65392 -336.983578)
		(end 320.53403 -336.983578)
		(stroke
			(width 0.2)
			(type default)
		)
		(fill no)
		(layer "In14.Cu")
	)
	(gr_circle
		(center 320.27114 -336.983578)
		(end 321.15125 -336.983578)
		(stroke
			(width 0.2)
			(type default)
		)
		(fill no)
		(layer "In14.Cu")
	)
	(gr_circle
		(center 320.5607 -336.239612)
		(end 321.4497 -336.239612)
		(stroke
			(width 0.2)
			(type default)
		)
		(fill no)
		(layer "In14.Cu")
	)
	(gr_circle
		(center 320.5607 -335.503012)
		(end 321.4497 -335.503012)
		(stroke
			(width 0.2)
			(type default)
		)
		(fill no)
		(layer "In14.Cu")
	)
	(gr_circle
		(center 320.973196 -338.592668)
		(end 321.862196 -338.592668)
		(stroke
			(width 0.2)
			(type default)
		)
		(fill no)
		(layer "In14.Cu")
	)
	(gr_circle
		(center 320.973196 -337.856068)
		(end 321.862196 -337.856068)
		(stroke
			(width 0.2)
			(type default)
		)
		(fill no)
		(layer "In14.Cu")
	)
	(gr_circle
		(center 321.49796 -337.416648)
		(end 322.38696 -337.416648)
		(stroke
			(width 0.2)
			(type default)
		)
		(fill no)
		(layer "In14.Cu")
	)
	(gr_circle
		(center 321.52336 -338.178648)
		(end 322.41236 -338.178648)
		(stroke
			(width 0.2)
			(type default)
		)
		(fill no)
		(layer "In14.Cu")
	)
	(gr_circle
		(center 322.05676 -338.534248)
		(end 322.94576 -338.534248)
		(stroke
			(width 0.2)
			(type default)
		)
		(fill no)
		(layer "In14.Cu")
	)
	(gr_circle
		(center 322.05676 -337.797648)
		(end 322.94576 -337.797648)
		(stroke
			(width 0.2)
			(type default)
		)
		(fill no)
		(layer "In14.Cu")
	)
	(gr_circle
		(center 322.05676 -337.061048)
		(end 322.94576 -337.061048)
		(stroke
			(width 0.2)
			(type default)
		)
		(fill no)
		(layer "In14.Cu")
	)
	(gr_circle
		(center 327.392284 -336.976466)
		(end 328.272394 -336.976466)
		(stroke
			(width 0.2)
			(type default)
		)
		(fill no)
		(layer "In14.Cu")
	)
	(gr_circle
		(center 327.692258 -104.30129)
		(end 328.581258 -104.30129)
		(stroke
			(width 0.2)
			(type default)
		)
		(fill no)
		(layer "In14.Cu")
	)
	(gr_circle
		(center 327.951084 -349.43161)
		(end 329.348084 -349.43161)
		(stroke
			(width 0.2)
			(type default)
		)
		(fill no)
		(layer "In14.Cu")
	)
	(gr_circle
		(center 328.009504 -336.976466)
		(end 328.889614 -336.976466)
		(stroke
			(width 0.2)
			(type default)
		)
		(fill no)
		(layer "In14.Cu")
	)
	(gr_circle
		(center 328.626724 -336.976466)
		(end 329.506834 -336.976466)
		(stroke
			(width 0.2)
			(type default)
		)
		(fill no)
		(layer "In14.Cu")
	)
	(gr_circle
		(center 328.918824 -336.253836)
		(end 329.807824 -336.253836)
		(stroke
			(width 0.2)
			(type default)
		)
		(fill no)
		(layer "In14.Cu")
	)
	(gr_circle
		(center 328.918824 -335.517236)
		(end 329.807824 -335.517236)
		(stroke
			(width 0.2)
			(type default)
		)
		(fill no)
		(layer "In14.Cu")
	)
	(gr_circle
		(center 329.32878 -338.585556)
		(end 330.21778 -338.585556)
		(stroke
			(width 0.2)
			(type default)
		)
		(fill no)
		(layer "In14.Cu")
	)
	(gr_circle
		(center 329.32878 -337.848956)
		(end 330.21778 -337.848956)
		(stroke
			(width 0.2)
			(type default)
		)
		(fill no)
		(layer "In14.Cu")
	)
	(gr_circle
		(center 329.853544 -337.409536)
		(end 330.742544 -337.409536)
		(stroke
			(width 0.2)
			(type default)
		)
		(fill no)
		(layer "In14.Cu")
	)
	(gr_circle
		(center 329.878944 -338.171536)
		(end 330.767944 -338.171536)
		(stroke
			(width 0.2)
			(type default)
		)
		(fill no)
		(layer "In14.Cu")
	)
	(gr_circle
		(center 330.412344 -338.527136)
		(end 331.301344 -338.527136)
		(stroke
			(width 0.2)
			(type default)
		)
		(fill no)
		(layer "In14.Cu")
	)
	(gr_circle
		(center 330.412344 -337.790536)
		(end 331.301344 -337.790536)
		(stroke
			(width 0.2)
			(type default)
		)
		(fill no)
		(layer "In14.Cu")
	)
	(gr_circle
		(center 330.412344 -337.053936)
		(end 331.301344 -337.053936)
		(stroke
			(width 0.2)
			(type default)
		)
		(fill no)
		(layer "In14.Cu")
	)
	(gr_circle
		(center 335.411064 -349.43161)
		(end 336.808064 -349.43161)
		(stroke
			(width 0.2)
			(type default)
		)
		(fill no)
		(layer "In14.Cu")
	)
	(gr_circle
		(center 335.7499 -336.961988)
		(end 336.63001 -336.961988)
		(stroke
			(width 0.2)
			(type default)
		)
		(fill no)
		(layer "In14.Cu")
	)
	(gr_circle
		(center 336.36712 -336.961988)
		(end 337.24723 -336.961988)
		(stroke
			(width 0.2)
			(type default)
		)
		(fill no)
		(layer "In14.Cu")
	)
	(gr_circle
		(center 336.98434 -336.961988)
		(end 337.86445 -336.961988)
		(stroke
			(width 0.2)
			(type default)
		)
		(fill no)
		(layer "In14.Cu")
	)
	(gr_circle
		(center 337.280504 -336.253836)
		(end 338.169504 -336.253836)
		(stroke
			(width 0.2)
			(type default)
		)
		(fill no)
		(layer "In14.Cu")
	)
	(gr_circle
		(center 337.280504 -335.517236)
		(end 338.169504 -335.517236)
		(stroke
			(width 0.2)
			(type default)
		)
		(fill no)
		(layer "In14.Cu")
	)
	(gr_circle
		(center 337.686396 -338.571078)
		(end 338.575396 -338.571078)
		(stroke
			(width 0.2)
			(type default)
		)
		(fill no)
		(layer "In14.Cu")
	)
	(gr_circle
		(center 337.686396 -337.834478)
		(end 338.575396 -337.834478)
		(stroke
			(width 0.2)
			(type default)
		)
		(fill no)
		(layer "In14.Cu")
	)
	(gr_circle
		(center 338.21116 -337.395058)
		(end 339.10016 -337.395058)
		(stroke
			(width 0.2)
			(type default)
		)
		(fill no)
		(layer "In14.Cu")
	)
	(gr_circle
		(center 338.23656 -338.157058)
		(end 339.12556 -338.157058)
		(stroke
			(width 0.2)
			(type default)
		)
		(fill no)
		(layer "In14.Cu")
	)
	(gr_circle
		(center 338.76996 -338.512658)
		(end 339.65896 -338.512658)
		(stroke
			(width 0.2)
			(type default)
		)
		(fill no)
		(layer "In14.Cu")
	)
	(gr_circle
		(center 338.76996 -337.776058)
		(end 339.65896 -337.776058)
		(stroke
			(width 0.2)
			(type default)
		)
		(fill no)
		(layer "In14.Cu")
	)
	(gr_circle
		(center 338.76996 -337.039458)
		(end 339.65896 -337.039458)
		(stroke
			(width 0.2)
			(type default)
		)
		(fill no)
		(layer "In14.Cu")
	)
	(gr_circle
		(center 339.73897 -352.973132)
		(end 340.62797 -352.973132)
		(stroke
			(width 0.2)
			(type default)
		)
		(fill no)
		(layer "In14.Cu")
	)
	(gr_circle
		(center 339.739224 -352.215196)
		(end 340.628224 -352.215196)
		(stroke
			(width 0.2)
			(type default)
		)
		(fill no)
		(layer "In14.Cu")
	)
	(gr_circle
		(center 339.739224 -351.453196)
		(end 340.628224 -351.453196)
		(stroke
			(width 0.2)
			(type default)
		)
		(fill no)
		(layer "In14.Cu")
	)
	(gr_circle
		(center 340.501224 -352.215196)
		(end 341.390224 -352.215196)
		(stroke
			(width 0.2)
			(type default)
		)
		(fill no)
		(layer "In14.Cu")
	)
	(gr_circle
		(center 340.501224 -351.453196)
		(end 341.390224 -351.453196)
		(stroke
			(width 0.2)
			(type default)
		)
		(fill no)
		(layer "In14.Cu")
	)
	(gr_circle
		(center 340.667848 -353.010216)
		(end 341.556848 -353.010216)
		(stroke
			(width 0.2)
			(type default)
		)
		(fill no)
		(layer "In14.Cu")
	)
	(gr_circle
		(center 341.263224 -352.215196)
		(end 342.152224 -352.215196)
		(stroke
			(width 0.2)
			(type default)
		)
		(fill no)
		(layer "In14.Cu")
	)
	(gr_circle
		(center 341.263224 -351.453196)
		(end 342.152224 -351.453196)
		(stroke
			(width 0.2)
			(type default)
		)
		(fill no)
		(layer "In14.Cu")
	)
	(gr_circle
		(center 341.302848 -353.010216)
		(end 342.191848 -353.010216)
		(stroke
			(width 0.2)
			(type default)
		)
		(fill no)
		(layer "In14.Cu")
	)
	(gr_circle
		(center 341.937848 -353.010216)
		(end 342.826848 -353.010216)
		(stroke
			(width 0.2)
			(type default)
		)
		(fill no)
		(layer "In14.Cu")
	)
	(gr_circle
		(center 342.025224 -352.215196)
		(end 342.914224 -352.215196)
		(stroke
			(width 0.2)
			(type default)
		)
		(fill no)
		(layer "In14.Cu")
	)
	(gr_circle
		(center 342.025224 -351.453196)
		(end 342.914224 -351.453196)
		(stroke
			(width 0.2)
			(type default)
		)
		(fill no)
		(layer "In14.Cu")
	)
	(gr_circle
		(center 342.572848 -353.010216)
		(end 343.461848 -353.010216)
		(stroke
			(width 0.2)
			(type default)
		)
		(fill no)
		(layer "In14.Cu")
	)
	(gr_circle
		(center 342.787224 -352.215196)
		(end 343.676224 -352.215196)
		(stroke
			(width 0.2)
			(type default)
		)
		(fill no)
		(layer "In14.Cu")
	)
	(gr_circle
		(center 342.787224 -351.453196)
		(end 343.676224 -351.453196)
		(stroke
			(width 0.2)
			(type default)
		)
		(fill no)
		(layer "In14.Cu")
	)
	(gr_circle
		(center 343.46515 -353.006152)
		(end 344.35415 -353.006152)
		(stroke
			(width 0.2)
			(type default)
		)
		(fill no)
		(layer "In14.Cu")
	)
	(gr_circle
		(center 343.465404 -352.248216)
		(end 344.354404 -352.248216)
		(stroke
			(width 0.2)
			(type default)
		)
		(fill no)
		(layer "In14.Cu")
	)
	(gr_circle
		(center 343.465404 -351.486216)
		(end 344.354404 -351.486216)
		(stroke
			(width 0.2)
			(type default)
		)
		(fill no)
		(layer "In14.Cu")
	)
	(gr_circle
		(center 344.016838 -159.073596)
		(end 344.905838 -159.073596)
		(stroke
			(width 0.2)
			(type default)
		)
		(fill no)
		(layer "In14.Cu")
	)
	(gr_circle
		(center 344.016838 -158.336996)
		(end 344.905838 -158.336996)
		(stroke
			(width 0.2)
			(type default)
		)
		(fill no)
		(layer "In14.Cu")
	)
	(gr_circle
		(center 344.016838 -157.600396)
		(end 344.905838 -157.600396)
		(stroke
			(width 0.2)
			(type default)
		)
		(fill no)
		(layer "In14.Cu")
	)
	(gr_circle
		(center 344.0811 -337.012788)
		(end 344.96121 -337.012788)
		(stroke
			(width 0.2)
			(type default)
		)
		(fill no)
		(layer "In14.Cu")
	)
	(gr_circle
		(center 344.550238 -157.955996)
		(end 345.439238 -157.955996)
		(stroke
			(width 0.2)
			(type default)
		)
		(fill no)
		(layer "In14.Cu")
	)
	(gr_circle
		(center 344.575638 -158.717996)
		(end 345.464638 -158.717996)
		(stroke
			(width 0.2)
			(type default)
		)
		(fill no)
		(layer "In14.Cu")
	)
	(gr_circle
		(center 344.69832 -337.012788)
		(end 345.57843 -337.012788)
		(stroke
			(width 0.2)
			(type default)
		)
		(fill no)
		(layer "In14.Cu")
	)
	(gr_circle
		(center 345.100402 -158.278576)
		(end 345.989402 -158.278576)
		(stroke
			(width 0.2)
			(type default)
		)
		(fill no)
		(layer "In14.Cu")
	)
	(gr_circle
		(center 345.100402 -157.541976)
		(end 345.989402 -157.541976)
		(stroke
			(width 0.2)
			(type default)
		)
		(fill no)
		(layer "In14.Cu")
	)
	(gr_circle
		(center 345.31554 -337.012788)
		(end 346.19565 -337.012788)
		(stroke
			(width 0.2)
			(type default)
		)
		(fill no)
		(layer "In14.Cu")
	)
	(gr_circle
		(center 345.623896 -336.317336)
		(end 346.512896 -336.317336)
		(stroke
			(width 0.2)
			(type default)
		)
		(fill no)
		(layer "In14.Cu")
	)
	(gr_circle
		(center 345.623896 -335.580736)
		(end 346.512896 -335.580736)
		(stroke
			(width 0.2)
			(type default)
		)
		(fill no)
		(layer "In14.Cu")
	)
	(gr_circle
		(center 345.684856 -160.633156)
		(end 346.573856 -160.633156)
		(stroke
			(width 0.2)
			(type default)
		)
		(fill no)
		(layer "In14.Cu")
	)
	(gr_circle
		(center 345.684856 -159.896556)
		(end 346.573856 -159.896556)
		(stroke
			(width 0.2)
			(type default)
		)
		(fill no)
		(layer "In14.Cu")
	)
	(gr_circle
		(center 345.802458 -159.151066)
		(end 346.682568 -159.151066)
		(stroke
			(width 0.2)
			(type default)
		)
		(fill no)
		(layer "In14.Cu")
	)
	(gr_circle
		(center 346.017596 -339.358478)
		(end 346.906596 -339.358478)
		(stroke
			(width 0.2)
			(type default)
		)
		(fill no)
		(layer "In14.Cu")
	)
	(gr_circle
		(center 346.017596 -338.621878)
		(end 346.906596 -338.621878)
		(stroke
			(width 0.2)
			(type default)
		)
		(fill no)
		(layer "In14.Cu")
	)
	(gr_circle
		(center 346.017596 -337.885278)
		(end 346.906596 -337.885278)
		(stroke
			(width 0.2)
			(type default)
		)
		(fill no)
		(layer "In14.Cu")
	)
	(gr_circle
		(center 346.419678 -159.151066)
		(end 347.299788 -159.151066)
		(stroke
			(width 0.2)
			(type default)
		)
		(fill no)
		(layer "In14.Cu")
	)
	(gr_circle
		(center 346.54236 -337.445858)
		(end 347.43136 -337.445858)
		(stroke
			(width 0.2)
			(type default)
		)
		(fill no)
		(layer "In14.Cu")
	)
	(gr_circle
		(center 346.56776 -339.731858)
		(end 347.45676 -339.731858)
		(stroke
			(width 0.2)
			(type default)
		)
		(fill no)
		(layer "In14.Cu")
	)
	(gr_circle
		(center 346.56776 -338.969858)
		(end 347.45676 -338.969858)
		(stroke
			(width 0.2)
			(type default)
		)
		(fill no)
		(layer "In14.Cu")
	)
	(gr_circle
		(center 346.56776 -338.207858)
		(end 347.45676 -338.207858)
		(stroke
			(width 0.2)
			(type default)
		)
		(fill no)
		(layer "In14.Cu")
	)
	(gr_circle
		(center 347.036898 -159.151066)
		(end 347.917008 -159.151066)
		(stroke
			(width 0.2)
			(type default)
		)
		(fill no)
		(layer "In14.Cu")
	)
	(gr_circle
		(center 352.322638 -167.430196)
		(end 353.211638 -167.430196)
		(stroke
			(width 0.2)
			(type default)
		)
		(fill no)
		(layer "In14.Cu")
	)
	(gr_circle
		(center 352.322638 -166.693596)
		(end 353.211638 -166.693596)
		(stroke
			(width 0.2)
			(type default)
		)
		(fill no)
		(layer "In14.Cu")
	)
	(gr_circle
		(center 352.322638 -165.956996)
		(end 353.211638 -165.956996)
		(stroke
			(width 0.2)
			(type default)
		)
		(fill no)
		(layer "In14.Cu")
	)
	(gr_circle
		(center 352.356928 -341.922862)
		(end 353.237038 -341.922862)
		(stroke
			(width 0.2)
			(type default)
		)
		(fill no)
		(layer "In14.Cu")
	)
	(gr_circle
		(center 352.856038 -166.312596)
		(end 353.745038 -166.312596)
		(stroke
			(width 0.2)
			(type default)
		)
		(fill no)
		(layer "In14.Cu")
	)
	(gr_circle
		(center 352.881438 -167.074596)
		(end 353.770438 -167.074596)
		(stroke
			(width 0.2)
			(type default)
		)
		(fill no)
		(layer "In14.Cu")
	)
	(gr_circle
		(center 352.974148 -341.922862)
		(end 353.854258 -341.922862)
		(stroke
			(width 0.2)
			(type default)
		)
		(fill no)
		(layer "In14.Cu")
	)
	(gr_circle
		(center 353.406202 -166.635176)
		(end 354.295202 -166.635176)
		(stroke
			(width 0.2)
			(type default)
		)
		(fill no)
		(layer "In14.Cu")
	)
	(gr_circle
		(center 353.406202 -165.898576)
		(end 354.295202 -165.898576)
		(stroke
			(width 0.2)
			(type default)
		)
		(fill no)
		(layer "In14.Cu")
	)
	(gr_circle
		(center 353.591368 -341.922862)
		(end 354.471478 -341.922862)
		(stroke
			(width 0.2)
			(type default)
		)
		(fill no)
		(layer "In14.Cu")
	)
	(gr_circle
		(center 353.899724 -341.22741)
		(end 354.788724 -341.22741)
		(stroke
			(width 0.2)
			(type default)
		)
		(fill no)
		(layer "In14.Cu")
	)
	(gr_circle
		(center 353.899724 -340.49081)
		(end 354.788724 -340.49081)
		(stroke
			(width 0.2)
			(type default)
		)
		(fill no)
		(layer "In14.Cu")
	)
	(gr_circle
		(center 353.990656 -168.982136)
		(end 354.879656 -168.982136)
		(stroke
			(width 0.2)
			(type default)
		)
		(fill no)
		(layer "In14.Cu")
	)
	(gr_circle
		(center 353.990656 -168.245536)
		(end 354.879656 -168.245536)
		(stroke
			(width 0.2)
			(type default)
		)
		(fill no)
		(layer "In14.Cu")
	)
	(gr_circle
		(center 354.108258 -167.507666)
		(end 354.988368 -167.507666)
		(stroke
			(width 0.2)
			(type default)
		)
		(fill no)
		(layer "In14.Cu")
	)
	(gr_circle
		(center 354.293424 -343.531952)
		(end 355.182424 -343.531952)
		(stroke
			(width 0.2)
			(type default)
		)
		(fill no)
		(layer "In14.Cu")
	)
	(gr_circle
		(center 354.293424 -342.795352)
		(end 355.182424 -342.795352)
		(stroke
			(width 0.2)
			(type default)
		)
		(fill no)
		(layer "In14.Cu")
	)
	(gr_circle
		(center 354.725478 -167.507666)
		(end 355.605588 -167.507666)
		(stroke
			(width 0.2)
			(type default)
		)
		(fill no)
		(layer "In14.Cu")
	)
	(gr_circle
		(center 354.818188 -342.355932)
		(end 355.707188 -342.355932)
		(stroke
			(width 0.2)
			(type default)
		)
		(fill no)
		(layer "In14.Cu")
	)
	(gr_circle
		(center 354.843588 -343.117932)
		(end 355.732588 -343.117932)
		(stroke
			(width 0.2)
			(type default)
		)
		(fill no)
		(layer "In14.Cu")
	)
	(gr_circle
		(center 355.342698 -167.507666)
		(end 356.222808 -167.507666)
		(stroke
			(width 0.2)
			(type default)
		)
		(fill no)
		(layer "In14.Cu")
	)
	(gr_circle
		(center 355.376988 -343.473532)
		(end 356.265988 -343.473532)
		(stroke
			(width 0.2)
			(type default)
		)
		(fill no)
		(layer "In14.Cu")
	)
	(gr_circle
		(center 355.376988 -342.736932)
		(end 356.265988 -342.736932)
		(stroke
			(width 0.2)
			(type default)
		)
		(fill no)
		(layer "In14.Cu")
	)
	(gr_circle
		(center 355.376988 -342.000332)
		(end 356.265988 -342.000332)
		(stroke
			(width 0.2)
			(type default)
		)
		(fill no)
		(layer "In14.Cu")
	)
	(gr_circle
		(center 359.58526 -152.71242)
		(end 360.98226 -152.71242)
		(stroke
			(width 0.2)
			(type default)
		)
		(fill no)
		(layer "In14.Cu")
	)
	(gr_circle
		(center 360.603038 -175.705516)
		(end 361.492038 -175.705516)
		(stroke
			(width 0.2)
			(type default)
		)
		(fill no)
		(layer "In14.Cu")
	)
	(gr_circle
		(center 360.603038 -174.968916)
		(end 361.492038 -174.968916)
		(stroke
			(width 0.2)
			(type default)
		)
		(fill no)
		(layer "In14.Cu")
	)
	(gr_circle
		(center 360.603038 -174.232316)
		(end 361.492038 -174.232316)
		(stroke
			(width 0.2)
			(type default)
		)
		(fill no)
		(layer "In14.Cu")
	)
	(gr_circle
		(center 361.136438 -174.587916)
		(end 362.025438 -174.587916)
		(stroke
			(width 0.2)
			(type default)
		)
		(fill no)
		(layer "In14.Cu")
	)
	(gr_circle
		(center 361.161838 -175.349916)
		(end 362.050838 -175.349916)
		(stroke
			(width 0.2)
			(type default)
		)
		(fill no)
		(layer "In14.Cu")
	)
	(gr_circle
		(center 361.686602 -174.910496)
		(end 362.575602 -174.910496)
		(stroke
			(width 0.2)
			(type default)
		)
		(fill no)
		(layer "In14.Cu")
	)
	(gr_circle
		(center 361.686602 -174.173896)
		(end 362.575602 -174.173896)
		(stroke
			(width 0.2)
			(type default)
		)
		(fill no)
		(layer "In14.Cu")
	)
	(gr_circle
		(center 362.271056 -177.254916)
		(end 363.160056 -177.254916)
		(stroke
			(width 0.2)
			(type default)
		)
		(fill no)
		(layer "In14.Cu")
	)
	(gr_circle
		(center 362.271056 -176.518316)
		(end 363.160056 -176.518316)
		(stroke
			(width 0.2)
			(type default)
		)
		(fill no)
		(layer "In14.Cu")
	)
	(gr_circle
		(center 362.396278 -175.859186)
		(end 363.276388 -175.859186)
		(stroke
			(width 0.2)
			(type default)
		)
		(fill no)
		(layer "In14.Cu")
	)
	(gr_circle
		(center 363.013498 -175.859186)
		(end 363.893608 -175.859186)
		(stroke
			(width 0.2)
			(type default)
		)
		(fill no)
		(layer "In14.Cu")
	)
	(gr_circle
		(center 363.630718 -175.859186)
		(end 364.510828 -175.859186)
		(stroke
			(width 0.2)
			(type default)
		)
		(fill no)
		(layer "In14.Cu")
	)
	(gr_circle
		(center 366.744504 -164.53358)
		(end 367.633504 -164.53358)
		(stroke
			(width 0.2)
			(type default)
		)
		(fill no)
		(layer "In14.Cu")
	)
	(gr_circle
		(center 366.744504 -163.89858)
		(end 367.633504 -163.89858)
		(stroke
			(width 0.2)
			(type default)
		)
		(fill no)
		(layer "In14.Cu")
	)
	(gr_circle
		(center 366.757204 -165.19398)
		(end 367.646204 -165.19398)
		(stroke
			(width 0.2)
			(type default)
		)
		(fill no)
		(layer "In14.Cu")
	)
	(gr_circle
		(center 367.379504 -164.53358)
		(end 368.268504 -164.53358)
		(stroke
			(width 0.2)
			(type default)
		)
		(fill no)
		(layer "In14.Cu")
	)
	(gr_circle
		(center 367.379504 -163.89858)
		(end 368.268504 -163.89858)
		(stroke
			(width 0.2)
			(type default)
		)
		(fill no)
		(layer "In14.Cu")
	)
	(gr_circle
		(center 367.392204 -165.19398)
		(end 368.281204 -165.19398)
		(stroke
			(width 0.2)
			(type default)
		)
		(fill no)
		(layer "In14.Cu")
	)
	(gr_circle
		(center 368.044984 -164.53358)
		(end 368.933984 -164.53358)
		(stroke
			(width 0.2)
			(type default)
		)
		(fill no)
		(layer "In14.Cu")
	)
	(gr_circle
		(center 368.044984 -163.89858)
		(end 368.933984 -163.89858)
		(stroke
			(width 0.2)
			(type default)
		)
		(fill no)
		(layer "In14.Cu")
	)
	(gr_circle
		(center 368.057684 -165.19398)
		(end 368.946684 -165.19398)
		(stroke
			(width 0.2)
			(type default)
		)
		(fill no)
		(layer "In14.Cu")
	)
	(gr_circle
		(center 368.679984 -164.53358)
		(end 369.568984 -164.53358)
		(stroke
			(width 0.2)
			(type default)
		)
		(fill no)
		(layer "In14.Cu")
	)
	(gr_circle
		(center 368.679984 -163.89858)
		(end 369.568984 -163.89858)
		(stroke
			(width 0.2)
			(type default)
		)
		(fill no)
		(layer "In14.Cu")
	)
	(gr_circle
		(center 368.692684 -165.19398)
		(end 369.581684 -165.19398)
		(stroke
			(width 0.2)
			(type default)
		)
		(fill no)
		(layer "In14.Cu")
	)
	(gr_circle
		(center 368.96421 -179.204874)
		(end 369.85321 -179.204874)
		(stroke
			(width 0.2)
			(type default)
		)
		(fill no)
		(layer "In14.Cu")
	)
	(gr_circle
		(center 369.314984 -164.53358)
		(end 370.203984 -164.53358)
		(stroke
			(width 0.2)
			(type default)
		)
		(fill no)
		(layer "In14.Cu")
	)
	(gr_circle
		(center 369.314984 -163.89858)
		(end 370.203984 -163.89858)
		(stroke
			(width 0.2)
			(type default)
		)
		(fill no)
		(layer "In14.Cu")
	)
	(gr_circle
		(center 369.327684 -165.19398)
		(end 370.216684 -165.19398)
		(stroke
			(width 0.2)
			(type default)
		)
		(fill no)
		(layer "In14.Cu")
	)
	(gr_circle
		(center 369.49761 -179.560474)
		(end 370.38661 -179.560474)
		(stroke
			(width 0.2)
			(type default)
		)
		(fill no)
		(layer "In14.Cu")
	)
	(gr_circle
		(center 369.49761 -178.798474)
		(end 370.38661 -178.798474)
		(stroke
			(width 0.2)
			(type default)
		)
		(fill no)
		(layer "In14.Cu")
	)
	(gr_circle
		(center 369.49761 -178.036474)
		(end 370.38661 -178.036474)
		(stroke
			(width 0.2)
			(type default)
		)
		(fill no)
		(layer "In14.Cu")
	)
	(gr_circle
		(center 369.52301 -180.322474)
		(end 370.41201 -180.322474)
		(stroke
			(width 0.2)
			(type default)
		)
		(fill no)
		(layer "In14.Cu")
	)
	(gr_circle
		(center 369.949984 -164.53358)
		(end 370.838984 -164.53358)
		(stroke
			(width 0.2)
			(type default)
		)
		(fill no)
		(layer "In14.Cu")
	)
	(gr_circle
		(center 369.949984 -163.89858)
		(end 370.838984 -163.89858)
		(stroke
			(width 0.2)
			(type default)
		)
		(fill no)
		(layer "In14.Cu")
	)
	(gr_circle
		(center 369.962684 -165.19398)
		(end 370.851684 -165.19398)
		(stroke
			(width 0.2)
			(type default)
		)
		(fill no)
		(layer "In14.Cu")
	)
	(gr_circle
		(center 370.047774 -179.883054)
		(end 370.936774 -179.883054)
		(stroke
			(width 0.2)
			(type default)
		)
		(fill no)
		(layer "In14.Cu")
	)
	(gr_circle
		(center 370.047774 -179.146454)
		(end 370.936774 -179.146454)
		(stroke
			(width 0.2)
			(type default)
		)
		(fill no)
		(layer "In14.Cu")
	)
	(gr_circle
		(center 370.529358 -182.141876)
		(end 371.418358 -182.141876)
		(stroke
			(width 0.2)
			(type default)
		)
		(fill no)
		(layer "In14.Cu")
	)
	(gr_circle
		(center 370.529358 -181.405276)
		(end 371.418358 -181.405276)
		(stroke
			(width 0.2)
			(type default)
		)
		(fill no)
		(layer "In14.Cu")
	)
	(gr_circle
		(center 370.686584 -164.53358)
		(end 371.575584 -164.53358)
		(stroke
			(width 0.2)
			(type default)
		)
		(fill no)
		(layer "In14.Cu")
	)
	(gr_circle
		(center 370.686584 -163.89858)
		(end 371.575584 -163.89858)
		(stroke
			(width 0.2)
			(type default)
		)
		(fill no)
		(layer "In14.Cu")
	)
	(gr_circle
		(center 370.699284 -165.19398)
		(end 371.588284 -165.19398)
		(stroke
			(width 0.2)
			(type default)
		)
		(fill no)
		(layer "In14.Cu")
	)
	(gr_circle
		(center 370.74221 -180.803804)
		(end 371.62232 -180.803804)
		(stroke
			(width 0.2)
			(type default)
		)
		(fill no)
		(layer "In14.Cu")
	)
	(gr_circle
		(center 371.35943 -180.803804)
		(end 372.23954 -180.803804)
		(stroke
			(width 0.2)
			(type default)
		)
		(fill no)
		(layer "In14.Cu")
	)
	(gr_circle
		(center 371.97665 -180.803804)
		(end 372.85676 -180.803804)
		(stroke
			(width 0.2)
			(type default)
		)
		(fill no)
		(layer "In14.Cu")
	)
	(gr_circle
		(center 377.367038 -180.678074)
		(end 378.256038 -180.678074)
		(stroke
			(width 0.2)
			(type default)
		)
		(fill no)
		(layer "In14.Cu")
	)
	(gr_circle
		(center 377.367038 -179.941474)
		(end 378.256038 -179.941474)
		(stroke
			(width 0.2)
			(type default)
		)
		(fill no)
		(layer "In14.Cu")
	)
	(gr_circle
		(center 377.367038 -179.204874)
		(end 378.256038 -179.204874)
		(stroke
			(width 0.2)
			(type default)
		)
		(fill no)
		(layer "In14.Cu")
	)
	(gr_circle
		(center 377.869958 -162.59683)
		(end 379.266958 -162.59683)
		(stroke
			(width 0.2)
			(type default)
		)
		(fill no)
		(layer "In14.Cu")
	)
	(gr_circle
		(center 377.900438 -179.560474)
		(end 378.789438 -179.560474)
		(stroke
			(width 0.2)
			(type default)
		)
		(fill no)
		(layer "In14.Cu")
	)
	(gr_circle
		(center 377.925838 -180.322474)
		(end 378.814838 -180.322474)
		(stroke
			(width 0.2)
			(type default)
		)
		(fill no)
		(layer "In14.Cu")
	)
	(gr_circle
		(center 378.450602 -179.883054)
		(end 379.339602 -179.883054)
		(stroke
			(width 0.2)
			(type default)
		)
		(fill no)
		(layer "In14.Cu")
	)
	(gr_circle
		(center 378.450602 -179.146454)
		(end 379.339602 -179.146454)
		(stroke
			(width 0.2)
			(type default)
		)
		(fill no)
		(layer "In14.Cu")
	)
	(gr_circle
		(center 379.035056 -182.230776)
		(end 379.924056 -182.230776)
		(stroke
			(width 0.2)
			(type default)
		)
		(fill no)
		(layer "In14.Cu")
	)
	(gr_circle
		(center 379.035056 -181.494176)
		(end 379.924056 -181.494176)
		(stroke
			(width 0.2)
			(type default)
		)
		(fill no)
		(layer "In14.Cu")
	)
	(gr_circle
		(center 379.152658 -180.755544)
		(end 380.032768 -180.755544)
		(stroke
			(width 0.2)
			(type default)
		)
		(fill no)
		(layer "In14.Cu")
	)
	(gr_circle
		(center 379.769878 -180.755544)
		(end 380.649988 -180.755544)
		(stroke
			(width 0.2)
			(type default)
		)
		(fill no)
		(layer "In14.Cu")
	)
	(gr_circle
		(center 380.387098 -180.755544)
		(end 381.267208 -180.755544)
		(stroke
			(width 0.2)
			(type default)
		)
		(fill no)
		(layer "In14.Cu")
	)
	(gr_arc
		(start 383.601976 -9.272016)
		(mid 384.656976 -8.83502)
		(end 385.093972 -7.78002)
		(stroke
			(width 0.2)
			(type default)
		)
		(layer "In14.Cu")
	)
	(gr_line
		(start 385.093972 -7.78002)
		(end 385.093972 0.40005)
		(stroke
			(width 0.2)
			(type default)
		)
		(layer "In14.Cu")
	)
	(gr_line
		(start 385.601972 -12.288012)
		(end 260.800088 -12.288012)
		(stroke
			(width 0.2)
			(type default)
		)
		(layer "In14.Cu")
	)
	(gr_arc
		(start 385.601972 -12.288012)
		(mid 387.375417 -11.553448)
		(end 388.109968 -9.780016)
		(stroke
			(width 0.2)
			(type default)
		)
		(layer "In14.Cu")
	)
	(gr_arc
		(start 385.601972 -11.780012)
		(mid 387.016183 -11.194227)
		(end 387.601968 -9.780016)
		(stroke
			(width 1.016)
			(type default)
		)
		(layer "In14.Cu")
	)
	(gr_circle
		(center 385.698238 -180.678074)
		(end 386.587238 -180.678074)
		(stroke
			(width 0.2)
			(type default)
		)
		(fill no)
		(layer "In14.Cu")
	)
	(gr_circle
		(center 385.698238 -179.941474)
		(end 386.587238 -179.941474)
		(stroke
			(width 0.2)
			(type default)
		)
		(fill no)
		(layer "In14.Cu")
	)
	(gr_circle
		(center 385.698238 -179.204874)
		(end 386.587238 -179.204874)
		(stroke
			(width 0.2)
			(type default)
		)
		(fill no)
		(layer "In14.Cu")
	)
	(gr_circle
		(center 386.231638 -179.560474)
		(end 387.120638 -179.560474)
		(stroke
			(width 0.2)
			(type default)
		)
		(fill no)
		(layer "In14.Cu")
	)
	(gr_circle
		(center 386.257038 -180.322474)
		(end 387.146038 -180.322474)
		(stroke
			(width 0.2)
			(type default)
		)
		(fill no)
		(layer "In14.Cu")
	)
	(gr_circle
		(center 386.781802 -179.883054)
		(end 387.670802 -179.883054)
		(stroke
			(width 0.2)
			(type default)
		)
		(fill no)
		(layer "In14.Cu")
	)
	(gr_circle
		(center 386.781802 -179.146454)
		(end 387.670802 -179.146454)
		(stroke
			(width 0.2)
			(type default)
		)
		(fill no)
		(layer "In14.Cu")
	)
	(gr_circle
		(center 387.206998 -162.65271)
		(end 388.603998 -162.65271)
		(stroke
			(width 0.2)
			(type default)
		)
		(fill no)
		(layer "In14.Cu")
	)
	(gr_circle
		(center 387.293358 -157.001972)
		(end 388.182358 -157.001972)
		(stroke
			(width 0.2)
			(type default)
		)
		(fill no)
		(layer "In14.Cu")
	)
	(gr_circle
		(center 387.293358 -156.366972)
		(end 388.182358 -156.366972)
		(stroke
			(width 0.2)
			(type default)
		)
		(fill no)
		(layer "In14.Cu")
	)
	(gr_circle
		(center 387.293358 -155.724352)
		(end 388.182358 -155.724352)
		(stroke
			(width 0.2)
			(type default)
		)
		(fill no)
		(layer "In14.Cu")
	)
	(gr_circle
		(center 387.293358 -155.089352)
		(end 388.182358 -155.089352)
		(stroke
			(width 0.2)
			(type default)
		)
		(fill no)
		(layer "In14.Cu")
	)
	(gr_circle
		(center 387.293358 -154.428952)
		(end 388.182358 -154.428952)
		(stroke
			(width 0.2)
			(type default)
		)
		(fill no)
		(layer "In14.Cu")
	)
	(gr_circle
		(center 387.293358 -153.793952)
		(end 388.182358 -153.793952)
		(stroke
			(width 0.2)
			(type default)
		)
		(fill no)
		(layer "In14.Cu")
	)
	(gr_circle
		(center 387.366256 -182.230776)
		(end 388.255256 -182.230776)
		(stroke
			(width 0.2)
			(type default)
		)
		(fill no)
		(layer "In14.Cu")
	)
	(gr_circle
		(center 387.366256 -181.494176)
		(end 388.255256 -181.494176)
		(stroke
			(width 0.2)
			(type default)
		)
		(fill no)
		(layer "In14.Cu")
	)
	(gr_circle
		(center 387.483858 -180.755544)
		(end 388.363968 -180.755544)
		(stroke
			(width 0.2)
			(type default)
		)
		(fill no)
		(layer "In14.Cu")
	)
	(gr_line
		(start 387.601968 -9.780016)
		(end 387.601968 -0.500126)
		(stroke
			(width 1.016)
			(type default)
		)
		(layer "In14.Cu")
	)
	(gr_arc
		(start 387.601968 2.908046)
		(mid 385.828585 2.173457)
		(end 385.093972 0.40005)
		(stroke
			(width 0.2)
			(type default)
		)
		(layer "In14.Cu")
	)
	(gr_line
		(start 387.601968 2.908046)
		(end 456.202034 2.908046)
		(stroke
			(width 0.2)
			(type default)
		)
		(layer "In14.Cu")
	)
	(gr_circle
		(center 387.928358 -157.001972)
		(end 388.817358 -157.001972)
		(stroke
			(width 0.2)
			(type default)
		)
		(fill no)
		(layer "In14.Cu")
	)
	(gr_circle
		(center 387.928358 -156.366972)
		(end 388.817358 -156.366972)
		(stroke
			(width 0.2)
			(type default)
		)
		(fill no)
		(layer "In14.Cu")
	)
	(gr_circle
		(center 387.928358 -155.724352)
		(end 388.817358 -155.724352)
		(stroke
			(width 0.2)
			(type default)
		)
		(fill no)
		(layer "In14.Cu")
	)
	(gr_circle
		(center 387.928358 -155.089352)
		(end 388.817358 -155.089352)
		(stroke
			(width 0.2)
			(type default)
		)
		(fill no)
		(layer "In14.Cu")
	)
	(gr_circle
		(center 387.928358 -154.428952)
		(end 388.817358 -154.428952)
		(stroke
			(width 0.2)
			(type default)
		)
		(fill no)
		(layer "In14.Cu")
	)
	(gr_circle
		(center 387.928358 -153.793952)
		(end 388.817358 -153.793952)
		(stroke
			(width 0.2)
			(type default)
		)
		(fill no)
		(layer "In14.Cu")
	)
	(gr_circle
		(center 388.101078 -180.755544)
		(end 388.981188 -180.755544)
		(stroke
			(width 0.2)
			(type default)
		)
		(fill no)
		(layer "In14.Cu")
	)
	(gr_arc
		(start 388.102094 0)
		(mid 387.748465 -0.146487)
		(end 387.601968 -0.500126)
		(stroke
			(width 1.016)
			(type default)
		)
		(layer "In14.Cu")
	)
	(gr_line
		(start 388.102094 0)
		(end 455.701908 0)
		(stroke
			(width 1.016)
			(type default)
		)
		(layer "In14.Cu")
	)
	(gr_line
		(start 388.109968 -0.508)
		(end 388.109968 -9.780016)
		(stroke
			(width 0.2)
			(type default)
		)
		(layer "In14.Cu")
	)
	(gr_circle
		(center 388.718298 -180.755544)
		(end 389.598408 -180.755544)
		(stroke
			(width 0.2)
			(type default)
		)
		(fill no)
		(layer "In14.Cu")
	)
	(gr_circle
		(center 394.628878 -173.21911)
		(end 395.517878 -173.21911)
		(stroke
			(width 0.2)
			(type default)
		)
		(fill no)
		(layer "In14.Cu")
	)
	(gr_circle
		(center 394.628878 -172.45711)
		(end 395.517878 -172.45711)
		(stroke
			(width 0.2)
			(type default)
		)
		(fill no)
		(layer "In14.Cu")
	)
	(gr_circle
		(center 394.646658 -173.987714)
		(end 395.535658 -173.987714)
		(stroke
			(width 0.2)
			(type default)
		)
		(fill no)
		(layer "In14.Cu")
	)
	(gr_circle
		(center 394.672058 -174.749714)
		(end 395.561058 -174.749714)
		(stroke
			(width 0.2)
			(type default)
		)
		(fill no)
		(layer "In14.Cu")
	)
	(gr_circle
		(center 395.196822 -174.310294)
		(end 396.085822 -174.310294)
		(stroke
			(width 0.2)
			(type default)
		)
		(fill no)
		(layer "In14.Cu")
	)
	(gr_circle
		(center 395.196822 -173.573694)
		(end 396.085822 -173.573694)
		(stroke
			(width 0.2)
			(type default)
		)
		(fill no)
		(layer "In14.Cu")
	)
	(gr_circle
		(center 395.230858 -172.819314)
		(end 396.119858 -172.819314)
		(stroke
			(width 0.2)
			(type default)
		)
		(fill no)
		(layer "In14.Cu")
	)
	(gr_circle
		(center 395.781276 -176.657254)
		(end 396.670276 -176.657254)
		(stroke
			(width 0.2)
			(type default)
		)
		(fill no)
		(layer "In14.Cu")
	)
	(gr_circle
		(center 395.781276 -175.895254)
		(end 396.670276 -175.895254)
		(stroke
			(width 0.2)
			(type default)
		)
		(fill no)
		(layer "In14.Cu")
	)
	(gr_circle
		(center 395.898878 -175.182784)
		(end 396.778988 -175.182784)
		(stroke
			(width 0.2)
			(type default)
		)
		(fill no)
		(layer "In14.Cu")
	)
	(gr_circle
		(center 396.516098 -175.182784)
		(end 397.396208 -175.182784)
		(stroke
			(width 0.2)
			(type default)
		)
		(fill no)
		(layer "In14.Cu")
	)
	(gr_circle
		(center 397.133318 -175.182784)
		(end 398.013428 -175.182784)
		(stroke
			(width 0.2)
			(type default)
		)
		(fill no)
		(layer "In14.Cu")
	)
	(gr_circle
		(center 399.165064 -81.051146)
		(end 400.054064 -81.051146)
		(stroke
			(width 0.2)
			(type default)
		)
		(fill no)
		(layer "In14.Cu")
	)
	(gr_circle
		(center 402.436838 -166.527988)
		(end 403.325838 -166.527988)
		(stroke
			(width 0.2)
			(type default)
		)
		(fill no)
		(layer "In14.Cu")
	)
	(gr_circle
		(center 402.436838 -165.791388)
		(end 403.325838 -165.791388)
		(stroke
			(width 0.2)
			(type default)
		)
		(fill no)
		(layer "In14.Cu")
	)
	(gr_circle
		(center 402.436838 -165.054788)
		(end 403.325838 -165.054788)
		(stroke
			(width 0.2)
			(type default)
		)
		(fill no)
		(layer "In14.Cu")
	)
	(gr_circle
		(center 402.970238 -165.410388)
		(end 403.859238 -165.410388)
		(stroke
			(width 0.2)
			(type default)
		)
		(fill no)
		(layer "In14.Cu")
	)
	(gr_circle
		(center 402.995638 -166.172388)
		(end 403.884638 -166.172388)
		(stroke
			(width 0.2)
			(type default)
		)
		(fill no)
		(layer "In14.Cu")
	)
	(gr_circle
		(center 403.520402 -165.732968)
		(end 404.409402 -165.732968)
		(stroke
			(width 0.2)
			(type default)
		)
		(fill no)
		(layer "In14.Cu")
	)
	(gr_circle
		(center 403.520402 -164.996368)
		(end 404.409402 -164.996368)
		(stroke
			(width 0.2)
			(type default)
		)
		(fill no)
		(layer "In14.Cu")
	)
	(gr_circle
		(center 404.104856 -168.082214)
		(end 404.993856 -168.082214)
		(stroke
			(width 0.2)
			(type default)
		)
		(fill no)
		(layer "In14.Cu")
	)
	(gr_circle
		(center 404.104856 -167.320214)
		(end 404.993856 -167.320214)
		(stroke
			(width 0.2)
			(type default)
		)
		(fill no)
		(layer "In14.Cu")
	)
	(gr_circle
		(center 404.222458 -166.605458)
		(end 405.102568 -166.605458)
		(stroke
			(width 0.2)
			(type default)
		)
		(fill no)
		(layer "In14.Cu")
	)
	(gr_circle
		(center 404.839678 -166.605458)
		(end 405.719788 -166.605458)
		(stroke
			(width 0.2)
			(type default)
		)
		(fill no)
		(layer "In14.Cu")
	)
	(gr_circle
		(center 405.456898 -166.605458)
		(end 406.337008 -166.605458)
		(stroke
			(width 0.2)
			(type default)
		)
		(fill no)
		(layer "In14.Cu")
	)
	(gr_circle
		(center 410.818838 -161.701988)
		(end 411.707838 -161.701988)
		(stroke
			(width 0.2)
			(type default)
		)
		(fill no)
		(layer "In14.Cu")
	)
	(gr_circle
		(center 410.818838 -160.965388)
		(end 411.707838 -160.965388)
		(stroke
			(width 0.2)
			(type default)
		)
		(fill no)
		(layer "In14.Cu")
	)
	(gr_circle
		(center 410.818838 -160.228788)
		(end 411.707838 -160.228788)
		(stroke
			(width 0.2)
			(type default)
		)
		(fill no)
		(layer "In14.Cu")
	)
	(gr_circle
		(center 411.352238 -160.584388)
		(end 412.241238 -160.584388)
		(stroke
			(width 0.2)
			(type default)
		)
		(fill no)
		(layer "In14.Cu")
	)
	(gr_circle
		(center 411.377638 -161.346388)
		(end 412.266638 -161.346388)
		(stroke
			(width 0.2)
			(type default)
		)
		(fill no)
		(layer "In14.Cu")
	)
	(gr_circle
		(center 411.902402 -160.906968)
		(end 412.791402 -160.906968)
		(stroke
			(width 0.2)
			(type default)
		)
		(fill no)
		(layer "In14.Cu")
	)
	(gr_circle
		(center 411.902402 -160.170368)
		(end 412.791402 -160.170368)
		(stroke
			(width 0.2)
			(type default)
		)
		(fill no)
		(layer "In14.Cu")
	)
	(gr_circle
		(center 412.486856 -163.256214)
		(end 413.375856 -163.256214)
		(stroke
			(width 0.2)
			(type default)
		)
		(fill no)
		(layer "In14.Cu")
	)
	(gr_circle
		(center 412.486856 -162.494214)
		(end 413.375856 -162.494214)
		(stroke
			(width 0.2)
			(type default)
		)
		(fill no)
		(layer "In14.Cu")
	)
	(gr_circle
		(center 412.604458 -161.779458)
		(end 413.484568 -161.779458)
		(stroke
			(width 0.2)
			(type default)
		)
		(fill no)
		(layer "In14.Cu")
	)
	(gr_circle
		(center 413.221678 -161.779458)
		(end 414.101788 -161.779458)
		(stroke
			(width 0.2)
			(type default)
		)
		(fill no)
		(layer "In14.Cu")
	)
	(gr_circle
		(center 413.838898 -161.779458)
		(end 414.719008 -161.779458)
		(stroke
			(width 0.2)
			(type default)
		)
		(fill no)
		(layer "In14.Cu")
	)
	(gr_circle
		(center 424.33494 -353.10318)
		(end 425.21505 -353.10318)
		(stroke
			(width 0.2)
			(type default)
		)
		(fill no)
		(layer "In14.Cu")
	)
	(gr_circle
		(center 424.95216 -353.10318)
		(end 425.83227 -353.10318)
		(stroke
			(width 0.2)
			(type default)
		)
		(fill no)
		(layer "In14.Cu")
	)
	(gr_circle
		(center 425.56938 -353.10318)
		(end 426.44949 -353.10318)
		(stroke
			(width 0.2)
			(type default)
		)
		(fill no)
		(layer "In14.Cu")
	)
	(gr_circle
		(center 425.686474 -352.35769)
		(end 426.575474 -352.35769)
		(stroke
			(width 0.2)
			(type default)
		)
		(fill no)
		(layer "In14.Cu")
	)
	(gr_circle
		(center 425.686474 -351.62109)
		(end 426.575474 -351.62109)
		(stroke
			(width 0.2)
			(type default)
		)
		(fill no)
		(layer "In14.Cu")
	)
	(gr_circle
		(center 426.271436 -354.71227)
		(end 427.160436 -354.71227)
		(stroke
			(width 0.2)
			(type default)
		)
		(fill no)
		(layer "In14.Cu")
	)
	(gr_circle
		(center 426.271436 -353.97567)
		(end 427.160436 -353.97567)
		(stroke
			(width 0.2)
			(type default)
		)
		(fill no)
		(layer "In14.Cu")
	)
	(gr_circle
		(center 426.7962 -353.53625)
		(end 427.6852 -353.53625)
		(stroke
			(width 0.2)
			(type default)
		)
		(fill no)
		(layer "In14.Cu")
	)
	(gr_circle
		(center 426.8216 -354.29825)
		(end 427.7106 -354.29825)
		(stroke
			(width 0.2)
			(type default)
		)
		(fill no)
		(layer "In14.Cu")
	)
	(gr_circle
		(center 427.355 -354.65385)
		(end 428.244 -354.65385)
		(stroke
			(width 0.2)
			(type default)
		)
		(fill no)
		(layer "In14.Cu")
	)
	(gr_circle
		(center 427.355 -353.91725)
		(end 428.244 -353.91725)
		(stroke
			(width 0.2)
			(type default)
		)
		(fill no)
		(layer "In14.Cu")
	)
	(gr_circle
		(center 427.355 -353.18065)
		(end 428.244 -353.18065)
		(stroke
			(width 0.2)
			(type default)
		)
		(fill no)
		(layer "In14.Cu")
	)
	(gr_circle
		(center 432.01336 -361.827826)
		(end 433.41036 -361.827826)
		(stroke
			(width 0.2)
			(type default)
		)
		(fill no)
		(layer "In14.Cu")
	)
	(gr_circle
		(center 432.661568 -353.12858)
		(end 433.541678 -353.12858)
		(stroke
			(width 0.2)
			(type default)
		)
		(fill no)
		(layer "In14.Cu")
	)
	(gr_circle
		(center 433.278788 -353.12858)
		(end 434.158898 -353.12858)
		(stroke
			(width 0.2)
			(type default)
		)
		(fill no)
		(layer "In14.Cu")
	)
	(gr_circle
		(center 433.896008 -353.12858)
		(end 434.776118 -353.12858)
		(stroke
			(width 0.2)
			(type default)
		)
		(fill no)
		(layer "In14.Cu")
	)
	(gr_circle
		(center 434.013102 -352.38309)
		(end 434.902102 -352.38309)
		(stroke
			(width 0.2)
			(type default)
		)
		(fill no)
		(layer "In14.Cu")
	)
	(gr_circle
		(center 434.013102 -351.64649)
		(end 434.902102 -351.64649)
		(stroke
			(width 0.2)
			(type default)
		)
		(fill no)
		(layer "In14.Cu")
	)
	(gr_circle
		(center 434.598064 -354.73767)
		(end 435.487064 -354.73767)
		(stroke
			(width 0.2)
			(type default)
		)
		(fill no)
		(layer "In14.Cu")
	)
	(gr_circle
		(center 434.598064 -354.00107)
		(end 435.487064 -354.00107)
		(stroke
			(width 0.2)
			(type default)
		)
		(fill no)
		(layer "In14.Cu")
	)
	(gr_circle
		(center 435.122828 -353.56165)
		(end 436.011828 -353.56165)
		(stroke
			(width 0.2)
			(type default)
		)
		(fill no)
		(layer "In14.Cu")
	)
	(gr_circle
		(center 435.148228 -354.32365)
		(end 436.037228 -354.32365)
		(stroke
			(width 0.2)
			(type default)
		)
		(fill no)
		(layer "In14.Cu")
	)
	(gr_circle
		(center 435.469538 -361.496102)
		(end 436.358538 -361.496102)
		(stroke
			(width 0.2)
			(type default)
		)
		(fill no)
		(layer "In14.Cu")
	)
	(gr_circle
		(center 435.469538 -360.734102)
		(end 436.358538 -360.734102)
		(stroke
			(width 0.2)
			(type default)
		)
		(fill no)
		(layer "In14.Cu")
	)
	(gr_circle
		(center 435.469538 -359.972102)
		(end 436.358538 -359.972102)
		(stroke
			(width 0.2)
			(type default)
		)
		(fill no)
		(layer "In14.Cu")
	)
	(gr_circle
		(center 435.681628 -354.67925)
		(end 436.570628 -354.67925)
		(stroke
			(width 0.2)
			(type default)
		)
		(fill no)
		(layer "In14.Cu")
	)
	(gr_circle
		(center 435.681628 -353.94265)
		(end 436.570628 -353.94265)
		(stroke
			(width 0.2)
			(type default)
		)
		(fill no)
		(layer "In14.Cu")
	)
	(gr_circle
		(center 435.681628 -353.20605)
		(end 436.570628 -353.20605)
		(stroke
			(width 0.2)
			(type default)
		)
		(fill no)
		(layer "In14.Cu")
	)
	(gr_circle
		(center 436.231538 -361.496102)
		(end 437.120538 -361.496102)
		(stroke
			(width 0.2)
			(type default)
		)
		(fill no)
		(layer "In14.Cu")
	)
	(gr_circle
		(center 436.231538 -360.734102)
		(end 437.120538 -360.734102)
		(stroke
			(width 0.2)
			(type default)
		)
		(fill no)
		(layer "In14.Cu")
	)
	(gr_circle
		(center 436.231538 -359.972102)
		(end 437.120538 -359.972102)
		(stroke
			(width 0.2)
			(type default)
		)
		(fill no)
		(layer "In14.Cu")
	)
	(gr_circle
		(center 437.703214 -12.400788)
		(end 438.592214 -12.400788)
		(stroke
			(width 0.2)
			(type default)
		)
		(fill no)
		(layer "In14.Cu")
	)
	(gr_circle
		(center 438.06999 -13.069316)
		(end 438.95899 -13.069316)
		(stroke
			(width 0.2)
			(type default)
		)
		(fill no)
		(layer "In14.Cu")
	)
	(gr_circle
		(center 438.592214 -12.400788)
		(end 439.481214 -12.400788)
		(stroke
			(width 0.2)
			(type default)
		)
		(fill no)
		(layer "In14.Cu")
	)
	(gr_circle
		(center 438.71515 -13.061696)
		(end 439.60415 -13.061696)
		(stroke
			(width 0.2)
			(type default)
		)
		(fill no)
		(layer "In14.Cu")
	)
	(gr_circle
		(center 439.39333 -13.043916)
		(end 440.28233 -13.043916)
		(stroke
			(width 0.2)
			(type default)
		)
		(fill no)
		(layer "In14.Cu")
	)
	(gr_circle
		(center 439.481214 -12.400788)
		(end 440.370214 -12.400788)
		(stroke
			(width 0.2)
			(type default)
		)
		(fill no)
		(layer "In14.Cu")
	)
	(gr_circle
		(center 440.945524 -11.261852)
		(end 441.834524 -11.261852)
		(stroke
			(width 0.2)
			(type default)
		)
		(fill no)
		(layer "In14.Cu")
	)
	(gr_circle
		(center 440.945524 -10.626852)
		(end 441.834524 -10.626852)
		(stroke
			(width 0.2)
			(type default)
		)
		(fill no)
		(layer "In14.Cu")
	)
	(gr_circle
		(center 441.129674 -25.982422)
		(end 442.018674 -25.982422)
		(stroke
			(width 0.2)
			(type default)
		)
		(fill no)
		(layer "In14.Cu")
	)
	(gr_circle
		(center 441.354718 -20.73656)
		(end 442.243718 -20.73656)
		(stroke
			(width 0.2)
			(type default)
		)
		(fill no)
		(layer "In14.Cu")
	)
	(gr_circle
		(center 441.354718 -20.10156)
		(end 442.243718 -20.10156)
		(stroke
			(width 0.2)
			(type default)
		)
		(fill no)
		(layer "In14.Cu")
	)
	(gr_circle
		(center 441.354718 -19.21256)
		(end 442.243718 -19.21256)
		(stroke
			(width 0.2)
			(type default)
		)
		(fill no)
		(layer "In14.Cu")
	)
	(gr_circle
		(center 441.354718 -18.57756)
		(end 442.243718 -18.57756)
		(stroke
			(width 0.2)
			(type default)
		)
		(fill no)
		(layer "In14.Cu")
	)
	(gr_circle
		(center 441.475622 -14.123162)
		(end 442.364622 -14.123162)
		(stroke
			(width 0.2)
			(type default)
		)
		(fill no)
		(layer "In14.Cu")
	)
	(gr_circle
		(center 441.475622 -13.488162)
		(end 442.364622 -13.488162)
		(stroke
			(width 0.2)
			(type default)
		)
		(fill no)
		(layer "In14.Cu")
	)
	(gr_circle
		(center 441.56249 -25.461976)
		(end 442.45149 -25.461976)
		(stroke
			(width 0.2)
			(type default)
		)
		(fill no)
		(layer "In14.Cu")
	)
	(gr_circle
		(center 442.018674 -25.982422)
		(end 442.907674 -25.982422)
		(stroke
			(width 0.2)
			(type default)
		)
		(fill no)
		(layer "In14.Cu")
	)
	(gr_circle
		(center 442.371734 -20.983702)
		(end 443.260734 -20.983702)
		(stroke
			(width 0.2)
			(type default)
		)
		(fill no)
		(layer "In14.Cu")
	)
	(gr_circle
		(center 442.371734 -20.348702)
		(end 443.260734 -20.348702)
		(stroke
			(width 0.2)
			(type default)
		)
		(fill no)
		(layer "In14.Cu")
	)
	(gr_circle
		(center 442.371734 -19.459702)
		(end 443.260734 -19.459702)
		(stroke
			(width 0.2)
			(type default)
		)
		(fill no)
		(layer "In14.Cu")
	)
	(gr_circle
		(center 442.371734 -18.824702)
		(end 443.260734 -18.824702)
		(stroke
			(width 0.2)
			(type default)
		)
		(fill no)
		(layer "In14.Cu")
	)
	(gr_circle
		(center 442.45149 -25.461976)
		(end 443.34049 -25.461976)
		(stroke
			(width 0.2)
			(type default)
		)
		(fill no)
		(layer "In14.Cu")
	)
	(gr_circle
		(center 442.907674 -25.982422)
		(end 443.796674 -25.982422)
		(stroke
			(width 0.2)
			(type default)
		)
		(fill no)
		(layer "In14.Cu")
	)
	(gr_circle
		(center 443.34049 -25.461976)
		(end 444.22949 -25.461976)
		(stroke
			(width 0.2)
			(type default)
		)
		(fill no)
		(layer "In14.Cu")
	)
	(gr_circle
		(center 444.166244 -24.741632)
		(end 445.055244 -24.741632)
		(stroke
			(width 0.2)
			(type default)
		)
		(fill no)
		(layer "In14.Cu")
	)
	(gr_circle
		(center 450.669914 -14.526514)
		(end 451.558914 -14.526514)
		(stroke
			(width 0.2)
			(type default)
		)
		(fill no)
		(layer "In14.Cu")
	)
	(gr_circle
		(center 450.670676 -16.010382)
		(end 451.559676 -16.010382)
		(stroke
			(width 0.2)
			(type default)
		)
		(fill no)
		(layer "In14.Cu")
	)
	(gr_circle
		(center 450.670676 -15.273782)
		(end 451.559676 -15.273782)
		(stroke
			(width 0.2)
			(type default)
		)
		(fill no)
		(layer "In14.Cu")
	)
	(gr_circle
		(center 452.054976 -18.535142)
		(end 452.943976 -18.535142)
		(stroke
			(width 0.2)
			(type default)
		)
		(fill no)
		(layer "In14.Cu")
	)
	(gr_circle
		(center 452.054976 -17.798542)
		(end 452.943976 -17.798542)
		(stroke
			(width 0.2)
			(type default)
		)
		(fill no)
		(layer "In14.Cu")
	)
	(gr_line
		(start 455.694034 -9.780016)
		(end 455.694034 -0.508)
		(stroke
			(width 0.2)
			(type default)
		)
		(layer "In14.Cu")
	)
	(gr_arc
		(start 455.694034 -9.780016)
		(mid 456.428616 -11.553416)
		(end 458.20203 -12.288012)
		(stroke
			(width 0.2)
			(type default)
		)
		(layer "In14.Cu")
	)
	(gr_line
		(start 455.694034 -0.508)
		(end 388.109968 -0.508)
		(stroke
			(width 0.2)
			(type default)
		)
		(layer "In14.Cu")
	)
	(gr_arc
		(start 456.202034 -9.780016)
		(mid 456.787819 -11.194227)
		(end 458.20203 -11.780012)
		(stroke
			(width 1.016)
			(type default)
		)
		(layer "In14.Cu")
	)
	(gr_arc
		(start 456.202034 -0.500126)
		(mid 456.05556 -0.146464)
		(end 455.701908 0)
		(stroke
			(width 1.016)
			(type default)
		)
		(layer "In14.Cu")
	)
	(gr_line
		(start 456.202034 -0.500126)
		(end 456.202034 -9.780016)
		(stroke
			(width 1.016)
			(type default)
		)
		(layer "In14.Cu")
	)
	(gr_line
		(start 458.20203 -11.780012)
		(end 469.799924 -11.780012)
		(stroke
			(width 1.016)
			(type default)
		)
		(layer "In14.Cu")
	)
	(gr_arc
		(start 458.71003 -7.78002)
		(mid 459.147026 -8.83502)
		(end 460.202026 -9.272016)
		(stroke
			(width 0.2)
			(type default)
		)
		(layer "In14.Cu")
	)
	(gr_arc
		(start 458.71003 0.40005)
		(mid 457.975475 2.173515)
		(end 456.202034 2.908046)
		(stroke
			(width 0.2)
			(type default)
		)
		(layer "In14.Cu")
	)
	(gr_line
		(start 458.71003 0.40005)
		(end 458.71003 -7.78002)
		(stroke
			(width 0.2)
			(type default)
		)
		(layer "In14.Cu")
	)
	(gr_line
		(start 460.202026 -9.272016)
		(end 464.439 -9.272016)
		(stroke
			(width 0.2)
			(type default)
		)
		(layer "In14.Cu")
	)
	(gr_line
		(start 463.300064 -441.989972)
		(end 277.314914 -441.989972)
		(stroke
			(width 1.016)
			(type default)
		)
		(layer "In14.Cu")
	)
	(gr_arc
		(start 463.300064 -441.989972)
		(mid 464.71429 -441.404198)
		(end 465.30006 -439.989976)
		(stroke
			(width 1.016)
			(type default)
		)
		(layer "In14.Cu")
	)
	(gr_arc
		(start 463.300064 -441.481972)
		(mid 464.355064 -441.044976)
		(end 464.79206 -439.989976)
		(stroke
			(width 0.2)
			(type default)
		)
		(layer "In14.Cu")
	)
	(gr_line
		(start 464.439 -12.288012)
		(end 458.20203 -12.288012)
		(stroke
			(width 0.2)
			(type default)
		)
		(layer "In14.Cu")
	)
	(gr_line
		(start 464.439 -9.272016)
		(end 464.439 -12.288012)
		(stroke
			(width 0.2)
			(type default)
		)
		(layer "In14.Cu")
	)
	(gr_line
		(start 464.447636 -12.288012)
		(end 464.447636 -9.272016)
		(stroke
			(width 0.2)
			(type default)
		)
		(layer "In14.Cu")
	)
	(gr_line
		(start 464.447636 -9.272016)
		(end 469.799924 -9.272016)
		(stroke
			(width 0.2)
			(type default)
		)
		(layer "In14.Cu")
	)
	(gr_line
		(start 464.79206 -439.989976)
		(end 464.79206 -418.46881)
		(stroke
			(width 0.2)
			(type default)
		)
		(layer "In14.Cu")
	)
	(gr_line
		(start 464.79206 -418.46881)
		(end 467.808056 -418.46881)
		(stroke
			(width 0.2)
			(type default)
		)
		(layer "In14.Cu")
	)
	(gr_line
		(start 464.79206 -418.45738)
		(end 464.79206 -409.528264)
		(stroke
			(width 0.2)
			(type default)
		)
		(layer "In14.Cu")
	)
	(gr_line
		(start 465.30006 -409.528518)
		(end 465.30006 -439.989976)
		(stroke
			(width 1.016)
			(type default)
		)
		(layer "In14.Cu")
	)
	(gr_arc
		(start 465.526628 -407.75509)
		(mid 464.983024 -408.568632)
		(end 464.79206 -409.528264)
		(stroke
			(width 0.2)
			(type default)
		)
		(layer "In14.Cu")
	)
	(gr_line
		(start 465.526628 -407.75509)
		(end 467.355174 -405.926544)
		(stroke
			(width 0.2)
			(type default)
		)
		(layer "In14.Cu")
	)
	(gr_arc
		(start 465.885784 -408.114246)
		(mid 465.452221 -408.76312)
		(end 465.30006 -409.528518)
		(stroke
			(width 1.016)
			(type default)
		)
		(layer "In14.Cu")
	)
	(gr_arc
		(start 467.355174 -405.926544)
		(mid 467.678507 -405.442687)
		(end 467.792054 -404.871936)
		(stroke
			(width 0.2)
			(type default)
		)
		(layer "In14.Cu")
	)
	(gr_line
		(start 467.71433 -406.2857)
		(end 465.885784 -408.114246)
		(stroke
			(width 1.016)
			(type default)
		)
		(layer "In14.Cu")
	)
	(gr_arc
		(start 467.71433 -406.2857)
		(mid 468.147828 -405.636947)
		(end 468.300054 -404.871682)
		(stroke
			(width 1.016)
			(type default)
		)
		(layer "In14.Cu")
	)
	(gr_line
		(start 467.792054 -404.871936)
		(end 467.792054 -82.82813)
		(stroke
			(width 0.2)
			(type default)
		)
		(layer "In14.Cu")
	)
	(gr_arc
		(start 467.808056 -439.989976)
		(mid 468.245052 -441.044976)
		(end 469.300052 -441.481972)
		(stroke
			(width 0.2)
			(type default)
		)
		(layer "In14.Cu")
	)
	(gr_line
		(start 467.808056 -418.46881)
		(end 467.808056 -439.989976)
		(stroke
			(width 0.2)
			(type default)
		)
		(layer "In14.Cu")
	)
	(gr_line
		(start 467.808056 -418.45738)
		(end 464.79206 -418.45738)
		(stroke
			(width 0.2)
			(type default)
		)
		(layer "In14.Cu")
	)
	(gr_line
		(start 467.808056 -410.356812)
		(end 467.808056 -418.45738)
		(stroke
			(width 0.2)
			(type default)
		)
		(layer "In14.Cu")
	)
	(gr_arc
		(start 468.244936 -409.30195)
		(mid 467.921608 -409.785939)
		(end 467.808056 -410.356812)
		(stroke
			(width 0.2)
			(type default)
		)
		(layer "In14.Cu")
	)
	(gr_line
		(start 468.300054 -82.828384)
		(end 468.300054 -404.871682)
		(stroke
			(width 1.016)
			(type default)
		)
		(layer "In14.Cu")
	)
	(gr_arc
		(start 468.526622 -81.054956)
		(mid 467.983009 -81.868496)
		(end 467.792054 -82.82813)
		(stroke
			(width 0.2)
			(type default)
		)
		(layer "In14.Cu")
	)
	(gr_line
		(start 468.526622 -81.054956)
		(end 470.85504 -78.726538)
		(stroke
			(width 0.2)
			(type default)
		)
		(layer "In14.Cu")
	)
	(gr_arc
		(start 468.885778 -81.414112)
		(mid 468.452215 -82.062986)
		(end 468.300054 -82.828384)
		(stroke
			(width 1.016)
			(type default)
		)
		(layer "In14.Cu")
	)
	(gr_line
		(start 469.300052 -441.481972)
		(end 471.79992 -441.481972)
		(stroke
			(width 0.2)
			(type default)
		)
		(layer "In14.Cu")
	)
	(gr_line
		(start 469.487758 -408.059128)
		(end 468.244936 -409.30195)
		(stroke
			(width 0.2)
			(type default)
		)
		(layer "In14.Cu")
	)
	(gr_arc
		(start 469.487758 -408.059128)
		(mid 470.464844 -406.596826)
		(end 470.80805 -404.871936)
		(stroke
			(width 0.2)
			(type default)
		)
		(layer "In14.Cu")
	)
	(gr_line
		(start 469.799924 -12.288012)
		(end 464.447636 -12.288012)
		(stroke
			(width 0.2)
			(type default)
		)
		(layer "In14.Cu")
	)
	(gr_arc
		(start 469.799924 -9.272016)
		(mid 470.854924 -8.83502)
		(end 471.29192 -7.78002)
		(stroke
			(width 0.2)
			(type default)
		)
		(layer "In14.Cu")
	)
	(gr_line
		(start 469.799924 11.892026)
		(end 1.999996 11.892026)
		(stroke
			(width 0.2)
			(type default)
		)
		(layer "In14.Cu")
	)
	(gr_line
		(start 470.80805 -83.656678)
		(end 470.80805 -404.871936)
		(stroke
			(width 0.2)
			(type default)
		)
		(layer "In14.Cu")
	)
	(gr_arc
		(start 470.85504 -78.726538)
		(mid 471.178373 -78.242681)
		(end 471.29192 -77.67193)
		(stroke
			(width 0.2)
			(type default)
		)
		(layer "In14.Cu")
	)
	(gr_line
		(start 471.214196 -79.085694)
		(end 468.885778 -81.414112)
		(stroke
			(width 1.016)
			(type default)
		)
		(layer "In14.Cu")
	)
	(gr_arc
		(start 471.214196 -79.085694)
		(mid 471.6477 -78.436942)
		(end 471.79992 -77.671676)
		(stroke
			(width 1.016)
			(type default)
		)
		(layer "In14.Cu")
	)
	(gr_arc
		(start 471.245184 -82.601562)
		(mid 470.921671 -83.085639)
		(end 470.80805 -83.656678)
		(stroke
			(width 0.2)
			(type default)
		)
		(layer "In14.Cu")
	)
	(gr_line
		(start 471.29192 -77.67193)
		(end 471.29192 -13.780008)
		(stroke
			(width 0.2)
			(type default)
		)
		(layer "In14.Cu")
	)
	(gr_arc
		(start 471.29192 -13.780008)
		(mid 470.854924 -12.725008)
		(end 469.799924 -12.288012)
		(stroke
			(width 0.2)
			(type default)
		)
		(layer "In14.Cu")
	)
	(gr_line
		(start 471.29192 -7.78002)
		(end 471.29192 10.40003)
		(stroke
			(width 0.2)
			(type default)
		)
		(layer "In14.Cu")
	)
	(gr_arc
		(start 471.29192 10.40003)
		(mid 470.854924 11.45503)
		(end 469.799924 11.892026)
		(stroke
			(width 0.2)
			(type default)
		)
		(layer "In14.Cu")
	)
	(gr_arc
		(start 471.79992 -13.780008)
		(mid 471.214139 -12.365784)
		(end 469.799924 -11.780012)
		(stroke
			(width 1.016)
			(type default)
		)
		(layer "In14.Cu")
	)
	(gr_line
		(start 471.79992 -13.780008)
		(end 471.79992 -77.671676)
		(stroke
			(width 1.016)
			(type default)
		)
		(layer "In14.Cu")
	)
	(gr_line
		(start 472.987624 -80.859122)
		(end 471.245184 -82.601562)
		(stroke
			(width 0.2)
			(type default)
		)
		(layer "In14.Cu")
	)
	(gr_arc
		(start 472.987624 -80.859122)
		(mid 473.964715 -79.396821)
		(end 474.307916 -77.67193)
		(stroke
			(width 0.2)
			(type default)
		)
		(layer "In14.Cu")
	)
	(gr_arc
		(start 474.307916 -461.028288)
		(mid 474.744912 -462.083288)
		(end 475.799912 -462.520284)
		(stroke
			(width 0.2)
			(type default)
		)
		(layer "In14.Cu")
	)
	(gr_arc
		(start 474.307916 -443.989968)
		(mid 473.573331 -442.216561)
		(end 471.79992 -441.481972)
		(stroke
			(width 0.2)
			(type default)
		)
		(layer "In14.Cu")
	)
	(gr_line
		(start 474.307916 -443.989968)
		(end 474.307916 -461.028288)
		(stroke
			(width 0.2)
			(type default)
		)
		(layer "In14.Cu")
	)
	(gr_line
		(start 474.307916 10.40003)
		(end 474.307916 -77.67193)
		(stroke
			(width 0.2)
			(type default)
		)
		(layer "In14.Cu")
	)
	(gr_line
		(start 475.799912 -462.520284)
		(end 531.7998 -462.520284)
		(stroke
			(width 0.2)
			(type default)
		)
		(layer "In14.Cu")
	)
	(gr_arc
		(start 475.799912 11.892026)
		(mid 474.744912 11.45503)
		(end 474.307916 10.40003)
		(stroke
			(width 0.2)
			(type default)
		)
		(layer "In14.Cu")
	)
	(gr_line
		(start 513.5118 -451.028308)
		(end 513.5118 -312.408316)
		(stroke
			(width 0.2)
			(type default)
		)
		(layer "In14.Cu")
	)
	(gr_arc
		(start 513.5118 -451.028308)
		(mid 514.246378 -452.801725)
		(end 516.019796 -453.536304)
		(stroke
			(width 0.2)
			(type default)
		)
		(layer "In14.Cu")
	)
	(gr_arc
		(start 516.019796 -309.90032)
		(mid 514.246383 -310.634897)
		(end 513.5118 -312.408316)
		(stroke
			(width 0.2)
			(type default)
		)
		(layer "In14.Cu")
	)
	(gr_line
		(start 516.019796 -309.90032)
		(end 531.7998 -309.90032)
		(stroke
			(width 0.2)
			(type default)
		)
		(layer "In14.Cu")
	)
	(gr_arc
		(start 531.7998 -462.520284)
		(mid 532.8548 -462.083288)
		(end 533.291796 -461.028288)
		(stroke
			(width 0.2)
			(type default)
		)
		(layer "In14.Cu")
	)
	(gr_line
		(start 531.7998 -453.536304)
		(end 516.019796 -453.536304)
		(stroke
			(width 0.2)
			(type default)
		)
		(layer "In14.Cu")
	)
	(gr_arc
		(start 531.7998 -309.90032)
		(mid 532.8548 -309.463324)
		(end 533.291796 -308.408324)
		(stroke
			(width 0.2)
			(type default)
		)
		(layer "In14.Cu")
	)
	(gr_line
		(start 531.7998 11.892026)
		(end 475.799912 11.892026)
		(stroke
			(width 0.2)
			(type default)
		)
		(layer "In14.Cu")
	)
	(gr_line
		(start 533.291796 -461.028288)
		(end 533.291796 -455.0283)
		(stroke
			(width 0.2)
			(type default)
		)
		(layer "In14.Cu")
	)
	(gr_arc
		(start 533.291796 -455.0283)
		(mid 532.8548 -453.9733)
		(end 531.7998 -453.536304)
		(stroke
			(width 0.2)
			(type default)
		)
		(layer "In14.Cu")
	)
	(gr_line
		(start 533.291796 -308.408324)
		(end 533.291796 10.40003)
		(stroke
			(width 0.2)
			(type default)
		)
		(layer "In14.Cu")
	)
	(gr_arc
		(start 533.291796 10.40003)
		(mid 532.8548 11.45503)
		(end 531.7998 11.892026)
		(stroke
			(width 0.2)
			(type default)
		)
		(layer "In14.Cu")
	)
	(gr_poly
		(pts
			(xy 32.7152 -366.31753) (xy 32.7152 -362.1024) (xy 32.7152 -361.8992) (xy 32.6898 -361.8738) (xy 28.2956 -361.8738)
			(xy 28.245308 -361.924092) (xy 28.245308 -362.086144) (xy 28.245308 -366.318292) (xy 28.2702 -366.34293)
			(xy 32.6898 -366.34293)
		)
		(stroke
			(width 0)
			(type solid)
		)
		(fill yes)
		(layer "In15.Cu")
		(net "GND")
	)
	(gr_poly
		(pts
			(xy 312.3692 -362.88853) (xy 312.3692 -358.6734) (xy 312.3692 -358.4702) (xy 312.3438 -358.4448)
			(xy 307.9496 -358.4448) (xy 307.899308 -358.495092) (xy 307.899308 -358.657144) (xy 307.899308 -362.889292)
			(xy 307.9242 -362.91393) (xy 312.3438 -362.91393)
		)
		(stroke
			(width 0)
			(type solid)
		)
		(fill yes)
		(layer "In15.Cu")
		(net "GND")
	)
	(gr_poly
		(pts
			(xy 8.62076 -102.117144) (xy 8.878824 -101.85908) (xy 8.878824 -97.439988) (xy 8.669274 -97.230438)
			(xy 5.98551 -97.230438) (xy 5.494782 -97.721166) (xy 5.36956 -97.846388) (xy 5.11175 -98.104198)
			(xy 5.11175 -101.859334) (xy 5.36956 -102.117144) (xy 5.494782 -102.242366) (xy 8.495538 -102.242366)
		)
		(stroke
			(width 0)
			(type solid)
		)
		(fill yes)
		(layer "In15.Cu")
		(net "GND")
	)
	(gr_poly
		(pts
			(xy 441.045092 -43.578018) (xy 441.045092 -43.451018) (xy 441.045092 -38.853618) (xy 440.918092 -38.726618)
			(xy 434.288692 -38.726618) (xy 433.780692 -38.726618) (xy 433.628292 -38.879018) (xy 433.628292 -43.001946)
			(xy 433.628292 -43.618658) (xy 433.780692 -43.771058) (xy 438.893458 -43.771058) (xy 440.852052 -43.771058)
		)
		(stroke
			(width 0)
			(type solid)
		)
		(fill yes)
		(layer "In15.Cu")
		(net "P12V_AUX")
	)
	(gr_poly
		(pts
			(xy 155.952952 -319.820798) (xy 155.952952 -316.907418) (xy 155.693364 -316.64783) (xy 151.944832 -316.64783)
			(xy 151.40559 -316.108588) (xy 151.40559 -315.483494) (xy 151.140414 -315.218318) (xy 147.148804 -315.218318)
			(xy 147.023582 -315.34354) (xy 146.703796 -315.663326) (xy 146.703796 -318.473074) (xy 147.209256 -318.978534)
			(xy 150.965154 -318.978534) (xy 151.2951 -319.30848) (xy 151.2951 -319.870074) (xy 151.382476 -319.95745)
			(xy 151.549608 -319.95745) (xy 155.8163 -319.95745)
		)
		(stroke
			(width 0)
			(type solid)
		)
		(fill yes)
		(layer "In15.Cu")
		(net "GND")
	)
	(gr_poly
		(pts
			(arc
				(start 13.051028 -361.178602)
				(mid 12.791948 -361.178602)
				(end 13.051028 -361.178602)
			)
		)
		(stroke
			(width 0)
			(type solid)
		)
		(fill yes)
		(layer "In15.Cu")
		(net "GND")
	)
	(gr_poly
		(pts
			(arc
				(start 13.055092 -358.791002)
				(mid 12.796012 -358.791002)
				(end 13.055092 -358.791002)
			)
		)
		(stroke
			(width 0)
			(type solid)
		)
		(fill yes)
		(layer "In15.Cu")
		(net "GND")
	)
	(gr_poly
		(pts
			(arc
				(start 14.948154 -358.833674)
				(mid 14.689074 -358.833674)
				(end 14.948154 -358.833674)
			)
		)
		(stroke
			(width 0)
			(type solid)
		)
		(fill yes)
		(layer "In15.Cu")
		(net "GND")
	)
	(gr_poly
		(pts
			(arc
				(start 14.952218 -356.446074)
				(mid 14.693138 -356.446074)
				(end 14.952218 -356.446074)
			)
		)
		(stroke
			(width 0)
			(type solid)
		)
		(fill yes)
		(layer "In15.Cu")
		(net "GND")
	)
	(gr_poly
		(pts
			(arc
				(start 18.293334 -366.872266)
				(mid 18.034254 -366.872266)
				(end 18.293334 -366.872266)
			)
		)
		(stroke
			(width 0)
			(type solid)
		)
		(fill yes)
		(layer "In15.Cu")
		(net "GND")
	)
	(gr_poly
		(pts
			(arc
				(start 42.484294 -371.49913)
				(mid 42.225214 -371.49913)
				(end 42.484294 -371.49913)
			)
		)
		(stroke
			(width 0)
			(type solid)
		)
		(fill yes)
		(layer "In15.Cu")
		(net "GND")
	)
	(gr_poly
		(pts
			(arc
				(start 44.186094 -369.03533)
				(mid 43.927014 -369.03533)
				(end 44.186094 -369.03533)
			)
		)
		(stroke
			(width 0)
			(type solid)
		)
		(fill yes)
		(layer "In15.Cu")
		(net "GND")
	)
	(gr_poly
		(pts
			(arc
				(start 44.669202 -368.37493)
				(mid 44.410122 -368.37493)
				(end 44.669202 -368.37493)
			)
		)
		(stroke
			(width 0)
			(type solid)
		)
		(fill yes)
		(layer "In15.Cu")
		(net "GND")
	)
	(gr_poly
		(pts
			(arc
				(start 45.883322 -368.37493)
				(mid 45.624242 -368.37493)
				(end 45.883322 -368.37493)
			)
		)
		(stroke
			(width 0)
			(type solid)
		)
		(fill yes)
		(layer "In15.Cu")
		(net "GND")
	)
	(gr_poly
		(pts
			(arc
				(start 77.19695 -368.37493)
				(mid 76.93787 -368.37493)
				(end 77.19695 -368.37493)
			)
		)
		(stroke
			(width 0)
			(type solid)
		)
		(fill yes)
		(layer "In15.Cu")
		(net "GND")
	)
	(gr_poly
		(pts
			(arc
				(start 78.41107 -368.37493)
				(mid 78.15199 -368.37493)
				(end 78.41107 -368.37493)
			)
		)
		(stroke
			(width 0)
			(type solid)
		)
		(fill yes)
		(layer "In15.Cu")
		(net "GND")
	)
	(gr_poly
		(pts
			(arc
				(start 80.471772 -393.902438)
				(mid 80.212692 -393.902438)
				(end 80.471772 -393.902438)
			)
		)
		(stroke
			(width 0)
			(type solid)
		)
		(fill yes)
		(layer "In15.Cu")
		(net "GND")
	)
	(gr_poly
		(pts
			(arc
				(start 81.671668 -393.902438)
				(mid 81.412588 -393.902438)
				(end 81.671668 -393.902438)
			)
		)
		(stroke
			(width 0)
			(type solid)
		)
		(fill yes)
		(layer "In15.Cu")
		(net "GND")
	)
	(gr_poly
		(pts
			(arc
				(start 82.871818 -393.927838)
				(mid 82.612738 -393.927838)
				(end 82.871818 -393.927838)
			)
		)
		(stroke
			(width 0)
			(type solid)
		)
		(fill yes)
		(layer "In15.Cu")
		(net "GND")
	)
	(gr_poly
		(pts
			(arc
				(start 84.071714 -393.877038)
				(mid 83.812634 -393.877038)
				(end 84.071714 -393.877038)
			)
		)
		(stroke
			(width 0)
			(type solid)
		)
		(fill yes)
		(layer "In15.Cu")
		(net "GND")
	)
	(gr_poly
		(pts
			(arc
				(start 85.271864 -393.927838)
				(mid 85.012784 -393.927838)
				(end 85.271864 -393.927838)
			)
		)
		(stroke
			(width 0)
			(type solid)
		)
		(fill yes)
		(layer "In15.Cu")
		(net "GND")
	)
	(gr_poly
		(pts
			(arc
				(start 86.47176 -393.927838)
				(mid 86.21268 -393.927838)
				(end 86.47176 -393.927838)
			)
		)
		(stroke
			(width 0)
			(type solid)
		)
		(fill yes)
		(layer "In15.Cu")
		(net "GND")
	)
	(gr_poly
		(pts
			(arc
				(start 87.67191 -393.877038)
				(mid 87.41283 -393.877038)
				(end 87.67191 -393.877038)
			)
		)
		(stroke
			(width 0)
			(type solid)
		)
		(fill yes)
		(layer "In15.Cu")
		(net "GND")
	)
	(gr_poly
		(pts
			(arc
				(start 88.871806 -393.902438)
				(mid 88.612726 -393.902438)
				(end 88.871806 -393.902438)
			)
		)
		(stroke
			(width 0)
			(type solid)
		)
		(fill yes)
		(layer "In15.Cu")
		(net "GND")
	)
	(gr_poly
		(pts
			(arc
				(start 90.071956 -393.927838)
				(mid 89.812876 -393.927838)
				(end 90.071956 -393.927838)
			)
		)
		(stroke
			(width 0)
			(type solid)
		)
		(fill yes)
		(layer "In15.Cu")
		(net "GND")
	)
	(gr_poly
		(pts
			(arc
				(start 91.271852 -393.927838)
				(mid 91.012772 -393.927838)
				(end 91.271852 -393.927838)
			)
		)
		(stroke
			(width 0)
			(type solid)
		)
		(fill yes)
		(layer "In15.Cu")
		(net "GND")
	)
	(gr_poly
		(pts
			(arc
				(start 92.472002 -393.927838)
				(mid 92.212922 -393.927838)
				(end 92.472002 -393.927838)
			)
		)
		(stroke
			(width 0)
			(type solid)
		)
		(fill yes)
		(layer "In15.Cu")
		(net "GND")
	)
	(gr_poly
		(pts
			(arc
				(start 93.671898 -393.927838)
				(mid 93.412818 -393.927838)
				(end 93.671898 -393.927838)
			)
		)
		(stroke
			(width 0)
			(type solid)
		)
		(fill yes)
		(layer "In15.Cu")
		(net "GND")
	)
	(gr_poly
		(pts
			(arc
				(start 94.871794 -393.877038)
				(mid 94.612714 -393.877038)
				(end 94.871794 -393.877038)
			)
		)
		(stroke
			(width 0)
			(type solid)
		)
		(fill yes)
		(layer "In15.Cu")
		(net "GND")
	)
	(gr_poly
		(pts
			(arc
				(start 96.07169 -393.927838)
				(mid 95.81261 -393.927838)
				(end 96.07169 -393.927838)
			)
		)
		(stroke
			(width 0)
			(type solid)
		)
		(fill yes)
		(layer "In15.Cu")
		(net "GND")
	)
	(gr_poly
		(pts
			(arc
				(start 97.27184 -393.927838)
				(mid 97.01276 -393.927838)
				(end 97.27184 -393.927838)
			)
		)
		(stroke
			(width 0)
			(type solid)
		)
		(fill yes)
		(layer "In15.Cu")
		(net "GND")
	)
	(gr_poly
		(pts
			(arc
				(start 98.471736 -393.902438)
				(mid 98.212656 -393.902438)
				(end 98.471736 -393.902438)
			)
		)
		(stroke
			(width 0)
			(type solid)
		)
		(fill yes)
		(layer "In15.Cu")
		(net "GND")
	)
	(gr_poly
		(pts
			(arc
				(start 101.02215 -368.37493)
				(mid 100.76307 -368.37493)
				(end 101.02215 -368.37493)
			)
		)
		(stroke
			(width 0)
			(type solid)
		)
		(fill yes)
		(layer "In15.Cu")
		(net "GND")
	)
	(gr_poly
		(pts
			(arc
				(start 102.23627 -368.37493)
				(mid 101.97719 -368.37493)
				(end 102.23627 -368.37493)
			)
		)
		(stroke
			(width 0)
			(type solid)
		)
		(fill yes)
		(layer "In15.Cu")
		(net "GND")
	)
	(gr_poly
		(pts
			(arc
				(start 107.999784 -377.009152)
				(mid 107.740704 -377.009152)
				(end 107.999784 -377.009152)
			)
		)
		(stroke
			(width 0)
			(type solid)
		)
		(fill yes)
		(layer "In15.Cu")
		(net "GND")
	)
	(gr_poly
		(pts
			(arc
				(start 107.999784 -375.795032)
				(mid 107.740704 -375.795032)
				(end 107.999784 -375.795032)
			)
		)
		(stroke
			(width 0)
			(type solid)
		)
		(fill yes)
		(layer "In15.Cu")
		(net "GND")
	)
	(gr_poly
		(pts
			(arc
				(start 108.660184 -377.49226)
				(mid 108.401104 -377.49226)
				(end 108.660184 -377.49226)
			)
		)
		(stroke
			(width 0)
			(type solid)
		)
		(fill yes)
		(layer "In15.Cu")
		(net "GND")
	)
	(gr_poly
		(pts
			(arc
				(start 108.660184 -375.30786)
				(mid 108.401104 -375.30786)
				(end 108.660184 -375.30786)
			)
		)
		(stroke
			(width 0)
			(type solid)
		)
		(fill yes)
		(layer "In15.Cu")
		(net "GND")
	)
	(gr_poly
		(pts
			(arc
				(start 109.320584 -377.009152)
				(mid 109.061504 -377.009152)
				(end 109.320584 -377.009152)
			)
		)
		(stroke
			(width 0)
			(type solid)
		)
		(fill yes)
		(layer "In15.Cu")
		(net "GND")
	)
	(gr_poly
		(pts
			(arc
				(start 109.320584 -375.795032)
				(mid 109.061504 -375.795032)
				(end 109.320584 -375.795032)
			)
		)
		(stroke
			(width 0)
			(type solid)
		)
		(fill yes)
		(layer "In15.Cu")
		(net "GND")
	)
	(gr_poly
		(pts
			(arc
				(start 115.043966 -393.902438)
				(mid 114.784886 -393.902438)
				(end 115.043966 -393.902438)
			)
		)
		(stroke
			(width 0)
			(type solid)
		)
		(fill yes)
		(layer "In15.Cu")
		(net "GND")
	)
	(gr_poly
		(pts
			(arc
				(start 116.243862 -393.902438)
				(mid 115.984782 -393.902438)
				(end 116.243862 -393.902438)
			)
		)
		(stroke
			(width 0)
			(type solid)
		)
		(fill yes)
		(layer "In15.Cu")
		(net "GND")
	)
	(gr_poly
		(pts
			(arc
				(start 117.444012 -393.927838)
				(mid 117.184932 -393.927838)
				(end 117.444012 -393.927838)
			)
		)
		(stroke
			(width 0)
			(type solid)
		)
		(fill yes)
		(layer "In15.Cu")
		(net "GND")
	)
	(gr_poly
		(pts
			(arc
				(start 118.643908 -393.877038)
				(mid 118.384828 -393.877038)
				(end 118.643908 -393.877038)
			)
		)
		(stroke
			(width 0)
			(type solid)
		)
		(fill yes)
		(layer "In15.Cu")
		(net "GND")
	)
	(gr_poly
		(pts
			(arc
				(start 119.844058 -393.927838)
				(mid 119.584978 -393.927838)
				(end 119.844058 -393.927838)
			)
		)
		(stroke
			(width 0)
			(type solid)
		)
		(fill yes)
		(layer "In15.Cu")
		(net "GND")
	)
	(gr_poly
		(pts
			(arc
				(start 121.043954 -393.927838)
				(mid 120.784874 -393.927838)
				(end 121.043954 -393.927838)
			)
		)
		(stroke
			(width 0)
			(type solid)
		)
		(fill yes)
		(layer "In15.Cu")
		(net "GND")
	)
	(gr_poly
		(pts
			(arc
				(start 122.244104 -393.877038)
				(mid 121.985024 -393.877038)
				(end 122.244104 -393.877038)
			)
		)
		(stroke
			(width 0)
			(type solid)
		)
		(fill yes)
		(layer "In15.Cu")
		(net "GND")
	)
	(gr_poly
		(pts
			(arc
				(start 123.444 -393.902438)
				(mid 123.18492 -393.902438)
				(end 123.444 -393.902438)
			)
		)
		(stroke
			(width 0)
			(type solid)
		)
		(fill yes)
		(layer "In15.Cu")
		(net "GND")
	)
	(gr_poly
		(pts
			(arc
				(start 124.64415 -393.927838)
				(mid 124.38507 -393.927838)
				(end 124.64415 -393.927838)
			)
		)
		(stroke
			(width 0)
			(type solid)
		)
		(fill yes)
		(layer "In15.Cu")
		(net "GND")
	)
	(gr_poly
		(pts
			(arc
				(start 125.844046 -393.927838)
				(mid 125.584966 -393.927838)
				(end 125.844046 -393.927838)
			)
		)
		(stroke
			(width 0)
			(type solid)
		)
		(fill yes)
		(layer "In15.Cu")
		(net "GND")
	)
	(gr_poly
		(pts
			(arc
				(start 127.044196 -393.927838)
				(mid 126.785116 -393.927838)
				(end 127.044196 -393.927838)
			)
		)
		(stroke
			(width 0)
			(type solid)
		)
		(fill yes)
		(layer "In15.Cu")
		(net "GND")
	)
	(gr_poly
		(pts
			(arc
				(start 128.244092 -393.927838)
				(mid 127.985012 -393.927838)
				(end 128.244092 -393.927838)
			)
		)
		(stroke
			(width 0)
			(type solid)
		)
		(fill yes)
		(layer "In15.Cu")
		(net "GND")
	)
	(gr_poly
		(pts
			(arc
				(start 129.443988 -393.877038)
				(mid 129.184908 -393.877038)
				(end 129.443988 -393.877038)
			)
		)
		(stroke
			(width 0)
			(type solid)
		)
		(fill yes)
		(layer "In15.Cu")
		(net "GND")
	)
	(gr_poly
		(pts
			(arc
				(start 130.643884 -393.927838)
				(mid 130.384804 -393.927838)
				(end 130.643884 -393.927838)
			)
		)
		(stroke
			(width 0)
			(type solid)
		)
		(fill yes)
		(layer "In15.Cu")
		(net "GND")
	)
	(gr_poly
		(pts
			(arc
				(start 131.844034 -393.927838)
				(mid 131.584954 -393.927838)
				(end 131.844034 -393.927838)
			)
		)
		(stroke
			(width 0)
			(type solid)
		)
		(fill yes)
		(layer "In15.Cu")
		(net "GND")
	)
	(gr_poly
		(pts
			(arc
				(start 133.04393 -393.902438)
				(mid 132.78485 -393.902438)
				(end 133.04393 -393.902438)
			)
		)
		(stroke
			(width 0)
			(type solid)
		)
		(fill yes)
		(layer "In15.Cu")
		(net "GND")
	)
	(gr_poly
		(pts
			(arc
				(start 142.111984 -371.49913)
				(mid 141.852904 -371.49913)
				(end 142.111984 -371.49913)
			)
		)
		(stroke
			(width 0)
			(type solid)
		)
		(fill yes)
		(layer "In15.Cu")
		(net "GND")
	)
	(gr_poly
		(pts
			(arc
				(start 142.136368 -368.85499)
				(mid 141.877288 -368.85499)
				(end 142.136368 -368.85499)
			)
		)
		(stroke
			(width 0)
			(type solid)
		)
		(fill yes)
		(layer "In15.Cu")
		(net "GND")
	)
	(gr_poly
		(pts
			(arc
				(start 142.595092 -372.15953)
				(mid 142.336012 -372.15953)
				(end 142.595092 -372.15953)
			)
		)
		(stroke
			(width 0)
			(type solid)
		)
		(fill yes)
		(layer "In15.Cu")
		(net "GND")
	)
	(gr_poly
		(pts
			(arc
				(start 142.595092 -370.83873)
				(mid 142.336012 -370.83873)
				(end 142.595092 -370.83873)
			)
		)
		(stroke
			(width 0)
			(type solid)
		)
		(fill yes)
		(layer "In15.Cu")
		(net "GND")
	)
	(gr_poly
		(pts
			(arc
				(start 147.571714 -393.902438)
				(mid 147.312634 -393.902438)
				(end 147.571714 -393.902438)
			)
		)
		(stroke
			(width 0)
			(type solid)
		)
		(fill yes)
		(layer "In15.Cu")
		(net "GND")
	)
	(gr_poly
		(pts
			(arc
				(start 148.77161 -393.902438)
				(mid 148.51253 -393.902438)
				(end 148.77161 -393.902438)
			)
		)
		(stroke
			(width 0)
			(type solid)
		)
		(fill yes)
		(layer "In15.Cu")
		(net "GND")
	)
	(gr_poly
		(pts
			(arc
				(start 149.97176 -393.927838)
				(mid 149.71268 -393.927838)
				(end 149.97176 -393.927838)
			)
		)
		(stroke
			(width 0)
			(type solid)
		)
		(fill yes)
		(layer "In15.Cu")
		(net "GND")
	)
	(gr_poly
		(pts
			(arc
				(start 151.171656 -393.877038)
				(mid 150.912576 -393.877038)
				(end 151.171656 -393.877038)
			)
		)
		(stroke
			(width 0)
			(type solid)
		)
		(fill yes)
		(layer "In15.Cu")
		(net "GND")
	)
	(gr_poly
		(pts
			(arc
				(start 152.371806 -393.927838)
				(mid 152.112726 -393.927838)
				(end 152.371806 -393.927838)
			)
		)
		(stroke
			(width 0)
			(type solid)
		)
		(fill yes)
		(layer "In15.Cu")
		(net "GND")
	)
	(gr_poly
		(pts
			(arc
				(start 153.571702 -393.927838)
				(mid 153.312622 -393.927838)
				(end 153.571702 -393.927838)
			)
		)
		(stroke
			(width 0)
			(type solid)
		)
		(fill yes)
		(layer "In15.Cu")
		(net "GND")
	)
	(gr_poly
		(pts
			(arc
				(start 154.771852 -393.877038)
				(mid 154.512772 -393.877038)
				(end 154.771852 -393.877038)
			)
		)
		(stroke
			(width 0)
			(type solid)
		)
		(fill yes)
		(layer "In15.Cu")
		(net "GND")
	)
	(gr_poly
		(pts
			(arc
				(start 155.971748 -393.902438)
				(mid 155.712668 -393.902438)
				(end 155.971748 -393.902438)
			)
		)
		(stroke
			(width 0)
			(type solid)
		)
		(fill yes)
		(layer "In15.Cu")
		(net "GND")
	)
	(gr_poly
		(pts
			(arc
				(start 157.171898 -393.927838)
				(mid 156.912818 -393.927838)
				(end 157.171898 -393.927838)
			)
		)
		(stroke
			(width 0)
			(type solid)
		)
		(fill yes)
		(layer "In15.Cu")
		(net "GND")
	)
	(gr_poly
		(pts
			(arc
				(start 158.371794 -393.927838)
				(mid 158.112714 -393.927838)
				(end 158.371794 -393.927838)
			)
		)
		(stroke
			(width 0)
			(type solid)
		)
		(fill yes)
		(layer "In15.Cu")
		(net "GND")
	)
	(gr_poly
		(pts
			(arc
				(start 159.571944 -393.927838)
				(mid 159.312864 -393.927838)
				(end 159.571944 -393.927838)
			)
		)
		(stroke
			(width 0)
			(type solid)
		)
		(fill yes)
		(layer "In15.Cu")
		(net "GND")
	)
	(gr_poly
		(pts
			(arc
				(start 160.77184 -393.927838)
				(mid 160.51276 -393.927838)
				(end 160.77184 -393.927838)
			)
		)
		(stroke
			(width 0)
			(type solid)
		)
		(fill yes)
		(layer "In15.Cu")
		(net "GND")
	)
	(gr_poly
		(pts
			(arc
				(start 161.971736 -393.877038)
				(mid 161.712656 -393.877038)
				(end 161.971736 -393.877038)
			)
		)
		(stroke
			(width 0)
			(type solid)
		)
		(fill yes)
		(layer "In15.Cu")
		(net "GND")
	)
	(gr_poly
		(pts
			(arc
				(start 163.171632 -393.927838)
				(mid 162.912552 -393.927838)
				(end 163.171632 -393.927838)
			)
		)
		(stroke
			(width 0)
			(type solid)
		)
		(fill yes)
		(layer "In15.Cu")
		(net "GND")
	)
	(gr_poly
		(pts
			(arc
				(start 164.371782 -393.927838)
				(mid 164.112702 -393.927838)
				(end 164.371782 -393.927838)
			)
		)
		(stroke
			(width 0)
			(type solid)
		)
		(fill yes)
		(layer "In15.Cu")
		(net "GND")
	)
	(gr_poly
		(pts
			(arc
				(start 165.571678 -393.902438)
				(mid 165.312598 -393.902438)
				(end 165.571678 -393.902438)
			)
		)
		(stroke
			(width 0)
			(type solid)
		)
		(fill yes)
		(layer "In15.Cu")
		(net "GND")
	)
	(gr_poly
		(pts
			(arc
				(start 170.374564 -380.533656)
				(mid 170.115484 -380.533656)
				(end 170.374564 -380.533656)
			)
		)
		(stroke
			(width 0)
			(type solid)
		)
		(fill yes)
		(layer "In15.Cu")
		(net "GND")
	)
	(gr_poly
		(pts
			(arc
				(start 170.374564 -379.319536)
				(mid 170.115484 -379.319536)
				(end 170.374564 -379.319536)
			)
		)
		(stroke
			(width 0)
			(type solid)
		)
		(fill yes)
		(layer "In15.Cu")
		(net "GND")
	)
	(gr_poly
		(pts
			(arc
				(start 170.374564 -377.130056)
				(mid 170.115484 -377.130056)
				(end 170.374564 -377.130056)
			)
		)
		(stroke
			(width 0)
			(type solid)
		)
		(fill yes)
		(layer "In15.Cu")
		(net "GND")
	)
	(gr_poly
		(pts
			(arc
				(start 171.034964 -381.020828)
				(mid 170.775884 -381.020828)
				(end 171.034964 -381.020828)
			)
		)
		(stroke
			(width 0)
			(type solid)
		)
		(fill yes)
		(layer "In15.Cu")
		(net "GND")
	)
	(gr_poly
		(pts
			(arc
				(start 171.034964 -378.836428)
				(mid 170.775884 -378.836428)
				(end 171.034964 -378.836428)
			)
		)
		(stroke
			(width 0)
			(type solid)
		)
		(fill yes)
		(layer "In15.Cu")
		(net "GND")
	)
	(gr_poly
		(pts
			(arc
				(start 171.034964 -377.617228)
				(mid 170.775884 -377.617228)
				(end 171.034964 -377.617228)
			)
		)
		(stroke
			(width 0)
			(type solid)
		)
		(fill yes)
		(layer "In15.Cu")
		(net "GND")
	)
	(gr_poly
		(pts
			(arc
				(start 171.034964 -375.432828)
				(mid 170.775884 -375.432828)
				(end 171.034964 -375.432828)
			)
		)
		(stroke
			(width 0)
			(type solid)
		)
		(fill yes)
		(layer "In15.Cu")
		(net "GND")
	)
	(gr_poly
		(pts
			(arc
				(start 171.607988 -375.816876)
				(mid 171.348908 -375.816876)
				(end 171.607988 -375.816876)
			)
		)
		(stroke
			(width 0)
			(type solid)
		)
		(fill yes)
		(layer "In15.Cu")
		(net "GND")
	)
	(gr_poly
		(pts
			(arc
				(start 171.695364 -380.533656)
				(mid 171.436284 -380.533656)
				(end 171.695364 -380.533656)
			)
		)
		(stroke
			(width 0)
			(type solid)
		)
		(fill yes)
		(layer "In15.Cu")
		(net "GND")
	)
	(gr_poly
		(pts
			(arc
				(start 171.695364 -379.319536)
				(mid 171.436284 -379.319536)
				(end 171.695364 -379.319536)
			)
		)
		(stroke
			(width 0)
			(type solid)
		)
		(fill yes)
		(layer "In15.Cu")
		(net "GND")
	)
	(gr_poly
		(pts
			(arc
				(start 171.695364 -377.130056)
				(mid 171.436284 -377.130056)
				(end 171.695364 -377.130056)
			)
		)
		(stroke
			(width 0)
			(type solid)
		)
		(fill yes)
		(layer "In15.Cu")
		(net "GND")
	)
	(gr_poly
		(pts
			(arc
				(start 303.943766 -402.284438)
				(mid 303.684686 -402.284438)
				(end 303.943766 -402.284438)
			)
		)
		(stroke
			(width 0)
			(type solid)
		)
		(fill yes)
		(layer "In15.Cu")
		(net "GND")
	)
	(gr_poly
		(pts
			(arc
				(start 305.143662 -402.284438)
				(mid 304.884582 -402.284438)
				(end 305.143662 -402.284438)
			)
		)
		(stroke
			(width 0)
			(type solid)
		)
		(fill yes)
		(layer "In15.Cu")
		(net "GND")
	)
	(gr_poly
		(pts
			(arc
				(start 306.343812 -402.309838)
				(mid 306.084732 -402.309838)
				(end 306.343812 -402.309838)
			)
		)
		(stroke
			(width 0)
			(type solid)
		)
		(fill yes)
		(layer "In15.Cu")
		(net "GND")
	)
	(gr_poly
		(pts
			(arc
				(start 307.543708 -402.259038)
				(mid 307.284628 -402.259038)
				(end 307.543708 -402.259038)
			)
		)
		(stroke
			(width 0)
			(type solid)
		)
		(fill yes)
		(layer "In15.Cu")
		(net "GND")
	)
	(gr_poly
		(pts
			(arc
				(start 308.743858 -402.309838)
				(mid 308.484778 -402.309838)
				(end 308.743858 -402.309838)
			)
		)
		(stroke
			(width 0)
			(type solid)
		)
		(fill yes)
		(layer "In15.Cu")
		(net "GND")
	)
	(gr_poly
		(pts
			(arc
				(start 309.943754 -402.309838)
				(mid 309.684674 -402.309838)
				(end 309.943754 -402.309838)
			)
		)
		(stroke
			(width 0)
			(type solid)
		)
		(fill yes)
		(layer "In15.Cu")
		(net "GND")
	)
	(gr_poly
		(pts
			(arc
				(start 311.143904 -402.259038)
				(mid 310.884824 -402.259038)
				(end 311.143904 -402.259038)
			)
		)
		(stroke
			(width 0)
			(type solid)
		)
		(fill yes)
		(layer "In15.Cu")
		(net "GND")
	)
	(gr_poly
		(pts
			(arc
				(start 312.3438 -402.284438)
				(mid 312.08472 -402.284438)
				(end 312.3438 -402.284438)
			)
		)
		(stroke
			(width 0)
			(type solid)
		)
		(fill yes)
		(layer "In15.Cu")
		(net "GND")
	)
	(gr_poly
		(pts
			(arc
				(start 313.54395 -402.309838)
				(mid 313.28487 -402.309838)
				(end 313.54395 -402.309838)
			)
		)
		(stroke
			(width 0)
			(type solid)
		)
		(fill yes)
		(layer "In15.Cu")
		(net "GND")
	)
	(gr_poly
		(pts
			(arc
				(start 314.743846 -402.309838)
				(mid 314.484766 -402.309838)
				(end 314.743846 -402.309838)
			)
		)
		(stroke
			(width 0)
			(type solid)
		)
		(fill yes)
		(layer "In15.Cu")
		(net "GND")
	)
	(gr_poly
		(pts
			(arc
				(start 315.943996 -402.309838)
				(mid 315.684916 -402.309838)
				(end 315.943996 -402.309838)
			)
		)
		(stroke
			(width 0)
			(type solid)
		)
		(fill yes)
		(layer "In15.Cu")
		(net "GND")
	)
	(gr_poly
		(pts
			(arc
				(start 317.143892 -402.309838)
				(mid 316.884812 -402.309838)
				(end 317.143892 -402.309838)
			)
		)
		(stroke
			(width 0)
			(type solid)
		)
		(fill yes)
		(layer "In15.Cu")
		(net "GND")
	)
	(gr_poly
		(pts
			(arc
				(start 318.343788 -402.259038)
				(mid 318.084708 -402.259038)
				(end 318.343788 -402.259038)
			)
		)
		(stroke
			(width 0)
			(type solid)
		)
		(fill yes)
		(layer "In15.Cu")
		(net "GND")
	)
	(gr_poly
		(pts
			(arc
				(start 319.543684 -402.309838)
				(mid 319.284604 -402.309838)
				(end 319.543684 -402.309838)
			)
		)
		(stroke
			(width 0)
			(type solid)
		)
		(fill yes)
		(layer "In15.Cu")
		(net "GND")
	)
	(gr_poly
		(pts
			(arc
				(start 320.743834 -402.309838)
				(mid 320.484754 -402.309838)
				(end 320.743834 -402.309838)
			)
		)
		(stroke
			(width 0)
			(type solid)
		)
		(fill yes)
		(layer "In15.Cu")
		(net "GND")
	)
	(gr_poly
		(pts
			(arc
				(start 321.94373 -402.284438)
				(mid 321.68465 -402.284438)
				(end 321.94373 -402.284438)
			)
		)
		(stroke
			(width 0)
			(type solid)
		)
		(fill yes)
		(layer "In15.Cu")
		(net "GND")
	)
	(gr_poly
		(pts
			(arc
				(start 332.713584 -377.41733)
				(mid 332.454504 -377.41733)
				(end 332.713584 -377.41733)
			)
		)
		(stroke
			(width 0)
			(type solid)
		)
		(fill yes)
		(layer "In15.Cu")
		(net "GND")
	)
	(gr_poly
		(pts
			(arc
				(start 333.196692 -378.07773)
				(mid 332.937612 -378.07773)
				(end 333.196692 -378.07773)
			)
		)
		(stroke
			(width 0)
			(type solid)
		)
		(fill yes)
		(layer "In15.Cu")
		(net "GND")
	)
	(gr_poly
		(pts
			(arc
				(start 333.196692 -376.75693)
				(mid 332.937612 -376.75693)
				(end 333.196692 -376.75693)
			)
		)
		(stroke
			(width 0)
			(type solid)
		)
		(fill yes)
		(layer "In15.Cu")
		(net "GND")
	)
	(gr_poly
		(pts
			(arc
				(start 334.410812 -378.07773)
				(mid 334.151732 -378.07773)
				(end 334.410812 -378.07773)
			)
		)
		(stroke
			(width 0)
			(type solid)
		)
		(fill yes)
		(layer "In15.Cu")
		(net "GND")
	)
	(gr_poly
		(pts
			(arc
				(start 334.410812 -376.75693)
				(mid 334.151732 -376.75693)
				(end 334.410812 -376.75693)
			)
		)
		(stroke
			(width 0)
			(type solid)
		)
		(fill yes)
		(layer "In15.Cu")
		(net "GND")
	)
	(gr_poly
		(pts
			(arc
				(start 334.897984 -377.41733)
				(mid 334.638904 -377.41733)
				(end 334.897984 -377.41733)
			)
		)
		(stroke
			(width 0)
			(type solid)
		)
		(fill yes)
		(layer "In15.Cu")
		(net "GND")
	)
	(gr_poly
		(pts
			(arc
				(start 336.471514 -402.284438)
				(mid 336.212434 -402.284438)
				(end 336.471514 -402.284438)
			)
		)
		(stroke
			(width 0)
			(type solid)
		)
		(fill yes)
		(layer "In15.Cu")
		(net "GND")
	)
	(gr_poly
		(pts
			(arc
				(start 337.67141 -402.284438)
				(mid 337.41233 -402.284438)
				(end 337.67141 -402.284438)
			)
		)
		(stroke
			(width 0)
			(type solid)
		)
		(fill yes)
		(layer "In15.Cu")
		(net "GND")
	)
	(gr_poly
		(pts
			(arc
				(start 338.87156 -402.309838)
				(mid 338.61248 -402.309838)
				(end 338.87156 -402.309838)
			)
		)
		(stroke
			(width 0)
			(type solid)
		)
		(fill yes)
		(layer "In15.Cu")
		(net "GND")
	)
	(gr_poly
		(pts
			(arc
				(start 340.071456 -402.259038)
				(mid 339.812376 -402.259038)
				(end 340.071456 -402.259038)
			)
		)
		(stroke
			(width 0)
			(type solid)
		)
		(fill yes)
		(layer "In15.Cu")
		(net "GND")
	)
	(gr_poly
		(pts
			(arc
				(start 341.271606 -402.309838)
				(mid 341.012526 -402.309838)
				(end 341.271606 -402.309838)
			)
		)
		(stroke
			(width 0)
			(type solid)
		)
		(fill yes)
		(layer "In15.Cu")
		(net "GND")
	)
	(gr_poly
		(pts
			(arc
				(start 342.471502 -402.309838)
				(mid 342.212422 -402.309838)
				(end 342.471502 -402.309838)
			)
		)
		(stroke
			(width 0)
			(type solid)
		)
		(fill yes)
		(layer "In15.Cu")
		(net "GND")
	)
	(gr_poly
		(pts
			(arc
				(start 343.671652 -402.259038)
				(mid 343.412572 -402.259038)
				(end 343.671652 -402.259038)
			)
		)
		(stroke
			(width 0)
			(type solid)
		)
		(fill yes)
		(layer "In15.Cu")
		(net "GND")
	)
	(gr_poly
		(pts
			(arc
				(start 344.871548 -402.284438)
				(mid 344.612468 -402.284438)
				(end 344.871548 -402.284438)
			)
		)
		(stroke
			(width 0)
			(type solid)
		)
		(fill yes)
		(layer "In15.Cu")
		(net "GND")
	)
	(gr_poly
		(pts
			(arc
				(start 346.071698 -402.309838)
				(mid 345.812618 -402.309838)
				(end 346.071698 -402.309838)
			)
		)
		(stroke
			(width 0)
			(type solid)
		)
		(fill yes)
		(layer "In15.Cu")
		(net "GND")
	)
	(gr_poly
		(pts
			(arc
				(start 347.271594 -402.309838)
				(mid 347.012514 -402.309838)
				(end 347.271594 -402.309838)
			)
		)
		(stroke
			(width 0)
			(type solid)
		)
		(fill yes)
		(layer "In15.Cu")
		(net "GND")
	)
	(gr_poly
		(pts
			(arc
				(start 348.471744 -402.309838)
				(mid 348.212664 -402.309838)
				(end 348.471744 -402.309838)
			)
		)
		(stroke
			(width 0)
			(type solid)
		)
		(fill yes)
		(layer "In15.Cu")
		(net "GND")
	)
	(gr_poly
		(pts
			(arc
				(start 349.67164 -402.309838)
				(mid 349.41256 -402.309838)
				(end 349.67164 -402.309838)
			)
		)
		(stroke
			(width 0)
			(type solid)
		)
		(fill yes)
		(layer "In15.Cu")
		(net "GND")
	)
	(gr_poly
		(pts
			(arc
				(start 350.871536 -402.259038)
				(mid 350.612456 -402.259038)
				(end 350.871536 -402.259038)
			)
		)
		(stroke
			(width 0)
			(type solid)
		)
		(fill yes)
		(layer "In15.Cu")
		(net "GND")
	)
	(gr_poly
		(pts
			(arc
				(start 352.071432 -402.309838)
				(mid 351.812352 -402.309838)
				(end 352.071432 -402.309838)
			)
		)
		(stroke
			(width 0)
			(type solid)
		)
		(fill yes)
		(layer "In15.Cu")
		(net "GND")
	)
	(gr_poly
		(pts
			(arc
				(start 353.271582 -402.309838)
				(mid 353.012502 -402.309838)
				(end 353.271582 -402.309838)
			)
		)
		(stroke
			(width 0)
			(type solid)
		)
		(fill yes)
		(layer "In15.Cu")
		(net "GND")
	)
	(gr_poly
		(pts
			(arc
				(start 354.471478 -402.284438)
				(mid 354.212398 -402.284438)
				(end 354.471478 -402.284438)
			)
		)
		(stroke
			(width 0)
			(type solid)
		)
		(fill yes)
		(layer "In15.Cu")
		(net "GND")
	)
	(gr_poly
		(pts
			(arc
				(start 371.043962 -402.284438)
				(mid 370.784882 -402.284438)
				(end 371.043962 -402.284438)
			)
		)
		(stroke
			(width 0)
			(type solid)
		)
		(fill yes)
		(layer "In15.Cu")
		(net "GND")
	)
	(gr_poly
		(pts
			(arc
				(start 372.243858 -402.284438)
				(mid 371.984778 -402.284438)
				(end 372.243858 -402.284438)
			)
		)
		(stroke
			(width 0)
			(type solid)
		)
		(fill yes)
		(layer "In15.Cu")
		(net "GND")
	)
	(gr_poly
		(pts
			(arc
				(start 373.444008 -402.309838)
				(mid 373.184928 -402.309838)
				(end 373.444008 -402.309838)
			)
		)
		(stroke
			(width 0)
			(type solid)
		)
		(fill yes)
		(layer "In15.Cu")
		(net "GND")
	)
	(gr_poly
		(pts
			(arc
				(start 374.643904 -402.259038)
				(mid 374.384824 -402.259038)
				(end 374.643904 -402.259038)
			)
		)
		(stroke
			(width 0)
			(type solid)
		)
		(fill yes)
		(layer "In15.Cu")
		(net "GND")
	)
	(gr_poly
		(pts
			(arc
				(start 375.844054 -402.309838)
				(mid 375.584974 -402.309838)
				(end 375.844054 -402.309838)
			)
		)
		(stroke
			(width 0)
			(type solid)
		)
		(fill yes)
		(layer "In15.Cu")
		(net "GND")
	)
	(gr_poly
		(pts
			(arc
				(start 377.04395 -402.309838)
				(mid 376.78487 -402.309838)
				(end 377.04395 -402.309838)
			)
		)
		(stroke
			(width 0)
			(type solid)
		)
		(fill yes)
		(layer "In15.Cu")
		(net "GND")
	)
	(gr_poly
		(pts
			(arc
				(start 378.2441 -402.259038)
				(mid 377.98502 -402.259038)
				(end 378.2441 -402.259038)
			)
		)
		(stroke
			(width 0)
			(type solid)
		)
		(fill yes)
		(layer "In15.Cu")
		(net "GND")
	)
	(gr_poly
		(pts
			(arc
				(start 379.443996 -402.284438)
				(mid 379.184916 -402.284438)
				(end 379.443996 -402.284438)
			)
		)
		(stroke
			(width 0)
			(type solid)
		)
		(fill yes)
		(layer "In15.Cu")
		(net "GND")
	)
	(gr_poly
		(pts
			(arc
				(start 380.644146 -402.309838)
				(mid 380.385066 -402.309838)
				(end 380.644146 -402.309838)
			)
		)
		(stroke
			(width 0)
			(type solid)
		)
		(fill yes)
		(layer "In15.Cu")
		(net "GND")
	)
	(gr_poly
		(pts
			(arc
				(start 381.844042 -402.309838)
				(mid 381.584962 -402.309838)
				(end 381.844042 -402.309838)
			)
		)
		(stroke
			(width 0)
			(type solid)
		)
		(fill yes)
		(layer "In15.Cu")
		(net "GND")
	)
	(gr_poly
		(pts
			(arc
				(start 383.044192 -402.309838)
				(mid 382.785112 -402.309838)
				(end 383.044192 -402.309838)
			)
		)
		(stroke
			(width 0)
			(type solid)
		)
		(fill yes)
		(layer "In15.Cu")
		(net "GND")
	)
	(gr_poly
		(pts
			(arc
				(start 384.244088 -402.309838)
				(mid 383.985008 -402.309838)
				(end 384.244088 -402.309838)
			)
		)
		(stroke
			(width 0)
			(type solid)
		)
		(fill yes)
		(layer "In15.Cu")
		(net "GND")
	)
	(gr_poly
		(pts
			(arc
				(start 385.443984 -402.259038)
				(mid 385.184904 -402.259038)
				(end 385.443984 -402.259038)
			)
		)
		(stroke
			(width 0)
			(type solid)
		)
		(fill yes)
		(layer "In15.Cu")
		(net "GND")
	)
	(gr_poly
		(pts
			(arc
				(start 386.64388 -402.309838)
				(mid 386.3848 -402.309838)
				(end 386.64388 -402.309838)
			)
		)
		(stroke
			(width 0)
			(type solid)
		)
		(fill yes)
		(layer "In15.Cu")
		(net "GND")
	)
	(gr_poly
		(pts
			(arc
				(start 387.84403 -402.309838)
				(mid 387.58495 -402.309838)
				(end 387.84403 -402.309838)
			)
		)
		(stroke
			(width 0)
			(type solid)
		)
		(fill yes)
		(layer "In15.Cu")
		(net "GND")
	)
	(gr_poly
		(pts
			(arc
				(start 389.043926 -402.284438)
				(mid 388.784846 -402.284438)
				(end 389.043926 -402.284438)
			)
		)
		(stroke
			(width 0)
			(type solid)
		)
		(fill yes)
		(layer "In15.Cu")
		(net "GND")
	)
	(gr_poly
		(pts
			(arc
				(start 403.57171 -402.284438)
				(mid 403.31263 -402.284438)
				(end 403.57171 -402.284438)
			)
		)
		(stroke
			(width 0)
			(type solid)
		)
		(fill yes)
		(layer "In15.Cu")
		(net "GND")
	)
	(gr_poly
		(pts
			(arc
				(start 404.771606 -402.284438)
				(mid 404.512526 -402.284438)
				(end 404.771606 -402.284438)
			)
		)
		(stroke
			(width 0)
			(type solid)
		)
		(fill yes)
		(layer "In15.Cu")
		(net "GND")
	)
	(gr_poly
		(pts
			(arc
				(start 405.971756 -402.309838)
				(mid 405.712676 -402.309838)
				(end 405.971756 -402.309838)
			)
		)
		(stroke
			(width 0)
			(type solid)
		)
		(fill yes)
		(layer "In15.Cu")
		(net "GND")
	)
	(gr_poly
		(pts
			(arc
				(start 407.171652 -402.259038)
				(mid 406.912572 -402.259038)
				(end 407.171652 -402.259038)
			)
		)
		(stroke
			(width 0)
			(type solid)
		)
		(fill yes)
		(layer "In15.Cu")
		(net "GND")
	)
	(gr_poly
		(pts
			(arc
				(start 408.371802 -402.309838)
				(mid 408.112722 -402.309838)
				(end 408.371802 -402.309838)
			)
		)
		(stroke
			(width 0)
			(type solid)
		)
		(fill yes)
		(layer "In15.Cu")
		(net "GND")
	)
	(gr_poly
		(pts
			(arc
				(start 409.571698 -402.309838)
				(mid 409.312618 -402.309838)
				(end 409.571698 -402.309838)
			)
		)
		(stroke
			(width 0)
			(type solid)
		)
		(fill yes)
		(layer "In15.Cu")
		(net "GND")
	)
	(gr_poly
		(pts
			(arc
				(start 410.771848 -402.259038)
				(mid 410.512768 -402.259038)
				(end 410.771848 -402.259038)
			)
		)
		(stroke
			(width 0)
			(type solid)
		)
		(fill yes)
		(layer "In15.Cu")
		(net "GND")
	)
	(gr_poly
		(pts
			(arc
				(start 411.971744 -402.284438)
				(mid 411.712664 -402.284438)
				(end 411.971744 -402.284438)
			)
		)
		(stroke
			(width 0)
			(type solid)
		)
		(fill yes)
		(layer "In15.Cu")
		(net "GND")
	)
	(gr_poly
		(pts
			(arc
				(start 413.171894 -402.309838)
				(mid 412.912814 -402.309838)
				(end 413.171894 -402.309838)
			)
		)
		(stroke
			(width 0)
			(type solid)
		)
		(fill yes)
		(layer "In15.Cu")
		(net "GND")
	)
	(gr_poly
		(pts
			(arc
				(start 414.37179 -402.309838)
				(mid 414.11271 -402.309838)
				(end 414.37179 -402.309838)
			)
		)
		(stroke
			(width 0)
			(type solid)
		)
		(fill yes)
		(layer "In15.Cu")
		(net "GND")
	)
	(gr_poly
		(pts
			(arc
				(start 415.57194 -402.309838)
				(mid 415.31286 -402.309838)
				(end 415.57194 -402.309838)
			)
		)
		(stroke
			(width 0)
			(type solid)
		)
		(fill yes)
		(layer "In15.Cu")
		(net "GND")
	)
	(gr_poly
		(pts
			(arc
				(start 416.771836 -402.309838)
				(mid 416.512756 -402.309838)
				(end 416.771836 -402.309838)
			)
		)
		(stroke
			(width 0)
			(type solid)
		)
		(fill yes)
		(layer "In15.Cu")
		(net "GND")
	)
	(gr_poly
		(pts
			(arc
				(start 417.971732 -402.259038)
				(mid 417.712652 -402.259038)
				(end 417.971732 -402.259038)
			)
		)
		(stroke
			(width 0)
			(type solid)
		)
		(fill yes)
		(layer "In15.Cu")
		(net "GND")
	)
	(gr_poly
		(pts
			(arc
				(start 419.171628 -402.309838)
				(mid 418.912548 -402.309838)
				(end 419.171628 -402.309838)
			)
		)
		(stroke
			(width 0)
			(type solid)
		)
		(fill yes)
		(layer "In15.Cu")
		(net "GND")
	)
	(gr_poly
		(pts
			(arc
				(start 420.371778 -402.309838)
				(mid 420.112698 -402.309838)
				(end 420.371778 -402.309838)
			)
		)
		(stroke
			(width 0)
			(type solid)
		)
		(fill yes)
		(layer "In15.Cu")
		(net "GND")
	)
	(gr_poly
		(pts
			(arc
				(start 421.571674 -402.284438)
				(mid 421.312594 -402.284438)
				(end 421.571674 -402.284438)
			)
		)
		(stroke
			(width 0)
			(type solid)
		)
		(fill yes)
		(layer "In15.Cu")
		(net "GND")
	)
	(gr_poly
		(pts
			(arc
				(start 425.23156 -390.617456)
				(mid 424.97248 -390.617456)
				(end 425.23156 -390.617456)
			)
		)
		(stroke
			(width 0)
			(type solid)
		)
		(fill yes)
		(layer "In15.Cu")
		(net "GND")
	)
	(gr_poly
		(pts
			(xy 229.6795 -435.74208) (xy 229.6795 -422.049194) (xy 234.763056 -416.965638) (xy 272.06448 -416.965638)
			(xy 280.05024 -408.979878)
			(arc
				(start 280.05024 -394.963396)
				(mid 280.046339 -394.943873)
				(end 280.035254 -394.927328)
			)
			(arc
				(start 279.651206 -394.54328)
				(mid 279.634672 -394.532169)
				(end 279.615138 -394.528294)
			)
			(xy 278.21382 -394.528294) (xy 241.711734 -394.528294) (xy 240.424208 -394.528294) (xy 239.91189 -395.040612)
			(xy 239.91189 -404.086822) (xy 239.91189 -405.227536) (xy 239.91189 -405.609298) (xy 234.87634 -410.644848)
			(xy 229.69855 -410.644848) (xy 229.676198 -410.6672) (xy 227.067872 -413.275526) (xy 196.769482 -413.275526)
			(xy 196.26072 -413.784288) (xy 196.26072 -414.072832) (xy 196.26072 -421.757602)
			(arc
				(start 206.039974 -431.536856)
				(mid 206.051085 -431.55339)
				(end 206.05496 -431.572924)
			)
			(xy 206.05496 -435.09946) (xy 207.43418 -436.47868) (xy 228.9429 -436.47868)
		)
		(stroke
			(width 0)
			(type solid)
		)
		(fill yes)
		(layer "In15.Cu")
		(net "P12V_PSU")
	)
	(gr_poly
		(pts
			(arc
				(start 6.795008 -404.849584)
				(mid 6.830929 -404.834705)
				(end 6.845808 -404.798784)
			)
			(arc
				(start 6.845808 -396.324836)
				(mid 6.890013 -396.103076)
				(end 7.015734 -395.915134)
			)
			(arc
				(start 9.847326 -393.083542)
				(mid 9.858437 -393.067008)
				(end 9.862312 -393.047474)
			)
			(arc
				(start 9.862312 -388.789926)
				(mid 9.858411 -388.770403)
				(end 9.847326 -388.753858)
			)
			(arc
				(start 4.112768 -383.019554)
				(mid 4.086777 -383.005548)
				(end 4.057396 -383.008378)
			)
			(xy 4.043172 -383.014474) (xy 4.026154 -383.039874)
			(arc
				(start 4.026154 -403.383496)
				(mid 4.030055 -403.403019)
				(end 4.04114 -403.419564)
			)
			(arc
				(start 5.456174 -404.834598)
				(mid 5.472708 -404.845709)
				(end 5.492242 -404.849584)
			)
		)
		(stroke
			(width 0)
			(type solid)
		)
		(fill yes)
		(layer "In15.Cu")
		(net "GND")
	)
	(gr_poly
		(pts
			(arc
				(start 56.669686 -335.144872)
				(mid 56.689043 -335.141039)
				(end 56.7055 -335.13014)
			)
			(arc
				(start 56.934354 -334.901286)
				(mid 56.945465 -334.884752)
				(end 56.94934 -334.865218)
			)
			(xy 56.94934 -327.111868) (xy 56.185816 -326.348344) (xy 23.696168 -326.348344) (xy 22.98446 -327.060052)
			(xy 22.98446 -333.504794) (xy 23.00351 -333.53121)
			(arc
				(start 23.019258 -333.536544)
				(mid 23.279549 -333.89824)
				(end 23.019258 -334.259936)
			)
			(xy 23.00351 -334.26527) (xy 22.98446 -334.291686)
			(arc
				(start 22.98446 -334.623918)
				(mid 22.988361 -334.643441)
				(end 22.999446 -334.659986)
			)
			(arc
				(start 23.4696 -335.13014)
				(mid 23.486046 -335.141066)
				(end 23.505414 -335.144872)
			)
		)
		(stroke
			(width 0)
			(type solid)
		)
		(fill yes)
		(layer "In15.Cu")
		(net "PVDDIO_P1")
	)
	(gr_poly
		(pts
			(arc
				(start 81.154778 -2.750312)
				(mid 81.182917 -2.732466)
				(end 81.193894 -2.701036)
			)
			(arc
				(start 81.193894 -0.5588)
				(mid 81.179015 -0.522879)
				(end 81.143094 -0.508)
			)
			(arc
				(start 13.660882 -0.508)
				(mid 13.624961 -0.522879)
				(end 13.610082 -0.5588)
			)
			(arc
				(start 13.610082 -2.701036)
				(mid 13.621129 -2.732411)
				(end 13.649198 -2.750312)
			)
			(xy 13.762482 -2.77749) (xy 13.794486 -2.762504)
			(arc
				(start 13.80236 -2.746756)
				(mid 13.928356 -2.557713)
				(end 14.095984 -2.404364)
			)
			(xy 14.11732 -2.363216) (xy 14.11732 -1.014984) (xy 80.686656 -1.014984) (xy 80.686656 -2.363216)
			(arc
				(start 80.707992 -2.404364)
				(mid 80.875659 -2.55768)
				(end 81.001616 -2.746756)
			)
			(xy 81.00949 -2.762504) (xy 81.041494 -2.77749)
		)
		(stroke
			(width 0)
			(type solid)
		)
		(fill yes)
		(layer "In15.Cu")
		(net "GND")
	)
	(gr_poly
		(pts
			(arc
				(start 194.154806 -8.03021)
				(mid 194.182945 -8.012364)
				(end 194.193922 -7.980934)
			)
			(arc
				(start 194.193922 -5.838698)
				(mid 194.179043 -5.802777)
				(end 194.143122 -5.787898)
			)
			(arc
				(start 126.66091 -5.787898)
				(mid 126.624989 -5.802777)
				(end 126.61011 -5.838698)
			)
			(arc
				(start 126.61011 -7.980934)
				(mid 126.621157 -8.012309)
				(end 126.649226 -8.03021)
			)
			(xy 126.76251 -8.057388) (xy 126.794514 -8.042402)
			(arc
				(start 126.802388 -8.026654)
				(mid 126.928384 -7.837611)
				(end 127.096012 -7.684262)
			)
			(xy 127.117348 -7.643114) (xy 127.117348 -6.295136) (xy 193.686684 -6.295136) (xy 193.686684 -7.643114)
			(arc
				(start 193.70802 -7.684262)
				(mid 193.875687 -7.837578)
				(end 194.001644 -8.026654)
			)
			(xy 194.009518 -8.042402) (xy 194.041522 -8.057388)
		)
		(stroke
			(width 0)
			(type solid)
		)
		(fill yes)
		(layer "In15.Cu")
		(net "GND")
	)
	(gr_poly
		(pts
			(arc
				(start 455.654918 -2.75082)
				(mid 455.683057 -2.732974)
				(end 455.694034 -2.701544)
			)
			(arc
				(start 455.694034 -0.5588)
				(mid 455.679155 -0.522879)
				(end 455.643234 -0.508)
			)
			(arc
				(start 388.160768 -0.508)
				(mid 388.124847 -0.522879)
				(end 388.109968 -0.5588)
			)
			(arc
				(start 388.109968 -2.701036)
				(mid 388.121015 -2.732411)
				(end 388.149084 -2.750312)
			)
			(xy 388.262368 -2.77749) (xy 388.294372 -2.762504)
			(arc
				(start 388.302246 -2.746756)
				(mid 388.428345 -2.557672)
				(end 388.596124 -2.404364)
			)
			(arc
				(start 388.596124 -2.404364)
				(mid 388.610195 -2.388884)
				(end 388.616952 -2.369058)
			)
			(xy 388.616952 -1.014984) (xy 455.186796 -1.014984) (xy 455.186796 -2.36347)
			(arc
				(start 455.208132 -2.404618)
				(mid 455.3758 -2.558068)
				(end 455.501756 -2.747264)
			)
			(xy 455.50963 -2.763012) (xy 455.54138 -2.777744)
		)
		(stroke
			(width 0)
			(type solid)
		)
		(fill yes)
		(layer "In15.Cu")
		(net "GND")
	)
	(gr_poly
		(pts
			(arc
				(start 403.563328 -318.63284)
				(mid 403.582715 -318.62889)
				(end 403.599142 -318.617854)
			)
			(arc
				(start 404.00351 -318.21374)
				(mid 404.014621 -318.197206)
				(end 404.018496 -318.177672)
			)
			(arc
				(start 404.018496 -315.934598)
				(mid 404.014546 -315.915211)
				(end 404.00351 -315.898784)
			)
			(arc
				(start 403.106128 -315.001402)
				(mid 403.089594 -314.990291)
				(end 403.07006 -314.986416)
			)
			(arc
				(start 401.530566 -314.986416)
				(mid 401.511179 -314.990366)
				(end 401.494752 -315.001402)
			)
			(arc
				(start 401.318476 -315.177424)
				(mid 401.200556 -315.256308)
				(end 401.061428 -315.284104)
			)
			(arc
				(start 400.896328 -315.284104)
				(mid 400.757189 -315.256334)
				(end 400.63928 -315.177424)
			)
			(xy 400.486372 -315.024516)
			(arc
				(start 400.467322 -315.004196)
				(mid 400.449967 -314.991073)
				(end 400.428714 -314.986416)
			)
			(arc
				(start 395.534388 -314.986416)
				(mid 395.515001 -314.990366)
				(end 395.498574 -315.001402)
			)
			(arc
				(start 394.817092 -315.682884)
				(mid 394.80603 -315.699301)
				(end 394.802106 -315.718698)
			)
			(arc
				(start 394.802106 -317.735458)
				(mid 394.806007 -317.754981)
				(end 394.817092 -317.771526)
			)
			(arc
				(start 395.66342 -318.617854)
				(mid 395.679954 -318.628965)
				(end 395.699488 -318.63284)
			)
		)
		(stroke
			(width 0)
			(type solid)
		)
		(fill yes)
		(layer "In15.Cu")
		(net "GND")
	)
	(gr_poly
		(pts
			(arc
				(start 7.548626 -137.9601)
				(mid 7.568149 -137.956199)
				(end 7.584694 -137.945114)
			)
			(arc
				(start 7.679944 -137.849864)
				(mid 7.691055 -137.83333)
				(end 7.69493 -137.813796)
			)
			(xy 7.69493 -135.794496) (xy 7.67461 -135.767572)
			(arc
				(start 7.6581 -135.762746)
				(mid 7.381151 -135.39597)
				(end 7.6581 -135.029194)
			)
			(xy 7.67461 -135.024368) (xy 7.69493 -134.997444)
			(arc
				(start 7.69493 -132.962396)
				(mid 7.691029 -132.942873)
				(end 7.679944 -132.926328)
			)
			(arc
				(start 7.584694 -132.831078)
				(mid 7.56816 -132.819967)
				(end 7.548626 -132.816092)
			)
			(arc
				(start 4.00177 -132.816092)
				(mid 3.982247 -132.819993)
				(end 3.965702 -132.831078)
			)
			(arc
				(start 3.870452 -132.926328)
				(mid 3.859341 -132.942862)
				(end 3.855466 -132.962396)
			)
			(arc
				(start 3.855466 -137.813796)
				(mid 3.859367 -137.833319)
				(end 3.870452 -137.849864)
			)
			(arc
				(start 3.965702 -137.945114)
				(mid 3.982236 -137.956225)
				(end 4.00177 -137.9601)
			)
		)
		(stroke
			(width 0)
			(type solid)
		)
		(fill yes)
		(layer "In15.Cu")
		(net "GND")
	)
	(gr_poly
		(pts
			(arc
				(start 192.033398 -363.35462)
				(mid 192.052921 -363.350719)
				(end 192.069466 -363.339634)
			)
			(arc
				(start 197.233286 -358.175814)
				(mid 197.244397 -358.15928)
				(end 197.248272 -358.139746)
			)
			(arc
				(start 197.248272 -352.069146)
				(mid 197.244371 -352.049623)
				(end 197.233286 -352.033078)
			)
			(arc
				(start 196.755258 -351.55505)
				(mid 196.738724 -351.543939)
				(end 196.71919 -351.540064)
			)
			(arc
				(start 191.678052 -351.540064)
				(mid 191.658529 -351.543965)
				(end 191.641984 -351.55505)
			)
			(arc
				(start 191.634618 -351.562416)
				(mid 191.623507 -351.57895)
				(end 191.619632 -351.598484)
			)
			(arc
				(start 191.619632 -353.568254)
				(mid 191.623533 -353.587777)
				(end 191.634618 -353.604322)
			)
			(xy 191.701928 -353.671632) (xy 191.71158 -353.671632)
			(arc
				(start 192.481454 -354.441506)
				(mid 192.492565 -354.45804)
				(end 192.49644 -354.477574)
			)
			(arc
				(start 192.49644 -356.745032)
				(mid 192.492539 -356.764555)
				(end 192.481454 -356.7811)
			)
			(arc
				(start 191.764666 -357.497888)
				(mid 191.748132 -357.508999)
				(end 191.728598 -357.512874)
			)
			(arc
				(start 187.955682 -357.512874)
				(mid 187.936159 -357.508973)
				(end 187.919614 -357.497888)
			)
			(arc
				(start 186.852306 -356.43058)
				(mid 186.841195 -356.414046)
				(end 186.83732 -356.394512)
			)
			(arc
				(start 186.83732 -353.281742)
				(mid 186.833419 -353.262219)
				(end 186.822334 -353.245674)
			)
			(arc
				(start 185.10631 -351.52965)
				(mid 185.089776 -351.518539)
				(end 185.070242 -351.514664)
			)
			(arc
				(start 183.591962 -351.514664)
				(mid 183.572439 -351.518565)
				(end 183.555894 -351.52965)
			)
			(arc
				(start 183.30799 -351.777554)
				(mid 183.296879 -351.794088)
				(end 183.293004 -351.813622)
			)
			(arc
				(start 183.293004 -353.542854)
				(mid 183.296905 -353.562377)
				(end 183.30799 -353.578922)
			)
			(arc
				(start 184.38495 -354.655882)
				(mid 184.396061 -354.672416)
				(end 184.399936 -354.69195)
			)
			(arc
				(start 184.399936 -362.923074)
				(mid 184.403837 -362.942597)
				(end 184.414922 -362.959142)
			)
			(arc
				(start 184.795414 -363.339634)
				(mid 184.811948 -363.350745)
				(end 184.831482 -363.35462)
			)
		)
		(stroke
			(width 0)
			(type solid)
		)
		(fill yes)
		(layer "In15.Cu")
		(net "SW_P12V_AUX_PVDD11_S3_P1_FLT")
	)
	(gr_poly
		(pts
			(arc
				(start 438.154826 -362.830872)
				(mid 438.174349 -362.826971)
				(end 438.190894 -362.815886)
			)
			(arc
				(start 438.433972 -362.572808)
				(mid 438.445083 -362.556274)
				(end 438.448958 -362.53674)
			)
			(arc
				(start 438.448958 -351.554034)
				(mid 438.445057 -351.534511)
				(end 438.433972 -351.517966)
			)
			(arc
				(start 438.290462 -351.374456)
				(mid 438.273928 -351.363345)
				(end 438.254394 -351.35947)
			)
			(arc
				(start 432.698906 -351.35947)
				(mid 432.679383 -351.363371)
				(end 432.662838 -351.374456)
			)
			(arc
				(start 432.3588 -351.678494)
				(mid 432.347689 -351.695028)
				(end 432.343814 -351.714562)
			)
			(arc
				(start 432.343814 -353.894898)
				(mid 432.347715 -353.914421)
				(end 432.3588 -353.930966)
			)
			(arc
				(start 433.187094 -354.75926)
				(mid 433.198205 -354.775794)
				(end 433.20208 -354.795328)
			)
			(arc
				(start 433.20208 -356.594918)
				(mid 433.198179 -356.614441)
				(end 433.187094 -356.630986)
			)
			(arc
				(start 432.500786 -357.317294)
				(mid 432.484252 -357.328405)
				(end 432.464718 -357.33228)
			)
			(arc
				(start 428.482506 -357.33228)
				(mid 428.462983 -357.328379)
				(end 428.446438 -357.317294)
			)
			(arc
				(start 427.657768 -356.528624)
				(mid 427.646657 -356.51209)
				(end 427.642782 -356.492556)
			)
			(arc
				(start 427.642782 -353.281742)
				(mid 427.638881 -353.262219)
				(end 427.627796 -353.245674)
			)
			(arc
				(start 427.065186 -352.683064)
				(mid 427.054075 -352.66653)
				(end 427.0502 -352.646996)
			)
			(arc
				(start 427.0502 -351.642172)
				(mid 427.046299 -351.622649)
				(end 427.035214 -351.606104)
			)
			(arc
				(start 426.778166 -351.349056)
				(mid 426.761632 -351.337945)
				(end 426.742098 -351.33407)
			)
			(arc
				(start 424.290998 -351.33407)
				(mid 424.271475 -351.337971)
				(end 424.25493 -351.349056)
			)
			(arc
				(start 424.032172 -351.571814)
				(mid 424.021061 -351.588348)
				(end 424.017186 -351.607882)
			)
			(arc
				(start 424.017186 -353.809554)
				(mid 424.021087 -353.829077)
				(end 424.032172 -353.845622)
			)
			(arc
				(start 425.938188 -355.751638)
				(mid 425.949299 -355.768172)
				(end 425.953174 -355.787706)
			)
			(xy 425.953174 -356.634288) (xy 425.951142 -356.63632)
			(arc
				(start 425.951142 -362.13034)
				(mid 425.955043 -362.149863)
				(end 425.966128 -362.166408)
			)
			(arc
				(start 426.615606 -362.815886)
				(mid 426.63214 -362.826997)
				(end 426.651674 -362.830872)
			)
		)
		(stroke
			(width 0)
			(type solid)
		)
		(fill yes)
		(layer "In15.Cu")
		(net "SW_P12V_AUX_PVDD11_S3_P0_FLT")
	)
	(gr_poly
		(pts
			(xy 108.436918 -24.151082) (xy 108.6612 -23.9268) (xy 108.6612 -20.1422) (xy 108.3564 -19.8374) (xy 105.204768 -19.8374)
			(xy 104.6226 -19.8374) (xy 103.8352 -20.6248) (xy 103.8352 -24.54148) (xy 104.799891 -24.54148) (xy 104.803956 -24.485932)
			(xy 104.816066 -24.431567) (xy 104.835963 -24.379546) (xy 104.863222 -24.330975) (xy 104.897262 -24.286892)
			(xy 104.937359 -24.248234) (xy 104.982656 -24.215826) (xy 105.03219 -24.190359) (xy 105.084904 -24.172376)
			(xy 105.139674 -24.162259) (xy 105.195333 -24.160225) (xy 105.250696 -24.166317) (xy 105.304582 -24.180404)
			(xy 105.355842 -24.202188) (xy 105.403385 -24.231202) (xy 105.446196 -24.26683) (xy 105.483363 -24.308311)
			(xy 105.514095 -24.354762) (xy 105.537736 -24.405193) (xy 105.553782 -24.458528) (xy 105.561892 -24.513632)
			(xy 105.5624 -24.54148) (xy 106.273091 -24.54148) (xy 106.277156 -24.485932) (xy 106.289266 -24.431567)
			(xy 106.309163 -24.379546) (xy 106.336422 -24.330975) (xy 106.370462 -24.286892) (xy 106.410559 -24.248234)
			(xy 106.455856 -24.215826) (xy 106.50539 -24.190359) (xy 106.558104 -24.172376) (xy 106.612874 -24.162259)
			(xy 106.668533 -24.160225) (xy 106.723896 -24.166317) (xy 106.777782 -24.180404) (xy 106.829042 -24.202188)
			(xy 106.876585 -24.231202) (xy 106.919396 -24.26683) (xy 106.956563 -24.308311) (xy 106.987295 -24.354762)
			(xy 107.010936 -24.405193) (xy 107.026982 -24.458528) (xy 107.035092 -24.513632) (xy 107.0356 -24.54148)
			(xy 107.035092 -24.569328) (xy 107.026982 -24.624432) (xy 107.010936 -24.677767) (xy 106.987295 -24.728198)
			(xy 106.956563 -24.774649) (xy 106.919396 -24.81613) (xy 106.876585 -24.851758) (xy 106.829042 -24.880772)
			(xy 106.777782 -24.902556) (xy 106.723896 -24.916643) (xy 106.668533 -24.922735) (xy 106.612874 -24.920701)
			(xy 106.558104 -24.910584) (xy 106.50539 -24.892601) (xy 106.455856 -24.867134) (xy 106.410559 -24.834726)
			(xy 106.370462 -24.796068) (xy 106.336422 -24.751985) (xy 106.309163 -24.703414) (xy 106.289266 -24.651393)
			(xy 106.277156 -24.597028) (xy 106.273091 -24.54148) (xy 105.5624 -24.54148) (xy 105.561892 -24.569328)
			(xy 105.553782 -24.624432) (xy 105.537736 -24.677767) (xy 105.514095 -24.728198) (xy 105.483363 -24.774649)
			(xy 105.446196 -24.81613) (xy 105.403385 -24.851758) (xy 105.355842 -24.880772) (xy 105.304582 -24.902556)
			(xy 105.250696 -24.916643) (xy 105.195333 -24.922735) (xy 105.139674 -24.920701) (xy 105.084904 -24.910584)
			(xy 105.03219 -24.892601) (xy 104.982656 -24.867134) (xy 104.937359 -24.834726) (xy 104.897262 -24.796068)
			(xy 104.863222 -24.751985) (xy 104.835963 -24.703414) (xy 104.816066 -24.651393) (xy 104.803956 -24.597028)
			(xy 104.799891 -24.54148) (xy 103.8352 -24.54148) (xy 103.8352 -25.3746) (xy 104.0384 -25.5778) (xy 107.0102 -25.5778)
		)
		(stroke
			(width 0)
			(type solid)
		)
		(fill yes)
		(layer "In15.Cu")
		(net "GND")
	)
	(gr_poly
		(pts
			(xy 125.505718 -31.1658) (xy 125.515787 -31.165373) (xy 125.534386 -31.157654) (xy 125.541786 -31.150814)
			(xy 125.918214 -30.774386) (xy 125.925609 -30.767532) (xy 125.944208 -30.75979) (xy 125.954282 -30.7594)
			(xy 127.156718 -30.7594) (xy 127.166787 -30.758973) (xy 127.185386 -30.751254) (xy 127.192786 -30.744414)
			(xy 128.026414 -29.910786) (xy 128.033268 -29.903391) (xy 128.04101 -29.884792) (xy 128.0414 -29.874718)
			(xy 128.0414 -28.682696) (xy 128.041074 -28.6738) (xy 128.034999 -28.65708) (xy 128.023555 -28.643459)
			(xy 128.016 -28.638754) (xy 127.927862 -28.5877) (xy 127.900938 -28.5877) (xy 127.889 -28.594558)
			(xy 127.867202 -28.606699) (xy 127.821109 -28.625802) (xy 127.772916 -28.638722) (xy 127.723448 -28.645238)
			(xy 127.6985 -28.645612) (xy 127.671248 -28.645126) (xy 127.6173 -28.63737) (xy 127.565005 -28.622014)
			(xy 127.515427 -28.599373) (xy 127.469576 -28.569906) (xy 127.428386 -28.534214) (xy 127.392694 -28.493024)
			(xy 127.363227 -28.447173) (xy 127.340586 -28.397595) (xy 127.32523 -28.3453) (xy 127.317474 -28.291352)
			(xy 127.317474 -28.236848) (xy 127.32523 -28.1829) (xy 127.340586 -28.130605) (xy 127.363227 -28.081027)
			(xy 127.392694 -28.035176) (xy 127.428386 -27.993986) (xy 127.469576 -27.958294) (xy 127.515427 -27.928827)
			(xy 127.565005 -27.906186) (xy 127.6173 -27.89083) (xy 127.671248 -27.883074) (xy 127.6985 -27.882596)
			(xy 127.723443 -27.883026) (xy 127.772899 -27.889566) (xy 127.821083 -27.902484) (xy 127.867179 -27.92156)
			(xy 127.889 -27.93365) (xy 127.900938 -27.940508) (xy 127.927862 -27.940508) (xy 128.016 -27.889454)
			(xy 128.023493 -27.884675) (xy 128.034908 -27.871071) (xy 128.041 -27.85439) (xy 128.0414 -27.845512)
			(xy 128.0414 -27.072082) (xy 128.040973 -27.062013) (xy 128.033254 -27.043414) (xy 128.026414 -27.036014)
			(xy 127.548386 -26.557986) (xy 127.540991 -26.551132) (xy 127.522392 -26.54339) (xy 127.512318 -26.543)
			(xy 123.490482 -26.543) (xy 123.480413 -26.543427) (xy 123.461814 -26.551146) (xy 123.454414 -26.557986)
			(xy 122.468386 -27.544014) (xy 122.461532 -27.551409) (xy 122.45379 -27.570008) (xy 122.4534 -27.580082)
			(xy 122.4534 -29.530294) (xy 126.789178 -29.530294) (xy 126.793249 -29.474672) (xy 126.805375 -29.420235)
			(xy 126.825298 -29.368144) (xy 126.852594 -29.319509) (xy 126.88668 -29.275366) (xy 126.926829 -29.236657)
			(xy 126.972187 -29.204206) (xy 127.021787 -29.178705) (xy 127.074571 -29.160698) (xy 127.129414 -29.150568)
			(xy 127.185148 -29.148531) (xy 127.240585 -29.154631) (xy 127.294542 -29.168737) (xy 127.345871 -29.190549)
			(xy 127.393477 -29.219603) (xy 127.436345 -29.255278) (xy 127.473562 -29.296815) (xy 127.504335 -29.343328)
			(xy 127.528007 -29.393825) (xy 127.544075 -29.447232) (xy 127.552195 -29.502408) (xy 127.552704 -29.530294)
			(xy 127.552195 -29.55818) (xy 127.544075 -29.613356) (xy 127.528007 -29.666763) (xy 127.504335 -29.71726)
			(xy 127.473562 -29.763773) (xy 127.436345 -29.80531) (xy 127.393477 -29.840985) (xy 127.345871 -29.870039)
			(xy 127.294542 -29.891851) (xy 127.240585 -29.905957) (xy 127.185148 -29.912057) (xy 127.129414 -29.91002)
			(xy 127.074571 -29.89989) (xy 127.021787 -29.881883) (xy 126.972187 -29.856382) (xy 126.926829 -29.823931)
			(xy 126.88668 -29.785222) (xy 126.852594 -29.741079) (xy 126.825298 -29.692444) (xy 126.805375 -29.640353)
			(xy 126.793249 -29.585916) (xy 126.789178 -29.530294) (xy 122.4534 -29.530294) (xy 122.4534 -30.255718)
			(xy 122.453827 -30.265787) (xy 122.461546 -30.284386) (xy 122.468386 -30.291786) (xy 123.327414 -31.150814)
			(xy 123.334809 -31.157668) (xy 123.353408 -31.16541) (xy 123.363482 -31.1658)
		)
		(stroke
			(width 0)
			(type solid)
		)
		(fill yes)
		(layer "In15.Cu")
		(net "GND")
	)
	(gr_poly
		(pts
			(arc
				(start 124.102114 -12.795504)
				(mid 126.234222 -11.912198)
				(end 127.117348 -9.780016)
			)
			(arc
				(start 127.117348 -9.256776)
				(mid 127.111697 -9.233491)
				(end 127.096012 -9.215374)
			)
			(arc
				(start 127.096012 -9.215374)
				(mid 126.928345 -9.062058)
				(end 126.802388 -8.872982)
			)
			(xy 126.794514 -8.857234) (xy 126.76251 -8.842248)
			(arc
				(start 126.649226 -8.869426)
				(mid 126.621087 -8.887272)
				(end 126.61011 -8.918702)
			)
			(arc
				(start 126.61011 -9.780016)
				(mid 125.875535 -11.553437)
				(end 124.102114 -12.288012)
			)
			(arc
				(start 83.70189 -12.288012)
				(mid 81.928469 -11.553437)
				(end 81.193894 -9.780016)
			)
			(arc
				(start 81.193894 -3.638804)
				(mid 81.182847 -3.607429)
				(end 81.154778 -3.589528)
			)
			(xy 81.041494 -3.56235) (xy 81.00949 -3.577336)
			(arc
				(start 81.001616 -3.593084)
				(mid 80.87562 -3.782127)
				(end 80.707992 -3.935476)
			)
			(arc
				(start 80.707992 -3.935476)
				(mid 80.692292 -3.953586)
				(end 80.686656 -3.976878)
			)
			(arc
				(start 80.686656 -9.780524)
				(mid 81.569887 -11.912452)
				(end 83.70189 -12.795504)
			)
		)
		(stroke
			(width 0)
			(type solid)
		)
		(fill yes)
		(layer "In15.Cu")
		(net "GND")
	)
	(gr_poly
		(pts
			(xy 113.577116 -171.643802) (xy 115.254278 -171.643802) (xy 115.290854 -171.607226) (xy 115.290854 -169.674286)
			(xy 115.290854 -169.629074) (xy 114.39906 -168.73728) (xy 114.39906 -165.691058) (xy 114.65052 -165.439598)
			(xy 115.13058 -165.439598) (xy 118.482364 -165.439598) (xy 118.95836 -164.963602) (xy 121.806716 -164.963602)
			(xy 121.857516 -164.912802) (xy 123.560078 -164.912802) (xy 123.584716 -164.888164) (xy 123.584716 -162.952684)
			(xy 123.584716 -162.863276) (xy 122.70994 -161.9885) (xy 122.70994 -160.958022) (xy 122.70994 -159.71012)
			(xy 123.081542 -159.338518) (xy 123.0884 -159.338518) (xy 126.124716 -156.302202) (xy 127.36576 -156.302202)
			(xy 130.264916 -156.302202) (xy 130.315716 -156.251402) (xy 132.013198 -156.251402) (xy 132.042916 -156.221684)
			(xy 132.042916 -154.291284) (xy 132.042916 -154.196796) (xy 131.17322 -153.3271) (xy 131.17322 -150.215092)
			(xy 130.518154 -149.560026) (xy 130.01498 -149.056852) (xy 129.593848 -148.63572) (xy 107.678474 -148.63572)
			(xy 105.95102 -150.363174) (xy 105.95102 -150.984147) (xy 109.251238 -150.984147) (xy 109.251238 -150.899425)
			(xy 109.259291 -150.815088) (xy 109.275325 -150.731898) (xy 109.299193 -150.650608) (xy 109.330681 -150.571956)
			(xy 109.369503 -150.496653) (xy 109.415306 -150.425381) (xy 109.467677 -150.358785) (xy 109.526142 -150.29747)
			(xy 109.59017 -150.241989) (xy 109.659182 -150.192846) (xy 109.732552 -150.150486) (xy 109.809617 -150.115291)
			(xy 109.889679 -150.087582) (xy 109.972012 -150.067608) (xy 110.055871 -150.055551) (xy 110.140496 -150.05152)
			(xy 110.225121 -150.055551) (xy 110.30898 -150.067608) (xy 110.391313 -150.087582) (xy 110.471375 -150.115291)
			(xy 110.54844 -150.150486) (xy 110.62181 -150.192846) (xy 110.690822 -150.241989) (xy 110.75485 -150.29747)
			(xy 110.813315 -150.358785) (xy 110.865686 -150.425381) (xy 110.911489 -150.496653) (xy 110.950311 -150.571956)
			(xy 110.981799 -150.650608) (xy 111.005667 -150.731898) (xy 111.021701 -150.815088) (xy 111.029754 -150.899425)
			(xy 111.030258 -150.941786) (xy 111.029754 -150.984134) (xy 111.751614 -150.984134) (xy 111.751614 -150.899438)
			(xy 111.759665 -150.815124) (xy 111.775694 -150.731958) (xy 111.799555 -150.650691) (xy 111.831034 -150.572061)
			(xy 111.869845 -150.49678) (xy 111.915635 -150.425528) (xy 111.967991 -150.358952) (xy 112.026439 -150.297654)
			(xy 112.090449 -150.242189) (xy 112.159441 -150.19306) (xy 112.232791 -150.150711) (xy 112.309834 -150.115527)
			(xy 112.389873 -150.087825) (xy 112.472182 -150.067857) (xy 112.556017 -150.055804) (xy 112.640618 -150.051774)
			(xy 112.725219 -150.055804) (xy 112.809054 -150.067857) (xy 112.891363 -150.087825) (xy 112.971402 -150.115527)
			(xy 113.048445 -150.150711) (xy 113.121795 -150.19306) (xy 113.190787 -150.242189) (xy 113.254797 -150.297654)
			(xy 113.313245 -150.358952) (xy 113.365601 -150.425528) (xy 113.411391 -150.49678) (xy 113.450202 -150.572061)
			(xy 113.481681 -150.650691) (xy 113.505542 -150.731958) (xy 113.521571 -150.815124) (xy 113.529622 -150.899438)
			(xy 113.530126 -150.941786) (xy 113.529622 -150.984134) (xy 113.521571 -151.068448) (xy 113.505542 -151.151614)
			(xy 113.481681 -151.232881) (xy 113.450202 -151.311511) (xy 113.411391 -151.386792) (xy 113.365601 -151.458044)
			(xy 113.313245 -151.52462) (xy 113.254797 -151.585918) (xy 113.190787 -151.641383) (xy 113.121795 -151.690512)
			(xy 113.048445 -151.732861) (xy 112.971402 -151.768045) (xy 112.891363 -151.795747) (xy 112.809054 -151.815715)
			(xy 112.725219 -151.827768) (xy 112.640618 -151.831799) (xy 112.556017 -151.827768) (xy 112.472182 -151.815715)
			(xy 112.389873 -151.795747) (xy 112.309834 -151.768045) (xy 112.232791 -151.732861) (xy 112.159441 -151.690512)
			(xy 112.090449 -151.641383) (xy 112.026439 -151.585918) (xy 111.967991 -151.52462) (xy 111.915635 -151.458044)
			(xy 111.869845 -151.386792) (xy 111.831034 -151.311511) (xy 111.799555 -151.232881) (xy 111.775694 -151.151614)
			(xy 111.759665 -151.068448) (xy 111.751614 -150.984134) (xy 111.029754 -150.984134) (xy 111.029754 -150.984147)
			(xy 111.021701 -151.068484) (xy 111.005667 -151.151674) (xy 110.981799 -151.232964) (xy 110.950311 -151.311616)
			(xy 110.911489 -151.386919) (xy 110.865686 -151.458191) (xy 110.813315 -151.524787) (xy 110.75485 -151.586102)
			(xy 110.690822 -151.641583) (xy 110.62181 -151.690726) (xy 110.54844 -151.733086) (xy 110.471375 -151.768281)
			(xy 110.391313 -151.79599) (xy 110.30898 -151.815964) (xy 110.225121 -151.828021) (xy 110.140496 -151.832053)
			(xy 110.055871 -151.828021) (xy 109.972012 -151.815964) (xy 109.889679 -151.79599) (xy 109.809617 -151.768281)
			(xy 109.732552 -151.733086) (xy 109.659182 -151.690726) (xy 109.59017 -151.641583) (xy 109.526142 -151.586102)
			(xy 109.467677 -151.524787) (xy 109.415306 -151.458191) (xy 109.369503 -151.386919) (xy 109.330681 -151.311616)
			(xy 109.299193 -151.232964) (xy 109.275325 -151.151674) (xy 109.259291 -151.068484) (xy 109.251238 -150.984147)
			(xy 105.95102 -150.984147) (xy 105.95102 -160.753552) (xy 110.096554 -164.899086) (xy 110.096554 -171.248832)
			(xy 110.52556 -171.677838) (xy 113.54308 -171.677838)
		)
		(stroke
			(width 0)
			(type solid)
		)
		(fill yes)
		(layer "In15.Cu")
		(net "SW_P12V_AUX_PVDDCR_SOC_P1_FLT")
	)
	(gr_poly
		(pts
			(xy 467.792054 -357.299006)
			(arc
				(start 467.792054 -82.82813)
				(mid 467.983012 -81.868498)
				(end 468.526622 -81.054956)
			)
			(arc
				(start 470.85504 -78.726538)
				(mid 471.178373 -78.242681)
				(end 471.29192 -77.67193)
			)
			(arc
				(start 471.29192 -13.780008)
				(mid 470.854924 -12.725008)
				(end 469.799924 -12.288012)
			)
			(arc
				(start 458.20203 -12.288012)
				(mid 456.428609 -11.553437)
				(end 455.694034 -9.780016)
			)
			(xy 455.694034 -3.638296)
			(arc
				(start 455.693526 -3.63093)
				(mid 455.680691 -3.603937)
				(end 455.654918 -3.588766)
			)
			(xy 455.541634 -3.561842) (xy 455.509884 -3.576574) (xy 455.509884 -3.576828) (xy 455.50963 -3.576828)
			(arc
				(start 455.501756 -3.592576)
				(mid 455.377933 -3.779283)
				(end 455.213466 -3.931412)
			)
			(xy 455.212704 -3.93192)
			(arc
				(start 455.208132 -3.935222)
				(mid 455.192432 -3.953332)
				(end 455.186796 -3.976624)
			)
			(arc
				(start 455.186796 -9.780524)
				(mid 456.070027 -11.912452)
				(end 458.20203 -12.795504)
			)
			(arc
				(start 469.799924 -12.795504)
				(mid 470.496073 -13.083859)
				(end 470.784428 -13.780008)
			)
			(arc
				(start 470.784428 -77.672184)
				(mid 470.70959 -78.048688)
				(end 470.496392 -78.36789)
			)
			(arc
				(start 468.167974 -80.696308)
				(mid 467.514407 -81.674395)
				(end 467.284816 -82.82813)
			)
			(xy 467.284816 -356.98684) (xy 467.630256 -357.33228) (xy 467.75878 -357.33228)
		)
		(stroke
			(width 0)
			(type solid)
		)
		(fill yes)
		(layer "In15.Cu")
		(net "GND")
	)
	(gr_poly
		(pts
			(xy 44.975526 -358.578404) (xy 47.237396 -358.578404) (xy 47.24527 -358.568498) (xy 52.996338 -358.568498)
			(xy 53.000148 -358.564688) (xy 55.211726 -358.564688) (xy 57.556908 -356.219506) (xy 57.556908 -354.007928)
			(arc
				(start 57.556908 -353.838764)
				(mid 57.568019 -353.82223)
				(end 57.571894 -353.802696)
			)
			(xy 57.571894 -348.895416) (xy 57.564274 -348.87662) (xy 57.556908 -348.869508)
			(arc
				(start 57.223406 -348.536006)
				(mid 57.212295 -348.519472)
				(end 57.20842 -348.499938)
			)
			(xy 57.20842 -347.190822) (xy 57.2008 -347.172026) (xy 57.193434 -347.164914)
			(arc
				(start 57.037224 -347.008704)
				(mid 57.02069 -346.997593)
				(end 57.001156 -346.993718)
			)
			(arc
				(start 53.977794 -346.993718)
				(mid 53.941873 -347.008597)
				(end 53.926994 -347.044518)
			)
			(xy 53.926994 -348.97695) (xy 53.934614 -348.995746) (xy 53.94198 -349.002858)
			(arc
				(start 54.981094 -350.041972)
				(mid 54.992205 -350.058506)
				(end 54.99608 -350.07804)
			)
			(arc
				(start 54.99608 -352.233738)
				(mid 54.992179 -352.253261)
				(end 54.981094 -352.269806)
			)
			(arc
				(start 54.597046 -352.653854)
				(mid 54.580512 -352.664965)
				(end 54.560978 -352.66884)
			)
			(arc
				(start 49.971706 -352.66884)
				(mid 49.952183 -352.664939)
				(end 49.935638 -352.653854)
			)
			(arc
				(start 49.23028 -351.948496)
				(mid 49.219169 -351.931962)
				(end 49.215294 -351.912428)
			)
			(arc
				(start 49.215294 -349.47606)
				(mid 49.214048 -349.465128)
				(end 49.210468 -349.454724)
			)
			(arc
				(start 49.20996 -349.453454)
				(mid 49.207243 -349.444102)
				(end 49.206404 -349.434404)
			)
			(xy 49.206404 -348.861126) (xy 49.198784 -348.84233) (xy 49.191418 -348.835218)
			(arc
				(start 48.744886 -348.388686)
				(mid 48.733775 -348.372152)
				(end 48.7299 -348.352618)
			)
			(xy 48.7299 -347.203522) (xy 48.72228 -347.184726) (xy 48.714914 -347.177614)
			(arc
				(start 48.521366 -346.984066)
				(mid 48.504832 -346.972955)
				(end 48.485298 -346.96908)
			)
			(xy 45.65142 -346.96908) (xy 45.632624 -346.9767) (xy 45.625512 -346.984066)
			(arc
				(start 45.58538 -347.024198)
				(mid 45.574269 -347.040732)
				(end 45.570394 -347.060266)
			)
			(arc
				(start 45.570394 -348.96679)
				(mid 45.574295 -348.986313)
				(end 45.58538 -349.002858)
			)
			(xy 45.649388 -349.066612) (xy 45.649388 -349.067628)
			(arc
				(start 46.522894 -349.941134)
				(mid 46.534005 -349.957668)
				(end 46.53788 -349.977202)
			)
			(arc
				(start 46.53788 -352.200718)
				(mid 46.533979 -352.220241)
				(end 46.522894 -352.236786)
			)
			(arc
				(start 46.119288 -352.640392)
				(mid 46.102754 -352.651503)
				(end 46.08322 -352.655378)
			)
			(arc
				(start 41.6814 -352.655378)
				(mid 41.661877 -352.651477)
				(end 41.645332 -352.640392)
			)
			(arc
				(start 40.89908 -351.89414)
				(mid 40.887969 -351.877606)
				(end 40.884094 -351.858072)
			)
			(xy 40.884094 -348.877636) (xy 40.876474 -348.85884) (xy 40.869108 -348.851728)
			(arc
				(start 40.627046 -348.609666)
				(mid 40.615935 -348.593132)
				(end 40.61206 -348.573598)
			)
			(xy 40.61206 -347.129862) (xy 40.60444 -347.111066) (xy 40.597074 -347.103954)
			(arc
				(start 40.446706 -346.953586)
				(mid 40.430172 -346.942475)
				(end 40.410638 -346.9386)
			)
			(xy 37.364162 -346.9386) (xy 37.345366 -346.94622) (xy 37.338254 -346.953586)
			(arc
				(start 37.27958 -347.01226)
				(mid 37.268469 -347.028794)
				(end 37.264594 -347.048328)
			)
			(xy 37.264594 -348.97695) (xy 37.272214 -348.995746) (xy 37.27958 -349.002858) (xy 38.082982 -349.80626)
			(xy 38.08476 -349.80626)
			(arc
				(start 38.181534 -349.903034)
				(mid 38.192645 -349.919568)
				(end 38.19652 -349.939102)
			)
			(arc
				(start 38.19652 -352.287078)
				(mid 38.192619 -352.306601)
				(end 38.181534 -352.323146)
			)
			(arc
				(start 37.874448 -352.630232)
				(mid 37.857914 -352.641343)
				(end 37.83838 -352.645218)
			)
			(arc
				(start 33.34766 -352.645218)
				(mid 33.328137 -352.641317)
				(end 33.311592 -352.630232)
			)
			(arc
				(start 32.61868 -351.93732)
				(mid 32.607569 -351.920786)
				(end 32.603694 -351.901252)
			)
			(xy 32.603694 -348.857316) (xy 32.596074 -348.83852) (xy 32.588708 -348.831408)
			(arc
				(start 32.275526 -348.518226)
				(mid 32.264415 -348.501692)
				(end 32.26054 -348.482158)
			)
			(xy 32.26054 -347.063822) (xy 32.25292 -347.045026) (xy 32.245554 -347.037914) (xy 32.17418 -346.96654)
			(xy 32.1691 -346.96654) (xy 32.168846 -346.966286) (xy 32.161734 -346.95892) (xy 32.142938 -346.9513)
			(xy 29.007562 -346.9513) (xy 29.007562 -346.959682)
			(arc
				(start 28.997148 -346.970096)
				(mid 28.986037 -346.98663)
				(end 28.982162 -347.006164)
			)
			(arc
				(start 28.982162 -348.991682)
				(mid 28.997041 -349.027603)
				(end 29.032962 -349.042482)
			)
			(arc
				(start 29.554678 -349.042482)
				(mid 29.574201 -349.046383)
				(end 29.590746 -349.057468)
			)
			(arc
				(start 29.880814 -349.347536)
				(mid 29.891925 -349.36407)
				(end 29.8958 -349.383604)
			)
			(xy 29.8958 -352.111818) (xy 32.465772 -354.68179) (xy 36.097972 -354.68179) (xy 41.136062 -359.71988)
			(xy 43.53433 -359.71988) (xy 43.83405 -359.71988)
		)
		(stroke
			(width 0)
			(type solid)
		)
		(fill yes)
		(layer "In15.Cu")
		(net "SW_P12V_AUX_PVDDIO_P1_FLT")
	)
	(gr_poly
		(pts
			(arc
				(start 299.863002 -359.95864)
				(mid 299.882525 -359.954739)
				(end 299.89907 -359.943654)
			)
			(arc
				(start 300.347888 -359.494836)
				(mid 300.358999 -359.478302)
				(end 300.362874 -359.458768)
			)
			(arc
				(start 300.362874 -354.641658)
				(mid 300.366775 -354.622135)
				(end 300.37786 -354.60559)
			)
			(arc
				(start 300.687994 -354.295456)
				(mid 300.704528 -354.284345)
				(end 300.724062 -354.28047)
			)
			(arc
				(start 302.543464 -354.28047)
				(mid 302.568607 -354.273812)
				(end 302.587152 -354.255578)
			)
			(arc
				(start 302.587152 -354.255578)
				(mid 302.911826 -353.937619)
				(end 303.351184 -353.821492)
			)
			(arc
				(start 303.351184 -353.821492)
				(mid 303.499571 -353.833956)
				(end 303.643792 -353.871022)
			)
			(xy 303.65192 -353.873816)
			(arc
				(start 303.980342 -353.873816)
				(mid 303.999865 -353.869915)
				(end 304.01641 -353.85883)
			)
			(arc
				(start 304.37836 -353.49688)
				(mid 304.389471 -353.480346)
				(end 304.393346 -353.460812)
			)
			(arc
				(start 304.393346 -348.864682)
				(mid 304.389445 -348.845159)
				(end 304.37836 -348.828614)
			)
			(arc
				(start 303.958498 -348.408752)
				(mid 303.947387 -348.392218)
				(end 303.943512 -348.372684)
			)
			(arc
				(start 303.943512 -347.157802)
				(mid 303.939611 -347.138279)
				(end 303.928526 -347.121734)
			)
			(arc
				(start 303.80051 -346.993718)
				(mid 303.783976 -346.982607)
				(end 303.764442 -346.978732)
			)
			(arc
				(start 300.824392 -346.978732)
				(mid 300.804869 -346.982633)
				(end 300.788324 -346.993718)
			)
			(arc
				(start 300.763432 -347.01861)
				(mid 300.752321 -347.035144)
				(end 300.748446 -347.054678)
			)
			(arc
				(start 300.748446 -348.992952)
				(mid 300.752347 -349.012475)
				(end 300.763432 -349.02902)
			)
			(arc
				(start 301.634906 -349.900494)
				(mid 301.646017 -349.917028)
				(end 301.649892 -349.936562)
			)
			(arc
				(start 301.649892 -352.26117)
				(mid 301.645991 -352.280693)
				(end 301.634906 -352.297238)
			)
			(arc
				(start 301.296578 -352.635566)
				(mid 301.280044 -352.646677)
				(end 301.26051 -352.650552)
			)
			(arc
				(start 296.880026 -352.650552)
				(mid 296.860503 -352.646651)
				(end 296.843958 -352.635566)
			)
			(arc
				(start 296.051732 -351.84334)
				(mid 296.040621 -351.826806)
				(end 296.036746 -351.807272)
			)
			(arc
				(start 296.036746 -348.872302)
				(mid 296.032845 -348.852779)
				(end 296.02176 -348.836234)
			)
			(arc
				(start 295.579038 -348.393512)
				(mid 295.567927 -348.376978)
				(end 295.564052 -348.357444)
			)
			(arc
				(start 295.564052 -347.233494)
				(mid 295.560151 -347.213971)
				(end 295.549066 -347.197426)
			)
			(arc
				(start 295.370758 -347.019118)
				(mid 295.354224 -347.008007)
				(end 295.33469 -347.004132)
			)
			(arc
				(start 292.470332 -347.004132)
				(mid 292.450809 -347.008033)
				(end 292.434264 -347.019118)
			)
			(arc
				(start 292.406832 -347.04655)
				(mid 292.395721 -347.063084)
				(end 292.391846 -347.082618)
			)
			(arc
				(start 292.391846 -349.033592)
				(mid 292.395747 -349.053115)
				(end 292.406832 -349.06966)
			)
			(arc
				(start 293.263066 -349.925894)
				(mid 293.274177 -349.942428)
				(end 293.278052 -349.961962)
			)
			(arc
				(start 293.278052 -352.24847)
				(mid 293.274151 -352.267993)
				(end 293.263066 -352.284538)
			)
			(arc
				(start 292.830758 -352.716846)
				(mid 292.814224 -352.727957)
				(end 292.79469 -352.731832)
			)
			(arc
				(start 288.594546 -352.731832)
				(mid 288.575023 -352.727931)
				(end 288.558478 -352.716846)
			)
			(arc
				(start 287.720532 -351.8789)
				(mid 287.709421 -351.862366)
				(end 287.705546 -351.842832)
			)
			(arc
				(start 287.705546 -348.872302)
				(mid 287.701645 -348.852779)
				(end 287.69056 -348.836234)
			)
			(arc
				(start 287.301178 -348.446852)
				(mid 287.290067 -348.430318)
				(end 287.286192 -348.410784)
			)
			(arc
				(start 287.286192 -347.234002)
				(mid 287.282291 -347.214479)
				(end 287.271206 -347.197934)
			)
			(arc
				(start 287.11271 -347.039438)
				(mid 287.096176 -347.028327)
				(end 287.076642 -347.024452)
			)
			(arc
				(start 284.174692 -347.024452)
				(mid 284.155169 -347.028353)
				(end 284.138624 -347.039438)
			)
			(arc
				(start 284.101032 -347.07703)
				(mid 284.089921 -347.093564)
				(end 284.086046 -347.113098)
			)
			(arc
				(start 284.086046 -349.020892)
				(mid 284.089947 -349.040415)
				(end 284.101032 -349.05696)
			)
			(arc
				(start 284.975046 -349.930974)
				(mid 284.986157 -349.947508)
				(end 284.990032 -349.967042)
			)
			(arc
				(start 284.990032 -352.279458)
				(mid 284.986131 -352.298981)
				(end 284.975046 -352.315526)
			)
			(arc
				(start 284.670246 -352.620326)
				(mid 284.653712 -352.631437)
				(end 284.634178 -352.635312)
			)
			(arc
				(start 280.156666 -352.635312)
				(mid 280.137143 -352.631411)
				(end 280.120598 -352.620326)
			)
			(arc
				(start 279.440132 -351.93986)
				(mid 279.429021 -351.923326)
				(end 279.425146 -351.903792)
			)
			(arc
				(start 279.425146 -348.829122)
				(mid 279.421245 -348.809599)
				(end 279.41016 -348.793054)
			)
			(arc
				(start 278.969978 -348.352872)
				(mid 278.958867 -348.336338)
				(end 278.954992 -348.316804)
			)
			(arc
				(start 278.954992 -347.142562)
				(mid 278.951091 -347.123039)
				(end 278.940006 -347.106494)
			)
			(arc
				(start 278.88311 -347.049598)
				(mid 278.866576 -347.038487)
				(end 278.847042 -347.034612)
			)
			(arc
				(start 275.871432 -347.034612)
				(mid 275.851909 -347.038513)
				(end 275.835364 -347.049598)
			)
			(arc
				(start 275.820632 -347.06433)
				(mid 275.809521 -347.080864)
				(end 275.805646 -347.100398)
			)
			(xy 275.805646 -348.972378)
			(arc
				(start 275.809456 -348.981268)
				(mid 275.812329 -348.990858)
				(end 275.813266 -349.000826)
			)
			(arc
				(start 275.813266 -349.048832)
				(mid 275.817167 -349.068355)
				(end 275.828252 -349.0849)
			)
			(arc
				(start 276.687026 -349.943674)
				(mid 276.698137 -349.960208)
				(end 276.702012 -349.979742)
			)
			(arc
				(start 276.702012 -355.728016)
				(mid 276.705913 -355.747539)
				(end 276.716998 -355.764084)
			)
			(arc
				(start 280.883106 -359.930192)
				(mid 280.89964 -359.941303)
				(end 280.919174 -359.945178)
			)
			(xy 292.166548 -359.945178) (xy 292.18509 -359.952798) (xy 292.190932 -359.95864)
		)
		(stroke
			(width 0)
			(type solid)
		)
		(fill yes)
		(layer "In15.Cu")
		(net "SW_P12V_AUX_PVDDIO_P0_FLT")
	)
	(gr_poly
		(pts
			(xy 395.334744 -176.942242) (xy 395.664944 -176.942242) (xy 395.674949 -176.941747) (xy 395.693433 -176.934081)
			(xy 395.707582 -176.919931) (xy 395.715247 -176.901447) (xy 395.715744 -176.891442) (xy 397.392144 -176.891442)
			(xy 397.402149 -176.890947) (xy 397.420633 -176.883281) (xy 397.434782 -176.869131) (xy 397.442447 -176.850647)
			(xy 397.442944 -176.840642) (xy 397.442944 -174.893224) (xy 396.47368 -173.92396) (xy 396.47368 -170.9039)
			(xy 398.996154 -168.381426) (xy 400.79549 -168.381426) (xy 400.802887 -168.374575) (xy 400.821485 -168.366833)
			(xy 400.831558 -168.36644) (xy 403.658324 -168.36644) (xy 403.658324 -168.364916) (xy 403.988524 -168.364916)
			(xy 403.99853 -168.364424) (xy 404.017016 -168.356761) (xy 404.031165 -168.342609) (xy 404.038826 -168.324122)
			(xy 404.039324 -168.314116) (xy 405.715724 -168.314116) (xy 405.72573 -168.313624) (xy 405.744216 -168.305961)
			(xy 405.758365 -168.291809) (xy 405.766026 -168.273322) (xy 405.766524 -168.263316) (xy 405.766524 -166.384224)
			(xy 404.982172 -165.599872) (xy 404.982172 -162.627056) (xy 405.40559 -162.203638) (xy 409.095702 -162.203638)
			(xy 409.105771 -162.204062) (xy 409.124372 -162.211781) (xy 409.13177 -162.218624) (xy 409.495498 -162.582352)
			(xy 409.502337 -162.589753) (xy 409.510052 -162.608351) (xy 409.510484 -162.61842) (xy 409.510484 -163.475924)
			(xy 409.518104 -163.49472) (xy 409.52547 -163.501832) (xy 409.574492 -163.550854) (xy 409.581888 -163.557707)
			(xy 409.600486 -163.565451) (xy 409.61056 -163.56584) (xy 414.101788 -163.56584) (xy 414.120584 -163.55822)
			(xy 414.127696 -163.550854) (xy 414.133538 -163.545012) (xy 414.140904 -163.5379) (xy 414.148524 -163.519104)
			(xy 414.148524 -161.482532) (xy 413.26816 -160.602168) (xy 409.192476 -156.526484) (xy 397.681958 -156.526484)
			(xy 392.714226 -151.558752) (xy 385.986528 -151.558752) (xy 385.53644 -152.00884) (xy 385.53644 -154.162252)
			(xy 393.797026 -154.162252) (xy 393.801099 -154.106593) (xy 393.813234 -154.05212) (xy 393.83317 -153.999994)
			(xy 393.860484 -153.951326) (xy 393.894592 -153.907154) (xy 393.934769 -153.868419) (xy 393.980157 -153.835947)
			(xy 394.029789 -153.810429) (xy 394.082609 -153.79241) (xy 394.137488 -153.782273) (xy 394.193259 -153.780235)
			(xy 394.248733 -153.786338) (xy 394.302726 -153.800454) (xy 394.354089 -153.822281) (xy 394.401727 -153.851354)
			(xy 394.444623 -153.887053) (xy 394.481865 -153.928617) (xy 394.512659 -153.975161) (xy 394.536347 -154.025692)
			(xy 394.552425 -154.079134) (xy 394.560551 -154.134348) (xy 394.56106 -154.162252) (xy 394.560551 -154.190156)
			(xy 394.552425 -154.24537) (xy 394.536347 -154.298812) (xy 394.512659 -154.349343) (xy 394.481865 -154.395887)
			(xy 394.444623 -154.437451) (xy 394.401727 -154.47315) (xy 394.354089 -154.502223) (xy 394.302726 -154.52405)
			(xy 394.248733 -154.538166) (xy 394.193259 -154.544269) (xy 394.137488 -154.542231) (xy 394.082609 -154.532094)
			(xy 394.029789 -154.514075) (xy 393.980157 -154.488557) (xy 393.934769 -154.456085) (xy 393.894592 -154.41735)
			(xy 393.860484 -154.373178) (xy 393.83317 -154.32451) (xy 393.813234 -154.272384) (xy 393.801099 -154.217911)
			(xy 393.797026 -154.162252) (xy 385.53644 -154.162252) (xy 385.53644 -162.695058) (xy 386.317994 -162.695058)
			(xy 386.317994 -162.610362) (xy 386.326045 -162.526048) (xy 386.342074 -162.442882) (xy 386.365935 -162.361615)
			(xy 386.397414 -162.282985) (xy 386.436225 -162.207704) (xy 386.482015 -162.136452) (xy 386.534371 -162.069876)
			(xy 386.592819 -162.008578) (xy 386.656829 -161.953113) (xy 386.725821 -161.903984) (xy 386.799171 -161.861635)
			(xy 386.876214 -161.826451) (xy 386.956253 -161.798749) (xy 387.038562 -161.778781) (xy 387.122397 -161.766728)
			(xy 387.206998 -161.762698) (xy 387.291599 -161.766728) (xy 387.375434 -161.778781) (xy 387.457743 -161.798749)
			(xy 387.537782 -161.826451) (xy 387.614825 -161.861635) (xy 387.688175 -161.903984) (xy 387.757167 -161.953113)
			(xy 387.821177 -162.008578) (xy 387.879625 -162.069876) (xy 387.931981 -162.136452) (xy 387.977771 -162.207704)
			(xy 388.016582 -162.282985) (xy 388.048061 -162.361615) (xy 388.071922 -162.442882) (xy 388.087951 -162.526048)
			(xy 388.096002 -162.610362) (xy 388.096506 -162.65271) (xy 388.096002 -162.695058) (xy 388.087951 -162.779372)
			(xy 388.071922 -162.862538) (xy 388.048061 -162.943805) (xy 388.016582 -163.022435) (xy 387.977771 -163.097716)
			(xy 387.931981 -163.168968) (xy 387.879625 -163.235544) (xy 387.821177 -163.296842) (xy 387.757167 -163.352307)
			(xy 387.688175 -163.401436) (xy 387.614825 -163.443785) (xy 387.537782 -163.478969) (xy 387.457743 -163.506671)
			(xy 387.375434 -163.526639) (xy 387.291599 -163.538692) (xy 387.206998 -163.542723) (xy 387.122397 -163.538692)
			(xy 387.038562 -163.526639) (xy 386.956253 -163.506671) (xy 386.876214 -163.478969) (xy 386.799171 -163.443785)
			(xy 386.725821 -163.401436) (xy 386.656829 -163.352307) (xy 386.592819 -163.296842) (xy 386.534371 -163.235544)
			(xy 386.482015 -163.168968) (xy 386.436225 -163.097716) (xy 386.397414 -163.022435) (xy 386.365935 -162.943805)
			(xy 386.342074 -162.862538) (xy 386.326045 -162.779372) (xy 386.317994 -162.695058) (xy 385.53644 -162.695058)
			(xy 385.53644 -165.195193) (xy 386.31774 -165.195193) (xy 386.31774 -165.110471) (xy 386.325793 -165.026134)
			(xy 386.341827 -164.942944) (xy 386.365695 -164.861654) (xy 386.397183 -164.783002) (xy 386.436005 -164.707699)
			(xy 386.481808 -164.636427) (xy 386.534179 -164.569831) (xy 386.592644 -164.508516) (xy 386.656672 -164.453035)
			(xy 386.725684 -164.403892) (xy 386.799054 -164.361532) (xy 386.876119 -164.326337) (xy 386.956181 -164.298628)
			(xy 387.038514 -164.278654) (xy 387.122373 -164.266597) (xy 387.206998 -164.262566) (xy 387.291623 -164.266597)
			(xy 387.375482 -164.278654) (xy 387.457815 -164.298628) (xy 387.537877 -164.326337) (xy 387.614942 -164.361532)
			(xy 387.688312 -164.403892) (xy 387.757324 -164.453035) (xy 387.821352 -164.508516) (xy 387.879817 -164.569831)
			(xy 387.932188 -164.636427) (xy 387.977991 -164.707699) (xy 388.016813 -164.783002) (xy 388.048301 -164.861654)
			(xy 388.072169 -164.942944) (xy 388.088203 -165.026134) (xy 388.096256 -165.110471) (xy 388.09676 -165.152832)
			(xy 388.096256 -165.195193) (xy 388.088203 -165.27953) (xy 388.072169 -165.36272) (xy 388.048301 -165.44401)
			(xy 388.016813 -165.522662) (xy 387.977991 -165.597965) (xy 387.932188 -165.669237) (xy 387.879817 -165.735833)
			(xy 387.821352 -165.797148) (xy 387.757324 -165.852629) (xy 387.688312 -165.901772) (xy 387.614942 -165.944132)
			(xy 387.537877 -165.979327) (xy 387.457815 -166.007036) (xy 387.375482 -166.02701) (xy 387.291623 -166.039067)
			(xy 387.206998 -166.043099) (xy 387.122373 -166.039067) (xy 387.038514 -166.02701) (xy 386.956181 -166.007036)
			(xy 386.876119 -165.979327) (xy 386.799054 -165.944132) (xy 386.725684 -165.901772) (xy 386.656672 -165.852629)
			(xy 386.592644 -165.797148) (xy 386.534179 -165.735833) (xy 386.481808 -165.669237) (xy 386.436005 -165.597965)
			(xy 386.397183 -165.522662) (xy 386.365695 -165.44401) (xy 386.341827 -165.36272) (xy 386.325793 -165.27953)
			(xy 386.31774 -165.195193) (xy 385.53644 -165.195193) (xy 385.53644 -167.781732) (xy 387.29666 -169.541952)
			(xy 390.823958 -169.541952) (xy 392.855958 -171.573952) (xy 392.855958 -176.870106) (xy 392.932158 -176.946306)
			(xy 395.334744 -176.946306)
		)
		(stroke
			(width 0)
			(type solid)
		)
		(fill yes)
		(layer "In15.Cu")
		(net "SW_P12V_AUX_PVDDCR_SOC_P0_FLT")
	)
	(gr_poly
		(pts
			(xy 453.286114 -30.026102) (xy 453.296183 -30.025676) (xy 453.314784 -30.017958) (xy 453.322182 -30.011116)
			(xy 454.52792 -28.805378) (xy 454.534599 -28.797966) (xy 454.54217 -28.77953) (xy 454.542652 -28.769564)
			(xy 454.542652 -23.584154) (xy 454.542168 -23.574191) (xy 454.53458 -23.555766) (xy 454.52792 -23.54834)
			(xy 454.288906 -23.309326) (xy 454.281509 -23.302476) (xy 454.262911 -23.294735) (xy 454.252838 -23.29434)
			(xy 452.604886 -23.29434) (xy 452.601584 -23.294848) (xy 452.573447 -23.298204) (xy 452.516889 -23.301765)
			(xy 452.488554 -23.30196) (xy 452.445482 -23.301451) (xy 452.359741 -23.293118) (xy 452.275208 -23.276533)
			(xy 452.192675 -23.251852) (xy 452.112915 -23.219307) (xy 452.036675 -23.179203) (xy 451.96467 -23.131914)
			(xy 451.897575 -23.077886) (xy 451.836018 -23.017623) (xy 451.780576 -22.95169) (xy 451.731769 -22.880706)
			(xy 451.690054 -22.805335) (xy 451.672452 -22.76602) (xy 451.668064 -22.757162) (xy 451.653898 -22.743402)
			(xy 451.635591 -22.735992) (xy 451.625716 -22.73554) (xy 451.362064 -22.73554) (xy 451.351922 -22.735986)
			(xy 451.333213 -22.743829) (xy 451.318982 -22.758285) (xy 451.31482 -22.767544) (xy 451.299294 -22.805242)
			(xy 451.262291 -22.877896) (xy 451.218794 -22.946858) (xy 451.169168 -23.01155) (xy 451.11383 -23.071429)
			(xy 451.053243 -23.125992) (xy 450.987918 -23.174782) (xy 450.918401 -23.217387) (xy 450.845277 -23.253452)
			(xy 450.769159 -23.282674) (xy 450.690686 -23.304806) (xy 450.610517 -23.319664) (xy 450.529325 -23.327122)
			(xy 450.488558 -23.327614) (xy 450.445165 -23.32709) (xy 450.358793 -23.318637) (xy 450.273653 -23.301815)
			(xy 450.190556 -23.276784) (xy 450.110291 -23.243781) (xy 450.03362 -23.203121) (xy 449.961271 -23.15519)
			(xy 449.893933 -23.100443) (xy 449.862702 -23.070312) (xy 449.847716 -23.05558) (xy 449.80606 -23.05558)
			(xy 449.537074 -23.324566) (xy 449.530382 -23.331976) (xy 449.522771 -23.350413) (xy 449.522765 -23.370359)
			(xy 449.530366 -23.3888) (xy 449.537074 -23.396194) (xy 449.543924 -23.403591) (xy 449.551665 -23.422189)
			(xy 449.55206 -23.432262) (xy 449.55206 -24.025098) (xy 449.551636 -24.035167) (xy 449.543918 -24.053769)
			(xy 449.537074 -24.061166) (xy 449.422266 -24.175974) (xy 449.414867 -24.182818) (xy 449.396269 -24.190544)
			(xy 449.386198 -24.19096) (xy 446.685162 -24.19096) (xy 446.675096 -24.191392) (xy 446.656507 -24.199122)
			(xy 446.649094 -24.205946) (xy 446.348866 -24.506174) (xy 446.342024 -24.513573) (xy 446.334306 -24.532172)
			(xy 446.33388 -24.542242) (xy 446.33388 -26.033476) (xy 446.333443 -26.04354) (xy 446.325706 -26.062122)
			(xy 446.318894 -26.069544) (xy 445.875918 -26.51252) (xy 443.647068 -26.51252) (xy 443.635536 -26.51307)
			(xy 443.614779 -26.523123) (xy 443.60719 -26.531824) (xy 443.58197 -26.563204) (xy 443.526717 -26.621767)
			(xy 443.466399 -26.675097) (xy 443.401509 -26.722758) (xy 443.332577 -26.764361) (xy 443.260168 -26.799564)
			(xy 443.184874 -26.82808) (xy 443.107311 -26.849675) (xy 443.028114 -26.864173) (xy 442.947931 -26.871456)
			(xy 442.907674 -26.87193) (xy 442.863879 -26.871407) (xy 442.776712 -26.862796) (xy 442.690817 -26.845649)
			(xy 442.607025 -26.820134) (xy 442.52615 -26.786497) (xy 442.487304 -26.766266) (xy 442.475838 -26.760848)
			(xy 442.45051 -26.760848) (xy 442.439044 -26.766266) (xy 442.4002 -26.786498) (xy 442.319316 -26.820106)
			(xy 442.235522 -26.845609) (xy 442.14963 -26.862762) (xy 442.062468 -26.871398) (xy 442.018674 -26.87193)
			(xy 441.974879 -26.871407) (xy 441.887712 -26.862796) (xy 441.801817 -26.845649) (xy 441.718025 -26.820134)
			(xy 441.63715 -26.786497) (xy 441.598304 -26.766266) (xy 441.586838 -26.760848) (xy 441.56151 -26.760848)
			(xy 441.550044 -26.766266) (xy 441.5112 -26.786498) (xy 441.430316 -26.820106) (xy 441.346522 -26.845609)
			(xy 441.26063 -26.862762) (xy 441.173468 -26.871398) (xy 441.129674 -26.87193) (xy 441.088572 -26.871454)
			(xy 441.006719 -26.863867) (xy 440.925914 -26.84876) (xy 440.846849 -26.826263) (xy 440.770196 -26.796566)
			(xy 440.69661 -26.759923) (xy 440.626719 -26.716648) (xy 440.561119 -26.667108) (xy 440.50037 -26.611727)
			(xy 440.444989 -26.550977) (xy 440.39545 -26.485377) (xy 440.352175 -26.415486) (xy 440.315533 -26.3419)
			(xy 440.285836 -26.265247) (xy 440.263339 -26.186182) (xy 440.248232 -26.105377) (xy 440.240646 -26.023524)
			(xy 440.240166 -25.982422) (xy 440.24072 -25.938122) (xy 440.249537 -25.849963) (xy 440.267075 -25.763117)
			(xy 440.293162 -25.678445) (xy 440.327538 -25.596786) (xy 440.369864 -25.51895) (xy 440.419718 -25.445708)
			(xy 440.476608 -25.377786) (xy 440.507882 -25.346406) (xy 440.514832 -25.338981) (xy 440.522694 -25.320245)
			(xy 440.523122 -25.310084) (xy 440.523122 -23.499318) (xy 440.522616 -23.489268) (xy 440.514894 -23.470708)
			(xy 440.508136 -23.46325) (xy 440.304174 -23.259288) (xy 440.296778 -23.252436) (xy 440.278179 -23.244697)
			(xy 440.268106 -23.244302) (xy 437.684418 -23.244302) (xy 437.674355 -23.24474) (xy 437.655772 -23.252476)
			(xy 437.64835 -23.259288) (xy 437.195722 -23.711916) (xy 437.188876 -23.719314) (xy 437.181144 -23.737913)
			(xy 437.180736 -23.747984) (xy 437.180736 -26.153872) (xy 438.228738 -26.153872) (xy 438.232809 -26.09825)
			(xy 438.244935 -26.043813) (xy 438.264858 -25.991722) (xy 438.292154 -25.943087) (xy 438.32624 -25.898944)
			(xy 438.366389 -25.860235) (xy 438.411747 -25.827784) (xy 438.461347 -25.802283) (xy 438.514131 -25.784276)
			(xy 438.568974 -25.774146) (xy 438.624708 -25.772109) (xy 438.680145 -25.778209) (xy 438.734102 -25.792315)
			(xy 438.785431 -25.814127) (xy 438.833037 -25.843181) (xy 438.875905 -25.878856) (xy 438.913122 -25.920393)
			(xy 438.943895 -25.966906) (xy 438.967567 -26.017403) (xy 438.983635 -26.07081) (xy 438.991755 -26.125986)
			(xy 438.992264 -26.153872) (xy 438.991755 -26.181758) (xy 438.983635 -26.236934) (xy 438.967567 -26.290341)
			(xy 438.943895 -26.340838) (xy 438.913122 -26.387351) (xy 438.875905 -26.428888) (xy 438.833037 -26.464563)
			(xy 438.785431 -26.493617) (xy 438.734102 -26.515429) (xy 438.680145 -26.529535) (xy 438.624708 -26.535635)
			(xy 438.568974 -26.533598) (xy 438.514131 -26.523468) (xy 438.461347 -26.505461) (xy 438.411747 -26.47996)
			(xy 438.366389 -26.447509) (xy 438.32624 -26.4088) (xy 438.292154 -26.364657) (xy 438.264858 -26.316022)
			(xy 438.244935 -26.263931) (xy 438.232809 -26.209494) (xy 438.228738 -26.153872) (xy 437.180736 -26.153872)
			(xy 437.180736 -26.170382) (xy 437.173116 -26.188924) (xy 437.16702 -26.19502) (xy 437.16702 -27.76093)
			(xy 437.167554 -27.770883) (xy 437.175215 -27.789263) (xy 437.189268 -27.803371) (xy 437.198262 -27.807666)
			(xy 437.238606 -27.824999) (xy 437.315983 -27.866518) (xy 437.388887 -27.915467) (xy 437.456608 -27.971368)
			(xy 437.518485 -28.033676) (xy 437.573913 -28.101784) (xy 437.598566 -28.13812) (xy 437.60608 -28.148313)
			(xy 437.628339 -28.160317) (xy 437.640984 -28.16098) (xy 438.414414 -28.16098) (xy 438.426032 -28.1604)
			(xy 438.446913 -28.150202) (xy 438.454546 -28.141422) (xy 438.481093 -28.108055) (xy 438.539599 -28.04602)
			(xy 438.603774 -27.989869) (xy 438.673027 -27.940116) (xy 438.746724 -27.897219) (xy 438.824188 -27.861571)
			(xy 438.904707 -27.8335) (xy 438.987543 -27.813264) (xy 439.071936 -27.801047) (xy 439.15711 -27.796962)
			(xy 439.242284 -27.801047) (xy 439.326677 -27.813264) (xy 439.409513 -27.8335) (xy 439.490032 -27.861571)
			(xy 439.567496 -27.897219) (xy 439.641193 -27.940116) (xy 439.710446 -27.989869) (xy 439.774621 -28.04602)
			(xy 439.833127 -28.108055) (xy 439.859674 -28.141422) (xy 439.866786 -28.15082) (xy 439.887868 -28.16098)
			(xy 439.917332 -28.16098) (xy 439.9274 -28.161408) (xy 439.945998 -28.169129) (xy 439.9534 -28.175966)
			(xy 440.64555 -28.868116) (xy 440.652947 -28.874964) (xy 440.671546 -28.882693) (xy 440.681618 -28.883102)
			(xy 445.131698 -28.883102) (xy 445.141768 -28.883525) (xy 445.160373 -28.891239) (xy 445.167766 -28.898088)
			(xy 446.280794 -30.011116) (xy 446.288188 -30.017972) (xy 446.306787 -30.025722) (xy 446.316862 -30.026102)
		)
		(stroke
			(width 0)
			(type solid)
		)
		(fill yes)
		(layer "In15.Cu")
		(net "P12V_AUX")
	)
	(gr_poly
		(pts
			(xy 440.12866 -22.572218) (xy 440.138688 -22.571805) (xy 440.157222 -22.564143) (xy 440.171411 -22.54997)
			(xy 440.179094 -22.531445) (xy 440.17946 -22.521418) (xy 440.17946 -22.333458) (xy 440.179892 -22.323393)
			(xy 440.187624 -22.304805) (xy 440.194446 -22.29739) (xy 441.38342 -21.108416) (xy 441.390104 -21.101006)
			(xy 441.397689 -21.08257) (xy 441.398152 -21.072602) (xy 441.398152 -14.726158) (xy 441.398584 -14.716092)
			(xy 441.406315 -14.697504) (xy 441.413138 -14.69009) (xy 441.74791 -14.355318) (xy 441.754707 -14.347968)
			(xy 441.762408 -14.329505) (xy 441.762896 -14.319504) (xy 441.762896 -10.64514) (xy 441.762462 -10.635075)
			(xy 441.754732 -10.616487) (xy 441.74791 -10.609072) (xy 441.360052 -10.221214) (xy 441.352652 -10.214373)
			(xy 441.334053 -10.206654) (xy 441.323984 -10.206228) (xy 437.480964 -10.206228) (xy 437.470897 -10.206658)
			(xy 437.452305 -10.214385) (xy 437.444896 -10.221214) (xy 436.91429 -10.75182) (xy 436.907437 -10.759215)
			(xy 436.899695 -10.777814) (xy 436.899304 -10.787888) (xy 436.899304 -14.484096) (xy 438.361836 -14.484096)
			(xy 438.362291 -14.456725) (xy 438.37011 -14.402545) (xy 438.385601 -14.350042) (xy 438.408446 -14.300295)
			(xy 438.438173 -14.254329) (xy 438.455816 -14.233398) (xy 438.461912 -14.226286) (xy 438.468262 -14.209268)
			(xy 438.468262 -14.123924) (xy 438.461912 -14.106906) (xy 438.455816 -14.099794) (xy 438.438163 -14.078873)
			(xy 438.408453 -14.032897) (xy 438.385619 -13.983147) (xy 438.370131 -13.930644) (xy 438.362308 -13.876466)
			(xy 438.361836 -13.849096) (xy 438.362252 -13.821841) (xy 438.37001 -13.767886) (xy 438.385369 -13.715585)
			(xy 438.408015 -13.666002) (xy 438.437488 -13.620146) (xy 438.473187 -13.578953) (xy 438.514385 -13.543259)
			(xy 438.560244 -13.513792) (xy 438.60983 -13.491152) (xy 438.662133 -13.4758) (xy 438.716089 -13.468048)
			(xy 438.743344 -13.467588) (xy 438.770713 -13.46809) (xy 438.82489 -13.475899) (xy 438.877393 -13.49138)
			(xy 438.92714 -13.514214) (xy 438.973109 -13.543931) (xy 438.994042 -13.561568) (xy 439.001154 -13.567664)
			(xy 439.018172 -13.574014) (xy 439.103516 -13.574014) (xy 439.120534 -13.567664) (xy 439.127646 -13.561568)
			(xy 439.148584 -13.543936) (xy 439.194555 -13.514224) (xy 439.244302 -13.491387) (xy 439.296801 -13.475894)
			(xy 439.350975 -13.468064) (xy 439.378344 -13.467588) (xy 439.405596 -13.468037) (xy 439.459545 -13.475799)
			(xy 439.51184 -13.49116) (xy 439.561417 -13.513806) (xy 439.607267 -13.543276) (xy 439.648457 -13.578971)
			(xy 439.684148 -13.620165) (xy 439.713613 -13.666018) (xy 439.736254 -13.715597) (xy 439.751609 -13.767894)
			(xy 439.759366 -13.821844) (xy 439.759852 -13.849096) (xy 439.759395 -13.876467) (xy 439.751577 -13.930647)
			(xy 439.736086 -13.98315) (xy 439.713242 -14.032897) (xy 439.683515 -14.078863) (xy 439.665872 -14.099794)
			(xy 439.659776 -14.106906) (xy 439.653426 -14.123924) (xy 439.653426 -14.209268) (xy 439.659776 -14.226286)
			(xy 439.665872 -14.233398) (xy 439.683519 -14.254324) (xy 439.713231 -14.300298) (xy 439.736066 -14.350047)
			(xy 439.751555 -14.402549) (xy 439.75938 -14.456726) (xy 439.759852 -14.484096) (xy 439.759319 -14.511345)
			(xy 439.751564 -14.565289) (xy 439.736211 -14.61758) (xy 439.713574 -14.667154) (xy 439.684112 -14.713003)
			(xy 439.648426 -14.754192) (xy 439.607241 -14.789883) (xy 439.561397 -14.819351) (xy 439.511825 -14.841995)
			(xy 439.459536 -14.857354) (xy 439.405593 -14.865115) (xy 439.378344 -14.865604) (xy 439.350975 -14.865111)
			(xy 439.296797 -14.8573) (xy 439.244294 -14.841817) (xy 439.194547 -14.818981) (xy 439.148579 -14.789262)
			(xy 439.127646 -14.771624) (xy 439.120534 -14.765528) (xy 439.103516 -14.759178) (xy 439.018172 -14.759178)
			(xy 439.001154 -14.765528) (xy 438.994042 -14.771624) (xy 438.973108 -14.789261) (xy 438.927135 -14.818972)
			(xy 438.877388 -14.841808) (xy 438.824888 -14.8573) (xy 438.770713 -14.865129) (xy 438.743344 -14.865604)
			(xy 438.716092 -14.865104) (xy 438.662142 -14.857353) (xy 438.609845 -14.842002) (xy 438.560265 -14.819364)
			(xy 438.514411 -14.789901) (xy 438.473218 -14.754211) (xy 438.437523 -14.713021) (xy 438.408055 -14.667171)
			(xy 438.385412 -14.617593) (xy 438.370056 -14.565297) (xy 438.362299 -14.511348) (xy 438.361836 -14.484096)
			(xy 436.899304 -14.484096) (xy 436.899304 -16.328136) (xy 438.173876 -16.328136) (xy 438.174345 -16.300766)
			(xy 438.182159 -16.246586) (xy 438.197646 -16.194082) (xy 438.220488 -16.144335) (xy 438.250214 -16.098369)
			(xy 438.267856 -16.077438) (xy 438.273952 -16.070326) (xy 438.280302 -16.053308) (xy 438.280302 -15.967964)
			(xy 438.273952 -15.950946) (xy 438.267856 -15.943834) (xy 438.250212 -15.922906) (xy 438.220502 -15.876931)
			(xy 438.197668 -15.827183) (xy 438.182178 -15.774681) (xy 438.17435 -15.720505) (xy 438.173876 -15.693136)
			(xy 438.174362 -15.665885) (xy 438.182118 -15.611937) (xy 438.197473 -15.559642) (xy 438.220115 -15.510065)
			(xy 438.249581 -15.464215) (xy 438.285272 -15.423024) (xy 438.326463 -15.387333) (xy 438.372313 -15.357867)
			(xy 438.42189 -15.335225) (xy 438.474185 -15.31987) (xy 438.528133 -15.312114) (xy 438.582635 -15.312114)
			(xy 438.636583 -15.31987) (xy 438.688878 -15.335225) (xy 438.738455 -15.357867) (xy 438.784305 -15.387333)
			(xy 438.825496 -15.423024) (xy 438.861187 -15.464215) (xy 438.890653 -15.510065) (xy 438.913295 -15.559642)
			(xy 438.92865 -15.611937) (xy 438.936406 -15.665885) (xy 438.936892 -15.693136) (xy 438.936449 -15.720507)
			(xy 438.928626 -15.774687) (xy 438.913132 -15.827191) (xy 438.890285 -15.876937) (xy 438.860555 -15.922903)
			(xy 438.842912 -15.943834) (xy 438.836816 -15.950946) (xy 438.830466 -15.967964) (xy 438.830466 -16.053308)
			(xy 438.836816 -16.070326) (xy 438.842912 -16.077438) (xy 438.860537 -16.098381) (xy 438.890251 -16.144351)
			(xy 438.913089 -16.194096) (xy 438.928584 -16.246594) (xy 438.936416 -16.300768) (xy 438.936892 -16.328136)
			(xy 438.936406 -16.355387) (xy 438.92865 -16.409335) (xy 438.913295 -16.46163) (xy 438.890653 -16.511207)
			(xy 438.861187 -16.557057) (xy 438.825496 -16.598248) (xy 438.784305 -16.633939) (xy 438.738455 -16.663405)
			(xy 438.688878 -16.686047) (xy 438.636583 -16.701402) (xy 438.582635 -16.709158) (xy 438.528133 -16.709158)
			(xy 438.474185 -16.701402) (xy 438.42189 -16.686047) (xy 438.372313 -16.663405) (xy 438.326463 -16.633939)
			(xy 438.285272 -16.598248) (xy 438.249581 -16.557057) (xy 438.220115 -16.511207) (xy 438.197473 -16.46163)
			(xy 438.182118 -16.409335) (xy 438.174362 -16.355387) (xy 438.173876 -16.328136) (xy 436.899304 -16.328136)
			(xy 436.899304 -16.92021) (xy 436.899704 -16.929697) (xy 436.906602 -16.947376) (xy 436.919425 -16.961364)
			(xy 436.927752 -16.96593) (xy 437.023002 -17.012412) (xy 437.051704 -17.009364) (xy 437.063388 -17.000474)
			(xy 437.083573 -16.985229) (xy 437.127204 -16.959637) (xy 437.173837 -16.940041) (xy 437.222652 -16.926786)
			(xy 437.272792 -16.920105) (xy 437.298084 -16.919702) (xy 437.325337 -16.920164) (xy 437.379288 -16.927919)
			(xy 437.431587 -16.943273) (xy 437.481167 -16.965914) (xy 437.527021 -16.995381) (xy 437.568215 -17.031074)
			(xy 437.603909 -17.072266) (xy 437.633378 -17.118119) (xy 437.656021 -17.167698) (xy 437.671377 -17.219996)
			(xy 437.679135 -17.273947) (xy 437.679135 -17.328453) (xy 437.671377 -17.382404) (xy 437.656021 -17.434702)
			(xy 437.633378 -17.484281) (xy 437.603909 -17.530134) (xy 437.568215 -17.571326) (xy 437.527021 -17.607019)
			(xy 437.481167 -17.636486) (xy 437.431587 -17.659127) (xy 437.379288 -17.674481) (xy 437.325337 -17.682236)
			(xy 437.298084 -17.682718) (xy 437.272793 -17.682305) (xy 437.222656 -17.675618) (xy 437.173842 -17.662362)
			(xy 437.127209 -17.64277) (xy 437.083575 -17.617187) (xy 437.063388 -17.601946) (xy 437.051704 -17.593056)
			(xy 437.023002 -17.590008) (xy 436.927752 -17.63649) (xy 436.919381 -17.641003) (xy 436.906513 -17.654987)
			(xy 436.899643 -17.672706) (xy 436.899304 -17.68221) (xy 436.899304 -22.102826) (xy 436.899732 -22.112894)
			(xy 436.907454 -22.131491) (xy 436.91429 -22.138894) (xy 437.332628 -22.557232) (xy 437.340025 -22.564081)
			(xy 437.358624 -22.571816) (xy 437.368696 -22.572218)
		)
		(stroke
			(width 0)
			(type solid)
		)
		(fill yes)
		(layer "In15.Cu")
		(net "P12V_OCP_SFF_R")
	)
	(gr_poly
		(pts
			(arc
				(start 82.284824 -353.490784)
				(mid 82.304015 -353.487019)
				(end 82.320384 -353.476306)
			)
			(xy 82.320638 -353.476052)
			(arc
				(start 86.388956 -349.407734)
				(mid 86.40549 -349.396623)
				(end 86.425024 -349.392748)
			)
			(arc
				(start 103.42753 -349.392748)
				(mid 103.446721 -349.388983)
				(end 103.46309 -349.37827)
			)
			(xy 103.463344 -349.378016)
			(arc
				(start 104.68864 -348.15272)
				(mid 104.705174 -348.141609)
				(end 104.724708 -348.137734)
			)
			(arc
				(start 106.17581 -348.137734)
				(mid 106.197225 -348.133)
				(end 106.214672 -348.1197)
			)
			(arc
				(start 108.597446 -345.298014)
				(mid 108.60633 -345.28269)
				(end 108.609384 -345.265248)
			)
			(arc
				(start 108.609384 -340.254336)
				(mid 108.594505 -340.218415)
				(end 108.558584 -340.203536)
			)
			(arc
				(start 104.234996 -340.203536)
				(mid 104.215473 -340.207437)
				(end 104.198928 -340.218522)
			)
			(arc
				(start 104.126284 -340.291166)
				(mid 104.115173 -340.3077)
				(end 104.111298 -340.327234)
			)
			(arc
				(start 104.111298 -342.092788)
				(mid 104.115199 -342.112311)
				(end 104.126284 -342.128856)
			)
			(arc
				(start 104.975914 -342.978486)
				(mid 104.987025 -342.99502)
				(end 104.9909 -343.014554)
			)
			(arc
				(start 104.9909 -344.786458)
				(mid 104.986999 -344.805981)
				(end 104.975914 -344.822526)
			)
			(arc
				(start 103.904288 -345.894152)
				(mid 103.887754 -345.905263)
				(end 103.86822 -345.909138)
			)
			(arc
				(start 100.062284 -345.909138)
				(mid 100.042761 -345.905237)
				(end 100.026216 -345.894152)
			)
			(arc
				(start 99.303586 -345.171522)
				(mid 99.292475 -345.154988)
				(end 99.2886 -345.135454)
			)
			(xy 99.2886 -341.435944) (xy 99.286822 -341.422482) (xy 99.281488 -341.403432)
			(arc
				(start 99.278186 -341.397844)
				(mid 99.187491 -341.1814)
				(end 99.15652 -340.948772)
			)
			(arc
				(start 99.15652 -340.948772)
				(mid 99.18747 -340.716138)
				(end 99.278186 -340.4997)
			)
			(xy 99.281488 -340.494112) (xy 99.286822 -340.475062) (xy 99.2886 -340.4616) (xy 99.2886 -335.408016)
			(xy 99.28098 -335.38922) (xy 99.273614 -335.382108)
			(arc
				(start 99.181666 -335.29016)
				(mid 99.165132 -335.279049)
				(end 99.145598 -335.275174)
			)
			(arc
				(start 95.91421 -335.275174)
				(mid 95.894687 -335.279075)
				(end 95.878142 -335.29016)
			)
			(arc
				(start 95.850456 -335.317846)
				(mid 95.839345 -335.33438)
				(end 95.83547 -335.353914)
			)
			(arc
				(start 95.83547 -337.139788)
				(mid 95.839371 -337.159311)
				(end 95.850456 -337.175856)
			)
			(arc
				(start 96.698054 -338.023454)
				(mid 96.709165 -338.039988)
				(end 96.71304 -338.059522)
			)
			(arc
				(start 96.71304 -340.584536)
				(mid 96.709139 -340.604059)
				(end 96.698054 -340.620604)
			)
			(arc
				(start 96.376744 -340.941914)
				(mid 96.36021 -340.953025)
				(end 96.340676 -340.9569)
			)
			(arc
				(start 91.958922 -340.9569)
				(mid 91.939399 -340.952999)
				(end 91.922854 -340.941914)
			)
			(arc
				(start 91.101672 -340.120732)
				(mid 91.090561 -340.104198)
				(end 91.086686 -340.084664)
			)
			(xy 91.086686 -337.091528) (xy 91.079066 -337.072732) (xy 91.0717 -337.06562)
			(arc
				(start 90.783156 -336.777076)
				(mid 90.772045 -336.760542)
				(end 90.76817 -336.741008)
			)
			(xy 90.76817 -335.409032) (xy 90.76055 -335.390236) (xy 90.753184 -335.383124)
			(arc
				(start 90.611706 -335.241646)
				(mid 90.595172 -335.230535)
				(end 90.575638 -335.22666)
			)
			(arc
				(start 87.583264 -335.22666)
				(mid 87.563741 -335.230561)
				(end 87.547196 -335.241646)
			)
			(arc
				(start 87.519256 -335.269586)
				(mid 87.508145 -335.28612)
				(end 87.50427 -335.305654)
			)
			(arc
				(start 87.50427 -337.068668)
				(mid 87.508171 -337.088191)
				(end 87.519256 -337.104736)
			)
			(arc
				(start 88.371934 -337.957414)
				(mid 88.383045 -337.973948)
				(end 88.38692 -337.993482)
			)
			(arc
				(start 88.38692 -340.607396)
				(mid 88.383019 -340.626919)
				(end 88.371934 -340.643464)
			)
			(arc
				(start 88.129364 -340.886034)
				(mid 88.11283 -340.897145)
				(end 88.093296 -340.90102)
			)
			(arc
				(start 83.663282 -340.90102)
				(mid 83.643759 -340.897119)
				(end 83.627214 -340.886034)
			)
			(arc
				(start 82.745072 -340.003892)
				(mid 82.733961 -339.987358)
				(end 82.730086 -339.967824)
			)
			(xy 82.730086 -337.066128) (xy 82.722466 -337.047332) (xy 82.7151 -337.04022)
			(arc
				(start 82.417666 -336.742786)
				(mid 82.406555 -336.726252)
				(end 82.40268 -336.706718)
			)
			(xy 82.40268 -335.35493) (xy 82.39506 -335.336134) (xy 82.387694 -335.329022)
			(arc
				(start 82.321146 -335.262474)
				(mid 82.304612 -335.251363)
				(end 82.285078 -335.247488)
			)
			(arc
				(start 79.213964 -335.247488)
				(mid 79.194441 -335.251389)
				(end 79.177896 -335.262474)
			)
			(xy 79.15275 -335.28762) (xy 79.15275 -335.287874) (xy 79.146654 -335.29397) (xy 79.146654 -337.20913)
			(xy 79.1591 -337.20913)
			(arc
				(start 79.1591 -337.222338)
				(mid 79.163001 -337.241861)
				(end 79.174086 -337.258406)
			)
			(arc
				(start 80.025494 -338.109814)
				(mid 80.036605 -338.126348)
				(end 80.04048 -338.145882)
			)
			(arc
				(start 80.04048 -340.612476)
				(mid 80.036579 -340.631999)
				(end 80.025494 -340.648544)
			)
			(arc
				(start 79.758286 -340.915752)
				(mid 79.741752 -340.926863)
				(end 79.722218 -340.930738)
			)
			(arc
				(start 75.3364 -340.930738)
				(mid 75.316877 -340.926837)
				(end 75.300332 -340.915752)
			)
			(arc
				(start 74.48296 -340.09838)
				(mid 74.471849 -340.081846)
				(end 74.467974 -340.062312)
			)
			(xy 74.467974 -337.187794) (xy 74.05116 -336.77098) (xy 74.05116 -336.729578) (xy 74.05116 -335.401666)
			(xy 74.04354 -335.38287) (xy 74.036174 -335.375758)
			(arc
				(start 73.906126 -335.24571)
				(mid 73.889592 -335.234599)
				(end 73.870058 -335.230724)
			)
			(arc
				(start 70.893432 -335.230724)
				(mid 70.873909 -335.234625)
				(end 70.857364 -335.24571)
			)
			(arc
				(start 70.806056 -335.297018)
				(mid 70.794945 -335.313552)
				(end 70.79107 -335.333086)
			)
			(arc
				(start 70.79107 -337.19516)
				(mid 70.794971 -337.214683)
				(end 70.806056 -337.231228)
			)
			(xy 70.816724 -337.241896) (xy 70.816724 -337.242404)
			(arc
				(start 71.790814 -338.216494)
				(mid 71.801925 -338.233028)
				(end 71.8058 -338.252562)
			)
			(arc
				(start 71.8058 -340.615778)
				(mid 71.809701 -340.635301)
				(end 71.820786 -340.651846)
			)
			(arc
				(start 72.340978 -341.172038)
				(mid 72.352089 -341.188572)
				(end 72.355964 -341.208106)
			)
			(arc
				(start 72.355964 -342.124538)
				(mid 72.359865 -342.144061)
				(end 72.37095 -342.160606)
			)
			(arc
				(start 73.589896 -343.379552)
				(mid 73.601007 -343.396086)
				(end 73.604882 -343.41562)
			)
			(arc
				(start 73.604882 -346.240862)
				(mid 73.600981 -346.260385)
				(end 73.589896 -346.27693)
			)
			(arc
				(start 71.719694 -348.147132)
				(mid 71.70316 -348.158243)
				(end 71.683626 -348.162118)
			)
			(arc
				(start 68.331842 -348.162118)
				(mid 68.312319 -348.158217)
				(end 68.295774 -348.147132)
			)
			(arc
				(start 67.161664 -347.013022)
				(mid 67.14513 -347.001911)
				(end 67.125596 -346.998036)
			)
			(arc
				(start 62.342776 -346.998036)
				(mid 62.323253 -347.001937)
				(end 62.306708 -347.013022)
			)
			(arc
				(start 62.271656 -347.048074)
				(mid 62.260545 -347.064608)
				(end 62.25667 -347.084142)
			)
			(arc
				(start 62.25667 -349.001588)
				(mid 62.260571 -349.021111)
				(end 62.271656 -349.037656)
			)
			(xy 63.180468 -349.946468)
			(arc
				(start 63.180976 -349.946976)
				(mid 63.197333 -349.957718)
				(end 63.216536 -349.961454)
			)
			(xy 63.22695 -349.961454)
			(arc
				(start 64.060324 -350.794828)
				(mid 64.071086 -350.810544)
				(end 64.07531 -350.829118)
			)
			(xy 64.075564 -350.83877) (xy 64.083184 -350.856042) (xy 66.703194 -353.475798)
			(arc
				(start 66.703702 -353.476306)
				(mid 66.720059 -353.487048)
				(end 66.739262 -353.490784)
			)
		)
		(stroke
			(width 0)
			(type solid)
		)
		(fill yes)
		(layer "In15.Cu")
		(net "SW_P12V_AUX_PVDDCR_CPU1_P1_FLT")
	)
	(gr_poly
		(pts
			(xy 16.024352 -415.13887) (xy 16.033682 -415.138461) (xy 16.051109 -415.131793) (xy 16.06499 -415.119323)
			(xy 16.069564 -415.111184) (xy 16.117316 -415.017966) (xy 16.115284 -414.989772) (xy 16.106902 -414.978088)
			(xy 16.090037 -414.953621) (xy 16.063285 -414.900561) (xy 16.045079 -414.843997) (xy 16.035858 -414.785295)
			(xy 16.035274 -414.755584) (xy 16.035761 -414.728333) (xy 16.043519 -414.674386) (xy 16.058875 -414.622092)
			(xy 16.081517 -414.572516) (xy 16.110984 -414.526666) (xy 16.146675 -414.485476) (xy 16.187865 -414.449785)
			(xy 16.233714 -414.420318) (xy 16.28329 -414.397676) (xy 16.335584 -414.38232) (xy 16.389531 -414.374561)
			(xy 16.416782 -414.374076) (xy 16.44924 -414.374725) (xy 16.513222 -414.385701) (xy 16.544036 -414.39592)
			(xy 16.55572 -414.399984) (xy 16.57985 -414.396682) (xy 16.657828 -414.341564) (xy 16.667426 -414.333995)
			(xy 16.678727 -414.312364) (xy 16.679418 -414.300162) (xy 16.679418 -413.873442) (xy 16.678988 -413.864053)
			(xy 16.672243 -413.846528) (xy 16.65967 -413.83258) (xy 16.651478 -413.827976) (xy 16.557244 -413.780732)
			(xy 16.52905 -413.783272) (xy 16.517366 -413.791908) (xy 16.492522 -413.809599) (xy 16.438393 -413.837693)
			(xy 16.380486 -413.856827) (xy 16.320275 -413.866516) (xy 16.289782 -413.867092) (xy 16.262533 -413.866605)
			(xy 16.208589 -413.858846) (xy 16.156299 -413.84349) (xy 16.106726 -413.820849) (xy 16.06088 -413.791384)
			(xy 16.019694 -413.755694) (xy 15.984006 -413.714506) (xy 15.954542 -413.668658) (xy 15.931903 -413.619084)
			(xy 15.91655 -413.566793) (xy 15.908794 -413.512849) (xy 15.908794 -413.458351) (xy 15.91655 -413.404407)
			(xy 15.931903 -413.352116) (xy 15.954542 -413.302542) (xy 15.984006 -413.256694) (xy 16.019694 -413.215506)
			(xy 16.06088 -413.179816) (xy 16.106726 -413.150351) (xy 16.156299 -413.12771) (xy 16.208589 -413.112354)
			(xy 16.262533 -413.104595) (xy 16.289782 -413.104076) (xy 16.316226 -413.10451) (xy 16.368612 -413.111775)
			(xy 16.394176 -413.118554) (xy 16.407638 -413.122364) (xy 16.434308 -413.115506) (xy 16.664432 -412.885128)
			(xy 16.671238 -412.877782) (xy 16.678955 -412.859319) (xy 16.679418 -412.849314) (xy 16.679418 -412.746952)
			(xy 16.678987 -412.736885) (xy 16.671262 -412.718292) (xy 16.664432 -412.710884) (xy 16.440404 -412.486856)
			(xy 16.433564 -412.479455) (xy 16.425845 -412.460857) (xy 16.425418 -412.450788) (xy 16.399002 -412.424372)
			(xy 15.014448 -412.424372) (xy 15.004383 -412.423939) (xy 14.985794 -412.416208) (xy 14.97838 -412.409386)
			(xy 14.684248 -412.115254) (xy 14.677404 -412.107855) (xy 14.669678 -412.089257) (xy 14.669262 -412.079186)
			(xy 14.669262 -407.528776) (xy 14.668834 -407.518709) (xy 14.661109 -407.500114) (xy 14.654276 -407.492708)
			(xy 13.296138 -406.13457) (xy 13.28874 -406.127726) (xy 13.270141 -406.120003) (xy 13.26007 -406.119584)
			(xy 11.902186 -406.119584) (xy 11.892117 -406.120009) (xy 11.873514 -406.127725) (xy 11.866118 -406.13457)
			(xy 11.69289 -406.307798) (xy 11.686034 -406.315192) (xy 11.678284 -406.333791) (xy 11.677904 -406.343866)
			(xy 11.677904 -407.286206) (xy 11.678328 -407.296276) (xy 11.686045 -407.314878) (xy 11.69289 -407.322274)
			(xy 12.977368 -408.606752) (xy 12.98421 -408.614152) (xy 12.99193 -408.63275) (xy 12.992354 -408.64282)
			(xy 12.992354 -408.78887) (xy 13.2748 -408.78887) (xy 13.278871 -408.733248) (xy 13.290997 -408.678811)
			(xy 13.31092 -408.62672) (xy 13.338216 -408.578085) (xy 13.372302 -408.533942) (xy 13.412451 -408.495233)
			(xy 13.457809 -408.462782) (xy 13.507409 -408.437281) (xy 13.560193 -408.419274) (xy 13.615036 -408.409144)
			(xy 13.67077 -408.407107) (xy 13.726207 -408.413207) (xy 13.780164 -408.427313) (xy 13.831493 -408.449125)
			(xy 13.879099 -408.478179) (xy 13.921967 -408.513854) (xy 13.959184 -408.555391) (xy 13.989957 -408.601904)
			(xy 14.013629 -408.652401) (xy 14.029697 -408.705808) (xy 14.037817 -408.760984) (xy 14.038326 -408.78887)
			(xy 14.037817 -408.816756) (xy 14.029697 -408.871932) (xy 14.013629 -408.925339) (xy 13.989957 -408.975836)
			(xy 13.959184 -409.022349) (xy 13.921967 -409.063886) (xy 13.879099 -409.099561) (xy 13.831493 -409.128615)
			(xy 13.780164 -409.150427) (xy 13.726207 -409.164533) (xy 13.67077 -409.170633) (xy 13.615036 -409.168596)
			(xy 13.560193 -409.158466) (xy 13.507409 -409.140459) (xy 13.457809 -409.114958) (xy 13.412451 -409.082507)
			(xy 13.372302 -409.043798) (xy 13.338216 -408.999655) (xy 13.31092 -408.95102) (xy 13.290997 -408.898929)
			(xy 13.278871 -408.844492) (xy 13.2748 -408.78887) (xy 12.992354 -408.78887) (xy 12.992354 -410.31287)
			(xy 13.2748 -410.31287) (xy 13.278871 -410.257248) (xy 13.290997 -410.202811) (xy 13.31092 -410.15072)
			(xy 13.338216 -410.102085) (xy 13.372302 -410.057942) (xy 13.412451 -410.019233) (xy 13.457809 -409.986782)
			(xy 13.507409 -409.961281) (xy 13.560193 -409.943274) (xy 13.615036 -409.933144) (xy 13.67077 -409.931107)
			(xy 13.726207 -409.937207) (xy 13.780164 -409.951313) (xy 13.831493 -409.973125) (xy 13.879099 -410.002179)
			(xy 13.921967 -410.037854) (xy 13.959184 -410.079391) (xy 13.989957 -410.125904) (xy 14.013629 -410.176401)
			(xy 14.029697 -410.229808) (xy 14.037817 -410.284984) (xy 14.038326 -410.31287) (xy 14.037817 -410.340756)
			(xy 14.029697 -410.395932) (xy 14.013629 -410.449339) (xy 13.989957 -410.499836) (xy 13.959184 -410.546349)
			(xy 13.921967 -410.587886) (xy 13.879099 -410.623561) (xy 13.831493 -410.652615) (xy 13.780164 -410.674427)
			(xy 13.726207 -410.688533) (xy 13.67077 -410.694633) (xy 13.615036 -410.692596) (xy 13.560193 -410.682466)
			(xy 13.507409 -410.664459) (xy 13.457809 -410.638958) (xy 13.412451 -410.606507) (xy 13.372302 -410.567798)
			(xy 13.338216 -410.523655) (xy 13.31092 -410.47502) (xy 13.290997 -410.422929) (xy 13.278871 -410.368492)
			(xy 13.2748 -410.31287) (xy 12.992354 -410.31287) (xy 12.992354 -411.83687) (xy 13.2748 -411.83687)
			(xy 13.278871 -411.781248) (xy 13.290997 -411.726811) (xy 13.31092 -411.67472) (xy 13.338216 -411.626085)
			(xy 13.372302 -411.581942) (xy 13.412451 -411.543233) (xy 13.457809 -411.510782) (xy 13.507409 -411.485281)
			(xy 13.560193 -411.467274) (xy 13.615036 -411.457144) (xy 13.67077 -411.455107) (xy 13.726207 -411.461207)
			(xy 13.780164 -411.475313) (xy 13.831493 -411.497125) (xy 13.879099 -411.526179) (xy 13.921967 -411.561854)
			(xy 13.959184 -411.603391) (xy 13.989957 -411.649904) (xy 14.013629 -411.700401) (xy 14.029697 -411.753808)
			(xy 14.037817 -411.808984) (xy 14.038326 -411.83687) (xy 14.037817 -411.864756) (xy 14.029697 -411.919932)
			(xy 14.013629 -411.973339) (xy 13.989957 -412.023836) (xy 13.959184 -412.070349) (xy 13.921967 -412.111886)
			(xy 13.879099 -412.147561) (xy 13.831493 -412.176615) (xy 13.780164 -412.198427) (xy 13.726207 -412.212533)
			(xy 13.67077 -412.218633) (xy 13.615036 -412.216596) (xy 13.560193 -412.206466) (xy 13.507409 -412.188459)
			(xy 13.457809 -412.162958) (xy 13.412451 -412.130507) (xy 13.372302 -412.091798) (xy 13.338216 -412.047655)
			(xy 13.31092 -411.99902) (xy 13.290997 -411.946929) (xy 13.278871 -411.892492) (xy 13.2748 -411.83687)
			(xy 12.992354 -411.83687) (xy 12.992354 -412.782512) (xy 12.999974 -412.801054) (xy 13.000736 -412.801816)
			(xy 13.000736 -413.111696) (xy 13.001159 -413.121766) (xy 13.008877 -413.140368) (xy 13.015722 -413.147764)
			(xy 13.389356 -413.521398) (xy 13.41882 -413.527494) (xy 13.433298 -413.521652) (xy 13.463526 -413.510055)
			(xy 13.526185 -413.493752) (xy 13.590409 -413.485552) (xy 13.622782 -413.485076) (xy 13.653515 -413.485521)
			(xy 13.714534 -413.492927) (xy 13.774214 -413.507635) (xy 13.831687 -413.529429) (xy 13.886114 -413.557992)
			(xy 13.936701 -413.592908) (xy 13.98271 -413.633666) (xy 14.023472 -413.679673) (xy 14.05839 -413.730257)
			(xy 14.086957 -413.784682) (xy 14.108755 -413.842153) (xy 14.123466 -413.901833) (xy 14.130877 -413.962851)
			(xy 14.13129 -413.993584) (xy 14.130787 -414.025545) (xy 14.384776 -414.025545) (xy 14.384776 -413.961623)
			(xy 14.392787 -413.898205) (xy 14.408684 -413.836291) (xy 14.432216 -413.776858) (xy 14.46301 -413.720843)
			(xy 14.500583 -413.669128) (xy 14.54434 -413.622531) (xy 14.593593 -413.581786) (xy 14.647564 -413.547535)
			(xy 14.705403 -413.520318) (xy 14.766196 -413.500565) (xy 14.828986 -413.488587) (xy 14.892782 -413.484574)
			(xy 14.956578 -413.488587) (xy 15.019368 -413.500565) (xy 15.080161 -413.520318) (xy 15.138 -413.547535)
			(xy 15.191971 -413.581786) (xy 15.241224 -413.622531) (xy 15.284981 -413.669128) (xy 15.322554 -413.720843)
			(xy 15.353348 -413.776858) (xy 15.37688 -413.836291) (xy 15.392777 -413.898205) (xy 15.400788 -413.961623)
			(xy 15.40129 -413.993584) (xy 15.400788 -414.025545) (xy 15.392777 -414.088963) (xy 15.37688 -414.150877)
			(xy 15.353348 -414.21031) (xy 15.322554 -414.266325) (xy 15.284981 -414.31804) (xy 15.241224 -414.364637)
			(xy 15.191971 -414.405382) (xy 15.138 -414.439633) (xy 15.080161 -414.46685) (xy 15.019368 -414.486603)
			(xy 14.956578 -414.498581) (xy 14.892782 -414.502595) (xy 14.828986 -414.498581) (xy 14.766196 -414.486603)
			(xy 14.705403 -414.46685) (xy 14.647564 -414.439633) (xy 14.593593 -414.405382) (xy 14.54434 -414.364637)
			(xy 14.500583 -414.31804) (xy 14.46301 -414.266325) (xy 14.432216 -414.21031) (xy 14.408684 -414.150877)
			(xy 14.392787 -414.088963) (xy 14.384776 -414.025545) (xy 14.130787 -414.025545) (xy 14.130781 -414.025955)
			(xy 14.122572 -414.090174) (xy 14.106297 -414.152836) (xy 14.094714 -414.183068) (xy 14.088872 -414.197546)
			(xy 14.094968 -414.22701) (xy 14.991842 -415.123884) (xy 14.999242 -415.130726) (xy 15.01784 -415.138447)
			(xy 15.02791 -415.13887)
		)
		(stroke
			(width 0)
			(type solid)
		)
		(fill yes)
		(layer "In15.Cu")
		(net "PV09_RETIMER_CPU1_VCCS")
	)
	(gr_poly
		(pts
			(arc
				(start 256.800604 -37.135308)
				(mid 258.932532 -36.252077)
				(end 259.815584 -34.120074)
			)
			(arc
				(start 259.815584 -13.780008)
				(mid 260.103939 -13.083859)
				(end 260.800088 -12.795504)
			)
			(arc
				(start 385.601972 -12.795504)
				(mid 387.734244 -11.912288)
				(end 388.61746 -9.780016)
			)
			(arc
				(start 388.61746 -3.976878)
				(mid 388.611809 -3.953593)
				(end 388.596124 -3.935476)
			)
			(arc
				(start 388.596124 -3.935476)
				(mid 388.428347 -3.782165)
				(end 388.302246 -3.593084)
			)
			(xy 388.294372 -3.577336) (xy 388.262368 -3.56235)
			(arc
				(start 388.149084 -3.589528)
				(mid 388.120945 -3.607374)
				(end 388.109968 -3.638804)
			)
			(arc
				(start 388.109968 -9.780016)
				(mid 387.375393 -11.553437)
				(end 385.601972 -12.288012)
			)
			(arc
				(start 260.800088 -12.288012)
				(mid 259.745088 -12.725008)
				(end 259.308092 -13.780008)
			)
			(arc
				(start 259.308092 -34.120074)
				(mid 258.573517 -35.893495)
				(end 256.800096 -36.62807)
			)
			(arc
				(start 225.300032 -36.62807)
				(mid 223.526611 -35.893495)
				(end 222.792036 -34.120074)
			)
			(arc
				(start 222.792036 -13.780008)
				(mid 222.35504 -12.725008)
				(end 221.30004 -12.288012)
			)
			(arc
				(start 196.701918 -12.288012)
				(mid 194.928497 -11.553437)
				(end 194.193922 -9.780016)
			)
			(arc
				(start 194.193922 -8.918702)
				(mid 194.182875 -8.887327)
				(end 194.154806 -8.869426)
			)
			(xy 194.041522 -8.842248) (xy 194.009518 -8.857234)
			(arc
				(start 194.001644 -8.872982)
				(mid 193.875648 -9.062025)
				(end 193.70802 -9.215374)
			)
			(arc
				(start 193.70802 -9.215374)
				(mid 193.69232 -9.233484)
				(end 193.686684 -9.256776)
			)
			(arc
				(start 193.686684 -9.780524)
				(mid 194.569915 -11.912452)
				(end 196.701918 -12.795504)
			)
			(arc
				(start 221.30004 -12.795504)
				(mid 221.996189 -13.083859)
				(end 222.284544 -13.780008)
			)
			(arc
				(start 222.284544 -34.120074)
				(mid 223.16785 -36.252182)
				(end 225.300032 -37.135308)
			)
		)
		(stroke
			(width 0)
			(type solid)
		)
		(fill yes)
		(layer "In15.Cu")
		(net "GND")
	)
	(gr_poly
		(pts
			(xy 380.696724 -180.526182) (xy 379.80366 -179.633118) (xy 379.80366 -177.22596) (xy 380.22022 -176.8094)
			(xy 384.52298 -176.8094) (xy 385.308094 -177.59426) (xy 385.308094 -180.553614) (xy 385.94538 -181.1909)
			(xy 385.94538 -182.337964) (xy 386.09778 -182.490364) (xy 389.016494 -182.490364) (xy 389.027924 -182.478934)
			(xy 389.027924 -180.526182) (xy 388.15772 -179.655978) (xy 388.15772 -176.774094) (xy 387.46303 -176.079404)
			(xy 387.161278 -175.777652) (xy 386.155438 -174.771812) (xy 386.155438 -170.080432) (xy 384.092958 -168.017952)
			(xy 384.092958 -160.016952) (xy 383.711958 -159.635952) (xy 365.421418 -159.635952) (xy 364.534958 -158.749492)
			(xy 364.534958 -150.042372) (xy 363.531658 -149.039072) (xy 352.823018 -149.039072) (xy 350.326452 -151.535638)
			(xy 340.642956 -151.535638) (xy 340.254844 -151.92375) (xy 340.254844 -152.754768) (xy 358.696256 -152.754768)
			(xy 358.696256 -152.670072) (xy 358.704307 -152.585758) (xy 358.720336 -152.502592) (xy 358.744197 -152.421325)
			(xy 358.775676 -152.342695) (xy 358.814487 -152.267414) (xy 358.860277 -152.196162) (xy 358.912633 -152.129586)
			(xy 358.971081 -152.068288) (xy 359.035091 -152.012823) (xy 359.104083 -151.963694) (xy 359.177433 -151.921345)
			(xy 359.254476 -151.886161) (xy 359.334515 -151.858459) (xy 359.416824 -151.838491) (xy 359.500659 -151.826438)
			(xy 359.58526 -151.822408) (xy 359.669861 -151.826438) (xy 359.753696 -151.838491) (xy 359.836005 -151.858459)
			(xy 359.916044 -151.886161) (xy 359.993087 -151.921345) (xy 360.066437 -151.963694) (xy 360.135429 -152.012823)
			(xy 360.199439 -152.068288) (xy 360.257887 -152.129586) (xy 360.310243 -152.196162) (xy 360.356033 -152.267414)
			(xy 360.394844 -152.342695) (xy 360.426323 -152.421325) (xy 360.450184 -152.502592) (xy 360.466213 -152.585758)
			(xy 360.474264 -152.670072) (xy 360.474768 -152.71242) (xy 360.474264 -152.754768) (xy 360.474263 -152.754781)
			(xy 361.196124 -152.754781) (xy 361.196124 -152.670059) (xy 361.204177 -152.585722) (xy 361.220211 -152.502532)
			(xy 361.244079 -152.421242) (xy 361.275567 -152.34259) (xy 361.314389 -152.267287) (xy 361.360192 -152.196015)
			(xy 361.412563 -152.129419) (xy 361.471028 -152.068104) (xy 361.535056 -152.012623) (xy 361.604068 -151.96348)
			(xy 361.677438 -151.92112) (xy 361.754503 -151.885925) (xy 361.834565 -151.858216) (xy 361.916898 -151.838242)
			(xy 362.000757 -151.826185) (xy 362.085382 -151.822154) (xy 362.170007 -151.826185) (xy 362.253866 -151.838242)
			(xy 362.336199 -151.858216) (xy 362.416261 -151.885925) (xy 362.493326 -151.92112) (xy 362.566696 -151.96348)
			(xy 362.635708 -152.012623) (xy 362.699736 -152.068104) (xy 362.758201 -152.129419) (xy 362.810572 -152.196015)
			(xy 362.856375 -152.267287) (xy 362.895197 -152.34259) (xy 362.926685 -152.421242) (xy 362.950553 -152.502532)
			(xy 362.966587 -152.585722) (xy 362.97464 -152.670059) (xy 362.975144 -152.71242) (xy 362.97464 -152.754781)
			(xy 362.966587 -152.839118) (xy 362.950553 -152.922308) (xy 362.926685 -153.003598) (xy 362.895197 -153.08225)
			(xy 362.856375 -153.157553) (xy 362.810572 -153.228825) (xy 362.758201 -153.295421) (xy 362.699736 -153.356736)
			(xy 362.635708 -153.412217) (xy 362.566696 -153.46136) (xy 362.493326 -153.50372) (xy 362.416261 -153.538915)
			(xy 362.336199 -153.566624) (xy 362.253866 -153.586598) (xy 362.170007 -153.598655) (xy 362.085382 -153.602687)
			(xy 362.000757 -153.598655) (xy 361.916898 -153.586598) (xy 361.834565 -153.566624) (xy 361.754503 -153.538915)
			(xy 361.677438 -153.50372) (xy 361.604068 -153.46136) (xy 361.535056 -153.412217) (xy 361.471028 -153.356736)
			(xy 361.412563 -153.295421) (xy 361.360192 -153.228825) (xy 361.314389 -153.157553) (xy 361.275567 -153.08225)
			(xy 361.244079 -153.003598) (xy 361.220211 -152.922308) (xy 361.204177 -152.839118) (xy 361.196124 -152.754781)
			(xy 360.474263 -152.754781) (xy 360.466213 -152.839082) (xy 360.450184 -152.922248) (xy 360.426323 -153.003515)
			(xy 360.394844 -153.082145) (xy 360.356033 -153.157426) (xy 360.310243 -153.228678) (xy 360.257887 -153.295254)
			(xy 360.199439 -153.356552) (xy 360.135429 -153.412017) (xy 360.066437 -153.461146) (xy 359.993087 -153.503495)
			(xy 359.916044 -153.538679) (xy 359.836005 -153.566381) (xy 359.753696 -153.586349) (xy 359.669861 -153.598402)
			(xy 359.58526 -153.602433) (xy 359.500659 -153.598402) (xy 359.416824 -153.586349) (xy 359.334515 -153.566381)
			(xy 359.254476 -153.538679) (xy 359.177433 -153.503495) (xy 359.104083 -153.461146) (xy 359.035091 -153.412017)
			(xy 358.971081 -153.356552) (xy 358.912633 -153.295254) (xy 358.860277 -153.228678) (xy 358.814487 -153.157426)
			(xy 358.775676 -153.082145) (xy 358.744197 -153.003515) (xy 358.720336 -152.922248) (xy 358.704307 -152.839082)
			(xy 358.696256 -152.754768) (xy 340.254844 -152.754768) (xy 340.254844 -160.55086) (xy 340.614508 -160.910524)
			(xy 345.568524 -160.910524) (xy 345.619324 -160.859724) (xy 347.346524 -160.859724) (xy 347.346524 -158.894018)
			(xy 347.346524 -158.830264) (xy 346.47378 -157.95752) (xy 346.47378 -155.477464) (xy 347.07322 -154.878024)
			(xy 351.54743 -154.878024) (xy 352.034094 -155.364688) (xy 352.034094 -158.592774) (xy 352.65106 -159.20974)
			(xy 352.65106 -160.609534) (xy 352.034094 -161.2265) (xy 352.034094 -162.635946) (xy 352.034094 -162.639178)
			(xy 376.980954 -162.639178) (xy 376.980954 -162.554482) (xy 376.989005 -162.470168) (xy 377.005034 -162.387002)
			(xy 377.028895 -162.305735) (xy 377.060374 -162.227105) (xy 377.099185 -162.151824) (xy 377.144975 -162.080572)
			(xy 377.197331 -162.013996) (xy 377.255779 -161.952698) (xy 377.319789 -161.897233) (xy 377.388781 -161.848104)
			(xy 377.462131 -161.805755) (xy 377.539174 -161.770571) (xy 377.619213 -161.742869) (xy 377.701522 -161.722901)
			(xy 377.785357 -161.710848) (xy 377.869958 -161.706818) (xy 377.954559 -161.710848) (xy 378.038394 -161.722901)
			(xy 378.120703 -161.742869) (xy 378.200742 -161.770571) (xy 378.277785 -161.805755) (xy 378.351135 -161.848104)
			(xy 378.420127 -161.897233) (xy 378.484137 -161.952698) (xy 378.542585 -162.013996) (xy 378.594941 -162.080572)
			(xy 378.640731 -162.151824) (xy 378.679542 -162.227105) (xy 378.711021 -162.305735) (xy 378.734882 -162.387002)
			(xy 378.750911 -162.470168) (xy 378.758962 -162.554482) (xy 378.759466 -162.59683) (xy 378.758962 -162.639178)
			(xy 378.750911 -162.723492) (xy 378.734882 -162.806658) (xy 378.711021 -162.887925) (xy 378.679542 -162.966555)
			(xy 378.640731 -163.041836) (xy 378.594941 -163.113088) (xy 378.542585 -163.179664) (xy 378.484137 -163.240962)
			(xy 378.420127 -163.296427) (xy 378.351135 -163.345556) (xy 378.277785 -163.387905) (xy 378.200742 -163.423089)
			(xy 378.120703 -163.450791) (xy 378.038394 -163.470759) (xy 377.954559 -163.482812) (xy 377.869958 -163.486843)
			(xy 377.785357 -163.482812) (xy 377.701522 -163.470759) (xy 377.619213 -163.450791) (xy 377.539174 -163.423089)
			(xy 377.462131 -163.387905) (xy 377.388781 -163.345556) (xy 377.319789 -163.296427) (xy 377.255779 -163.240962)
			(xy 377.197331 -163.179664) (xy 377.144975 -163.113088) (xy 377.099185 -163.041836) (xy 377.060374 -162.966555)
			(xy 377.028895 -162.887925) (xy 377.005034 -162.806658) (xy 376.989005 -162.723492) (xy 376.980954 -162.639178)
			(xy 352.034094 -162.639178) (xy 352.034094 -165.209728) (xy 352.034094 -169.14876) (xy 352.152458 -169.267124)
			(xy 353.874324 -169.267124) (xy 353.925124 -169.216324) (xy 355.652324 -169.216324) (xy 355.652324 -167.235632)
			(xy 354.743766 -166.327074) (xy 354.743766 -163.890706) (xy 354.903278 -163.731194) (xy 355.030278 -163.604194)
			(xy 355.95052 -162.683952) (xy 358.8512 -162.683952) (xy 360.364278 -164.19703) (xy 360.364278 -165.1393)
			(xy 376.980954 -165.1393) (xy 376.980954 -165.054604) (xy 376.989005 -164.97029) (xy 377.005034 -164.887124)
			(xy 377.028895 -164.805857) (xy 377.060374 -164.727227) (xy 377.099185 -164.651946) (xy 377.144975 -164.580694)
			(xy 377.197331 -164.514118) (xy 377.255779 -164.45282) (xy 377.319789 -164.397355) (xy 377.388781 -164.348226)
			(xy 377.462131 -164.305877) (xy 377.539174 -164.270693) (xy 377.619213 -164.242991) (xy 377.701522 -164.223023)
			(xy 377.785357 -164.21097) (xy 377.869958 -164.20694) (xy 377.954559 -164.21097) (xy 378.038394 -164.223023)
			(xy 378.120703 -164.242991) (xy 378.200742 -164.270693) (xy 378.277785 -164.305877) (xy 378.351135 -164.348226)
			(xy 378.420127 -164.397355) (xy 378.484137 -164.45282) (xy 378.542585 -164.514118) (xy 378.594941 -164.580694)
			(xy 378.640731 -164.651946) (xy 378.679542 -164.727227) (xy 378.711021 -164.805857) (xy 378.734882 -164.887124)
			(xy 378.750911 -164.97029) (xy 378.758962 -165.054604) (xy 378.759466 -165.096952) (xy 378.758962 -165.1393)
			(xy 378.750911 -165.223614) (xy 378.734882 -165.30678) (xy 378.711021 -165.388047) (xy 378.679542 -165.466677)
			(xy 378.640731 -165.541958) (xy 378.594941 -165.61321) (xy 378.542585 -165.679786) (xy 378.484137 -165.741084)
			(xy 378.420127 -165.796549) (xy 378.351135 -165.845678) (xy 378.277785 -165.888027) (xy 378.200742 -165.923211)
			(xy 378.120703 -165.950913) (xy 378.038394 -165.970881) (xy 377.954559 -165.982934) (xy 377.869958 -165.986965)
			(xy 377.785357 -165.982934) (xy 377.701522 -165.970881) (xy 377.619213 -165.950913) (xy 377.539174 -165.923211)
			(xy 377.462131 -165.888027) (xy 377.388781 -165.845678) (xy 377.319789 -165.796549) (xy 377.255779 -165.741084)
			(xy 377.197331 -165.679786) (xy 377.144975 -165.61321) (xy 377.099185 -165.541958) (xy 377.060374 -165.466677)
			(xy 377.028895 -165.388047) (xy 377.005034 -165.30678) (xy 376.989005 -165.223614) (xy 376.980954 -165.1393)
			(xy 360.364278 -165.1393) (xy 360.364278 -166.81704) (xy 360.8832 -167.335962) (xy 360.8832 -168.878758)
			(xy 360.364278 -169.39768) (xy 360.364278 -171.01693) (xy 360.364278 -173.541944) (xy 360.364278 -177.35931)
			(xy 360.542078 -177.53711) (xy 362.205524 -177.53711) (xy 362.205524 -177.491644) (xy 363.932724 -177.491644)
			(xy 363.932724 -175.510952) (xy 363.92866 -175.510952) (xy 363.03458 -174.616872) (xy 363.03458 -172.64126)
			(xy 364.53953 -171.13631) (xy 367.417858 -171.13631) (xy 368.569494 -172.287946) (xy 368.569494 -175.06188)
			(xy 369.02898 -175.521366) (xy 369.02898 -177.208434) (xy 368.569494 -177.66792) (xy 368.569494 -179.217066)
			(xy 368.569494 -182.19039) (xy 368.746278 -182.367174) (xy 368.848894 -182.46979) (xy 370.566696 -182.46979)
			(xy 370.566696 -182.464202) (xy 372.293896 -182.464202) (xy 372.293896 -180.48351) (xy 371.414294 -179.603908)
			(xy 371.414294 -177.104294) (xy 371.679978 -176.83861) (xy 372.429278 -176.08931) (xy 375.782078 -176.08931)
			(xy 377.014994 -177.322226) (xy 377.014994 -180.60162) (xy 377.53036 -181.116986) (xy 377.53036 -182.3085)
			(xy 377.712224 -182.490364) (xy 380.696724 -182.490364)
		)
		(stroke
			(width 0)
			(type solid)
		)
		(fill yes)
		(layer "In15.Cu")
		(net "SW_P12V_AUX_PVDDCR_CPU0_P0_FLT")
	)
	(gr_poly
		(pts
			(xy 352.659442 -356.115366) (xy 352.666554 -356.108) (xy 357.12654 -351.648014) (xy 357.133379 -351.640614)
			(xy 357.141092 -351.622015) (xy 357.141526 -351.611946) (xy 357.141526 -341.020146) (xy 357.140002 -341.008462)
			(xy 357.139494 -341.005668) (xy 357.120439 -340.925757) (xy 357.09032 -340.764242) (xy 357.079296 -340.682834)
			(xy 357.07828 -340.674452) (xy 357.070914 -340.659466) (xy 357.059484 -340.648036) (xy 357.056083 -340.644465)
			(xy 357.050587 -340.636277) (xy 357.048562 -340.63178) (xy 357.048562 -340.631526) (xy 357.041196 -340.614)
			(xy 357.039183 -340.609497) (xy 357.033679 -340.601313) (xy 357.030274 -340.597744) (xy 356.695248 -340.262718)
			(xy 356.688136 -340.255352) (xy 356.66934 -340.247732) (xy 352.12274 -340.247732) (xy 352.112675 -340.248167)
			(xy 352.09409 -340.2559) (xy 352.086672 -340.262718) (xy 352.06305 -340.28634) (xy 352.055684 -340.293452)
			(xy 352.048064 -340.312248) (xy 352.048064 -342.255856) (xy 352.055684 -342.274652) (xy 352.06305 -342.281764)
			(xy 352.93046 -343.149174) (xy 352.937299 -343.156575) (xy 352.945013 -343.175173) (xy 352.945446 -343.185242)
			(xy 352.945446 -345.47429) (xy 352.945023 -345.48436) (xy 352.937305 -345.502962) (xy 352.93046 -345.510358)
			(xy 352.513392 -345.927426) (xy 352.505997 -345.934279) (xy 352.487398 -345.942022) (xy 352.477324 -345.942412)
			(xy 348.076266 -345.942412) (xy 348.066198 -345.941983) (xy 348.047602 -345.934261) (xy 348.040198 -345.927426)
			(xy 347.69933 -345.586558) (xy 347.696132 -345.583464) (xy 347.688849 -345.578353) (xy 347.684852 -345.576398)
			(xy 347.677232 -345.572842) (xy 347.668342 -345.571826) (xy 347.668088 -345.571826) (xy 347.640208 -345.568508)
			(xy 347.585778 -345.554743) (xy 347.533951 -345.533155) (xy 347.485843 -345.504212) (xy 347.442491 -345.468536)
			(xy 347.40483 -345.426898) (xy 347.373672 -345.380193) (xy 347.349689 -345.32943) (xy 347.333397 -345.275702)
			(xy 347.325148 -345.220168) (xy 347.32468 -345.192096) (xy 347.325093 -345.166515) (xy 347.331934 -345.115812)
			(xy 347.345494 -345.06648) (xy 347.365528 -345.019404) (xy 347.391678 -344.975429) (xy 347.40723 -344.955114)
			(xy 347.412258 -344.948231) (xy 347.417837 -344.932136) (xy 347.418152 -344.923618) (xy 347.418152 -342.750648)
			(xy 347.410532 -342.731852) (xy 347.403166 -342.72474) (xy 346.981272 -342.302846) (xy 346.974426 -342.295448)
			(xy 346.9667 -342.276849) (xy 346.966286 -342.266778) (xy 346.966286 -340.477348) (xy 346.966718 -340.467282)
			(xy 346.974444 -340.44869) (xy 346.981272 -340.44128) (xy 347.403166 -340.019386) (xy 347.410014 -340.011988)
			(xy 347.417749 -339.99339) (xy 347.418152 -339.983318) (xy 347.418152 -335.491328) (xy 347.410532 -335.472532)
			(xy 347.403166 -335.46542) (xy 347.262704 -335.324958) (xy 347.255592 -335.317846) (xy 347.236796 -335.309972)
			(xy 343.847166 -335.309972) (xy 343.837098 -335.310401) (xy 343.8185 -335.31812) (xy 343.811098 -335.324958)
			(xy 343.787222 -335.348834) (xy 343.779856 -335.355946) (xy 343.772236 -335.374742) (xy 343.772236 -337.358228)
			(xy 343.779856 -337.377024) (xy 343.787222 -337.384136) (xy 344.66022 -338.257134) (xy 344.66707 -338.26453)
			(xy 344.674805 -338.28313) (xy 344.675206 -338.293202) (xy 344.675206 -340.684358) (xy 344.674773 -340.694424)
			(xy 344.667044 -340.713014) (xy 344.66022 -340.720426) (xy 344.456512 -340.924134) (xy 344.449117 -340.93099)
			(xy 344.430519 -340.938739) (xy 344.420444 -340.93912) (xy 339.949028 -340.93912) (xy 339.938963 -340.938684)
			(xy 339.920376 -340.930954) (xy 339.91296 -340.924134) (xy 339.038438 -340.049612) (xy 339.031586 -340.042216)
			(xy 339.023841 -340.023618) (xy 339.023452 -340.013544) (xy 339.023452 -337.066382) (xy 339.015832 -337.047586)
			(xy 339.008466 -337.040474) (xy 338.667852 -336.69986) (xy 338.661006 -336.692462) (xy 338.653278 -336.673863)
			(xy 338.652866 -336.663792) (xy 338.652866 -335.420462) (xy 338.645246 -335.401666) (xy 338.63788 -335.394554)
			(xy 338.480146 -335.23682) (xy 338.472745 -335.22998) (xy 338.454147 -335.222262) (xy 338.444078 -335.221834)
			(xy 335.52003 -335.221834) (xy 335.509966 -335.222271) (xy 335.491383 -335.230007) (xy 335.483962 -335.23682)
			(xy 335.456022 -335.26476) (xy 335.448656 -335.271872) (xy 335.441036 -335.290668) (xy 335.441036 -337.215988)
			(xy 335.448656 -337.234784) (xy 335.456022 -337.241896) (xy 336.30108 -338.086954) (xy 336.30792 -338.094355)
			(xy 336.315638 -338.112953) (xy 336.316066 -338.123022) (xy 336.316066 -340.531958) (xy 336.315632 -340.542023)
			(xy 336.307899 -340.560609) (xy 336.30108 -340.568026) (xy 335.983072 -340.886034) (xy 335.975675 -340.892883)
			(xy 335.957076 -340.900618) (xy 335.947004 -340.90102) (xy 331.549248 -340.90102) (xy 331.539182 -340.900588)
			(xy 331.520589 -340.892863) (xy 331.51318 -340.886034) (xy 330.681838 -340.054692) (xy 330.674989 -340.047295)
			(xy 330.667251 -340.028696) (xy 330.666852 -340.018624) (xy 330.666852 -337.081622) (xy 330.659232 -337.062826)
			(xy 330.651866 -337.055714) (xy 330.321412 -336.72526) (xy 330.314571 -336.71786) (xy 330.306849 -336.699262)
			(xy 330.306426 -336.689192) (xy 330.306426 -335.465674) (xy 330.298806 -335.446878) (xy 330.29144 -335.439766)
			(xy 330.138532 -335.286858) (xy 330.131133 -335.280016) (xy 330.112534 -335.272297) (xy 330.102464 -335.271872)
			(xy 327.145142 -335.271872) (xy 327.135076 -335.272305) (xy 327.116484 -335.280031) (xy 327.109074 -335.286858)
			(xy 327.098406 -335.297526) (xy 327.09104 -335.304638) (xy 327.08342 -335.323434) (xy 327.08342 -337.260692)
			(xy 327.09104 -337.279488) (xy 327.098406 -337.2866) (xy 327.9648 -338.152994) (xy 327.971647 -338.160392)
			(xy 327.979384 -338.17899) (xy 327.979786 -338.189062) (xy 327.979786 -340.524338) (xy 327.979356 -340.534405)
			(xy 327.97163 -340.552998) (xy 327.9648 -340.560406) (xy 327.621392 -340.903814) (xy 327.613997 -340.910668)
			(xy 327.595398 -340.918414) (xy 327.585324 -340.9188) (xy 323.149468 -340.9188) (xy 323.1394 -340.918371)
			(xy 323.120804 -340.910648) (xy 323.1134 -340.903814) (xy 322.419726 -340.21014) (xy 322.412886 -340.202739)
			(xy 322.40517 -340.184141) (xy 322.40474 -340.174072) (xy 322.40474 -337.173062) (xy 322.39712 -337.154266)
			(xy 322.389754 -337.147154) (xy 321.972432 -336.729832) (xy 321.965593 -336.722431) (xy 321.957878 -336.703833)
			(xy 321.957446 -336.693764) (xy 321.957446 -335.473294) (xy 321.949826 -335.454498) (xy 321.94246 -335.447386)
			(xy 321.812412 -335.317338) (xy 321.805016 -335.310486) (xy 321.786418 -335.302741) (xy 321.776344 -335.302352)
			(xy 318.835278 -335.302352) (xy 318.825211 -335.302781) (xy 318.806617 -335.310506) (xy 318.79921 -335.317338)
			(xy 318.742822 -335.373726) (xy 318.735456 -335.380838) (xy 318.727836 -335.399634) (xy 318.727836 -337.279488)
			(xy 318.735456 -337.298284) (xy 318.742822 -337.305396) (xy 319.61582 -338.178394) (xy 319.622676 -338.185788)
			(xy 319.630425 -338.204387) (xy 319.630806 -338.214462) (xy 319.630806 -339.993478) (xy 319.638426 -340.012274)
			(xy 319.645792 -340.019386) (xy 320.276474 -340.650068) (xy 320.283312 -340.657469) (xy 320.291026 -340.676067)
			(xy 320.29146 -340.686136) (xy 320.29146 -342.213946) (xy 320.29908 -342.232742) (xy 320.306446 -342.239854)
			(xy 321.476878 -343.410286) (xy 321.483713 -343.417688) (xy 321.49142 -343.436287) (xy 321.491864 -343.446354)
			(xy 321.491864 -346.25153) (xy 321.491435 -346.261597) (xy 321.483709 -346.28019) (xy 321.476878 -346.287598)
			(xy 319.59169 -348.172786) (xy 319.584291 -348.179632) (xy 319.565693 -348.187365) (xy 319.555622 -348.187772)
			(xy 316.575186 -348.187772) (xy 316.519052 -348.187772) (xy 315.32449 -346.99321) (xy 310.279542 -346.99321)
			(xy 310.277764 -346.994988) (xy 309.473854 -346.994988) (xy 309.455058 -347.002608) (xy 309.447946 -347.009974)
			(xy 309.167276 -347.290644) (xy 309.160428 -347.298041) (xy 309.152698 -347.31664) (xy 309.15229 -347.326712)
			(xy 309.15229 -349.554292) (xy 309.15991 -349.573088) (xy 309.167276 -349.5802) (xy 310.55437 -350.967294)
			(xy 310.561772 -350.97413) (xy 310.58037 -350.98184) (xy 310.590438 -350.98228) (xy 314.216542 -350.98228)
			(xy 314.226609 -350.98271) (xy 314.245205 -350.990433) (xy 314.25261 -350.997266) (xy 315.229424 -351.97408)
			(xy 327.06208 -351.97408) (xy 327.06208 -351.889384) (xy 327.070131 -351.80507) (xy 327.08616 -351.721904)
			(xy 327.110021 -351.640637) (xy 327.1415 -351.562007) (xy 327.180311 -351.486726) (xy 327.226101 -351.415474)
			(xy 327.278457 -351.348898) (xy 327.336905 -351.2876) (xy 327.400915 -351.232135) (xy 327.469907 -351.183006)
			(xy 327.543257 -351.140657) (xy 327.6203 -351.105473) (xy 327.700339 -351.077771) (xy 327.782648 -351.057803)
			(xy 327.866483 -351.04575) (xy 327.951084 -351.04172) (xy 328.035685 -351.04575) (xy 328.11952 -351.057803)
			(xy 328.201829 -351.077771) (xy 328.281868 -351.105473) (xy 328.358911 -351.140657) (xy 328.432261 -351.183006)
			(xy 328.501253 -351.232135) (xy 328.565263 -351.2876) (xy 328.623711 -351.348898) (xy 328.676067 -351.415474)
			(xy 328.721857 -351.486726) (xy 328.760668 -351.562007) (xy 328.792147 -351.640637) (xy 328.816008 -351.721904)
			(xy 328.832037 -351.80507) (xy 328.840088 -351.889384) (xy 328.840592 -351.931732) (xy 328.840088 -351.97408)
			(xy 334.52206 -351.97408) (xy 334.52206 -351.889384) (xy 334.530111 -351.80507) (xy 334.54614 -351.721904)
			(xy 334.570001 -351.640637) (xy 334.60148 -351.562007) (xy 334.640291 -351.486726) (xy 334.686081 -351.415474)
			(xy 334.738437 -351.348898) (xy 334.796885 -351.2876) (xy 334.860895 -351.232135) (xy 334.929887 -351.183006)
			(xy 335.003237 -351.140657) (xy 335.08028 -351.105473) (xy 335.160319 -351.077771) (xy 335.242628 -351.057803)
			(xy 335.326463 -351.04575) (xy 335.411064 -351.04172) (xy 335.495665 -351.04575) (xy 335.5795 -351.057803)
			(xy 335.661809 -351.077771) (xy 335.741848 -351.105473) (xy 335.818891 -351.140657) (xy 335.892241 -351.183006)
			(xy 335.961233 -351.232135) (xy 336.025243 -351.2876) (xy 336.083691 -351.348898) (xy 336.136047 -351.415474)
			(xy 336.181837 -351.486726) (xy 336.220648 -351.562007) (xy 336.252127 -351.640637) (xy 336.275988 -351.721904)
			(xy 336.292017 -351.80507) (xy 336.300068 -351.889384) (xy 336.300572 -351.931732) (xy 336.300068 -351.97408)
			(xy 336.292017 -352.058394) (xy 336.275988 -352.14156) (xy 336.252127 -352.222827) (xy 336.220648 -352.301457)
			(xy 336.181837 -352.376738) (xy 336.136047 -352.44799) (xy 336.083691 -352.514566) (xy 336.025243 -352.575864)
			(xy 335.961233 -352.631329) (xy 335.892241 -352.680458) (xy 335.818891 -352.722807) (xy 335.741848 -352.757991)
			(xy 335.661809 -352.785693) (xy 335.5795 -352.805661) (xy 335.495665 -352.817714) (xy 335.411064 -352.821745)
			(xy 335.326463 -352.817714) (xy 335.242628 -352.805661) (xy 335.160319 -352.785693) (xy 335.08028 -352.757991)
			(xy 335.003237 -352.722807) (xy 334.929887 -352.680458) (xy 334.860895 -352.631329) (xy 334.796885 -352.575864)
			(xy 334.738437 -352.514566) (xy 334.686081 -352.44799) (xy 334.640291 -352.376738) (xy 334.60148 -352.301457)
			(xy 334.570001 -352.222827) (xy 334.54614 -352.14156) (xy 334.530111 -352.058394) (xy 334.52206 -351.97408)
			(xy 328.840088 -351.97408) (xy 328.832037 -352.058394) (xy 328.816008 -352.14156) (xy 328.792147 -352.222827)
			(xy 328.760668 -352.301457) (xy 328.721857 -352.376738) (xy 328.676067 -352.44799) (xy 328.623711 -352.514566)
			(xy 328.565263 -352.575864) (xy 328.501253 -352.631329) (xy 328.432261 -352.680458) (xy 328.358911 -352.722807)
			(xy 328.281868 -352.757991) (xy 328.201829 -352.785693) (xy 328.11952 -352.805661) (xy 328.035685 -352.817714)
			(xy 327.951084 -352.821745) (xy 327.866483 -352.817714) (xy 327.782648 -352.805661) (xy 327.700339 -352.785693)
			(xy 327.6203 -352.757991) (xy 327.543257 -352.722807) (xy 327.469907 -352.680458) (xy 327.400915 -352.631329)
			(xy 327.336905 -352.575864) (xy 327.278457 -352.514566) (xy 327.226101 -352.44799) (xy 327.180311 -352.376738)
			(xy 327.1415 -352.301457) (xy 327.110021 -352.222827) (xy 327.08616 -352.14156) (xy 327.070131 -352.058394)
			(xy 327.06208 -351.97408) (xy 315.229424 -351.97408) (xy 319.363344 -356.108) (xy 319.370745 -356.11484)
			(xy 319.389343 -356.122558) (xy 319.399412 -356.122986) (xy 352.640646 -356.122986)
		)
		(stroke
			(width 0)
			(type solid)
		)
		(fill yes)
		(layer "In15.Cu")
		(net "SW_P12V_AUX_PVDDCR_CPU1_P0_FLT")
	)
	(gr_poly
		(pts
			(xy 441.615576 -25.877012) (xy 441.625765 -25.876493) (xy 441.644506 -25.868472) (xy 441.658689 -25.853829)
			(xy 441.66282 -25.8445) (xy 441.673015 -25.819529) (xy 441.69942 -25.772499) (xy 441.732183 -25.729655)
			(xy 441.770649 -25.691848) (xy 441.814055 -25.659832) (xy 441.861534 -25.634245) (xy 441.912143 -25.615595)
			(xy 441.964873 -25.604255) (xy 442.018674 -25.600449) (xy 442.072475 -25.604255) (xy 442.125205 -25.615595)
			(xy 442.175814 -25.634245) (xy 442.223293 -25.659832) (xy 442.266699 -25.691848) (xy 442.305165 -25.729655)
			(xy 442.337928 -25.772499) (xy 442.364333 -25.819529) (xy 442.374528 -25.8445) (xy 442.37861 -25.853867)
			(xy 442.392779 -25.868562) (xy 442.411565 -25.87655) (xy 442.421772 -25.877012) (xy 442.504576 -25.877012)
			(xy 442.514765 -25.876493) (xy 442.533506 -25.868472) (xy 442.547689 -25.853829) (xy 442.55182 -25.8445)
			(xy 442.562015 -25.819529) (xy 442.58842 -25.772499) (xy 442.621183 -25.729655) (xy 442.659649 -25.691848)
			(xy 442.703055 -25.659832) (xy 442.750534 -25.634245) (xy 442.801143 -25.615595) (xy 442.853873 -25.604255)
			(xy 442.907674 -25.600449) (xy 442.961475 -25.604255) (xy 443.014205 -25.615595) (xy 443.064814 -25.634245)
			(xy 443.112293 -25.659832) (xy 443.155699 -25.691848) (xy 443.194165 -25.729655) (xy 443.226928 -25.772499)
			(xy 443.253333 -25.819529) (xy 443.263528 -25.8445) (xy 443.26761 -25.853867) (xy 443.281779 -25.868562)
			(xy 443.300565 -25.87655) (xy 443.310772 -25.877012) (xy 444.432436 -25.877012) (xy 444.44244 -25.876518)
			(xy 444.460921 -25.868852) (xy 444.475066 -25.854701) (xy 444.482722 -25.836216) (xy 444.483236 -25.826212)
			(xy 444.483236 -25.193244) (xy 444.48367 -25.183179) (xy 444.491403 -25.164593) (xy 444.498222 -25.157176)
			(xy 445.08547 -24.569928) (xy 445.092871 -24.56309) (xy 445.11147 -24.555376) (xy 445.121538 -24.554942)
			(xy 445.158622 -24.554942) (xy 445.168689 -24.554513) (xy 445.187282 -24.546787) (xy 445.19469 -24.539956)
			(xy 445.681608 -24.053038) (xy 445.689005 -24.046189) (xy 445.707604 -24.038451) (xy 445.717676 -24.038052)
			(xy 445.740282 -24.038052) (xy 445.750344 -24.037612) (xy 445.768923 -24.029872) (xy 445.77635 -24.023066)
			(xy 445.835278 -23.964138) (xy 445.842117 -23.956737) (xy 445.849832 -23.938139) (xy 445.850264 -23.92807)
			(xy 445.850264 -19.0627) (xy 445.849906 -19.053683) (xy 445.843665 -19.036762) (xy 445.838072 -19.02968)
			(xy 445.810978 -18.997426) (xy 445.762329 -18.928652) (xy 445.720402 -18.855586) (xy 445.685574 -18.778882)
			(xy 445.658156 -18.699228) (xy 445.638394 -18.617337) (xy 445.626466 -18.533945) (xy 445.622478 -18.449798)
			(xy 445.626466 -18.365652) (xy 445.638394 -18.28226) (xy 445.658156 -18.200369) (xy 445.685575 -18.120715)
			(xy 445.720404 -18.044011) (xy 445.762331 -17.970945) (xy 445.81098 -17.902172) (xy 445.838072 -17.869916)
			(xy 445.843662 -17.862831) (xy 445.849913 -17.845914) (xy 445.850264 -17.836896) (xy 445.850264 -17.183354)
			(xy 445.850697 -17.173289) (xy 445.858431 -17.154703) (xy 445.86525 -17.147286) (xy 446.037208 -16.975328)
			(xy 446.044606 -16.96848) (xy 446.063204 -16.960744) (xy 446.073276 -16.960342) (xy 450.688964 -16.960342)
			(xy 450.688964 -16.966692) (xy 451.362318 -17.640046) (xy 451.369166 -17.647443) (xy 451.376897 -17.666042)
			(xy 451.377304 -17.676114) (xy 451.377304 -18.602198) (xy 451.377727 -18.612268) (xy 451.385441 -18.630873)
			(xy 451.39229 -18.638266) (xy 451.720458 -18.966434) (xy 451.727856 -18.973279) (xy 451.746455 -18.981002)
			(xy 451.756526 -18.98142) (xy 452.519542 -18.98142) (xy 452.529609 -18.98099) (xy 452.548205 -18.973267)
			(xy 452.55561 -18.966434) (xy 452.604378 -18.917666) (xy 452.611222 -18.910267) (xy 452.618947 -18.891668)
			(xy 452.619364 -18.881598) (xy 452.619364 -18.623534) (xy 452.619801 -18.613471) (xy 452.627539 -18.59489)
			(xy 452.63435 -18.587466) (xy 454.246488 -16.975328) (xy 454.253885 -16.968477) (xy 454.272483 -16.960734)
			(xy 454.282556 -16.960342) (xy 455.233024 -16.960342) (xy 455.243091 -16.959913) (xy 455.261684 -16.952186)
			(xy 455.269092 -16.945356) (xy 455.41819 -16.796258) (xy 455.425031 -16.788858) (xy 455.432752 -16.770259)
			(xy 455.433176 -16.76019) (xy 455.433176 -14.170406) (xy 455.432753 -14.160336) (xy 455.425038 -14.141732)
			(xy 455.41819 -14.134338) (xy 455.24039 -13.956538) (xy 455.232993 -13.949689) (xy 455.214394 -13.941952)
			(xy 455.204322 -13.941552) (xy 453.120252 -13.941552) (xy 453.108444 -13.942163) (xy 453.08729 -13.952665)
			(xy 453.072995 -13.971464) (xy 453.070214 -13.982954) (xy 453.061838 -14.024577) (xy 453.038175 -14.106122)
			(xy 453.00685 -14.185042) (xy 452.968148 -14.260618) (xy 452.922419 -14.332161) (xy 452.870082 -14.399022)
			(xy 452.811611 -14.460591) (xy 452.747539 -14.516308) (xy 452.67845 -14.565666) (xy 452.604972 -14.608216)
			(xy 452.527773 -14.64357) (xy 452.447557 -14.671408) (xy 452.365053 -14.691474) (xy 452.281012 -14.703588)
			(xy 452.1962 -14.707638) (xy 452.111388 -14.703588) (xy 452.027347 -14.691474) (xy 451.944843 -14.671408)
			(xy 451.864627 -14.64357) (xy 451.787428 -14.608216) (xy 451.71395 -14.565666) (xy 451.644861 -14.516308)
			(xy 451.580789 -14.460591) (xy 451.522318 -14.399022) (xy 451.469981 -14.332161) (xy 451.424252 -14.260618)
			(xy 451.38555 -14.185042) (xy 451.354225 -14.106122) (xy 451.330562 -14.024577) (xy 451.322186 -13.982954)
			(xy 451.319419 -13.971448) (xy 451.305158 -13.952598) (xy 451.283969 -13.942124) (xy 451.272148 -13.941552)
			(xy 450.277484 -13.941552) (xy 450.249798 -13.963904) (xy 450.245988 -13.98143) (xy 450.236326 -14.023439)
			(xy 450.209931 -14.105505) (xy 450.175721 -14.184632) (xy 450.134015 -14.260078) (xy 450.085205 -14.331134)
			(xy 450.02975 -14.397136) (xy 449.968169 -14.457462) (xy 449.90104 -14.511547) (xy 449.828994 -14.558883)
			(xy 449.752705 -14.599027) (xy 449.672891 -14.631602) (xy 449.590299 -14.656302) (xy 449.505705 -14.672895)
			(xy 449.419903 -14.681226) (xy 449.3768 -14.681708) (xy 449.332879 -14.681177) (xy 449.245464 -14.672514)
			(xy 449.15933 -14.655273) (xy 449.075316 -14.629622) (xy 448.994241 -14.59581) (xy 448.916896 -14.554168)
			(xy 448.844034 -14.505101) (xy 448.809872 -14.477492) (xy 448.802754 -14.472094) (xy 448.785897 -14.46621)
			(xy 448.768046 -14.466505) (xy 448.75958 -14.469364) (xy 448.718539 -14.484349) (xy 448.634184 -14.507124)
			(xy 448.591178 -14.51483) (xy 448.581984 -14.516857) (xy 448.565831 -14.526497) (xy 448.559682 -14.533626)
			(xy 448.540886 -14.557502) (xy 448.535637 -14.564835) (xy 448.53018 -14.582011) (xy 448.530218 -14.59103)
			(xy 448.530472 -14.606524) (xy 448.530472 -14.607032) (xy 448.529986 -14.634283) (xy 448.52223 -14.688231)
			(xy 448.506875 -14.740526) (xy 448.484233 -14.790103) (xy 448.454767 -14.835953) (xy 448.419076 -14.877144)
			(xy 448.377885 -14.912835) (xy 448.332035 -14.942301) (xy 448.282458 -14.964943) (xy 448.230163 -14.980298)
			(xy 448.176215 -14.988054) (xy 448.121713 -14.988054) (xy 448.067765 -14.980298) (xy 448.01547 -14.964943)
			(xy 447.965893 -14.942301) (xy 447.920043 -14.912835) (xy 447.878852 -14.877144) (xy 447.843161 -14.835953)
			(xy 447.813695 -14.790103) (xy 447.791053 -14.740526) (xy 447.775698 -14.688231) (xy 447.767942 -14.634283)
			(xy 447.767456 -14.607032) (xy 447.768023 -14.576842) (xy 447.777532 -14.517216) (xy 447.796332 -14.459838)
			(xy 447.823953 -14.406146) (xy 447.84137 -14.38148) (xy 447.846424 -14.373948) (xy 447.851361 -14.356509)
			(xy 447.851022 -14.347444) (xy 447.848482 -14.317218) (xy 447.847402 -14.307878) (xy 447.839308 -14.290921)
			(xy 447.832734 -14.284198) (xy 447.798686 -14.251142) (xy 447.73708 -14.178954) (xy 447.683507 -14.100619)
			(xy 447.638575 -14.017028) (xy 447.620136 -13.973302) (xy 447.61595 -13.964129) (xy 447.60179 -13.949797)
			(xy 447.583218 -13.941985) (xy 447.573146 -13.941552) (xy 443.08141 -13.941552) (xy 443.07134 -13.941975)
			(xy 443.052738 -13.949692) (xy 443.045342 -13.956538) (xy 442.344048 -14.657832) (xy 446.573146 -14.657832)
			(xy 446.577217 -14.60221) (xy 446.589343 -14.547773) (xy 446.609266 -14.495682) (xy 446.636562 -14.447047)
			(xy 446.670648 -14.402904) (xy 446.710797 -14.364195) (xy 446.756155 -14.331744) (xy 446.805755 -14.306243)
			(xy 446.858539 -14.288236) (xy 446.913382 -14.278106) (xy 446.969116 -14.276069) (xy 447.024553 -14.282169)
			(xy 447.07851 -14.296275) (xy 447.129839 -14.318087) (xy 447.177445 -14.347141) (xy 447.220313 -14.382816)
			(xy 447.25753 -14.424353) (xy 447.288303 -14.470866) (xy 447.311975 -14.521363) (xy 447.328043 -14.57477)
			(xy 447.336163 -14.629946) (xy 447.336672 -14.657832) (xy 447.336163 -14.685718) (xy 447.328043 -14.740894)
			(xy 447.311975 -14.794301) (xy 447.288303 -14.844798) (xy 447.25753 -14.891311) (xy 447.220313 -14.932848)
			(xy 447.177445 -14.968523) (xy 447.129839 -14.997577) (xy 447.07851 -15.019389) (xy 447.024553 -15.033495)
			(xy 446.969116 -15.039595) (xy 446.913382 -15.037558) (xy 446.858539 -15.027428) (xy 446.805755 -15.009421)
			(xy 446.756155 -14.98392) (xy 446.710797 -14.951469) (xy 446.670648 -14.91276) (xy 446.636562 -14.868617)
			(xy 446.609266 -14.819982) (xy 446.589343 -14.767891) (xy 446.577217 -14.713454) (xy 446.573146 -14.657832)
			(xy 442.344048 -14.657832) (xy 442.048646 -14.953234) (xy 442.0418 -14.960632) (xy 442.034071 -14.979231)
			(xy 442.03366 -14.989302) (xy 442.03366 -21.335746) (xy 442.033227 -21.345812) (xy 442.025497 -21.3644)
			(xy 442.018674 -21.371814) (xy 440.829954 -22.560534) (xy 440.823107 -22.567932) (xy 440.815377 -22.586531)
			(xy 440.814968 -22.596602) (xy 440.814968 -22.850348) (xy 440.815399 -22.860415) (xy 440.823122 -22.87901)
			(xy 440.829954 -22.886416) (xy 441.06973 -23.126446) (xy 441.078307 -23.134056) (xy 441.099938 -23.141572)
			(xy 441.111386 -23.140924) (xy 441.202318 -23.13051) (xy 441.221622 -23.118318) (xy 441.227972 -23.108158)
			(xy 441.250028 -23.073578) (xy 441.299572 -23.008206) (xy 441.354927 -22.947675) (xy 441.41562 -22.8925)
			(xy 441.481138 -22.843148) (xy 441.550922 -22.80004) (xy 441.624379 -22.763543) (xy 441.700886 -22.733965)
			(xy 441.779791 -22.71156) (xy 441.860425 -22.696517) (xy 441.942102 -22.688964) (xy 441.983114 -22.68855)
			(xy 441.983368 -22.68855) (xy 442.025786 -22.689054) (xy 442.110234 -22.697156) (xy 442.193526 -22.713262)
			(xy 442.274908 -22.737224) (xy 442.353638 -22.768825) (xy 442.391546 -22.787864) (xy 442.40271 -22.792845)
			(xy 442.427118 -22.792845) (xy 442.438282 -22.787864) (xy 442.47619 -22.768825) (xy 442.554921 -22.737226)
			(xy 442.636302 -22.713267) (xy 442.719595 -22.697164) (xy 442.804043 -22.689065) (xy 442.84646 -22.68855)
			(xy 442.846714 -22.68855) (xy 442.889064 -22.689054) (xy 442.973381 -22.697107) (xy 443.05655 -22.713138)
			(xy 443.137819 -22.737001) (xy 443.216451 -22.768482) (xy 443.291735 -22.807295) (xy 443.362989 -22.853088)
			(xy 443.429568 -22.905447) (xy 443.490867 -22.963897) (xy 443.546334 -23.027909) (xy 443.595464 -23.096904)
			(xy 443.637814 -23.170257) (xy 443.672999 -23.247303) (xy 443.700702 -23.327345) (xy 443.72067 -23.409658)
			(xy 443.732724 -23.493496) (xy 443.736755 -23.5781) (xy 443.732724 -23.662704) (xy 443.72067 -23.746542)
			(xy 443.700702 -23.828855) (xy 443.672999 -23.908897) (xy 443.637814 -23.985943) (xy 443.595464 -24.059296)
			(xy 443.546334 -24.128291) (xy 443.490867 -24.192303) (xy 443.429568 -24.250753) (xy 443.362989 -24.303112)
			(xy 443.291735 -24.348905) (xy 443.216451 -24.387718) (xy 443.137819 -24.419199) (xy 443.05655 -24.443062)
			(xy 442.973381 -24.459093) (xy 442.889064 -24.467146) (xy 442.846714 -24.467566) (xy 442.84646 -24.467566)
			(xy 442.804042 -24.467063) (xy 442.719594 -24.458963) (xy 442.6363 -24.442858) (xy 442.554919 -24.418897)
			(xy 442.476188 -24.387295) (xy 442.438282 -24.368252) (xy 442.427118 -24.363271) (xy 442.40271 -24.363271)
			(xy 442.391546 -24.368252) (xy 442.353638 -24.387292) (xy 442.274908 -24.418892) (xy 442.193526 -24.442854)
			(xy 442.110234 -24.458959) (xy 442.025786 -24.467061) (xy 441.983368 -24.467566) (xy 441.983114 -24.467566)
			(xy 441.942698 -24.46711) (xy 441.862199 -24.459777) (xy 441.782698 -24.44517) (xy 441.70485 -24.423409)
			(xy 441.629298 -24.394675) (xy 441.556665 -24.359204) (xy 441.487549 -24.317289) (xy 441.422522 -24.269276)
			(xy 441.36212 -24.21556) (xy 441.334144 -24.186388) (xy 441.323476 -24.174958) (xy 441.292996 -24.1681)
			(xy 441.19038 -24.20874) (xy 441.181113 -24.212899) (xy 441.166629 -24.227115) (xy 441.15879 -24.245836)
			(xy 441.158376 -24.255984) (xy 441.158376 -25.55748) (xy 441.158965 -25.569268) (xy 441.169461 -25.590375)
			(xy 441.188291 -25.604557) (xy 441.199778 -25.607264) (xy 441.226934 -25.612842) (xy 441.279382 -25.630799)
			(xy 441.32868 -25.656156) (xy 441.37379 -25.68838) (xy 441.413763 -25.726791) (xy 441.447758 -25.770582)
			(xy 441.475059 -25.81883) (xy 441.485528 -25.8445) (xy 441.48961 -25.853867) (xy 441.503779 -25.868562)
			(xy 441.522565 -25.87655) (xy 441.532772 -25.877012)
		)
		(stroke
			(width 0)
			(type solid)
		)
		(fill yes)
		(layer "In15.Cu")
		(net "P12V_OCP_SFF")
	)
	(gr_poly
		(pts
			(xy 80.104234 -182.515002) (xy 80.114301 -182.514573) (xy 80.132897 -182.50685) (xy 80.140302 -182.500016)
			(xy 80.16113 -182.479188) (xy 80.168526 -182.472337) (xy 80.187125 -182.464599) (xy 80.197198 -182.464202)
			(xy 81.852516 -182.464202) (xy 81.862522 -182.463711) (xy 81.881008 -182.456049) (xy 81.895157 -182.441896)
			(xy 81.902814 -182.423408) (xy 81.903316 -182.413402) (xy 81.903316 -180.53431) (xy 81.903316 -180.432456)
			(xy 80.75422 -179.28336) (xy 80.75422 -176.60112) (xy 80.971898 -176.383442) (xy 81.964784 -176.383442)
			(xy 82.364072 -176.78273) (xy 82.371471 -176.789573) (xy 82.39007 -176.797292) (xy 82.40014 -176.797716)
			(xy 86.228428 -176.797716) (xy 86.238496 -176.798145) (xy 86.257091 -176.805868) (xy 86.264496 -176.812702)
			(xy 86.510368 -177.058574) (xy 86.517206 -177.065975) (xy 86.524919 -177.084574) (xy 86.525354 -177.094642)
			(xy 86.525354 -180.467) (xy 87.18804 -181.129686) (xy 87.18804 -182.152544) (xy 87.46998 -182.434484)
			(xy 88.514174 -182.434484) (xy 88.524238 -182.434047) (xy 88.542821 -182.426312) (xy 88.550242 -182.419498)
			(xy 88.573356 -182.396384) (xy 88.573356 -182.39613) (xy 90.246454 -182.39613) (xy 90.256484 -182.395719)
			(xy 90.275022 -182.388058) (xy 90.289216 -182.373885) (xy 90.296904 -182.355359) (xy 90.297254 -182.34533)
			(xy 90.297254 -180.466238) (xy 90.297254 -180.398674) (xy 89.41054 -179.51196) (xy 89.41054 -177.145442)
			(xy 89.81186 -176.744122) (xy 94.674182 -176.744122) (xy 94.684245 -176.744561) (xy 94.702826 -176.752298)
			(xy 94.71025 -176.759108) (xy 94.955868 -177.004726) (xy 94.962714 -177.012124) (xy 94.970444 -177.030723)
			(xy 94.970854 -177.040794) (xy 94.970854 -180.53558) (xy 95.55734 -181.122066) (xy 95.55734 -182.238904)
			(xy 95.77832 -182.459884) (xy 96.897952 -182.459884) (xy 96.908018 -182.459451) (xy 96.926607 -182.451721)
			(xy 96.93402 -182.444898) (xy 96.95053 -182.428388) (xy 96.957926 -182.421537) (xy 96.976525 -182.413799)
			(xy 96.986598 -182.413402) (xy 98.641154 -182.413402) (xy 98.651182 -182.41299) (xy 98.669715 -182.405329)
			(xy 98.683902 -182.391155) (xy 98.691581 -182.372629) (xy 98.691954 -182.362602) (xy 98.691954 -180.48351)
			(xy 98.691954 -180.431694) (xy 97.79254 -179.53228) (xy 97.79254 -177.13198) (xy 98.165412 -176.759108)
			(xy 101.3587 -176.759108) (xy 101.722428 -176.39538) (xy 102.61092 -176.39538) (xy 102.974648 -176.759108)
			(xy 102.9843 -176.76876) (xy 103.43388 -177.218086) (xy 103.548688 -177.332894) (xy 103.555537 -177.340292)
			(xy 103.563275 -177.35889) (xy 103.563674 -177.368962) (xy 103.563674 -177.889916) (xy 103.564099 -177.899985)
			(xy 103.571815 -177.918588) (xy 103.57866 -177.925984) (xy 103.580692 -177.928016) (xy 103.588086 -177.934873)
			(xy 103.606685 -177.942623) (xy 103.61676 -177.943002) (xy 105.275634 -177.943002) (xy 105.285701 -177.942573)
			(xy 105.304297 -177.93485) (xy 105.311702 -177.928016) (xy 105.33253 -177.907188) (xy 105.339926 -177.900337)
			(xy 105.358525 -177.892599) (xy 105.368598 -177.892202) (xy 107.023916 -177.892202) (xy 107.033922 -177.891711)
			(xy 107.052408 -177.884049) (xy 107.066557 -177.869896) (xy 107.074214 -177.851408) (xy 107.074716 -177.841402)
			(xy 107.074716 -175.96231) (xy 107.074716 -175.860456) (xy 106.18724 -174.97298) (xy 106.18724 -171.002198)
			(xy 105.53573 -170.350688) (xy 105.053892 -169.86885) (xy 103.051864 -167.866822) (xy 103.045023 -167.859422)
			(xy 103.037307 -167.840823) (xy 103.036878 -167.830754) (xy 103.036878 -159.09163) (xy 102.59822 -158.652972)
			(xy 80.630268 -158.652972) (xy 61.129926 -158.652972) (xy 60.288678 -159.49422) (xy 59.602878 -160.18002)
			(xy 59.602878 -168.412414) (xy 59.603303 -168.422484) (xy 59.611019 -168.441086) (xy 59.617864 -168.448482)
			(xy 59.84748 -168.678098) (xy 59.854883 -168.684932) (xy 59.873481 -168.692637) (xy 59.883548 -168.693084)
			(xy 63.473838 -168.693084) (xy 63.483905 -168.692654) (xy 63.502498 -168.684928) (xy 63.509906 -168.678098)
			(xy 63.52413 -168.663874) (xy 63.531527 -168.657024) (xy 63.550126 -168.649289) (xy 63.560198 -168.648888)
			(xy 65.213992 -168.648888) (xy 65.224063 -168.648466) (xy 65.242668 -168.640752) (xy 65.25006 -168.633902)
			(xy 65.25133 -168.632632) (xy 65.258173 -168.625233) (xy 65.265894 -168.606634) (xy 65.266316 -168.596564)
			(xy 65.266316 -166.718996) (xy 65.266316 -166.650416) (xy 64.24168 -165.62578) (xy 64.24168 -162.90544)
			(xy 64.426084 -162.721036) (xy 65.520824 -162.721036) (xy 65.893696 -163.093654) (xy 65.901092 -163.100506)
			(xy 65.919691 -163.108249) (xy 65.929764 -163.10864) (xy 69.371464 -163.10864) (xy 69.381528 -163.109076)
			(xy 69.400112 -163.116811) (xy 69.407532 -163.123626) (xy 69.889878 -163.606226) (xy 69.889878 -166.004424)
			(xy 82.10067 -166.004424) (xy 82.10067 -165.919728) (xy 82.108721 -165.835414) (xy 82.12475 -165.752248)
			(xy 82.148611 -165.670981) (xy 82.18009 -165.592351) (xy 82.218901 -165.51707) (xy 82.264691 -165.445818)
			(xy 82.317047 -165.379242) (xy 82.375495 -165.317944) (xy 82.439505 -165.262479) (xy 82.508497 -165.21335)
			(xy 82.581847 -165.171001) (xy 82.65889 -165.135817) (xy 82.738929 -165.108115) (xy 82.821238 -165.088147)
			(xy 82.905073 -165.076094) (xy 82.989674 -165.072064) (xy 83.074275 -165.076094) (xy 83.15811 -165.088147)
			(xy 83.240419 -165.108115) (xy 83.320458 -165.135817) (xy 83.397501 -165.171001) (xy 83.470851 -165.21335)
			(xy 83.539843 -165.262479) (xy 83.603853 -165.317944) (xy 83.662301 -165.379242) (xy 83.714657 -165.445818)
			(xy 83.760447 -165.51707) (xy 83.799258 -165.592351) (xy 83.830737 -165.670981) (xy 83.854598 -165.752248)
			(xy 83.870627 -165.835414) (xy 83.878678 -165.919728) (xy 83.879182 -165.962076) (xy 83.878678 -166.004424)
			(xy 91.49867 -166.004424) (xy 91.49867 -165.919728) (xy 91.506721 -165.835414) (xy 91.52275 -165.752248)
			(xy 91.546611 -165.670981) (xy 91.57809 -165.592351) (xy 91.616901 -165.51707) (xy 91.662691 -165.445818)
			(xy 91.715047 -165.379242) (xy 91.773495 -165.317944) (xy 91.837505 -165.262479) (xy 91.906497 -165.21335)
			(xy 91.979847 -165.171001) (xy 92.05689 -165.135817) (xy 92.136929 -165.108115) (xy 92.219238 -165.088147)
			(xy 92.303073 -165.076094) (xy 92.387674 -165.072064) (xy 92.472275 -165.076094) (xy 92.55611 -165.088147)
			(xy 92.638419 -165.108115) (xy 92.718458 -165.135817) (xy 92.795501 -165.171001) (xy 92.868851 -165.21335)
			(xy 92.937843 -165.262479) (xy 93.001853 -165.317944) (xy 93.060301 -165.379242) (xy 93.112657 -165.445818)
			(xy 93.158447 -165.51707) (xy 93.197258 -165.592351) (xy 93.228737 -165.670981) (xy 93.252598 -165.752248)
			(xy 93.268627 -165.835414) (xy 93.276678 -165.919728) (xy 93.277182 -165.962076) (xy 93.276678 -166.004424)
			(xy 93.268627 -166.088738) (xy 93.252598 -166.171904) (xy 93.228737 -166.253171) (xy 93.197258 -166.331801)
			(xy 93.158447 -166.407082) (xy 93.112657 -166.478334) (xy 93.060301 -166.54491) (xy 93.001853 -166.606208)
			(xy 92.937843 -166.661673) (xy 92.868851 -166.710802) (xy 92.795501 -166.753151) (xy 92.718458 -166.788335)
			(xy 92.638419 -166.816037) (xy 92.55611 -166.836005) (xy 92.472275 -166.848058) (xy 92.387674 -166.852089)
			(xy 92.303073 -166.848058) (xy 92.219238 -166.836005) (xy 92.136929 -166.816037) (xy 92.05689 -166.788335)
			(xy 91.979847 -166.753151) (xy 91.906497 -166.710802) (xy 91.837505 -166.661673) (xy 91.773495 -166.606208)
			(xy 91.715047 -166.54491) (xy 91.662691 -166.478334) (xy 91.616901 -166.407082) (xy 91.57809 -166.331801)
			(xy 91.546611 -166.253171) (xy 91.52275 -166.171904) (xy 91.506721 -166.088738) (xy 91.49867 -166.004424)
			(xy 83.878678 -166.004424) (xy 83.870627 -166.088738) (xy 83.854598 -166.171904) (xy 83.830737 -166.253171)
			(xy 83.799258 -166.331801) (xy 83.760447 -166.407082) (xy 83.714657 -166.478334) (xy 83.662301 -166.54491)
			(xy 83.603853 -166.606208) (xy 83.539843 -166.661673) (xy 83.470851 -166.710802) (xy 83.397501 -166.753151)
			(xy 83.320458 -166.788335) (xy 83.240419 -166.816037) (xy 83.15811 -166.836005) (xy 83.074275 -166.848058)
			(xy 82.989674 -166.852089) (xy 82.905073 -166.848058) (xy 82.821238 -166.836005) (xy 82.738929 -166.816037)
			(xy 82.65889 -166.788335) (xy 82.581847 -166.753151) (xy 82.508497 -166.710802) (xy 82.439505 -166.661673)
			(xy 82.375495 -166.606208) (xy 82.317047 -166.54491) (xy 82.264691 -166.478334) (xy 82.218901 -166.407082)
			(xy 82.18009 -166.331801) (xy 82.148611 -166.253171) (xy 82.12475 -166.171904) (xy 82.108721 -166.088738)
			(xy 82.10067 -166.004424) (xy 69.889878 -166.004424) (xy 69.889878 -166.249858) (xy 70.36562 -166.7256)
			(xy 70.36562 -168.4655) (xy 70.326574 -168.504546) (xy 82.10067 -168.504546) (xy 82.10067 -168.41985)
			(xy 82.108721 -168.335536) (xy 82.12475 -168.25237) (xy 82.148611 -168.171103) (xy 82.18009 -168.092473)
			(xy 82.218901 -168.017192) (xy 82.264691 -167.94594) (xy 82.317047 -167.879364) (xy 82.375495 -167.818066)
			(xy 82.439505 -167.762601) (xy 82.508497 -167.713472) (xy 82.581847 -167.671123) (xy 82.65889 -167.635939)
			(xy 82.738929 -167.608237) (xy 82.821238 -167.588269) (xy 82.905073 -167.576216) (xy 82.989674 -167.572186)
			(xy 83.074275 -167.576216) (xy 83.15811 -167.588269) (xy 83.240419 -167.608237) (xy 83.320458 -167.635939)
			(xy 83.397501 -167.671123) (xy 83.470851 -167.713472) (xy 83.539843 -167.762601) (xy 83.603853 -167.818066)
			(xy 83.662301 -167.879364) (xy 83.714657 -167.94594) (xy 83.760447 -168.017192) (xy 83.799258 -168.092473)
			(xy 83.830737 -168.171103) (xy 83.854598 -168.25237) (xy 83.870627 -168.335536) (xy 83.878678 -168.41985)
			(xy 83.879182 -168.462198) (xy 83.878678 -168.504546) (xy 91.49867 -168.504546) (xy 91.49867 -168.41985)
			(xy 91.506721 -168.335536) (xy 91.52275 -168.25237) (xy 91.546611 -168.171103) (xy 91.57809 -168.092473)
			(xy 91.616901 -168.017192) (xy 91.662691 -167.94594) (xy 91.715047 -167.879364) (xy 91.773495 -167.818066)
			(xy 91.837505 -167.762601) (xy 91.906497 -167.713472) (xy 91.979847 -167.671123) (xy 92.05689 -167.635939)
			(xy 92.136929 -167.608237) (xy 92.219238 -167.588269) (xy 92.303073 -167.576216) (xy 92.387674 -167.572186)
			(xy 92.472275 -167.576216) (xy 92.55611 -167.588269) (xy 92.638419 -167.608237) (xy 92.718458 -167.635939)
			(xy 92.795501 -167.671123) (xy 92.868851 -167.713472) (xy 92.937843 -167.762601) (xy 93.001853 -167.818066)
			(xy 93.060301 -167.879364) (xy 93.112657 -167.94594) (xy 93.158447 -168.017192) (xy 93.197258 -168.092473)
			(xy 93.228737 -168.171103) (xy 93.252598 -168.25237) (xy 93.268627 -168.335536) (xy 93.276678 -168.41985)
			(xy 93.277182 -168.462198) (xy 93.276678 -168.504546) (xy 93.268627 -168.58886) (xy 93.252598 -168.672026)
			(xy 93.228737 -168.753293) (xy 93.197258 -168.831923) (xy 93.158447 -168.907204) (xy 93.112657 -168.978456)
			(xy 93.060301 -169.045032) (xy 93.001853 -169.10633) (xy 92.937843 -169.161795) (xy 92.868851 -169.210924)
			(xy 92.795501 -169.253273) (xy 92.718458 -169.288457) (xy 92.638419 -169.316159) (xy 92.55611 -169.336127)
			(xy 92.472275 -169.34818) (xy 92.387674 -169.352211) (xy 92.303073 -169.34818) (xy 92.219238 -169.336127)
			(xy 92.136929 -169.316159) (xy 92.05689 -169.288457) (xy 91.979847 -169.253273) (xy 91.906497 -169.210924)
			(xy 91.837505 -169.161795) (xy 91.773495 -169.10633) (xy 91.715047 -169.045032) (xy 91.662691 -168.978456)
			(xy 91.616901 -168.907204) (xy 91.57809 -168.831923) (xy 91.546611 -168.753293) (xy 91.52275 -168.672026)
			(xy 91.506721 -168.58886) (xy 91.49867 -168.504546) (xy 83.878678 -168.504546) (xy 83.870627 -168.58886)
			(xy 83.854598 -168.672026) (xy 83.830737 -168.753293) (xy 83.799258 -168.831923) (xy 83.760447 -168.907204)
			(xy 83.714657 -168.978456) (xy 83.662301 -169.045032) (xy 83.603853 -169.10633) (xy 83.539843 -169.161795)
			(xy 83.470851 -169.210924) (xy 83.397501 -169.253273) (xy 83.320458 -169.288457) (xy 83.240419 -169.316159)
			(xy 83.15811 -169.336127) (xy 83.074275 -169.34818) (xy 82.989674 -169.352211) (xy 82.905073 -169.34818)
			(xy 82.821238 -169.336127) (xy 82.738929 -169.316159) (xy 82.65889 -169.288457) (xy 82.581847 -169.253273)
			(xy 82.508497 -169.210924) (xy 82.439505 -169.161795) (xy 82.375495 -169.10633) (xy 82.317047 -169.045032)
			(xy 82.264691 -168.978456) (xy 82.218901 -168.907204) (xy 82.18009 -168.831923) (xy 82.148611 -168.753293)
			(xy 82.12475 -168.672026) (xy 82.108721 -168.58886) (xy 82.10067 -168.504546) (xy 70.326574 -168.504546)
			(xy 69.889878 -168.941242) (xy 69.889878 -177.206402) (xy 69.890301 -177.216473) (xy 69.898013 -177.235079)
			(xy 69.904864 -177.24247) (xy 70.027292 -177.364898) (xy 70.034404 -177.372264) (xy 70.0532 -177.379884)
			(xy 71.797672 -177.379884) (xy 71.807736 -177.379447) (xy 71.82632 -177.371713) (xy 71.83374 -177.364898)
			(xy 71.83755 -177.361088) (xy 71.844947 -177.35424) (xy 71.863546 -177.34651) (xy 71.873618 -177.346102)
			(xy 73.528936 -177.346102) (xy 73.538939 -177.345608) (xy 73.557419 -177.337942) (xy 73.571561 -177.32379)
			(xy 73.579214 -177.305305) (xy 73.579736 -177.295302) (xy 73.579736 -175.41621) (xy 73.579736 -175.357536)
			(xy 72.7075 -174.4853) (xy 72.7075 -170.9039) (xy 72.888602 -170.722798) (xy 73.440798 -170.722798)
			(xy 73.450868 -170.723221) (xy 73.469473 -170.730934) (xy 73.476866 -170.737784) (xy 74.373486 -171.634404)
			(xy 74.380889 -171.641236) (xy 74.399488 -171.648939) (xy 74.409554 -171.64939) (xy 77.587094 -171.64939)
			(xy 77.597165 -171.649812) (xy 77.615772 -171.657523) (xy 77.623162 -171.664376) (xy 78.256892 -172.298106)
			(xy 78.263738 -172.305505) (xy 78.271472 -172.324103) (xy 78.271878 -172.334174) (xy 78.271878 -174.97552)
			(xy 78.73746 -175.441102) (xy 78.73746 -176.933098) (xy 78.271878 -177.39868) (xy 78.271878 -179.105814)
			(xy 78.271878 -181.713886) (xy 78.271878 -182.388002) (xy 78.272301 -182.398073) (xy 78.280013 -182.416679)
			(xy 78.286864 -182.42407) (xy 78.36281 -182.500016) (xy 78.369922 -182.507382) (xy 78.388718 -182.515002)
		)
		(stroke
			(width 0)
			(type solid)
		)
		(fill yes)
		(layer "In15.Cu")
		(net "SW_P12V_AUX_PVDDCR_CPU0_P1_FLT")
	)
	(gr_poly
		(pts
			(xy 450.112638 -428.150274) (xy 450.122705 -428.149843) (xy 450.141297 -428.142116) (xy 450.148706 -428.135288)
			(xy 450.505068 -427.778926) (xy 450.511906 -427.771525) (xy 450.519619 -427.752926) (xy 450.520054 -427.742858)
			(xy 450.520054 -427.364144) (xy 450.49948 -427.336966) (xy 450.48297 -427.332394) (xy 450.456664 -427.324449)
			(xy 450.406485 -427.302053) (xy 450.360034 -427.272696) (xy 450.318271 -427.236984) (xy 450.282058 -427.195654)
			(xy 450.252144 -427.149559) (xy 450.229146 -427.099653) (xy 450.21354 -427.046966) (xy 450.205647 -426.992585)
			(xy 450.205094 -426.96511) (xy 450.205645 -426.937197) (xy 450.21385 -426.881976) (xy 450.229999 -426.828535)
			(xy 450.241416 -426.803058) (xy 450.24548 -426.794422) (xy 450.24675 -426.776388) (xy 450.225414 -426.702728)
			(xy 450.22259 -426.694038) (xy 450.211771 -426.679333) (xy 450.204332 -426.674026) (xy 450.204078 -426.674026)
			(xy 450.170078 -426.651844) (xy 450.105851 -426.60218) (xy 450.046417 -426.546871) (xy 449.992272 -426.486375)
			(xy 449.943864 -426.421197) (xy 449.901597 -426.351878) (xy 449.865824 -426.278996) (xy 449.836841 -426.203158)
			(xy 449.81489 -426.124994) (xy 449.800153 -426.045154) (xy 449.792753 -425.964304) (xy 449.792344 -425.92371)
			(xy 449.792827 -425.881772) (xy 449.80072 -425.798269) (xy 449.816436 -425.715879) (xy 449.839836 -425.635334)
			(xy 449.870712 -425.557349) (xy 449.90879 -425.482615) (xy 449.953733 -425.411797) (xy 450.005141 -425.345522)
			(xy 450.062557 -425.28438) (xy 450.125473 -425.228912) (xy 450.15912 -425.203874) (xy 450.166232 -425.198794)
			(xy 450.180964 -425.17695) (xy 450.183497 -425.173028) (xy 450.187212 -425.164464) (xy 450.18833 -425.159932)
			(xy 450.192394 -425.142914) (xy 450.192394 -425.119546) (xy 450.188838 -425.105576) (xy 450.186552 -425.100496)
			(xy 450.174425 -425.074408) (xy 450.157272 -425.019497) (xy 450.148538 -424.962635) (xy 450.147944 -424.933872)
			(xy 450.147944 -424.93311) (xy 450.14841 -424.905812) (xy 450.156194 -424.851775) (xy 450.171605 -424.7994)
			(xy 450.194327 -424.749757) (xy 450.223896 -424.703863) (xy 450.259707 -424.662654) (xy 450.301029 -424.626973)
			(xy 450.347017 -424.597549) (xy 450.396731 -424.574984) (xy 450.449154 -424.559739) (xy 450.476112 -424.555412)
			(xy 450.485085 -424.553757) (xy 450.501093 -424.545032) (xy 450.507354 -424.538394) (xy 450.507608 -424.53814)
			(xy 450.513284 -424.531017) (xy 450.519652 -424.513966) (xy 450.520054 -424.504866) (xy 450.520054 -424.173396)
			(xy 450.518022 -424.159426) (xy 450.51218 -424.13936) (xy 450.508624 -424.133518) (xy 450.49548 -424.111024)
			(xy 450.474743 -424.063231) (xy 450.4607 -424.013061) (xy 450.453613 -423.961447) (xy 450.453613 -423.909349)
			(xy 450.460701 -423.857736) (xy 450.474744 -423.807566) (xy 450.495481 -423.759773) (xy 450.508624 -423.737278)
			(xy 450.51218 -423.731436) (xy 450.518022 -423.71137) (xy 450.520054 -423.6974) (xy 450.520054 -422.861994)
			(xy 450.519628 -422.851925) (xy 450.511907 -422.833327) (xy 450.505068 -422.825926) (xy 446.782952 -419.10381)
			(xy 446.77584 -419.096444) (xy 446.757044 -419.088824) (xy 443.662054 -419.088824) (xy 443.649631 -419.089431)
			(xy 443.627646 -419.101003) (xy 443.620144 -419.110922) (xy 443.565534 -419.190678) (xy 443.56274 -419.21557)
			(xy 443.567312 -419.227254) (xy 443.578336 -419.256821) (xy 443.593824 -419.317995) (xy 443.601631 -419.380614)
			(xy 443.60211 -419.412166) (xy 443.601666 -419.442899) (xy 443.594261 -419.503919) (xy 443.579555 -419.5636)
			(xy 443.557761 -419.621074) (xy 443.529199 -419.675502) (xy 443.494284 -419.726089) (xy 443.453525 -419.7721)
			(xy 443.407518 -419.812861) (xy 443.356933 -419.84778) (xy 443.302507 -419.876346) (xy 443.245035 -419.898144)
			(xy 443.185354 -419.912855) (xy 443.124335 -419.920264) (xy 443.093602 -419.920674) (xy 443.059722 -419.920102)
			(xy 442.992567 -419.911059) (xy 442.959744 -419.90264) (xy 442.95949 -419.90264) (xy 442.958728 -419.902386)
			(xy 442.947345 -419.900027) (xy 442.924586 -419.904644) (xy 442.91504 -419.911276) (xy 442.850778 -419.960298)
			(xy 442.841824 -419.967898) (xy 442.831484 -419.988952) (xy 442.830966 -420.000684) (xy 442.830966 -420.204392)
			(xy 442.831314 -420.213124) (xy 442.837189 -420.229568) (xy 442.848284 -420.243053) (xy 442.855604 -420.247826)
			(xy 442.93028 -420.29253) (xy 442.937942 -420.296767) (xy 442.955081 -420.30028) (xy 442.972399 -420.297794)
			(xy 442.980318 -420.294054) (xy 442.980572 -420.2938) (xy 443.008356 -420.279474) (xy 443.066671 -420.256956)
			(xy 443.127306 -420.241748) (xy 443.189346 -420.23408) (xy 443.220602 -420.233602) (xy 443.252562 -420.234104)
			(xy 443.252609 -420.23411) (xy 444.235584 -420.23411) (xy 444.239655 -420.178488) (xy 444.251781 -420.124051)
			(xy 444.271704 -420.07196) (xy 444.299 -420.023325) (xy 444.333086 -419.979182) (xy 444.373235 -419.940473)
			(xy 444.418593 -419.908022) (xy 444.468193 -419.882521) (xy 444.520977 -419.864514) (xy 444.57582 -419.854384)
			(xy 444.631554 -419.852347) (xy 444.686991 -419.858447) (xy 444.740948 -419.872553) (xy 444.792277 -419.894365)
			(xy 444.839883 -419.923419) (xy 444.882751 -419.959094) (xy 444.919968 -420.000631) (xy 444.950741 -420.047144)
			(xy 444.974413 -420.097641) (xy 444.990481 -420.151048) (xy 444.998601 -420.206224) (xy 444.99911 -420.23411)
			(xy 445.505584 -420.23411) (xy 445.509655 -420.178488) (xy 445.521781 -420.124051) (xy 445.541704 -420.07196)
			(xy 445.569 -420.023325) (xy 445.603086 -419.979182) (xy 445.643235 -419.940473) (xy 445.688593 -419.908022)
			(xy 445.738193 -419.882521) (xy 445.790977 -419.864514) (xy 445.84582 -419.854384) (xy 445.901554 -419.852347)
			(xy 445.956991 -419.858447) (xy 446.010948 -419.872553) (xy 446.062277 -419.894365) (xy 446.109883 -419.923419)
			(xy 446.152751 -419.959094) (xy 446.189968 -420.000631) (xy 446.220741 -420.047144) (xy 446.244413 -420.097641)
			(xy 446.260481 -420.151048) (xy 446.268601 -420.206224) (xy 446.26911 -420.23411) (xy 446.268601 -420.261996)
			(xy 446.260481 -420.317172) (xy 446.244413 -420.370579) (xy 446.220741 -420.421076) (xy 446.189968 -420.467589)
			(xy 446.152751 -420.509126) (xy 446.109883 -420.544801) (xy 446.062277 -420.573855) (xy 446.010948 -420.595667)
			(xy 445.956991 -420.609773) (xy 445.901554 -420.615873) (xy 445.84582 -420.613836) (xy 445.790977 -420.603706)
			(xy 445.738193 -420.585699) (xy 445.688593 -420.560198) (xy 445.643235 -420.527747) (xy 445.603086 -420.489038)
			(xy 445.569 -420.444895) (xy 445.541704 -420.39626) (xy 445.521781 -420.344169) (xy 445.509655 -420.289732)
			(xy 445.505584 -420.23411) (xy 444.99911 -420.23411) (xy 444.998601 -420.261996) (xy 444.990481 -420.317172)
			(xy 444.974413 -420.370579) (xy 444.950741 -420.421076) (xy 444.919968 -420.467589) (xy 444.882751 -420.509126)
			(xy 444.839883 -420.544801) (xy 444.792277 -420.573855) (xy 444.740948 -420.595667) (xy 444.686991 -420.609773)
			(xy 444.631554 -420.615873) (xy 444.57582 -420.613836) (xy 444.520977 -420.603706) (xy 444.468193 -420.585699)
			(xy 444.418593 -420.560198) (xy 444.373235 -420.527747) (xy 444.333086 -420.489038) (xy 444.299 -420.444895)
			(xy 444.271704 -420.39626) (xy 444.251781 -420.344169) (xy 444.239655 -420.289732) (xy 444.235584 -420.23411)
			(xy 443.252609 -420.23411) (xy 443.315979 -420.242116) (xy 443.377891 -420.258012) (xy 443.437323 -420.281543)
			(xy 443.493337 -420.312337) (xy 443.54505 -420.349909) (xy 443.591646 -420.393666) (xy 443.632391 -420.442918)
			(xy 443.666641 -420.496888) (xy 443.693857 -420.554725) (xy 443.713609 -420.615517) (xy 443.725587 -420.678305)
			(xy 443.729601 -420.7421) (xy 443.725587 -420.805895) (xy 443.713609 -420.868683) (xy 443.693857 -420.929475)
			(xy 443.666641 -420.987312) (xy 443.632391 -421.041282) (xy 443.591646 -421.090534) (xy 443.54505 -421.134291)
			(xy 443.493337 -421.171863) (xy 443.437323 -421.202657) (xy 443.377891 -421.226188) (xy 443.315979 -421.242084)
			(xy 443.252562 -421.250096) (xy 443.220602 -421.250618) (xy 443.189346 -421.250141) (xy 443.127305 -421.242478)
			(xy 443.066671 -421.227268) (xy 443.008359 -421.20474) (xy 442.980572 -421.19042) (xy 442.980318 -421.190166)
			(xy 442.972407 -421.186429) (xy 442.955094 -421.183992) (xy 442.937967 -421.187507) (xy 442.93028 -421.19169)
			(xy 442.855604 -421.236394) (xy 442.848318 -421.241204) (xy 442.837257 -421.254695) (xy 442.83134 -421.271107)
			(xy 442.830966 -421.279828) (xy 442.830966 -421.480742) (xy 442.831398 -421.490807) (xy 442.839131 -421.509395)
			(xy 442.845952 -421.51681) (xy 443.06998 -421.740838) (xy 443.07738 -421.747678) (xy 443.095979 -421.755393)
			(xy 443.106048 -421.755824) (xy 446.492884 -421.755824) (xy 446.502947 -421.756263) (xy 446.521527 -421.764002)
			(xy 446.528952 -421.77081) (xy 446.75298 -421.994838) (xy 446.759823 -422.002238) (xy 446.767547 -422.020836)
			(xy 446.767966 -422.030906) (xy 446.767966 -422.134538) (xy 447.037458 -422.134538) (xy 447.041529 -422.078916)
			(xy 447.053655 -422.024479) (xy 447.073578 -421.972388) (xy 447.100874 -421.923753) (xy 447.13496 -421.87961)
			(xy 447.175109 -421.840901) (xy 447.220467 -421.80845) (xy 447.270067 -421.782949) (xy 447.322851 -421.764942)
			(xy 447.377694 -421.754812) (xy 447.433428 -421.752775) (xy 447.488865 -421.758875) (xy 447.542822 -421.772981)
			(xy 447.594151 -421.794793) (xy 447.641757 -421.823847) (xy 447.684625 -421.859522) (xy 447.721842 -421.901059)
			(xy 447.752615 -421.947572) (xy 447.776287 -421.998069) (xy 447.792355 -422.051476) (xy 447.800475 -422.106652)
			(xy 447.800984 -422.134538) (xy 447.800475 -422.162424) (xy 447.792355 -422.2176) (xy 447.776287 -422.271007)
			(xy 447.752615 -422.321504) (xy 447.721842 -422.368017) (xy 447.684625 -422.409554) (xy 447.641757 -422.445229)
			(xy 447.594151 -422.474283) (xy 447.542822 -422.496095) (xy 447.488865 -422.510201) (xy 447.433428 -422.516301)
			(xy 447.377694 -422.514264) (xy 447.322851 -422.504134) (xy 447.270067 -422.486127) (xy 447.220467 -422.460626)
			(xy 447.175109 -422.428175) (xy 447.13496 -422.389466) (xy 447.100874 -422.345323) (xy 447.073578 -422.296688)
			(xy 447.053655 -422.244597) (xy 447.041529 -422.19016) (xy 447.037458 -422.134538) (xy 446.767966 -422.134538)
			(xy 446.767966 -422.77411) (xy 448.280538 -422.77411) (xy 448.284582 -422.695656) (xy 448.296671 -422.618034)
			(xy 448.316678 -422.542066) (xy 448.344389 -422.468558) (xy 448.379512 -422.398289) (xy 448.421674 -422.332004)
			(xy 448.470428 -422.270405) (xy 448.525257 -422.214145) (xy 448.58558 -422.163821) (xy 448.650758 -422.119967)
			(xy 448.720099 -422.083046) (xy 448.79287 -422.053451) (xy 448.868297 -422.031496) (xy 448.945582 -422.017412)
			(xy 449.023906 -422.011349) (xy 449.102438 -422.013372) (xy 449.180346 -422.023458) (xy 449.256803 -422.041502)
			(xy 449.331001 -422.067312) (xy 449.402151 -422.100614) (xy 449.4695 -422.141055) (xy 449.532334 -422.188206)
			(xy 449.589986 -422.241569) (xy 449.641846 -422.300576) (xy 449.687365 -422.364603) (xy 449.726058 -422.432971)
			(xy 449.757517 -422.504955) (xy 449.781408 -422.579792) (xy 449.797477 -422.656689) (xy 449.805554 -422.734831)
			(xy 449.80606 -422.77411) (xy 449.805554 -422.813389) (xy 449.797477 -422.891531) (xy 449.781408 -422.968428)
			(xy 449.757517 -423.043265) (xy 449.726058 -423.115249) (xy 449.687365 -423.183617) (xy 449.641846 -423.247644)
			(xy 449.589986 -423.306651) (xy 449.532334 -423.360014) (xy 449.4695 -423.407165) (xy 449.402151 -423.447606)
			(xy 449.331001 -423.480908) (xy 449.256803 -423.506718) (xy 449.180346 -423.524762) (xy 449.102438 -423.534848)
			(xy 449.023906 -423.536871) (xy 448.945582 -423.530808) (xy 448.868297 -423.516724) (xy 448.79287 -423.494769)
			(xy 448.720099 -423.465174) (xy 448.650758 -423.428253) (xy 448.58558 -423.384399) (xy 448.525257 -423.334075)
			(xy 448.470428 -423.277815) (xy 448.421674 -423.216216) (xy 448.379512 -423.149931) (xy 448.344389 -423.079662)
			(xy 448.316678 -423.006154) (xy 448.296671 -422.930186) (xy 448.284582 -422.852564) (xy 448.280538 -422.77411)
			(xy 446.767966 -422.77411) (xy 446.767966 -424.190922) (xy 446.768536 -424.20204) (xy 446.777939 -424.222191)
			(xy 446.794975 -424.236482) (xy 446.805558 -424.239944) (xy 446.91681 -424.27017) (xy 446.94856 -424.257216)
			(xy 446.957196 -424.24223) (xy 446.977713 -424.208289) (xy 447.024755 -424.144431) (xy 447.078172 -424.085802)
			(xy 447.137389 -424.033036) (xy 447.201764 -423.986704) (xy 447.270601 -423.947307) (xy 447.343158 -423.91527)
			(xy 447.418648 -423.890939) (xy 447.496257 -423.874578) (xy 447.575145 -423.866364) (xy 447.614802 -423.865802)
			(xy 447.634396 -423.865943) (xy 447.673531 -423.867974) (xy 447.693034 -423.869866) (xy 447.700146 -423.870628)
			(xy 447.714116 -423.868088) (xy 447.743072 -423.853864) (xy 447.751454 -423.847006) (xy 447.75501 -423.842434)
			(xy 447.779109 -423.812995) (xy 447.832251 -423.758547) (xy 447.890549 -423.709659) (xy 447.953424 -423.666817)
			(xy 448.020252 -423.630447) (xy 448.090368 -423.600909) (xy 448.163076 -423.578498) (xy 448.237653 -423.563436)
			(xy 448.31336 -423.555872) (xy 448.351402 -423.555414) (xy 448.390046 -423.555903) (xy 448.466938 -423.563723)
			(xy 448.542643 -423.579281) (xy 448.616387 -423.602418) (xy 448.687411 -423.632897) (xy 448.754988 -423.670405)
			(xy 448.818423 -423.714558) (xy 448.877066 -423.764901) (xy 448.930315 -423.820919) (xy 448.977623 -423.882037)
			(xy 449.018506 -423.947627) (xy 449.052543 -424.017016) (xy 449.079385 -424.089493) (xy 449.098758 -424.164314)
			(xy 449.110461 -424.240711) (xy 449.114376 -424.3179) (xy 449.110461 -424.395089) (xy 449.098758 -424.471486)
			(xy 449.079385 -424.546307) (xy 449.052543 -424.618784) (xy 449.018506 -424.688173) (xy 448.977623 -424.753763)
			(xy 448.930315 -424.814881) (xy 448.877066 -424.870899) (xy 448.818423 -424.921242) (xy 448.754988 -424.965395)
			(xy 448.687411 -425.002903) (xy 448.616387 -425.033382) (xy 448.542643 -425.056519) (xy 448.466938 -425.072077)
			(xy 448.390046 -425.079897) (xy 448.351402 -425.08043) (xy 448.331808 -425.08029) (xy 448.292673 -425.078259)
			(xy 448.27317 -425.076366) (xy 448.266058 -425.075604) (xy 448.252088 -425.078144) (xy 448.223132 -425.092368)
			(xy 448.21475 -425.099226) (xy 448.211194 -425.103798) (xy 448.187096 -425.133239) (xy 448.133956 -425.187692)
			(xy 448.07566 -425.236584) (xy 448.012785 -425.279431) (xy 447.945958 -425.315805) (xy 447.875841 -425.345345)
			(xy 447.803132 -425.367759) (xy 447.728553 -425.382823) (xy 447.652845 -425.390387) (xy 447.614802 -425.390818)
			(xy 447.575146 -425.390305) (xy 447.496263 -425.382065) (xy 447.418662 -425.365683) (xy 447.343179 -425.341336)
			(xy 447.27063 -425.309287) (xy 447.201799 -425.269883) (xy 447.137429 -425.223549) (xy 447.078215 -425.170784)
			(xy 447.024795 -425.11216) (xy 446.977748 -425.048309) (xy 446.957196 -425.01439) (xy 446.94856 -424.999404)
			(xy 446.91681 -424.98645) (xy 446.805558 -425.016676) (xy 446.794963 -425.020113) (xy 446.777925 -425.034419)
			(xy 446.768506 -425.054575) (xy 446.767966 -425.065698) (xy 446.767966 -426.07611) (xy 447.664588 -426.07611)
			(xy 447.668632 -425.997656) (xy 447.680721 -425.920034) (xy 447.700728 -425.844066) (xy 447.728439 -425.770558)
			(xy 447.763562 -425.700289) (xy 447.805724 -425.634004) (xy 447.854478 -425.572405) (xy 447.909307 -425.516145)
			(xy 447.96963 -425.465821) (xy 448.034808 -425.421967) (xy 448.104149 -425.385046) (xy 448.17692 -425.355451)
			(xy 448.252347 -425.333496) (xy 448.329632 -425.319412) (xy 448.407956 -425.313349) (xy 448.486488 -425.315372)
			(xy 448.564396 -425.325458) (xy 448.640853 -425.343502) (xy 448.715051 -425.369312) (xy 448.786201 -425.402614)
			(xy 448.85355 -425.443055) (xy 448.916384 -425.490206) (xy 448.974036 -425.543569) (xy 449.025896 -425.602576)
			(xy 449.071415 -425.666603) (xy 449.110108 -425.734971) (xy 449.141567 -425.806955) (xy 449.165458 -425.881792)
			(xy 449.181527 -425.958689) (xy 449.189604 -426.036831) (xy 449.19011 -426.07611) (xy 449.189604 -426.115389)
			(xy 449.181527 -426.193531) (xy 449.165458 -426.270428) (xy 449.141567 -426.345265) (xy 449.110108 -426.417249)
			(xy 449.071415 -426.485617) (xy 449.025896 -426.549644) (xy 448.974036 -426.608651) (xy 448.916384 -426.662014)
			(xy 448.85355 -426.709165) (xy 448.786201 -426.749606) (xy 448.715051 -426.782908) (xy 448.640853 -426.808718)
			(xy 448.564396 -426.826762) (xy 448.486488 -426.836848) (xy 448.407956 -426.838871) (xy 448.329632 -426.832808)
			(xy 448.252347 -426.818724) (xy 448.17692 -426.796769) (xy 448.104149 -426.767174) (xy 448.034808 -426.730253)
			(xy 447.96963 -426.686399) (xy 447.909307 -426.636075) (xy 447.854478 -426.579815) (xy 447.805724 -426.518216)
			(xy 447.763562 -426.451931) (xy 447.728439 -426.381662) (xy 447.700728 -426.308154) (xy 447.680721 -426.232186)
			(xy 447.668632 -426.154564) (xy 447.664588 -426.07611) (xy 446.767966 -426.07611) (xy 446.767966 -427.830742)
			(xy 446.768398 -427.840807) (xy 446.776131 -427.859395) (xy 446.782952 -427.86681) (xy 447.05143 -428.135288)
			(xy 447.05883 -428.142131) (xy 447.077428 -428.149856) (xy 447.087498 -428.150274)
		)
		(stroke
			(width 0)
			(type solid)
		)
		(fill yes)
		(layer "In15.Cu")
		(net "PV09_RETIMER_CPU0_VCCS")
	)
	(gr_poly
		(pts
			(xy 173.09211 -388.916164) (xy 173.102953 -388.915673) (xy 173.122709 -388.906735) (xy 173.13021 -388.898892)
			(xy 173.187868 -388.83336) (xy 173.194218 -388.812532) (xy 173.192948 -388.80161) (xy 173.191528 -388.789659)
			(xy 173.19 -388.765638) (xy 173.1899 -388.753604) (xy 173.190363 -388.726351) (xy 173.19812 -388.6724)
			(xy 173.213475 -388.620102) (xy 173.236118 -388.570522) (xy 173.265586 -388.524669) (xy 173.30128 -388.483477)
			(xy 173.342472 -388.447783) (xy 173.388326 -388.418316) (xy 173.437906 -388.395674) (xy 173.490204 -388.380319)
			(xy 173.544155 -388.372563) (xy 173.571408 -388.372096) (xy 173.600145 -388.372616) (xy 173.656969 -388.381232)
			(xy 173.71186 -388.398267) (xy 173.763577 -388.423337) (xy 173.810953 -388.455876) (xy 173.852916 -388.495149)
			(xy 173.871128 -388.517384) (xy 173.877986 -388.526274) (xy 173.896782 -388.53618) (xy 173.983904 -388.54126)
			(xy 173.994678 -388.541426) (xy 174.01481 -388.533795) (xy 174.022766 -388.526528) (xy 183.423814 -379.125226)
			(xy 183.430622 -379.117881) (xy 183.438341 -379.099417) (xy 183.4388 -379.089412) (xy 183.4388 -373.044466)
			(xy 183.438256 -373.034481) (xy 183.430534 -373.016058) (xy 183.423814 -373.008652) (xy 182.062628 -371.647466)
			(xy 182.055282 -371.64066) (xy 182.036819 -371.632943) (xy 182.026814 -371.63248) (xy 172.817282 -371.63248)
			(xy 172.807213 -371.632906) (xy 172.788611 -371.640623) (xy 172.781214 -371.647466) (xy 170.758866 -373.669814)
			(xy 170.752015 -373.67721) (xy 170.744275 -373.695809) (xy 170.74388 -373.705882) (xy 170.74388 -374.95099)
			(xy 170.744388 -374.961824) (xy 170.753352 -374.981551) (xy 170.761152 -374.98909) (xy 170.82643 -375.046748)
			(xy 170.847258 -375.053098) (xy 170.857926 -375.051828) (xy 170.869751 -375.050423) (xy 170.893517 -375.048899)
			(xy 170.905424 -375.04878) (xy 170.931937 -375.049229) (xy 170.984457 -375.056531) (xy 171.035473 -375.070994)
			(xy 171.084012 -375.092342) (xy 171.12915 -375.120168) (xy 171.170028 -375.153943) (xy 171.205867 -375.193023)
			(xy 171.235986 -375.236665) (xy 171.25981 -375.284037) (xy 171.276887 -375.334238) (xy 171.28236 -375.360184)
			(xy 171.284392 -375.370344) (xy 171.295568 -375.387108) (xy 171.37253 -375.43867) (xy 171.392342 -375.442734)
			(xy 171.402248 -375.440702) (xy 171.421088 -375.43706) (xy 171.459261 -375.433118) (xy 171.478448 -375.432828)
			(xy 171.50588 -375.433321) (xy 171.560185 -375.441135) (xy 171.612826 -375.456597) (xy 171.66273 -375.479393)
			(xy 171.708882 -375.509059) (xy 171.750344 -375.54499) (xy 171.78627 -375.586456) (xy 171.81593 -375.632612)
			(xy 171.83872 -375.682519) (xy 171.854175 -375.735162) (xy 171.861983 -375.789468) (xy 171.861983 -375.844332)
			(xy 171.854175 -375.898638) (xy 171.83872 -375.951281) (xy 171.81593 -376.001188) (xy 171.78627 -376.047344)
			(xy 171.750344 -376.08881) (xy 171.708882 -376.124741) (xy 171.66273 -376.154407) (xy 171.612826 -376.177203)
			(xy 171.560185 -376.192665) (xy 171.50588 -376.200479) (xy 171.478448 -376.200924) (xy 171.446444 -376.1994)
			(xy 171.434797 -376.199039) (xy 171.413133 -376.207553) (xy 171.397397 -376.224705) (xy 171.393612 -376.235722)
			(xy 171.383503 -376.268376) (xy 171.355737 -376.330842) (xy 171.319865 -376.389031) (xy 171.298616 -376.415808)
			(xy 171.29328 -376.422787) (xy 171.287291 -376.439289) (xy 171.286932 -376.448066) (xy 171.286932 -376.49658)
			(xy 173.226991 -376.49658) (xy 173.230998 -376.311676) (xy 173.243011 -376.127118) (xy 173.263007 -375.943254)
			(xy 173.290949 -375.76043) (xy 173.326785 -375.578987) (xy 173.370447 -375.399266) (xy 173.421854 -375.221606)
			(xy 173.480908 -375.04634) (xy 173.547499 -374.873796) (xy 173.621502 -374.704299) (xy 173.702778 -374.538167)
			(xy 173.791174 -374.375711) (xy 173.886525 -374.217237) (xy 173.988651 -374.063042) (xy 174.09736 -373.913416)
			(xy 174.212449 -373.76864) (xy 174.333702 -373.628985) (xy 174.460891 -373.494714) (xy 174.593776 -373.366078)
			(xy 174.73211 -373.243319) (xy 174.875631 -373.126669) (xy 175.02407 -373.016345) (xy 175.17715 -372.912554)
			(xy 175.334581 -372.815492) (xy 175.49607 -372.725342) (xy 175.661312 -372.642271) (xy 175.829998 -372.566436)
			(xy 176.00181 -372.49798) (xy 176.176426 -372.43703) (xy 176.353519 -372.383703) (xy 176.532756 -372.338096)
			(xy 176.7138 -372.300297) (xy 176.896311 -372.270376) (xy 177.079948 -372.248389) (xy 177.264364 -372.234377)
			(xy 177.449214 -372.228367) (xy 177.634151 -372.230371) (xy 177.818828 -372.240384) (xy 178.002898 -372.258387)
			(xy 178.186014 -372.284348) (xy 178.367835 -372.318216) (xy 178.548018 -372.359928) (xy 178.726224 -372.409407)
			(xy 178.90212 -372.466559) (xy 179.075375 -372.531277) (xy 179.245664 -372.60344) (xy 179.412667 -372.682911)
			(xy 179.576071 -372.769542) (xy 179.735568 -372.863171) (xy 179.89086 -372.96362) (xy 180.041655 -373.070703)
			(xy 180.18767 -373.184217) (xy 180.32863 -373.303949) (xy 180.464271 -373.429676) (xy 180.594339 -373.56116)
			(xy 180.718589 -373.698156) (xy 180.836787 -373.840405) (xy 180.948713 -373.98764) (xy 181.054156 -374.139586)
			(xy 181.152917 -374.295957) (xy 181.244812 -374.45646) (xy 181.329668 -374.620792) (xy 181.407326 -374.788647)
			(xy 181.477639 -374.959707) (xy 181.540476 -375.133653) (xy 181.59572 -375.310158) (xy 181.643265 -375.48889)
			(xy 181.683023 -375.669514) (xy 181.71492 -375.851691) (xy 181.738895 -376.035078) (xy 181.754903 -376.219332)
			(xy 181.762915 -376.404106) (xy 181.763416 -376.49658) (xy 181.762915 -376.589054) (xy 181.754903 -376.773828)
			(xy 181.738895 -376.958082) (xy 181.71492 -377.141469) (xy 181.683023 -377.323646) (xy 181.643265 -377.50427)
			(xy 181.59572 -377.683002) (xy 181.540476 -377.859507) (xy 181.477639 -378.033453) (xy 181.407326 -378.204513)
			(xy 181.329668 -378.372368) (xy 181.244812 -378.5367) (xy 181.152917 -378.697203) (xy 181.054156 -378.853574)
			(xy 180.948713 -379.00552) (xy 180.836787 -379.152755) (xy 180.718589 -379.295004) (xy 180.594339 -379.432)
			(xy 180.464271 -379.563484) (xy 180.32863 -379.689211) (xy 180.18767 -379.808943) (xy 180.041655 -379.922457)
			(xy 179.89086 -380.02954) (xy 179.735568 -380.129989) (xy 179.576071 -380.223618) (xy 179.412667 -380.310249)
			(xy 179.245664 -380.38972) (xy 179.075375 -380.461883) (xy 178.90212 -380.526601) (xy 178.726224 -380.583753)
			(xy 178.548018 -380.633232) (xy 178.367835 -380.674944) (xy 178.186014 -380.708812) (xy 178.002898 -380.734773)
			(xy 177.818828 -380.752776) (xy 177.634151 -380.762789) (xy 177.449214 -380.764793) (xy 177.264364 -380.758783)
			(xy 177.079948 -380.744771) (xy 176.896311 -380.722784) (xy 176.7138 -380.692863) (xy 176.532756 -380.655064)
			(xy 176.353519 -380.609457) (xy 176.176426 -380.55613) (xy 176.00181 -380.49518) (xy 175.829998 -380.426724)
			(xy 175.661312 -380.350889) (xy 175.49607 -380.267818) (xy 175.334581 -380.177668) (xy 175.17715 -380.080606)
			(xy 175.02407 -379.976815) (xy 174.875631 -379.866491) (xy 174.73211 -379.749841) (xy 174.593776 -379.627082)
			(xy 174.460891 -379.498446) (xy 174.333702 -379.364175) (xy 174.212449 -379.22452) (xy 174.09736 -379.079744)
			(xy 173.988651 -378.930118) (xy 173.886525 -378.775923) (xy 173.791174 -378.617449) (xy 173.702778 -378.454993)
			(xy 173.621502 -378.288861) (xy 173.547499 -378.119364) (xy 173.480908 -377.94682) (xy 173.421854 -377.771554)
			(xy 173.370447 -377.593894) (xy 173.326785 -377.414173) (xy 173.290949 -377.23273) (xy 173.263007 -377.049906)
			(xy 173.243011 -376.866042) (xy 173.230998 -376.681484) (xy 173.226991 -376.49658) (xy 171.286932 -376.49658)
			(xy 171.286932 -376.60199) (xy 171.287351 -376.610756) (xy 171.293331 -376.627241) (xy 171.298616 -376.634248)
			(xy 171.316007 -376.656035) (xy 171.346433 -376.702748) (xy 171.359322 -376.727466) (xy 171.363724 -376.735405)
			(xy 171.377 -376.747766) (xy 171.38523 -376.751596) (xy 171.413424 -376.76328) (xy 171.42187 -376.766376)
			(xy 171.439833 -376.767039) (xy 171.448476 -376.76455) (xy 171.477047 -376.755935) (xy 171.535989 -376.746627)
			(xy 171.565824 -376.746008) (xy 171.593259 -376.746499) (xy 171.647569 -376.754311) (xy 171.700215 -376.769772)
			(xy 171.750125 -376.792568) (xy 171.796283 -376.822234) (xy 171.837749 -376.858168) (xy 171.87368 -376.899636)
			(xy 171.903344 -376.945796) (xy 171.926136 -376.995707) (xy 171.941594 -377.048354) (xy 171.949403 -377.102665)
			(xy 171.949403 -377.157535) (xy 171.941594 -377.211846) (xy 171.926136 -377.264493) (xy 171.903344 -377.314404)
			(xy 171.87368 -377.360564) (xy 171.837749 -377.402032) (xy 171.796283 -377.437966) (xy 171.750125 -377.467632)
			(xy 171.700215 -377.490428) (xy 171.647569 -377.505889) (xy 171.593259 -377.513701) (xy 171.565824 -377.514104)
			(xy 171.542074 -377.513753) (xy 171.494937 -377.50789) (xy 171.448889 -377.496239) (xy 171.426632 -377.487942)
			(xy 171.414186 -377.483116) (xy 171.388532 -377.486418) (xy 171.298108 -377.55322) (xy 171.28744 -377.576588)
			(xy 171.288456 -377.589796) (xy 171.289472 -377.617228) (xy 171.288981 -377.64466) (xy 171.28117 -377.698965)
			(xy 171.26571 -377.751606) (xy 171.242917 -377.801511) (xy 171.213254 -377.847665) (xy 171.177325 -377.889128)
			(xy 171.135862 -377.925057) (xy 171.089708 -377.954719) (xy 171.039802 -377.977511) (xy 170.987161 -377.99297)
			(xy 170.932856 -378.000781) (xy 170.905424 -378.001276) (xy 170.893516 -378.001164) (xy 170.86975 -377.999642)
			(xy 170.857926 -377.998228) (xy 170.847258 -377.996958) (xy 170.82643 -378.003308) (xy 170.761152 -378.060966)
			(xy 170.753358 -378.068503) (xy 170.744424 -378.088236) (xy 170.74388 -378.099066) (xy 170.74388 -378.35459)
			(xy 170.744388 -378.365424) (xy 170.753352 -378.385151) (xy 170.761152 -378.39269) (xy 170.82643 -378.450348)
			(xy 170.847258 -378.456698) (xy 170.857926 -378.455428) (xy 170.869751 -378.454023) (xy 170.893517 -378.452499)
			(xy 170.905424 -378.45238) (xy 170.932856 -378.452848) (xy 170.987162 -378.46066) (xy 171.039804 -378.47612)
			(xy 171.08971 -378.498915) (xy 171.135863 -378.52858) (xy 171.177325 -378.564512) (xy 171.213251 -378.605979)
			(xy 171.24291 -378.652136) (xy 171.265698 -378.702045) (xy 171.281152 -378.754688) (xy 171.288956 -378.808995)
			(xy 171.289472 -378.836428) (xy 171.28871 -378.860558) (xy 171.287694 -378.873766) (xy 171.298616 -378.897134)
			(xy 171.38904 -378.963174) (xy 171.414694 -378.966476) (xy 171.426886 -378.96165) (xy 171.449113 -378.953401)
			(xy 171.495077 -378.941778) (xy 171.542119 -378.93588) (xy 171.565824 -378.935488) (xy 171.593253 -378.935979)
			(xy 171.647552 -378.943789) (xy 171.700187 -378.959247) (xy 171.750087 -378.982038) (xy 171.796235 -379.011698)
			(xy 171.837693 -379.047624) (xy 171.873616 -379.089084) (xy 171.903273 -379.135234) (xy 171.926061 -379.185135)
			(xy 171.941516 -379.237771) (xy 171.949323 -379.292071) (xy 171.949323 -379.346929) (xy 171.941516 -379.401229)
			(xy 171.926061 -379.453865) (xy 171.903273 -379.503766) (xy 171.873616 -379.549916) (xy 171.837693 -379.591376)
			(xy 171.796235 -379.627302) (xy 171.750087 -379.656962) (xy 171.700187 -379.679753) (xy 171.647552 -379.695211)
			(xy 171.593253 -379.703021) (xy 171.565824 -379.703584) (xy 171.536325 -379.703025) (xy 171.478024 -379.693968)
			(xy 171.449746 -379.68555) (xy 171.441131 -379.683262) (xy 171.423337 -379.684056) (xy 171.414948 -379.687074)
			(xy 171.386754 -379.698758) (xy 171.378488 -379.702628) (xy 171.365205 -379.715124) (xy 171.360846 -379.723142)
			(xy 171.347708 -379.74869) (xy 171.31652 -379.79694) (xy 171.298616 -379.819408) (xy 171.29328 -379.826387)
			(xy 171.287291 -379.842889) (xy 171.286932 -379.851666) (xy 171.286932 -380.00559) (xy 171.287351 -380.014356)
			(xy 171.293331 -380.030841) (xy 171.298616 -380.037848) (xy 171.316007 -380.059635) (xy 171.346433 -380.106348)
			(xy 171.359322 -380.131066) (xy 171.363724 -380.139005) (xy 171.377 -380.151366) (xy 171.38523 -380.155196)
			(xy 171.413424 -380.16688) (xy 171.42187 -380.169976) (xy 171.439833 -380.170639) (xy 171.448476 -380.16815)
			(xy 171.477047 -380.159535) (xy 171.535989 -380.150227) (xy 171.565824 -380.149608) (xy 171.593259 -380.150099)
			(xy 171.647569 -380.157911) (xy 171.700215 -380.173372) (xy 171.750125 -380.196168) (xy 171.796283 -380.225834)
			(xy 171.837749 -380.261768) (xy 171.87368 -380.303236) (xy 171.903344 -380.349396) (xy 171.926136 -380.399307)
			(xy 171.941594 -380.451954) (xy 171.949403 -380.506265) (xy 171.949403 -380.561135) (xy 171.941594 -380.615446)
			(xy 171.926136 -380.668093) (xy 171.903344 -380.718004) (xy 171.87368 -380.764164) (xy 171.837749 -380.805632)
			(xy 171.796283 -380.841566) (xy 171.750125 -380.871232) (xy 171.700215 -380.894028) (xy 171.647569 -380.909489)
			(xy 171.593259 -380.917301) (xy 171.565824 -380.917704) (xy 171.542074 -380.917353) (xy 171.494937 -380.91149)
			(xy 171.448889 -380.899839) (xy 171.426632 -380.891542) (xy 171.414186 -380.886716) (xy 171.388532 -380.890018)
			(xy 171.298108 -380.95682) (xy 171.28744 -380.980188) (xy 171.288456 -380.993396) (xy 171.289472 -381.020828)
			(xy 171.288981 -381.04826) (xy 171.28117 -381.102565) (xy 171.26571 -381.155206) (xy 171.242917 -381.205111)
			(xy 171.213254 -381.251265) (xy 171.177325 -381.292728) (xy 171.135862 -381.328657) (xy 171.089708 -381.358319)
			(xy 171.039802 -381.381111) (xy 170.987161 -381.39657) (xy 170.932856 -381.404381) (xy 170.905424 -381.404876)
			(xy 170.893516 -381.404764) (xy 170.86975 -381.403242) (xy 170.857926 -381.401828) (xy 170.847258 -381.400558)
			(xy 170.82643 -381.406908) (xy 170.761152 -381.464566) (xy 170.753358 -381.472103) (xy 170.744424 -381.491836)
			(xy 170.74388 -381.502666) (xy 170.74388 -385.124198) (xy 170.744302 -385.134269) (xy 170.752014 -385.152876)
			(xy 170.758866 -385.160266) (xy 171.235878 -385.637278) (xy 171.261786 -385.64439) (xy 171.274994 -385.641088)
			(xy 171.298457 -385.635386) (xy 171.346355 -385.629272) (xy 171.370498 -385.628896) (xy 171.397751 -385.629359)
			(xy 171.451702 -385.637116) (xy 171.504 -385.652472) (xy 171.55358 -385.675114) (xy 171.599433 -385.704582)
			(xy 171.640625 -385.740276) (xy 171.676319 -385.781469) (xy 171.705787 -385.827322) (xy 171.728429 -385.876902)
			(xy 171.743784 -385.9292) (xy 171.751541 -385.983151) (xy 171.752006 -386.010404) (xy 171.751387 -386.042257)
			(xy 171.740835 -386.105082) (xy 171.724529 -386.152136) (xy 172.518322 -386.152136) (xy 172.522393 -386.096514)
			(xy 172.534519 -386.042077) (xy 172.554442 -385.989986) (xy 172.581738 -385.941351) (xy 172.615824 -385.897208)
			(xy 172.655973 -385.858499) (xy 172.701331 -385.826048) (xy 172.750931 -385.800547) (xy 172.803715 -385.78254)
			(xy 172.858558 -385.77241) (xy 172.914292 -385.770373) (xy 172.969729 -385.776473) (xy 173.023686 -385.790579)
			(xy 173.075015 -385.812391) (xy 173.122621 -385.841445) (xy 173.165489 -385.87712) (xy 173.202706 -385.918657)
			(xy 173.233479 -385.96517) (xy 173.2398 -385.978654) (xy 174.400462 -385.978654) (xy 174.404533 -385.923032)
			(xy 174.416659 -385.868595) (xy 174.436582 -385.816504) (xy 174.463878 -385.767869) (xy 174.497964 -385.723726)
			(xy 174.538113 -385.685017) (xy 174.583471 -385.652566) (xy 174.633071 -385.627065) (xy 174.685855 -385.609058)
			(xy 174.740698 -385.598928) (xy 174.796432 -385.596891) (xy 174.851869 -385.602991) (xy 174.905826 -385.617097)
			(xy 174.957155 -385.638909) (xy 175.004761 -385.667963) (xy 175.047629 -385.703638) (xy 175.084846 -385.745175)
			(xy 175.115619 -385.791688) (xy 175.139291 -385.842185) (xy 175.155359 -385.895592) (xy 175.163479 -385.950768)
			(xy 175.163988 -385.978654) (xy 175.163479 -386.00654) (xy 175.155359 -386.061716) (xy 175.139291 -386.115123)
			(xy 175.115619 -386.16562) (xy 175.084846 -386.212133) (xy 175.047629 -386.25367) (xy 175.004761 -386.289345)
			(xy 174.957155 -386.318399) (xy 174.905826 -386.340211) (xy 174.851869 -386.354317) (xy 174.796432 -386.360417)
			(xy 174.740698 -386.35838) (xy 174.685855 -386.34825) (xy 174.633071 -386.330243) (xy 174.583471 -386.304742)
			(xy 174.538113 -386.272291) (xy 174.497964 -386.233582) (xy 174.463878 -386.189439) (xy 174.436582 -386.140804)
			(xy 174.416659 -386.088713) (xy 174.404533 -386.034276) (xy 174.400462 -385.978654) (xy 173.2398 -385.978654)
			(xy 173.257151 -386.015667) (xy 173.273219 -386.069074) (xy 173.281339 -386.12425) (xy 173.281848 -386.152136)
			(xy 173.281339 -386.180022) (xy 173.273219 -386.235198) (xy 173.257151 -386.288605) (xy 173.233479 -386.339102)
			(xy 173.202706 -386.385615) (xy 173.165489 -386.427152) (xy 173.122621 -386.462827) (xy 173.075015 -386.491881)
			(xy 173.023686 -386.513693) (xy 172.969729 -386.527799) (xy 172.914292 -386.533899) (xy 172.858558 -386.531862)
			(xy 172.803715 -386.521732) (xy 172.750931 -386.503725) (xy 172.701331 -386.478224) (xy 172.655973 -386.445773)
			(xy 172.615824 -386.407064) (xy 172.581738 -386.362921) (xy 172.554442 -386.314286) (xy 172.534519 -386.262195)
			(xy 172.522393 -386.207758) (xy 172.518322 -386.152136) (xy 171.724529 -386.152136) (xy 171.719976 -386.165275)
			(xy 171.70527 -386.193538) (xy 171.702329 -386.199201) (xy 171.699103 -386.211544) (xy 171.69892 -386.217922)
			(xy 171.69892 -386.660898) (xy 173.271178 -386.660898) (xy 173.275249 -386.605276) (xy 173.287375 -386.550839)
			(xy 173.307298 -386.498748) (xy 173.334594 -386.450113) (xy 173.36868 -386.40597) (xy 173.408829 -386.367261)
			(xy 173.454187 -386.33481) (xy 173.503787 -386.309309) (xy 173.556571 -386.291302) (xy 173.611414 -386.281172)
			(xy 173.667148 -386.279135) (xy 173.722585 -386.285235) (xy 173.776542 -386.299341) (xy 173.827871 -386.321153)
			(xy 173.875477 -386.350207) (xy 173.918345 -386.385882) (xy 173.955562 -386.427419) (xy 173.986335 -386.473932)
			(xy 174.010007 -386.524429) (xy 174.026075 -386.577836) (xy 174.034195 -386.633012) (xy 174.034704 -386.660898)
			(xy 174.034195 -386.688784) (xy 174.026075 -386.74396) (xy 174.010007 -386.797367) (xy 173.986335 -386.847864)
			(xy 173.955562 -386.894377) (xy 173.918345 -386.935914) (xy 173.875477 -386.971589) (xy 173.827871 -387.000643)
			(xy 173.776542 -387.022455) (xy 173.722585 -387.036561) (xy 173.667148 -387.042661) (xy 173.611414 -387.040624)
			(xy 173.556571 -387.030494) (xy 173.503787 -387.012487) (xy 173.454187 -386.986986) (xy 173.408829 -386.954535)
			(xy 173.36868 -386.915826) (xy 173.334594 -386.871683) (xy 173.307298 -386.823048) (xy 173.287375 -386.770957)
			(xy 173.275249 -386.71652) (xy 173.271178 -386.660898) (xy 171.69892 -386.660898) (xy 171.69892 -387.737604)
			(xy 173.18939 -387.737604) (xy 173.193461 -387.681982) (xy 173.205587 -387.627545) (xy 173.22551 -387.575454)
			(xy 173.252806 -387.526819) (xy 173.286892 -387.482676) (xy 173.327041 -387.443967) (xy 173.372399 -387.411516)
			(xy 173.421999 -387.386015) (xy 173.474783 -387.368008) (xy 173.529626 -387.357878) (xy 173.58536 -387.355841)
			(xy 173.640797 -387.361941) (xy 173.694754 -387.376047) (xy 173.746083 -387.397859) (xy 173.793689 -387.426913)
			(xy 173.836557 -387.462588) (xy 173.873774 -387.504125) (xy 173.904547 -387.550638) (xy 173.928219 -387.601135)
			(xy 173.944287 -387.654542) (xy 173.952407 -387.709718) (xy 173.952916 -387.737604) (xy 173.952407 -387.76549)
			(xy 173.944287 -387.820666) (xy 173.928219 -387.874073) (xy 173.904547 -387.92457) (xy 173.873774 -387.971083)
			(xy 173.836557 -388.01262) (xy 173.793689 -388.048295) (xy 173.746083 -388.077349) (xy 173.694754 -388.099161)
			(xy 173.640797 -388.113267) (xy 173.58536 -388.119367) (xy 173.529626 -388.11733) (xy 173.474783 -388.1072)
			(xy 173.421999 -388.089193) (xy 173.372399 -388.063692) (xy 173.327041 -388.031241) (xy 173.286892 -387.992532)
			(xy 173.252806 -387.948389) (xy 173.22551 -387.899754) (xy 173.205587 -387.847663) (xy 173.193461 -387.793226)
			(xy 173.18939 -387.737604) (xy 171.69892 -387.737604) (xy 171.69892 -388.738618) (xy 171.699347 -388.748686)
			(xy 171.707068 -388.767284) (xy 171.713906 -388.774686) (xy 171.840398 -388.901178) (xy 171.847742 -388.907991)
			(xy 171.866205 -388.915728) (xy 171.876212 -388.916164)
		)
		(stroke
			(width 0)
			(type solid)
		)
		(fill yes)
		(layer "In15.Cu")
		(net "P1V8_CPU1_RT_1D")
	)
	(gr_poly
		(pts
			(xy 206.320898 -73.50252) (xy 206.330777 -73.502064) (xy 206.349083 -73.494628) (xy 206.356458 -73.488042)
			(xy 206.356712 -73.487788) (xy 207.74152 -72.10298) (xy 207.742028 -72.102472) (xy 207.748617 -72.095093)
			(xy 207.75608 -72.076794) (xy 207.756506 -72.066912) (xy 207.756506 -67.84086) (xy 207.756076 -67.830793)
			(xy 207.748352 -67.812198) (xy 207.74152 -67.804792) (xy 206.848202 -66.911474) (xy 206.84109 -66.904108)
			(xy 206.822294 -66.896488) (xy 199.65035 -66.896488) (xy 199.640284 -66.89692) (xy 199.621691 -66.904646)
			(xy 199.614282 -66.911474) (xy 199.60463 -66.920872) (xy 199.597282 -66.927675) (xy 199.578819 -66.935386)
			(xy 199.568816 -66.935858) (xy 199.472804 -66.935858) (xy 199.471788 -66.935858) (xy 199.460358 -66.936112)
			(xy 189.497716 -66.936112) (xy 189.487756 -66.936602) (xy 189.469337 -66.944195) (xy 189.461902 -66.950844)
			(xy 188.990986 -67.42176) (xy 188.98362 -67.428872) (xy 188.976 -67.447668) (xy 188.976 -67.525392)
			(xy 203.656436 -67.525392) (xy 203.660509 -67.469733) (xy 203.672644 -67.41526) (xy 203.69258 -67.363134)
			(xy 203.719894 -67.314466) (xy 203.754002 -67.270294) (xy 203.794179 -67.231559) (xy 203.839567 -67.199087)
			(xy 203.889199 -67.173569) (xy 203.942019 -67.15555) (xy 203.996898 -67.145413) (xy 204.052669 -67.143375)
			(xy 204.108143 -67.149478) (xy 204.162136 -67.163594) (xy 204.213499 -67.185421) (xy 204.261137 -67.214494)
			(xy 204.304033 -67.250193) (xy 204.341275 -67.291757) (xy 204.372069 -67.338301) (xy 204.395757 -67.388832)
			(xy 204.411835 -67.442274) (xy 204.419961 -67.497488) (xy 204.42047 -67.525392) (xy 204.419961 -67.553296)
			(xy 204.415956 -67.58051) (xy 206.291432 -67.58051) (xy 206.295505 -67.524851) (xy 206.30764 -67.470378)
			(xy 206.327576 -67.418252) (xy 206.35489 -67.369584) (xy 206.388998 -67.325412) (xy 206.429175 -67.286677)
			(xy 206.474563 -67.254205) (xy 206.524195 -67.228687) (xy 206.577015 -67.210668) (xy 206.631894 -67.200531)
			(xy 206.687665 -67.198493) (xy 206.743139 -67.204596) (xy 206.797132 -67.218712) (xy 206.848495 -67.240539)
			(xy 206.896133 -67.269612) (xy 206.939029 -67.305311) (xy 206.976271 -67.346875) (xy 207.007065 -67.393419)
			(xy 207.030753 -67.44395) (xy 207.046831 -67.497392) (xy 207.054957 -67.552606) (xy 207.055466 -67.58051)
			(xy 207.054957 -67.608414) (xy 207.046831 -67.663628) (xy 207.030753 -67.71707) (xy 207.007065 -67.767601)
			(xy 206.976271 -67.814145) (xy 206.939029 -67.855709) (xy 206.896133 -67.891408) (xy 206.848495 -67.920481)
			(xy 206.797132 -67.942308) (xy 206.743139 -67.956424) (xy 206.687665 -67.962527) (xy 206.631894 -67.960489)
			(xy 206.577015 -67.950352) (xy 206.524195 -67.932333) (xy 206.474563 -67.906815) (xy 206.429175 -67.874343)
			(xy 206.388998 -67.835608) (xy 206.35489 -67.791436) (xy 206.327576 -67.742768) (xy 206.30764 -67.690642)
			(xy 206.295505 -67.636169) (xy 206.291432 -67.58051) (xy 204.415956 -67.58051) (xy 204.411835 -67.60851)
			(xy 204.395757 -67.661952) (xy 204.372069 -67.712483) (xy 204.341275 -67.759027) (xy 204.304033 -67.800591)
			(xy 204.261137 -67.83629) (xy 204.213499 -67.865363) (xy 204.162136 -67.88719) (xy 204.108143 -67.901306)
			(xy 204.052669 -67.907409) (xy 203.996898 -67.905371) (xy 203.942019 -67.895234) (xy 203.889199 -67.877215)
			(xy 203.839567 -67.851697) (xy 203.794179 -67.819225) (xy 203.754002 -67.78049) (xy 203.719894 -67.736318)
			(xy 203.69258 -67.68765) (xy 203.672644 -67.635524) (xy 203.660509 -67.581051) (xy 203.656436 -67.525392)
			(xy 188.976 -67.525392) (xy 188.976 -68.696586) (xy 199.142094 -68.696586) (xy 199.146167 -68.640927)
			(xy 199.158302 -68.586454) (xy 199.178238 -68.534328) (xy 199.205552 -68.48566) (xy 199.23966 -68.441488)
			(xy 199.279837 -68.402753) (xy 199.325225 -68.370281) (xy 199.374857 -68.344763) (xy 199.427677 -68.326744)
			(xy 199.482556 -68.316607) (xy 199.538327 -68.314569) (xy 199.593801 -68.320672) (xy 199.647794 -68.334788)
			(xy 199.699157 -68.356615) (xy 199.746795 -68.385688) (xy 199.789691 -68.421387) (xy 199.826933 -68.462951)
			(xy 199.857727 -68.509495) (xy 199.881415 -68.560026) (xy 199.897493 -68.613468) (xy 199.905619 -68.668682)
			(xy 199.906128 -68.696586) (xy 199.905619 -68.72449) (xy 199.897493 -68.779704) (xy 199.881415 -68.833146)
			(xy 199.857727 -68.883677) (xy 199.826933 -68.930221) (xy 199.789691 -68.971785) (xy 199.746795 -69.007484)
			(xy 199.699157 -69.036557) (xy 199.647794 -69.058384) (xy 199.593801 -69.0725) (xy 199.538327 -69.078603)
			(xy 199.482556 -69.076565) (xy 199.427677 -69.066428) (xy 199.374857 -69.048409) (xy 199.325225 -69.022891)
			(xy 199.279837 -68.990419) (xy 199.23966 -68.951684) (xy 199.205552 -68.907512) (xy 199.178238 -68.858844)
			(xy 199.158302 -68.806718) (xy 199.146167 -68.752245) (xy 199.142094 -68.696586) (xy 188.976 -68.696586)
			(xy 188.976 -69.620892) (xy 205.393034 -69.620892) (xy 205.397107 -69.565233) (xy 205.409242 -69.51076)
			(xy 205.429178 -69.458634) (xy 205.456492 -69.409966) (xy 205.4906 -69.365794) (xy 205.530777 -69.327059)
			(xy 205.576165 -69.294587) (xy 205.625797 -69.269069) (xy 205.678617 -69.25105) (xy 205.733496 -69.240913)
			(xy 205.789267 -69.238875) (xy 205.844741 -69.244978) (xy 205.898734 -69.259094) (xy 205.950097 -69.280921)
			(xy 205.997735 -69.309994) (xy 206.040631 -69.345693) (xy 206.077873 -69.387257) (xy 206.108667 -69.433801)
			(xy 206.132355 -69.484332) (xy 206.148433 -69.537774) (xy 206.156559 -69.592988) (xy 206.157068 -69.620892)
			(xy 206.156559 -69.648796) (xy 206.148433 -69.70401) (xy 206.132355 -69.757452) (xy 206.108667 -69.807983)
			(xy 206.077873 -69.854527) (xy 206.040631 -69.896091) (xy 205.997735 -69.93179) (xy 205.950097 -69.960863)
			(xy 205.898734 -69.98269) (xy 205.844741 -69.996806) (xy 205.789267 -70.002909) (xy 205.733496 -70.000871)
			(xy 205.678617 -69.990734) (xy 205.625797 -69.972715) (xy 205.576165 -69.947197) (xy 205.530777 -69.914725)
			(xy 205.4906 -69.87599) (xy 205.456492 -69.831818) (xy 205.429178 -69.78315) (xy 205.409242 -69.731024)
			(xy 205.397107 -69.676551) (xy 205.393034 -69.620892) (xy 188.976 -69.620892) (xy 188.976 -71.375778)
			(xy 191.326514 -71.375778) (xy 191.330587 -71.320119) (xy 191.342722 -71.265646) (xy 191.362658 -71.21352)
			(xy 191.389972 -71.164852) (xy 191.42408 -71.12068) (xy 191.464257 -71.081945) (xy 191.509645 -71.049473)
			(xy 191.559277 -71.023955) (xy 191.612097 -71.005936) (xy 191.666976 -70.995799) (xy 191.722747 -70.993761)
			(xy 191.778221 -70.999864) (xy 191.832214 -71.01398) (xy 191.883577 -71.035807) (xy 191.931215 -71.06488)
			(xy 191.974111 -71.100579) (xy 192.011353 -71.142143) (xy 192.042147 -71.188687) (xy 192.065835 -71.239218)
			(xy 192.081913 -71.29266) (xy 192.090039 -71.347874) (xy 192.090548 -71.375778) (xy 192.090039 -71.403682)
			(xy 192.081913 -71.458896) (xy 192.065835 -71.512338) (xy 192.042147 -71.562869) (xy 192.011353 -71.609413)
			(xy 191.974111 -71.650977) (xy 191.931215 -71.686676) (xy 191.883577 -71.715749) (xy 191.832214 -71.737576)
			(xy 191.778221 -71.751692) (xy 191.722747 -71.757795) (xy 191.666976 -71.755757) (xy 191.612097 -71.74562)
			(xy 191.559277 -71.727601) (xy 191.509645 -71.702083) (xy 191.464257 -71.669611) (xy 191.42408 -71.630876)
			(xy 191.389972 -71.586704) (xy 191.362658 -71.538036) (xy 191.342722 -71.48591) (xy 191.330587 -71.431437)
			(xy 191.326514 -71.375778) (xy 188.976 -71.375778) (xy 188.976 -72.188667) (xy 192.814724 -72.188667)
			(xy 192.814724 -72.134133) (xy 192.822485 -72.080153) (xy 192.837848 -72.027827) (xy 192.860501 -71.97822)
			(xy 192.889983 -71.932341) (xy 192.925693 -71.891124) (xy 192.966906 -71.855409) (xy 193.012781 -71.825922)
			(xy 193.062386 -71.803263) (xy 193.11471 -71.787894) (xy 193.168689 -71.780127) (xy 193.195956 -71.779638)
			(xy 193.222904 -71.780114) (xy 193.276265 -71.787696) (xy 193.328031 -71.802703) (xy 193.377174 -71.824836)
			(xy 193.422718 -71.853656) (xy 193.46376 -71.888591) (xy 193.499485 -71.928947) (xy 193.529183 -71.973924)
			(xy 193.541142 -71.998078) (xy 193.546059 -72.007319) (xy 193.561778 -72.021111) (xy 193.58169 -72.027498)
			(xy 193.602499 -72.025422) (xy 193.620757 -72.015227) (xy 193.627502 -72.007222) (xy 193.64452 -71.986394)
			(xy 193.654027 -71.974707) (xy 193.666463 -71.947286) (xy 193.670357 -71.91743) (xy 193.665371 -71.887737)
			(xy 193.65194 -71.86079) (xy 193.64198 -71.849488) (xy 193.623497 -71.829203) (xy 193.591935 -71.784309)
			(xy 193.567134 -71.735355) (xy 193.549606 -71.683351) (xy 193.54419 -71.656448) (xy 193.541239 -71.642586)
			(xy 193.528673 -71.617191) (xy 193.509607 -71.596232) (xy 193.485512 -71.581324) (xy 193.458246 -71.573618)
			(xy 193.429912 -71.573708) (xy 193.416174 -71.5772) (xy 193.39043 -71.584075) (xy 193.33766 -71.591467)
			(xy 193.311018 -71.591932) (xy 193.283744 -71.59153) (xy 193.229751 -71.583769) (xy 193.177412 -71.568403)
			(xy 193.127793 -71.545745) (xy 193.081903 -71.516255) (xy 193.040678 -71.480535) (xy 193.004956 -71.439311)
			(xy 192.975464 -71.393423) (xy 192.952803 -71.343805) (xy 192.937435 -71.291467) (xy 192.929672 -71.237474)
			(xy 192.929672 -71.182926) (xy 192.937435 -71.128933) (xy 192.952803 -71.076595) (xy 192.975464 -71.026977)
			(xy 193.004956 -70.981089) (xy 193.040678 -70.939865) (xy 193.081903 -70.904145) (xy 193.127793 -70.874655)
			(xy 193.177412 -70.851997) (xy 193.229751 -70.836631) (xy 193.283744 -70.82887) (xy 193.311018 -70.828408)
			(xy 193.338854 -70.828858) (xy 193.393942 -70.836888) (xy 193.420746 -70.84441) (xy 193.43539 -70.848253)
			(xy 193.465649 -70.848098) (xy 193.494534 -70.83908) (xy 193.519507 -70.821993) (xy 193.538376 -70.798337)
			(xy 193.544444 -70.784466) (xy 193.555376 -70.758118) (xy 193.583991 -70.708771) (xy 193.619631 -70.66423)
			(xy 193.6615 -70.625489) (xy 193.708668 -70.593408) (xy 193.760085 -70.568702) (xy 193.814604 -70.551921)
			(xy 193.871014 -70.543439) (xy 193.899536 -70.542912) (xy 193.926805 -70.543391) (xy 193.980788 -70.551157)
			(xy 194.033116 -70.566525) (xy 194.082724 -70.589184) (xy 194.103206 -70.602348) (xy 197.082662 -70.602348)
			(xy 197.086735 -70.546689) (xy 197.09887 -70.492216) (xy 197.118806 -70.44009) (xy 197.14612 -70.391422)
			(xy 197.180228 -70.34725) (xy 197.220405 -70.308515) (xy 197.265793 -70.276043) (xy 197.315425 -70.250525)
			(xy 197.368245 -70.232506) (xy 197.423124 -70.222369) (xy 197.478895 -70.220331) (xy 197.534369 -70.226434)
			(xy 197.588362 -70.24055) (xy 197.639725 -70.262377) (xy 197.687363 -70.29145) (xy 197.730259 -70.327149)
			(xy 197.767501 -70.368713) (xy 197.798295 -70.415257) (xy 197.821983 -70.465788) (xy 197.838061 -70.51923)
			(xy 197.846187 -70.574444) (xy 197.846696 -70.602348) (xy 197.846187 -70.630252) (xy 197.838061 -70.685466)
			(xy 197.821983 -70.738908) (xy 197.798295 -70.789439) (xy 197.767501 -70.835983) (xy 197.730259 -70.877547)
			(xy 197.687363 -70.913246) (xy 197.659306 -70.930369) (xy 202.362808 -70.930369) (xy 202.362808 -70.875831)
			(xy 202.37057 -70.821848) (xy 202.385934 -70.769518) (xy 202.408589 -70.719908) (xy 202.438073 -70.674027)
			(xy 202.473787 -70.632808) (xy 202.515003 -70.597091) (xy 202.560882 -70.567603) (xy 202.61049 -70.544945)
			(xy 202.662818 -70.529576) (xy 202.716801 -70.521811) (xy 202.74407 -70.521322) (xy 202.770441 -70.521746)
			(xy 202.822683 -70.528991) (xy 202.873429 -70.543363) (xy 202.921712 -70.564586) (xy 202.966613 -70.592256)
			(xy 203.007275 -70.625846) (xy 203.042924 -70.664716) (xy 203.058268 -70.686168) (xy 203.066661 -70.697484)
			(xy 203.088362 -70.715431) (xy 203.114144 -70.72676) (xy 203.14204 -70.730609) (xy 203.169926 -70.726684)
			(xy 203.195676 -70.715284) (xy 203.217327 -70.697277) (xy 203.225654 -70.685914) (xy 203.240995 -70.664349)
			(xy 203.276673 -70.625263) (xy 203.317406 -70.591476) (xy 203.362413 -70.563636) (xy 203.410833 -70.542276)
			(xy 203.461738 -70.527805) (xy 203.514153 -70.520501) (xy 203.540614 -70.520052) (xy 203.567884 -70.520511)
			(xy 203.621868 -70.528275) (xy 203.674198 -70.543642) (xy 203.723808 -70.5663) (xy 203.769689 -70.595787)
			(xy 203.810906 -70.631504) (xy 203.846621 -70.672723) (xy 203.876107 -70.718605) (xy 203.898763 -70.768216)
			(xy 203.914128 -70.820546) (xy 203.915551 -70.83044) (xy 206.085946 -70.83044) (xy 206.090019 -70.774781)
			(xy 206.102154 -70.720308) (xy 206.12209 -70.668182) (xy 206.149404 -70.619514) (xy 206.183512 -70.575342)
			(xy 206.223689 -70.536607) (xy 206.269077 -70.504135) (xy 206.318709 -70.478617) (xy 206.371529 -70.460598)
			(xy 206.426408 -70.450461) (xy 206.482179 -70.448423) (xy 206.537653 -70.454526) (xy 206.591646 -70.468642)
			(xy 206.643009 -70.490469) (xy 206.690647 -70.519542) (xy 206.733543 -70.555241) (xy 206.770785 -70.596805)
			(xy 206.801579 -70.643349) (xy 206.825267 -70.69388) (xy 206.841345 -70.747322) (xy 206.849471 -70.802536)
			(xy 206.84998 -70.83044) (xy 206.849471 -70.858344) (xy 206.841345 -70.913558) (xy 206.825267 -70.967)
			(xy 206.801579 -71.017531) (xy 206.770785 -71.064075) (xy 206.733543 -71.105639) (xy 206.690647 -71.141338)
			(xy 206.643009 -71.170411) (xy 206.591646 -71.192238) (xy 206.537653 -71.206354) (xy 206.482179 -71.212457)
			(xy 206.426408 -71.210419) (xy 206.371529 -71.200282) (xy 206.318709 -71.182263) (xy 206.269077 -71.156745)
			(xy 206.223689 -71.124273) (xy 206.183512 -71.085538) (xy 206.149404 -71.041366) (xy 206.12209 -70.992698)
			(xy 206.102154 -70.940572) (xy 206.090019 -70.886099) (xy 206.085946 -70.83044) (xy 203.915551 -70.83044)
			(xy 203.92189 -70.87453) (xy 203.92189 -70.92907) (xy 203.914128 -70.983054) (xy 203.898763 -71.035384)
			(xy 203.876107 -71.084995) (xy 203.846621 -71.130877) (xy 203.810906 -71.172096) (xy 203.769689 -71.207813)
			(xy 203.723808 -71.2373) (xy 203.674198 -71.259958) (xy 203.621868 -71.275325) (xy 203.567884 -71.283089)
			(xy 203.540614 -71.283576) (xy 203.514244 -71.283122) (xy 203.462006 -71.275877) (xy 203.411262 -71.261507)
			(xy 203.36298 -71.240288) (xy 203.31808 -71.212624) (xy 203.277416 -71.17904) (xy 203.241763 -71.140178)
			(xy 203.226416 -71.11873) (xy 203.218042 -71.107399) (xy 203.196336 -71.089452) (xy 203.170551 -71.078123)
			(xy 203.142651 -71.074277) (xy 203.114762 -71.078205) (xy 203.08901 -71.089609) (xy 203.067357 -71.107619)
			(xy 203.05903 -71.118984) (xy 203.043698 -71.140556) (xy 203.008019 -71.179642) (xy 202.967284 -71.213429)
			(xy 202.922275 -71.241268) (xy 202.873854 -71.262627) (xy 202.822948 -71.277096) (xy 202.770531 -71.284398)
			(xy 202.74407 -71.284846) (xy 202.716801 -71.284389) (xy 202.662818 -71.276624) (xy 202.61049 -71.261255)
			(xy 202.560882 -71.238597) (xy 202.515003 -71.209109) (xy 202.473787 -71.173392) (xy 202.438073 -71.132173)
			(xy 202.408589 -71.086292) (xy 202.385934 -71.036682) (xy 202.37057 -70.984352) (xy 202.362808 -70.930369)
			(xy 197.659306 -70.930369) (xy 197.639725 -70.942319) (xy 197.588362 -70.964146) (xy 197.534369 -70.978262)
			(xy 197.478895 -70.984365) (xy 197.423124 -70.982327) (xy 197.368245 -70.97219) (xy 197.315425 -70.954171)
			(xy 197.265793 -70.928653) (xy 197.220405 -70.896181) (xy 197.180228 -70.857446) (xy 197.14612 -70.813274)
			(xy 197.118806 -70.764606) (xy 197.09887 -70.71248) (xy 197.086735 -70.658007) (xy 197.082662 -70.602348)
			(xy 194.103206 -70.602348) (xy 194.128604 -70.618671) (xy 194.16982 -70.654387) (xy 194.205535 -70.695604)
			(xy 194.235021 -70.741485) (xy 194.257678 -70.791094) (xy 194.273045 -70.843422) (xy 194.28081 -70.897405)
			(xy 194.281298 -70.924674) (xy 194.280817 -70.952372) (xy 194.272808 -71.007185) (xy 194.256967 -71.060267)
			(xy 194.233628 -71.110506) (xy 194.203278 -71.156848) (xy 194.185286 -71.177912) (xy 194.175456 -71.189794)
			(xy 194.162752 -71.217875) (xy 194.158993 -71.248465) (xy 194.164519 -71.278787) (xy 194.17883 -71.306084)
			(xy 194.18935 -71.317358) (xy 194.210222 -71.338939) (xy 194.245551 -71.387479) (xy 194.272839 -71.440955)
			(xy 194.291411 -71.498046) (xy 194.300131 -71.55307) (xy 197.708264 -71.55307) (xy 197.712337 -71.497411)
			(xy 197.724472 -71.442938) (xy 197.744408 -71.390812) (xy 197.771722 -71.342144) (xy 197.80583 -71.297972)
			(xy 197.846007 -71.259237) (xy 197.891395 -71.226765) (xy 197.941027 -71.201247) (xy 197.993847 -71.183228)
			(xy 198.048726 -71.173091) (xy 198.104497 -71.171053) (xy 198.159971 -71.177156) (xy 198.213964 -71.191272)
			(xy 198.265327 -71.213099) (xy 198.312965 -71.242172) (xy 198.355861 -71.277871) (xy 198.393103 -71.319435)
			(xy 198.423897 -71.365979) (xy 198.447585 -71.41651) (xy 198.463663 -71.469952) (xy 198.463747 -71.47052)
			(xy 203.917548 -71.47052) (xy 203.921621 -71.414861) (xy 203.933756 -71.360388) (xy 203.953692 -71.308262)
			(xy 203.981006 -71.259594) (xy 204.015114 -71.215422) (xy 204.055291 -71.176687) (xy 204.100679 -71.144215)
			(xy 204.150311 -71.118697) (xy 204.203131 -71.100678) (xy 204.25801 -71.090541) (xy 204.313781 -71.088503)
			(xy 204.369255 -71.094606) (xy 204.423248 -71.108722) (xy 204.474611 -71.130549) (xy 204.522249 -71.159622)
			(xy 204.565145 -71.195321) (xy 204.602387 -71.236885) (xy 204.633181 -71.283429) (xy 204.656869 -71.33396)
			(xy 204.672947 -71.387402) (xy 204.681073 -71.442616) (xy 204.681582 -71.47052) (xy 204.681073 -71.498424)
			(xy 204.672947 -71.553638) (xy 204.656869 -71.60708) (xy 204.633181 -71.657611) (xy 204.602387 -71.704155)
			(xy 204.565145 -71.745719) (xy 204.522249 -71.781418) (xy 204.474611 -71.810491) (xy 204.423248 -71.832318)
			(xy 204.369255 -71.846434) (xy 204.313781 -71.852537) (xy 204.25801 -71.850499) (xy 204.203131 -71.840362)
			(xy 204.150311 -71.822343) (xy 204.100679 -71.796825) (xy 204.055291 -71.764353) (xy 204.015114 -71.725618)
			(xy 203.981006 -71.681446) (xy 203.953692 -71.632778) (xy 203.933756 -71.580652) (xy 203.921621 -71.526179)
			(xy 203.917548 -71.47052) (xy 198.463747 -71.47052) (xy 198.471789 -71.525166) (xy 198.472298 -71.55307)
			(xy 198.471789 -71.580974) (xy 198.463663 -71.636188) (xy 198.447585 -71.68963) (xy 198.423897 -71.740161)
			(xy 198.393103 -71.786705) (xy 198.355861 -71.828269) (xy 198.312965 -71.863968) (xy 198.265327 -71.893041)
			(xy 198.213964 -71.914868) (xy 198.159971 -71.928984) (xy 198.104497 -71.935087) (xy 198.048726 -71.933049)
			(xy 197.993847 -71.922912) (xy 197.941027 -71.904893) (xy 197.891395 -71.879375) (xy 197.846007 -71.846903)
			(xy 197.80583 -71.808168) (xy 197.771722 -71.763996) (xy 197.744408 -71.715328) (xy 197.724472 -71.663202)
			(xy 197.712337 -71.608729) (xy 197.708264 -71.55307) (xy 194.300131 -71.55307) (xy 194.300808 -71.557342)
			(xy 194.301364 -71.58736) (xy 194.300905 -71.61493) (xy 194.29297 -71.669496) (xy 194.27726 -71.722351)
			(xy 194.254102 -71.772393) (xy 194.223979 -71.818578) (xy 194.206114 -71.839582) (xy 194.196528 -71.851211)
			(xy 194.184097 -71.878653) (xy 194.180216 -71.908527) (xy 194.185222 -71.938234) (xy 194.19868 -71.965187)
			(xy 194.208654 -71.976488) (xy 194.228098 -71.997881) (xy 194.260984 -72.045424) (xy 194.286329 -72.09738)
			(xy 194.303553 -72.152563) (xy 194.312263 -72.209712) (xy 194.312794 -72.238616) (xy 194.312291 -72.265884)
			(xy 194.304528 -72.319866) (xy 194.289162 -72.372193) (xy 194.266506 -72.421801) (xy 194.237021 -72.46768)
			(xy 194.201308 -72.508897) (xy 194.160093 -72.544612) (xy 194.114215 -72.574098) (xy 194.064608 -72.596756)
			(xy 194.012281 -72.612124) (xy 193.9583 -72.619889) (xy 193.931032 -72.620378) (xy 193.904428 -72.619915)
			(xy 193.851736 -72.612537) (xy 193.80058 -72.597906) (xy 193.751955 -72.576306) (xy 193.706804 -72.548156)
			(xy 193.666005 -72.514004) (xy 193.630349 -72.474511) (xy 193.615056 -72.452738) (xy 193.606387 -72.440784)
			(xy 193.583507 -72.422132) (xy 193.556253 -72.410792) (xy 193.526895 -72.407707) (xy 193.497879 -72.413137)
			(xy 193.471622 -72.426627) (xy 193.460624 -72.436482) (xy 193.439176 -72.456397) (xy 193.391309 -72.490073)
			(xy 193.33886 -72.516045) (xy 193.283061 -72.533703) (xy 193.225219 -72.542633) (xy 193.195956 -72.543162)
			(xy 193.168689 -72.542673) (xy 193.11471 -72.534906) (xy 193.062386 -72.519537) (xy 193.012781 -72.496878)
			(xy 192.966906 -72.467391) (xy 192.925693 -72.431676) (xy 192.889983 -72.390459) (xy 192.860501 -72.34458)
			(xy 192.837848 -72.294973) (xy 192.822485 -72.242647) (xy 192.814724 -72.188667) (xy 188.976 -72.188667)
			(xy 188.976 -72.853042) (xy 202.801218 -72.853042) (xy 202.805291 -72.797383) (xy 202.817426 -72.74291)
			(xy 202.837362 -72.690784) (xy 202.864676 -72.642116) (xy 202.898784 -72.597944) (xy 202.938961 -72.559209)
			(xy 202.984349 -72.526737) (xy 203.033981 -72.501219) (xy 203.086801 -72.4832) (xy 203.14168 -72.473063)
			(xy 203.197451 -72.471025) (xy 203.252925 -72.477128) (xy 203.306918 -72.491244) (xy 203.358281 -72.513071)
			(xy 203.405919 -72.542144) (xy 203.448815 -72.577843) (xy 203.486057 -72.619407) (xy 203.516851 -72.665951)
			(xy 203.540539 -72.716482) (xy 203.556617 -72.769924) (xy 203.564743 -72.825138) (xy 203.565252 -72.853042)
			(xy 203.564743 -72.880946) (xy 203.556617 -72.93616) (xy 203.540539 -72.989602) (xy 203.516851 -73.040133)
			(xy 203.486057 -73.086677) (xy 203.448815 -73.128241) (xy 203.405919 -73.16394) (xy 203.358281 -73.193013)
			(xy 203.306918 -73.21484) (xy 203.252925 -73.228956) (xy 203.197451 -73.235059) (xy 203.14168 -73.233021)
			(xy 203.086801 -73.222884) (xy 203.033981 -73.204865) (xy 202.984349 -73.179347) (xy 202.938961 -73.146875)
			(xy 202.898784 -73.10814) (xy 202.864676 -73.063968) (xy 202.837362 -73.0153) (xy 202.817426 -72.963174)
			(xy 202.805291 -72.908701) (xy 202.801218 -72.853042) (xy 188.976 -72.853042) (xy 188.976 -73.042526)
			(xy 188.976461 -73.052402) (xy 188.983907 -73.070699) (xy 188.990478 -73.078086) (xy 188.990732 -73.07834)
			(xy 189.399926 -73.487534) (xy 189.400434 -73.488042) (xy 189.407814 -73.494628) (xy 189.426113 -73.502087)
			(xy 189.435994 -73.50252)
		)
		(stroke
			(width 0)
			(type solid)
		)
		(fill yes)
		(layer "In15.Cu")
		(net "GND")
	)
	(gr_poly
		(pts
			(arc
				(start 194.446144 -441.481972)
				(mid 194.482065 -441.467093)
				(end 194.496944 -441.431172)
			)
			(arc
				(start 194.496944 -441.17006)
				(mid 194.792217 -440.457207)
				(end 195.50507 -440.161934)
			)
			(arc
				(start 276.314916 -440.161934)
				(mid 277.027769 -440.457207)
				(end 277.323042 -441.17006)
			)
			(arc
				(start 277.323042 -441.431172)
				(mid 277.337921 -441.467093)
				(end 277.373842 -441.481972)
			)
			(arc
				(start 463.300064 -441.481972)
				(mid 464.355064 -441.044976)
				(end 464.79206 -439.989976)
			)
			(arc
				(start 464.79206 -409.528264)
				(mid 464.983018 -408.568632)
				(end 465.526628 -407.75509)
			)
			(arc
				(start 467.355174 -405.926544)
				(mid 467.678507 -405.442687)
				(end 467.792054 -404.871936)
			)
			(xy 467.792054 -364.180374) (xy 467.76132 -364.14964) (xy 467.660736 -364.14964) (xy 467.284816 -364.52556)
			(arc
				(start 467.284816 -404.871936)
				(mid 467.209909 -405.248606)
				(end 466.996526 -405.567896)
			)
			(arc
				(start 465.16798 -407.396442)
				(mid 464.51433 -408.374514)
				(end 464.284568 -409.528264)
			)
			(arc
				(start 464.284568 -439.989976)
				(mid 463.996213 -440.686125)
				(end 463.300064 -440.97448)
			)
			(xy 410.91104 -440.97448)
			(arc
				(start 410.90342 -440.976766)
				(mid 410.82774 -440.99441)
				(end 410.750258 -441.000388)
			)
			(arc
				(start 410.74975 -441.000388)
				(mid 410.672265 -440.994435)
				(end 410.596588 -440.976766)
			)
			(xy 410.588968 -440.97448) (xy 406.911048 -440.97448)
			(arc
				(start 406.903428 -440.976766)
				(mid 406.827748 -440.99441)
				(end 406.750266 -441.000388)
			)
			(arc
				(start 406.749758 -441.000388)
				(mid 406.672273 -440.994435)
				(end 406.596596 -440.976766)
			)
			(xy 406.588976 -440.97448) (xy 402.911056 -440.97448)
			(arc
				(start 402.903436 -440.976766)
				(mid 402.827756 -440.99441)
				(end 402.750274 -441.000388)
			)
			(arc
				(start 402.749766 -441.000388)
				(mid 402.672281 -440.994435)
				(end 402.596604 -440.976766)
			)
			(xy 402.588984 -440.97448) (xy 398.911064 -440.97448)
			(arc
				(start 398.903444 -440.976766)
				(mid 398.827764 -440.99441)
				(end 398.750282 -441.000388)
			)
			(arc
				(start 398.749774 -441.000388)
				(mid 398.672289 -440.994435)
				(end 398.596612 -440.976766)
			)
			(xy 398.588992 -440.97448) (xy 393.91082 -440.97448)
			(arc
				(start 393.9032 -440.976766)
				(mid 393.82752 -440.99441)
				(end 393.750038 -441.000388)
			)
			(arc
				(start 393.74953 -441.000388)
				(mid 393.672045 -440.994435)
				(end 393.596368 -440.976766)
			)
			(xy 393.588748 -440.97448) (xy 389.910828 -440.97448)
			(arc
				(start 389.903208 -440.976766)
				(mid 389.827528 -440.99441)
				(end 389.750046 -441.000388)
			)
			(arc
				(start 389.749538 -441.000388)
				(mid 389.672053 -440.994435)
				(end 389.596376 -440.976766)
			)
			(xy 389.588756 -440.97448) (xy 385.910836 -440.97448)
			(arc
				(start 385.903216 -440.976766)
				(mid 385.827536 -440.99441)
				(end 385.750054 -441.000388)
			)
			(arc
				(start 385.749546 -441.000388)
				(mid 385.672061 -440.994435)
				(end 385.596384 -440.976766)
			)
			(xy 385.588764 -440.97448) (xy 381.910844 -440.97448)
			(arc
				(start 381.903224 -440.976766)
				(mid 381.827544 -440.99441)
				(end 381.750062 -441.000388)
			)
			(arc
				(start 381.749554 -441.000388)
				(mid 381.672069 -440.994435)
				(end 381.596392 -440.976766)
			)
			(xy 381.588772 -440.97448) (xy 343.810844 -440.97448)
			(arc
				(start 343.803224 -440.976766)
				(mid 343.727544 -440.99441)
				(end 343.650062 -441.000388)
			)
			(arc
				(start 343.649554 -441.000388)
				(mid 343.572069 -440.994435)
				(end 343.496392 -440.976766)
			)
			(xy 343.488772 -440.97448) (xy 339.810852 -440.97448)
			(arc
				(start 339.803232 -440.976766)
				(mid 339.727552 -440.99441)
				(end 339.65007 -441.000388)
			)
			(arc
				(start 339.649562 -441.000388)
				(mid 339.572077 -440.994435)
				(end 339.4964 -440.976766)
			)
			(xy 339.48878 -440.97448) (xy 335.81086 -440.97448)
			(arc
				(start 335.80324 -440.976766)
				(mid 335.72756 -440.99441)
				(end 335.650078 -441.000388)
			)
			(arc
				(start 335.64957 -441.000388)
				(mid 335.572085 -440.994435)
				(end 335.496408 -440.976766)
			)
			(xy 335.488788 -440.97448) (xy 331.810868 -440.97448)
			(arc
				(start 331.803248 -440.976766)
				(mid 331.727568 -440.99441)
				(end 331.650086 -441.000388)
			)
			(arc
				(start 331.649578 -441.000388)
				(mid 331.572093 -440.994435)
				(end 331.496416 -440.976766)
			)
			(xy 331.488796 -440.97448) (xy 326.810878 -440.97448)
			(arc
				(start 326.803258 -440.976766)
				(mid 326.727578 -440.99441)
				(end 326.650096 -441.000388)
			)
			(arc
				(start 326.649588 -441.000388)
				(mid 326.572103 -440.994435)
				(end 326.496426 -440.976766)
			)
			(xy 326.488806 -440.97448) (xy 322.810886 -440.97448)
			(arc
				(start 322.803266 -440.976766)
				(mid 322.727586 -440.99441)
				(end 322.650104 -441.000388)
			)
			(arc
				(start 322.649596 -441.000388)
				(mid 322.572111 -440.994435)
				(end 322.496434 -440.976766)
			)
			(xy 322.488814 -440.97448) (xy 318.810894 -440.97448)
			(arc
				(start 318.803274 -440.976766)
				(mid 318.727594 -440.99441)
				(end 318.650112 -441.000388)
			)
			(arc
				(start 318.649604 -441.000388)
				(mid 318.572119 -440.994435)
				(end 318.496442 -440.976766)
			)
			(xy 318.488822 -440.97448) (xy 314.810902 -440.97448)
			(arc
				(start 314.803282 -440.976766)
				(mid 314.727602 -440.99441)
				(end 314.65012 -441.000388)
			)
			(arc
				(start 314.649612 -441.000388)
				(mid 314.572127 -440.994435)
				(end 314.49645 -440.976766)
			)
			(xy 314.48883 -440.97448)
			(arc
				(start 277.817834 -440.97448)
				(mid 277.314992 -440.031472)
				(end 276.314916 -439.654696)
			)
			(arc
				(start 195.50507 -439.654696)
				(mid 194.504998 -440.031475)
				(end 194.002152 -440.97448)
			)
			(xy 154.911044 -440.97448)
			(arc
				(start 154.903424 -440.976766)
				(mid 154.827744 -440.99441)
				(end 154.750262 -441.000388)
			)
			(arc
				(start 154.749754 -441.000388)
				(mid 154.672269 -440.994435)
				(end 154.596592 -440.976766)
			)
			(xy 154.588972 -440.97448) (xy 150.911052 -440.97448)
			(arc
				(start 150.903432 -440.976766)
				(mid 150.827752 -440.99441)
				(end 150.75027 -441.000388)
			)
			(arc
				(start 150.749762 -441.000388)
				(mid 150.672277 -440.994435)
				(end 150.5966 -440.976766)
			)
			(xy 150.58898 -440.97448) (xy 146.91106 -440.97448)
			(arc
				(start 146.90344 -440.976766)
				(mid 146.82776 -440.99441)
				(end 146.750278 -441.000388)
			)
			(arc
				(start 146.74977 -441.000388)
				(mid 146.672285 -440.994435)
				(end 146.596608 -440.976766)
			)
			(xy 146.588988 -440.97448) (xy 142.911068 -440.97448)
			(arc
				(start 142.903448 -440.976766)
				(mid 142.827768 -440.99441)
				(end 142.750286 -441.000388)
			)
			(arc
				(start 142.749778 -441.000388)
				(mid 142.672293 -440.994435)
				(end 142.596616 -440.976766)
			)
			(xy 142.588996 -440.97448) (xy 137.910824 -440.97448)
			(arc
				(start 137.903204 -440.976766)
				(mid 137.827524 -440.99441)
				(end 137.750042 -441.000388)
			)
			(arc
				(start 137.749534 -441.000388)
				(mid 137.672049 -440.994435)
				(end 137.596372 -440.976766)
			)
			(xy 137.588752 -440.97448) (xy 133.910832 -440.97448)
			(arc
				(start 133.903212 -440.976766)
				(mid 133.827532 -440.99441)
				(end 133.75005 -441.000388)
			)
			(arc
				(start 133.749542 -441.000388)
				(mid 133.672057 -440.994435)
				(end 133.59638 -440.976766)
			)
			(xy 133.58876 -440.97448) (xy 129.91084 -440.97448)
			(arc
				(start 129.90322 -440.976766)
				(mid 129.82754 -440.99441)
				(end 129.750058 -441.000388)
			)
			(arc
				(start 129.74955 -441.000388)
				(mid 129.672065 -440.994435)
				(end 129.596388 -440.976766)
			)
			(xy 129.588768 -440.97448) (xy 125.910848 -440.97448)
			(arc
				(start 125.903228 -440.976766)
				(mid 125.827548 -440.99441)
				(end 125.750066 -441.000388)
			)
			(arc
				(start 125.749558 -441.000388)
				(mid 125.672073 -440.994435)
				(end 125.596396 -440.976766)
			)
			(xy 125.588776 -440.97448) (xy 87.811102 -440.97448)
			(arc
				(start 87.803482 -440.976766)
				(mid 87.727802 -440.99441)
				(end 87.65032 -441.000388)
			)
			(arc
				(start 87.649812 -441.000388)
				(mid 87.572327 -440.994435)
				(end 87.49665 -440.976766)
			)
			(xy 87.48903 -440.97448) (xy 83.81111 -440.97448)
			(arc
				(start 83.80349 -440.976766)
				(mid 83.72781 -440.99441)
				(end 83.650328 -441.000388)
			)
			(arc
				(start 83.64982 -441.000388)
				(mid 83.572335 -440.994435)
				(end 83.496658 -440.976766)
			)
			(xy 83.489038 -440.97448) (xy 79.811118 -440.97448)
			(arc
				(start 79.803498 -440.976766)
				(mid 79.727818 -440.99441)
				(end 79.650336 -441.000388)
			)
			(arc
				(start 79.649828 -441.000388)
				(mid 79.572343 -440.994435)
				(end 79.496666 -440.976766)
			)
			(xy 79.489046 -440.97448) (xy 75.811126 -440.97448)
			(arc
				(start 75.803506 -440.976766)
				(mid 75.727826 -440.99441)
				(end 75.650344 -441.000388)
			)
			(arc
				(start 75.649836 -441.000388)
				(mid 75.572351 -440.994435)
				(end 75.496674 -440.976766)
			)
			(xy 75.489054 -440.97448) (xy 70.810882 -440.97448)
			(arc
				(start 70.803262 -440.976766)
				(mid 70.727582 -440.99441)
				(end 70.6501 -441.000388)
			)
			(arc
				(start 70.649592 -441.000388)
				(mid 70.572107 -440.994435)
				(end 70.49643 -440.976766)
			)
			(xy 70.48881 -440.97448) (xy 66.81089 -440.97448)
			(arc
				(start 66.80327 -440.976766)
				(mid 66.72759 -440.99441)
				(end 66.650108 -441.000388)
			)
			(arc
				(start 66.6496 -441.000388)
				(mid 66.572115 -440.994435)
				(end 66.496438 -440.976766)
			)
			(xy 66.488818 -440.97448) (xy 62.810898 -440.97448)
			(arc
				(start 62.803278 -440.976766)
				(mid 62.727598 -440.99441)
				(end 62.650116 -441.000388)
			)
			(arc
				(start 62.649608 -441.000388)
				(mid 62.572123 -440.994435)
				(end 62.496446 -440.976766)
			)
			(xy 62.488826 -440.97448) (xy 58.810906 -440.97448)
			(arc
				(start 58.803286 -440.976766)
				(mid 58.727606 -440.99441)
				(end 58.650124 -441.000388)
			)
			(arc
				(start 58.649616 -441.000388)
				(mid 58.572131 -440.994435)
				(end 58.496454 -440.976766)
			)
			(xy 58.488834 -440.97448)
			(arc
				(start 8.50011 -440.97448)
				(mid 7.803871 -440.686141)
				(end 7.515352 -439.989976)
			)
			(arc
				(start 7.515352 -409.528518)
				(mid 7.285694 -408.374511)
				(end 6.63194 -407.396188)
			)
			(arc
				(start 3.303778 -404.068026)
				(mid 3.090447 -403.748703)
				(end 3.015488 -403.372066)
			)
			(arc
				(start 3.015488 -81.32826)
				(mid 2.785816 -80.174473)
				(end 2.132076 -79.196438)
			)
			(arc
				(start 1.303528 -78.36789)
				(mid 1.090411 -78.048655)
				(end 1.015492 -77.672184)
			)
			(arc
				(start 1.015492 -13.780008)
				(mid 1.303847 -13.083859)
				(end 1.999996 -12.795504)
			)
			(arc
				(start 11.102086 -12.795504)
				(mid 13.234194 -11.912198)
				(end 14.11732 -9.780016)
			)
			(arc
				(start 14.11732 -3.98907)
				(mid 14.115908 -3.977177)
				(end 14.111732 -3.965956)
			)
			(xy 14.098778 -3.94081) (xy 14.091412 -3.932174)
			(arc
				(start 14.086332 -3.928618)
				(mid 13.924474 -3.77767)
				(end 13.80236 -3.593084)
			)
			(xy 13.794232 -3.577082) (xy 13.762482 -3.56235)
			(arc
				(start 13.649198 -3.589274)
				(mid 13.62338 -3.604404)
				(end 13.61059 -3.631438)
			)
			(xy 13.610082 -3.638804)
			(arc
				(start 13.610082 -9.780016)
				(mid 12.875507 -11.553437)
				(end 11.102086 -12.288012)
			)
			(arc
				(start 1.999996 -12.288012)
				(mid 0.944996 -12.725008)
				(end 0.508 -13.780008)
			)
			(arc
				(start 0.508 -77.67193)
				(mid 0.621601 -78.242658)
				(end 0.94488 -78.726538)
			)
			(arc
				(start 1.773428 -79.555086)
				(mid 2.317047 -80.368624)
				(end 2.507996 -81.32826)
			)
			(arc
				(start 2.507996 -403.371812)
				(mid 2.621533 -403.942691)
				(end 2.944876 -404.426674)
			)
			(arc
				(start 6.273292 -407.75509)
				(mid 6.817042 -408.568731)
				(end 7.008114 -409.528518)
			)
			(arc
				(start 7.008114 -439.989976)
				(mid 7.44511 -441.044976)
				(end 8.50011 -441.481972)
			)
		)
		(stroke
			(width 0)
			(type solid)
		)
		(fill yes)
		(layer "In15.Cu")
		(net "GND")
	)
	(gr_poly
		(pts
			(xy 142.908274 -40.58158) (xy 142.919599 -40.580965) (xy 142.94003 -40.571192) (xy 142.947644 -40.562784)
			(xy 142.953232 -40.55618) (xy 142.96009 -40.548052) (xy 142.966186 -40.528494) (xy 142.955772 -40.433498)
			(xy 142.945612 -40.415718) (xy 142.936976 -40.409114) (xy 142.910528 -40.38845) (xy 142.862771 -40.34129)
			(xy 142.821631 -40.28826) (xy 142.787822 -40.230279) (xy 142.761932 -40.168356) (xy 142.744409 -40.103566)
			(xy 142.73556 -40.037035) (xy 142.735046 -40.003476) (xy 142.735598 -39.969644) (xy 142.744566 -39.902577)
			(xy 142.762354 -39.837293) (xy 142.788646 -39.774947) (xy 142.822979 -39.716641) (xy 142.864744 -39.663405)
			(xy 142.913204 -39.616182) (xy 142.940024 -39.595552) (xy 142.949166 -39.587897) (xy 142.95976 -39.566568)
			(xy 142.960344 -39.554658) (xy 142.960344 -39.473378) (xy 142.959776 -39.461462) (xy 142.94919 -39.440117)
			(xy 142.940024 -39.432484) (xy 142.913216 -39.411842) (xy 142.864769 -39.364609) (xy 142.823012 -39.311371)
			(xy 142.788681 -39.253068) (xy 142.762383 -39.190727) (xy 142.744581 -39.125451) (xy 142.73559 -39.05839)
			(xy 142.735046 -39.02456) (xy 142.735548 -38.992599) (xy 142.743559 -38.929181) (xy 142.759456 -38.867267)
			(xy 142.782988 -38.807834) (xy 142.813782 -38.751819) (xy 142.851355 -38.700104) (xy 142.895112 -38.653507)
			(xy 142.944365 -38.612762) (xy 142.998336 -38.578511) (xy 143.056175 -38.551294) (xy 143.116968 -38.531541)
			(xy 143.179758 -38.519563) (xy 143.243554 -38.51555) (xy 143.30735 -38.519563) (xy 143.37014 -38.531541)
			(xy 143.430933 -38.551294) (xy 143.488772 -38.578511) (xy 143.542743 -38.612762) (xy 143.591996 -38.653507)
			(xy 143.635753 -38.700104) (xy 143.673326 -38.751819) (xy 143.70412 -38.807834) (xy 143.727652 -38.867267)
			(xy 143.743549 -38.929181) (xy 143.75156 -38.992599) (xy 143.752062 -39.02456) (xy 143.751508 -39.058391)
			(xy 143.742536 -39.125455) (xy 143.724745 -39.190736) (xy 143.69845 -39.253079) (xy 143.664115 -39.311383)
			(xy 143.622348 -39.364615) (xy 143.573888 -39.411835) (xy 143.547084 -39.432484) (xy 143.537947 -39.440141)
			(xy 143.527366 -39.46147) (xy 143.526764 -39.473378) (xy 143.526764 -39.554658) (xy 143.52734 -39.56657)
			(xy 143.537936 -39.587901) (xy 143.547084 -39.595552) (xy 143.57389 -39.616195) (xy 143.622333 -39.663429)
			(xy 143.664085 -39.716668) (xy 143.698412 -39.774972) (xy 143.724705 -39.837312) (xy 143.742502 -39.902588)
			(xy 143.751488 -39.969647) (xy 143.752062 -40.003476) (xy 143.751525 -40.037035) (xy 143.742694 -40.103568)
			(xy 143.725183 -40.168361) (xy 143.699297 -40.230285) (xy 143.665485 -40.288264) (xy 143.624337 -40.341288)
			(xy 143.576568 -40.388434) (xy 143.550132 -40.409114) (xy 143.541496 -40.415718) (xy 143.531336 -40.433498)
			(xy 143.520922 -40.528494) (xy 143.527018 -40.548052) (xy 143.533876 -40.55618) (xy 143.539464 -40.562784)
			(xy 143.547085 -40.571172) (xy 143.567519 -40.580908) (xy 143.578834 -40.58158) (xy 143.841978 -40.58158)
			(xy 143.852041 -40.581142) (xy 143.870623 -40.573406) (xy 143.878046 -40.566594) (xy 152.443434 -32.001206)
			(xy 152.450834 -31.994364) (xy 152.469432 -31.986641) (xy 152.479502 -31.98622) (xy 159.290512 -31.98622)
			(xy 159.30227 -31.98563) (xy 159.32333 -31.975171) (xy 159.330898 -31.966154) (xy 159.351561 -31.939672)
			(xy 159.398732 -31.891851) (xy 159.451789 -31.850657) (xy 159.509807 -31.816806) (xy 159.571776 -31.790888)
			(xy 159.636618 -31.773354) (xy 159.703204 -31.764509) (xy 159.73679 -31.76397) (xy 159.767522 -31.764434)
			(xy 159.828538 -31.771841) (xy 159.888216 -31.786549) (xy 159.945686 -31.808343) (xy 160.00011 -31.836905)
			(xy 160.050695 -31.871819) (xy 160.096702 -31.912575) (xy 160.137462 -31.95858) (xy 160.172379 -32.009163)
			(xy 160.200944 -32.063585) (xy 160.222742 -32.121054) (xy 160.237453 -32.180731) (xy 160.244865 -32.241746)
			(xy 160.245298 -32.272478) (xy 160.245203 -32.285009) (xy 160.243933 -32.31004) (xy 160.242758 -32.322516)
			(xy 160.241742 -32.333946) (xy 160.249362 -32.355282) (xy 161.405824 -33.511744) (xy 161.413221 -33.518593)
			(xy 161.43182 -33.526327) (xy 161.441892 -33.52673) (xy 162.69716 -33.52673) (xy 162.708603 -33.526206)
			(xy 162.729226 -33.516287) (xy 162.736784 -33.50768) (xy 162.79368 -33.436306) (xy 162.79876 -33.413954)
			(xy 162.79622 -33.402524) (xy 162.791714 -33.381605) (xy 162.786877 -33.339085) (xy 162.786568 -33.317688)
			(xy 162.787054 -33.290437) (xy 162.79481 -33.236489) (xy 162.810165 -33.184194) (xy 162.832807 -33.134617)
			(xy 162.862273 -33.088767) (xy 162.897964 -33.047576) (xy 162.939155 -33.011885) (xy 162.985005 -32.982419)
			(xy 163.034582 -32.959777) (xy 163.086877 -32.944422) (xy 163.140825 -32.936666) (xy 163.195327 -32.936666)
			(xy 163.249275 -32.944422) (xy 163.30157 -32.959777) (xy 163.351147 -32.982419) (xy 163.396997 -33.011885)
			(xy 163.438188 -33.047576) (xy 163.473879 -33.088767) (xy 163.503345 -33.134617) (xy 163.525987 -33.184194)
			(xy 163.541342 -33.236489) (xy 163.549098 -33.290437) (xy 163.549584 -33.317688) (xy 163.549255 -33.339084)
			(xy 163.544417 -33.381601) (xy 163.539932 -33.402524) (xy 163.537392 -33.413954) (xy 163.542472 -33.436306)
			(xy 163.599368 -33.50768) (xy 163.607 -33.516194) (xy 163.627576 -33.526092) (xy 163.638992 -33.52673)
			(xy 172.225208 -33.52673) (xy 172.235277 -33.527155) (xy 172.253877 -33.534875) (xy 172.261276 -33.541716)
			(xy 175.011334 -36.291774) (xy 175.018176 -36.299173) (xy 175.025894 -36.317772) (xy 175.02632 -36.327842)
			(xy 175.02632 -36.342574) (xy 176.718722 -38.034976) (xy 176.726088 -38.041816) (xy 176.744621 -38.049558)
			(xy 176.764705 -38.049558) (xy 176.783238 -38.041816) (xy 176.790604 -38.034976) (xy 177.238914 -37.586666)
			(xy 177.245765 -37.57927) (xy 177.2535 -37.560671) (xy 177.2539 -37.550598) (xy 177.2539 -37.293042)
			(xy 177.253466 -37.282977) (xy 177.245737 -37.264387) (xy 177.238914 -37.256974) (xy 168.767506 -28.785566)
			(xy 168.760111 -28.778711) (xy 168.741512 -28.770964) (xy 168.731438 -28.77058) (xy 162.728402 -28.77058)
			(xy 162.718332 -28.770157) (xy 162.699729 -28.762441) (xy 162.692334 -28.755594) (xy 160.906206 -26.969466)
			(xy 160.898811 -26.962611) (xy 160.880212 -26.954864) (xy 160.870138 -26.95448) (xy 157.015434 -26.95448)
			(xy 157.005099 -26.954966) (xy 156.986092 -26.963089) (xy 156.978604 -26.970228) (xy 156.920438 -27.031442)
			(xy 156.913326 -27.050746) (xy 156.913834 -27.061414) (xy 156.914596 -27.08783) (xy 156.914094 -27.119791)
			(xy 156.906083 -27.183209) (xy 156.890186 -27.245123) (xy 156.866654 -27.304556) (xy 156.83586 -27.360571)
			(xy 156.798287 -27.412286) (xy 156.75453 -27.458883) (xy 156.705277 -27.499628) (xy 156.651306 -27.533879)
			(xy 156.593467 -27.561096) (xy 156.532674 -27.580849) (xy 156.469884 -27.592827) (xy 156.406088 -27.596841)
			(xy 156.342292 -27.592827) (xy 156.279502 -27.580849) (xy 156.218709 -27.561096) (xy 156.16087 -27.533879)
			(xy 156.106899 -27.499628) (xy 156.057646 -27.458883) (xy 156.013889 -27.412286) (xy 155.976316 -27.360571)
			(xy 155.945522 -27.304556) (xy 155.92199 -27.245123) (xy 155.906093 -27.183209) (xy 155.898082 -27.119791)
			(xy 155.89758 -27.08783) (xy 155.898342 -27.061414) (xy 155.89885 -27.050746) (xy 155.891738 -27.031442)
			(xy 155.833572 -26.970228) (xy 155.826094 -26.963074) (xy 155.807081 -26.954952) (xy 155.796742 -26.95448)
			(xy 152.007316 -26.95448) (xy 151.996503 -26.954921) (xy 151.976765 -26.963743) (xy 151.969216 -26.971498)
			(xy 151.911558 -27.036522) (xy 151.904954 -27.056842) (xy 151.906478 -27.067764) (xy 151.908057 -27.082444)
			(xy 151.909712 -27.111927) (xy 151.90978 -27.126692) (xy 151.909278 -27.158653) (xy 151.901267 -27.222071)
			(xy 151.88537 -27.283985) (xy 151.861838 -27.343418) (xy 151.831044 -27.399433) (xy 151.793471 -27.451148)
			(xy 151.749714 -27.497745) (xy 151.700461 -27.53849) (xy 151.64649 -27.572741) (xy 151.588651 -27.599958)
			(xy 151.527858 -27.619711) (xy 151.465068 -27.631689) (xy 151.401272 -27.635703) (xy 151.337476 -27.631689)
			(xy 151.274686 -27.619711) (xy 151.213893 -27.599958) (xy 151.156054 -27.572741) (xy 151.102083 -27.53849)
			(xy 151.05283 -27.497745) (xy 151.009073 -27.451148) (xy 150.9715 -27.399433) (xy 150.940706 -27.343418)
			(xy 150.917174 -27.283985) (xy 150.901277 -27.222071) (xy 150.893266 -27.158653) (xy 150.892764 -27.126692)
			(xy 150.892841 -27.111927) (xy 150.894492 -27.082445) (xy 150.896066 -27.067764) (xy 150.89759 -27.056842)
			(xy 150.890986 -27.036522) (xy 150.833328 -26.971498) (xy 150.825764 -26.963764) (xy 150.806035 -26.954935)
			(xy 150.795228 -26.95448) (xy 149.675342 -26.95448) (xy 149.665276 -26.954913) (xy 149.646685 -26.96264)
			(xy 149.639274 -26.969466) (xy 148.848869 -27.759871) (xy 149.703784 -27.759871) (xy 149.703784 -27.695949)
			(xy 149.711795 -27.632531) (xy 149.727692 -27.570617) (xy 149.751224 -27.511184) (xy 149.782018 -27.455169)
			(xy 149.819591 -27.403454) (xy 149.863348 -27.356857) (xy 149.912601 -27.316112) (xy 149.966572 -27.281861)
			(xy 150.024411 -27.254644) (xy 150.085204 -27.234891) (xy 150.147994 -27.222913) (xy 150.21179 -27.2189)
			(xy 150.275586 -27.222913) (xy 150.338376 -27.234891) (xy 150.399169 -27.254644) (xy 150.457008 -27.281861)
			(xy 150.510979 -27.316112) (xy 150.560232 -27.356857) (xy 150.603989 -27.403454) (xy 150.641562 -27.455169)
			(xy 150.672356 -27.511184) (xy 150.695888 -27.570617) (xy 150.711785 -27.632531) (xy 150.719796 -27.695949)
			(xy 150.720298 -27.72791) (xy 150.720207 -27.733709) (xy 152.483306 -27.733709) (xy 152.483306 -27.669787)
			(xy 152.491317 -27.606369) (xy 152.507214 -27.544455) (xy 152.530746 -27.485022) (xy 152.56154 -27.429007)
			(xy 152.599113 -27.377292) (xy 152.64287 -27.330695) (xy 152.692123 -27.28995) (xy 152.746094 -27.255699)
			(xy 152.803933 -27.228482) (xy 152.864726 -27.208729) (xy 152.927516 -27.196751) (xy 152.991312 -27.192738)
			(xy 153.055108 -27.196751) (xy 153.117898 -27.208729) (xy 153.178691 -27.228482) (xy 153.23653 -27.255699)
			(xy 153.290501 -27.28995) (xy 153.339754 -27.330695) (xy 153.383511 -27.377292) (xy 153.421084 -27.429007)
			(xy 153.451878 -27.485022) (xy 153.47541 -27.544455) (xy 153.491307 -27.606369) (xy 153.499318 -27.669787)
			(xy 153.49982 -27.701748) (xy 153.499318 -27.733709) (xy 153.491307 -27.797127) (xy 153.47541 -27.859041)
			(xy 153.451878 -27.918474) (xy 153.421084 -27.974489) (xy 153.383511 -28.026204) (xy 153.339754 -28.072801)
			(xy 153.290501 -28.113546) (xy 153.23653 -28.147797) (xy 153.178691 -28.175014) (xy 153.117898 -28.194767)
			(xy 153.055108 -28.206745) (xy 152.991312 -28.210759) (xy 152.927516 -28.206745) (xy 152.864726 -28.194767)
			(xy 152.803933 -28.175014) (xy 152.746094 -28.147797) (xy 152.692123 -28.113546) (xy 152.64287 -28.072801)
			(xy 152.599113 -28.026204) (xy 152.56154 -27.974489) (xy 152.530746 -27.918474) (xy 152.507214 -27.859041)
			(xy 152.491317 -27.797127) (xy 152.483306 -27.733709) (xy 150.720207 -27.733709) (xy 150.719796 -27.759871)
			(xy 150.711785 -27.823289) (xy 150.695888 -27.885203) (xy 150.672356 -27.944636) (xy 150.641562 -28.000651)
			(xy 150.603989 -28.052366) (xy 150.560232 -28.098963) (xy 150.510979 -28.139708) (xy 150.457008 -28.173959)
			(xy 150.399169 -28.201176) (xy 150.338376 -28.220929) (xy 150.275586 -28.232907) (xy 150.21179 -28.236921)
			(xy 150.147994 -28.232907) (xy 150.085204 -28.220929) (xy 150.024411 -28.201176) (xy 149.966572 -28.173959)
			(xy 149.912601 -28.139708) (xy 149.863348 -28.098963) (xy 149.819591 -28.052366) (xy 149.782018 -28.000651)
			(xy 149.751224 -27.944636) (xy 149.727692 -27.885203) (xy 149.711795 -27.823289) (xy 149.703784 -27.759871)
			(xy 148.848869 -27.759871) (xy 146.785076 -29.823664) (xy 146.778232 -29.831062) (xy 146.770508 -29.849661)
			(xy 146.77009 -29.859732) (xy 146.77009 -30.38856) (xy 156.316172 -30.38856) (xy 156.316674 -30.356599)
			(xy 156.324685 -30.293181) (xy 156.340582 -30.231267) (xy 156.364114 -30.171834) (xy 156.394908 -30.115819)
			(xy 156.432481 -30.064104) (xy 156.476238 -30.017507) (xy 156.525491 -29.976762) (xy 156.579462 -29.942511)
			(xy 156.637301 -29.915294) (xy 156.698094 -29.895541) (xy 156.760884 -29.883563) (xy 156.82468 -29.87955)
			(xy 156.888476 -29.883563) (xy 156.951266 -29.895541) (xy 157.012059 -29.915294) (xy 157.069898 -29.942511)
			(xy 157.123869 -29.976762) (xy 157.173122 -30.017507) (xy 157.216879 -30.064104) (xy 157.254452 -30.115819)
			(xy 157.285246 -30.171834) (xy 157.308778 -30.231267) (xy 157.324675 -30.293181) (xy 157.332686 -30.356599)
			(xy 157.333188 -30.38856) (xy 157.332658 -30.421934) (xy 157.323881 -30.488103) (xy 157.306526 -30.552555)
			(xy 157.280891 -30.614185) (xy 157.264608 -30.643322) (xy 157.257774 -30.656089) (xy 157.250832 -30.684187)
			(xy 157.252047 -30.713105) (xy 157.261322 -30.740522) (xy 157.277913 -30.764239) (xy 157.300488 -30.782352)
			(xy 157.327237 -30.793407) (xy 157.34157 -30.795468) (xy 157.372356 -30.799226) (xy 157.432758 -30.813316)
			(xy 157.490997 -30.834652) (xy 157.546206 -30.862915) (xy 157.597566 -30.897687) (xy 157.644313 -30.93845)
			(xy 157.685753 -30.984599) (xy 157.703918 -31.010606) (xy 159.717232 -31.010606) (xy 159.717687 -30.980164)
			(xy 159.724949 -30.919715) (xy 159.739383 -30.860566) (xy 159.760781 -30.803566) (xy 159.788836 -30.749531)
			(xy 159.823147 -30.699236) (xy 159.863222 -30.653401) (xy 159.908486 -30.612683) (xy 159.933132 -30.594808)
			(xy 159.942022 -30.588458) (xy 159.95269 -30.570678) (xy 159.965898 -30.475682) (xy 159.960056 -30.455616)
			(xy 159.953452 -30.447234) (xy 159.937188 -30.426723) (xy 159.909882 -30.382061) (xy 159.888931 -30.334089)
			(xy 159.874729 -30.283705) (xy 159.867542 -30.231853) (xy 159.867092 -30.20568) (xy 159.867578 -30.178429)
			(xy 159.875334 -30.124481) (xy 159.890689 -30.072186) (xy 159.913331 -30.022609) (xy 159.942797 -29.976759)
			(xy 159.978488 -29.935568) (xy 160.019679 -29.899877) (xy 160.065529 -29.870411) (xy 160.115106 -29.847769)
			(xy 160.167401 -29.832414) (xy 160.221349 -29.824658) (xy 160.275851 -29.824658) (xy 160.329799 -29.832414)
			(xy 160.382094 -29.847769) (xy 160.431671 -29.870411) (xy 160.477521 -29.899877) (xy 160.518712 -29.935568)
			(xy 160.554403 -29.976759) (xy 160.583869 -30.022609) (xy 160.606511 -30.072186) (xy 160.621866 -30.124481)
			(xy 160.629622 -30.178429) (xy 160.630108 -30.20568) (xy 160.629609 -30.234028) (xy 160.621241 -30.290104)
			(xy 160.60467 -30.344324) (xy 160.580262 -30.395498) (xy 160.548553 -30.442498) (xy 160.529778 -30.463744)
			(xy 160.522412 -30.471618) (xy 160.515554 -30.49143) (xy 160.523174 -30.586934) (xy 160.53308 -30.605222)
			(xy 160.541462 -30.61208) (xy 160.566819 -30.632782) (xy 160.612499 -30.679671) (xy 160.651781 -30.732036)
			(xy 160.684016 -30.78901) (xy 160.708671 -30.849651) (xy 160.725338 -30.912955) (xy 160.73374 -30.977875)
			(xy 160.734248 -31.010606) (xy 160.733746 -31.042567) (xy 160.725735 -31.105985) (xy 160.709838 -31.167899)
			(xy 160.686306 -31.227332) (xy 160.655512 -31.283347) (xy 160.617939 -31.335062) (xy 160.574182 -31.381659)
			(xy 160.524929 -31.422404) (xy 160.470958 -31.456655) (xy 160.413119 -31.483872) (xy 160.352326 -31.503625)
			(xy 160.289536 -31.515603) (xy 160.22574 -31.519617) (xy 160.161944 -31.515603) (xy 160.099154 -31.503625)
			(xy 160.038361 -31.483872) (xy 159.980522 -31.456655) (xy 159.926551 -31.422404) (xy 159.877298 -31.381659)
			(xy 159.833541 -31.335062) (xy 159.795968 -31.283347) (xy 159.765174 -31.227332) (xy 159.741642 -31.167899)
			(xy 159.725745 -31.105985) (xy 159.717734 -31.042567) (xy 159.717232 -31.010606) (xy 157.703918 -31.010606)
			(xy 157.721268 -31.035447) (xy 157.750333 -31.090239) (xy 157.772513 -31.148161) (xy 157.787481 -31.208352)
			(xy 157.795013 -31.269916) (xy 157.795468 -31.300928) (xy 157.794966 -31.332889) (xy 157.786955 -31.396307)
			(xy 157.771058 -31.458221) (xy 157.747526 -31.517654) (xy 157.716732 -31.573669) (xy 157.679159 -31.625384)
			(xy 157.635402 -31.671981) (xy 157.586149 -31.712726) (xy 157.532178 -31.746977) (xy 157.474339 -31.774194)
			(xy 157.413546 -31.793947) (xy 157.350756 -31.805925) (xy 157.28696 -31.809939) (xy 157.223164 -31.805925)
			(xy 157.160374 -31.793947) (xy 157.099581 -31.774194) (xy 157.041742 -31.746977) (xy 156.987771 -31.712726)
			(xy 156.938518 -31.671981) (xy 156.894761 -31.625384) (xy 156.857188 -31.573669) (xy 156.826394 -31.517654)
			(xy 156.802862 -31.458221) (xy 156.786965 -31.396307) (xy 156.778954 -31.332889) (xy 156.778452 -31.300928)
			(xy 156.779016 -31.267555) (xy 156.787782 -31.201387) (xy 156.805127 -31.136935) (xy 156.830753 -31.075304)
			(xy 156.847032 -31.046166) (xy 156.853925 -31.033426) (xy 156.860873 -31.005316) (xy 156.859657 -30.976385)
			(xy 156.850374 -30.948957) (xy 156.833769 -30.925234) (xy 156.811177 -30.907121) (xy 156.784411 -30.896074)
			(xy 156.77007 -30.89402) (xy 156.73929 -30.890225) (xy 156.678893 -30.876132) (xy 156.620659 -30.854795)
			(xy 156.565454 -30.826532) (xy 156.514098 -30.791762) (xy 156.467354 -30.751002) (xy 156.425916 -30.704858)
			(xy 156.390399 -30.654015) (xy 156.361333 -30.599229) (xy 156.339147 -30.541313) (xy 156.324173 -30.481129)
			(xy 156.316632 -30.41957) (xy 156.316172 -30.38856) (xy 146.77009 -30.38856) (xy 146.77009 -31.772098)
			(xy 146.77263 -31.783274) (xy 146.775424 -31.788608) (xy 146.78795 -31.815072) (xy 146.805624 -31.870888)
			(xy 146.814542 -31.928752) (xy 146.815048 -31.958026) (xy 146.814481 -31.987294) (xy 146.805542 -32.045145)
			(xy 146.787891 -32.100957) (xy 146.775424 -32.127444) (xy 146.77263 -32.132778) (xy 146.77009 -32.143954)
			(xy 146.77009 -32.184848) (xy 146.769658 -32.194914) (xy 146.76193 -32.213505) (xy 146.755104 -32.220916)
			(xy 145.179796 -33.796224) (xy 146.934682 -33.796224) (xy 146.935122 -33.765157) (xy 146.942695 -33.703487)
			(xy 146.957731 -33.643201) (xy 146.980006 -33.585198) (xy 147.009186 -33.530343) (xy 147.02663 -33.504632)
			(xy 147.032186 -33.49581) (xy 147.036411 -33.475418) (xy 147.0322 -33.455023) (xy 147.02663 -33.446212)
			(xy 147.00919 -33.4205) (xy 146.980021 -33.365641) (xy 146.957755 -33.307638) (xy 146.942723 -33.247353)
			(xy 146.935149 -33.185685) (xy 146.934682 -33.15462) (xy 146.935156 -33.123889) (xy 146.942563 -33.062874)
			(xy 146.957269 -33.003197) (xy 146.979062 -32.945728) (xy 147.007624 -32.891304) (xy 147.042537 -32.84072)
			(xy 147.083293 -32.794714) (xy 147.129297 -32.753955) (xy 147.179879 -32.719039) (xy 147.2343 -32.690475)
			(xy 147.291768 -32.668678) (xy 147.351444 -32.653968) (xy 147.412459 -32.646558) (xy 147.44319 -32.646112)
			(xy 147.473405 -32.646551) (xy 147.533408 -32.653737) (xy 147.592135 -32.667986) (xy 147.648759 -32.689097)
			(xy 147.702482 -32.716772) (xy 147.752544 -32.75062) (xy 147.775676 -32.770064) (xy 147.782815 -32.775687)
			(xy 147.799868 -32.781931) (xy 147.80895 -32.782256) (xy 147.83943 -32.782256) (xy 147.848512 -32.781934)
			(xy 147.865563 -32.775685) (xy 147.872704 -32.770064) (xy 147.895846 -32.750633) (xy 147.945911 -32.716793)
			(xy 147.999632 -32.689123) (xy 148.056253 -32.668012) (xy 148.114977 -32.653759) (xy 148.174976 -32.646563)
			(xy 148.20519 -32.646112) (xy 148.235923 -32.646547) (xy 148.29694 -32.653955) (xy 148.356619 -32.668664)
			(xy 148.414091 -32.69046) (xy 148.468515 -32.719024) (xy 148.5191 -32.75394) (xy 148.565107 -32.7947)
			(xy 148.605866 -32.840708) (xy 148.640781 -32.891293) (xy 148.669345 -32.945719) (xy 148.691139 -33.00319)
			(xy 148.705847 -33.06287) (xy 148.713254 -33.123887) (xy 148.713698 -33.15462) (xy 148.713233 -33.185686)
			(xy 148.705666 -33.247355) (xy 148.690636 -33.307641) (xy 148.668367 -33.365645) (xy 148.639191 -33.4205)
			(xy 148.62175 -33.446212) (xy 148.616158 -33.455014) (xy 148.611947 -33.475418) (xy 148.616172 -33.49582)
			(xy 148.62175 -33.504632) (xy 148.639207 -33.530333) (xy 148.668373 -33.585195) (xy 148.690636 -33.643201)
			(xy 148.705664 -33.703488) (xy 148.713233 -33.765158) (xy 148.713698 -33.796224) (xy 148.713266 -33.826956)
			(xy 148.705855 -33.887971) (xy 148.691143 -33.947648) (xy 148.669346 -34.005117) (xy 148.64078 -34.05954)
			(xy 148.605862 -34.110122) (xy 148.565103 -34.156127) (xy 148.519095 -34.196883) (xy 148.46851 -34.231797)
			(xy 148.414086 -34.260359) (xy 148.356616 -34.282153) (xy 148.296938 -34.296861) (xy 148.235922 -34.304269)
			(xy 148.20519 -34.304732) (xy 148.174974 -34.304319) (xy 148.11497 -34.297129) (xy 148.056241 -34.282876)
			(xy 147.999617 -34.261761) (xy 147.945896 -34.234081) (xy 147.895835 -34.200227) (xy 147.872704 -34.18078)
			(xy 147.865567 -34.175154) (xy 147.848513 -34.168911) (xy 147.83943 -34.168588) (xy 147.80895 -34.168588)
			(xy 147.799868 -34.168912) (xy 147.782818 -34.175161) (xy 147.775676 -34.18078) (xy 147.752535 -34.200212)
			(xy 147.70247 -34.234053) (xy 147.648749 -34.261724) (xy 147.592128 -34.282835) (xy 147.533403 -34.297088)
			(xy 147.473404 -34.304282) (xy 147.44319 -34.304732) (xy 147.41246 -34.304253) (xy 147.351447 -34.296844)
			(xy 147.291773 -34.282135) (xy 147.234306 -34.260341) (xy 147.179886 -34.231779) (xy 147.129304 -34.196865)
			(xy 147.0833 -34.15611) (xy 147.042543 -34.110107) (xy 147.007629 -34.059526) (xy 146.979065 -34.005106)
			(xy 146.957269 -33.947641) (xy 146.942558 -33.887966) (xy 146.935147 -33.826954) (xy 146.934682 -33.796224)
			(xy 145.179796 -33.796224) (xy 141.487906 -37.488114) (xy 141.481061 -37.495513) (xy 141.473331 -37.514111)
			(xy 141.47292 -37.524182) (xy 141.47292 -37.786521) (xy 142.735548 -37.786521) (xy 142.735548 -37.722599)
			(xy 142.743559 -37.659181) (xy 142.759456 -37.597267) (xy 142.782988 -37.537834) (xy 142.813782 -37.481819)
			(xy 142.851355 -37.430104) (xy 142.895112 -37.383507) (xy 142.944365 -37.342762) (xy 142.998336 -37.308511)
			(xy 143.056175 -37.281294) (xy 143.116968 -37.261541) (xy 143.179758 -37.249563) (xy 143.243554 -37.24555)
			(xy 143.30735 -37.249563) (xy 143.37014 -37.261541) (xy 143.430933 -37.281294) (xy 143.488772 -37.308511)
			(xy 143.542743 -37.342762) (xy 143.591996 -37.383507) (xy 143.635753 -37.430104) (xy 143.673326 -37.481819)
			(xy 143.70412 -37.537834) (xy 143.727652 -37.597267) (xy 143.743549 -37.659181) (xy 143.75156 -37.722599)
			(xy 143.752062 -37.75456) (xy 143.75156 -37.786521) (xy 143.743549 -37.849939) (xy 143.729821 -37.903404)
			(xy 144.00987 -37.903404) (xy 144.013941 -37.847782) (xy 144.026067 -37.793345) (xy 144.04599 -37.741254)
			(xy 144.073286 -37.692619) (xy 144.107372 -37.648476) (xy 144.147521 -37.609767) (xy 144.192879 -37.577316)
			(xy 144.242479 -37.551815) (xy 144.295263 -37.533808) (xy 144.350106 -37.523678) (xy 144.40584 -37.521641)
			(xy 144.461277 -37.527741) (xy 144.515234 -37.541847) (xy 144.566563 -37.563659) (xy 144.614169 -37.592713)
			(xy 144.657037 -37.628388) (xy 144.694254 -37.669925) (xy 144.725027 -37.716438) (xy 144.748699 -37.766935)
			(xy 144.764767 -37.820342) (xy 144.772887 -37.875518) (xy 144.773396 -37.903404) (xy 144.772887 -37.93129)
			(xy 144.764767 -37.986466) (xy 144.748699 -38.039873) (xy 144.725027 -38.09037) (xy 144.694254 -38.136883)
			(xy 144.657037 -38.17842) (xy 144.614169 -38.214095) (xy 144.566563 -38.243149) (xy 144.515234 -38.264961)
			(xy 144.461277 -38.279067) (xy 144.40584 -38.285167) (xy 144.350106 -38.28313) (xy 144.295263 -38.273)
			(xy 144.242479 -38.254993) (xy 144.192879 -38.229492) (xy 144.147521 -38.197041) (xy 144.107372 -38.158332)
			(xy 144.073286 -38.114189) (xy 144.04599 -38.065554) (xy 144.026067 -38.013463) (xy 144.013941 -37.959026)
			(xy 144.00987 -37.903404) (xy 143.729821 -37.903404) (xy 143.727652 -37.911853) (xy 143.70412 -37.971286)
			(xy 143.673326 -38.027301) (xy 143.635753 -38.079016) (xy 143.591996 -38.125613) (xy 143.542743 -38.166358)
			(xy 143.488772 -38.200609) (xy 143.430933 -38.227826) (xy 143.37014 -38.247579) (xy 143.30735 -38.259557)
			(xy 143.243554 -38.263571) (xy 143.179758 -38.259557) (xy 143.116968 -38.247579) (xy 143.056175 -38.227826)
			(xy 142.998336 -38.200609) (xy 142.944365 -38.166358) (xy 142.895112 -38.125613) (xy 142.851355 -38.079016)
			(xy 142.813782 -38.027301) (xy 142.782988 -37.971286) (xy 142.759456 -37.911853) (xy 142.743559 -37.849939)
			(xy 142.735548 -37.786521) (xy 141.47292 -37.786521) (xy 141.47292 -38.392354) (xy 141.495272 -38.42004)
			(xy 141.512798 -38.424104) (xy 141.539204 -38.430466) (xy 141.590017 -38.449656) (xy 141.637594 -38.475859)
			(xy 141.680974 -38.508545) (xy 141.719279 -38.547053) (xy 141.751735 -38.590605) (xy 141.777685 -38.63832)
			(xy 141.796606 -38.689233) (xy 141.808114 -38.742315) (xy 141.811977 -38.796493) (xy 141.808116 -38.850671)
			(xy 141.79661 -38.903754) (xy 141.777691 -38.954668) (xy 141.751742 -39.002384) (xy 141.719288 -39.045937)
			(xy 141.680984 -39.084446) (xy 141.637606 -39.117134) (xy 141.590029 -39.143338) (xy 141.539218 -39.16253)
			(xy 141.512798 -39.168832) (xy 141.495272 -39.172896) (xy 141.47292 -39.200582) (xy 141.47292 -40.146478)
			(xy 141.473358 -40.156541) (xy 141.481094 -40.175123) (xy 141.487906 -40.182546) (xy 141.871954 -40.566594)
			(xy 141.879355 -40.573433) (xy 141.897953 -40.581148) (xy 141.908022 -40.58158)
		)
		(stroke
			(width 0)
			(type solid)
		)
		(fill yes)
		(layer "In15.Cu")
		(net "P5V_AUX")
	)
	(gr_poly
		(pts
			(xy 180.80228 -409.133548) (xy 180.812703 -409.133042) (xy 180.831844 -409.124781) (xy 180.839364 -409.117546)
			(xy 180.897276 -409.05557) (xy 180.904388 -409.035758) (xy 180.903626 -409.02509) (xy 180.902864 -408.99969)
			(xy 180.90335 -408.972439) (xy 180.911106 -408.918491) (xy 180.926461 -408.866196) (xy 180.949103 -408.816619)
			(xy 180.978569 -408.770769) (xy 181.01426 -408.729578) (xy 181.055451 -408.693887) (xy 181.101301 -408.664421)
			(xy 181.150878 -408.641779) (xy 181.203173 -408.626424) (xy 181.257121 -408.618668) (xy 181.311623 -408.618668)
			(xy 181.365571 -408.626424) (xy 181.417866 -408.641779) (xy 181.467443 -408.664421) (xy 181.513293 -408.693887)
			(xy 181.554484 -408.729578) (xy 181.590175 -408.770769) (xy 181.619641 -408.816619) (xy 181.642283 -408.866196)
			(xy 181.657638 -408.918491) (xy 181.665394 -408.972439) (xy 181.66588 -408.99969) (xy 181.665118 -409.02509)
			(xy 181.664356 -409.035758) (xy 181.671468 -409.05557) (xy 181.72938 -409.117546) (xy 181.736879 -409.124814)
			(xy 181.756032 -409.133085) (xy 181.766464 -409.133548) (xy 182.47106 -409.133548) (xy 182.479611 -409.133228)
			(xy 182.495764 -409.127614) (xy 182.50917 -409.116996) (xy 182.513986 -409.109926) (xy 182.566818 -409.025852)
			(xy 182.568342 -409.000198) (xy 182.562754 -408.98826) (xy 182.550978 -408.962436) (xy 182.534342 -408.908173)
			(xy 182.525926 -408.852046) (xy 182.525416 -408.823668) (xy 182.52565 -408.805649) (xy 182.529085 -408.769776)
			(xy 182.532274 -408.75204) (xy 182.53456 -408.73934) (xy 182.52694 -408.714956) (xy 182.446168 -408.637994)
			(xy 182.421784 -408.631136) (xy 182.40883 -408.634184) (xy 182.387121 -408.639051) (xy 182.342937 -408.644275)
			(xy 182.320692 -408.644598) (xy 182.293442 -408.644111) (xy 182.239496 -408.636354) (xy 182.187204 -408.620998)
			(xy 182.137629 -408.598357) (xy 182.09178 -408.568891) (xy 182.050592 -408.533201) (xy 182.014903 -408.492012)
			(xy 181.985438 -408.446162) (xy 181.962798 -408.396587) (xy 181.947444 -408.344294) (xy 181.939688 -408.290348)
			(xy 181.939688 -408.235848) (xy 181.947445 -408.181902) (xy 181.962799 -408.129609) (xy 181.98544 -408.080034)
			(xy 182.014905 -408.034185) (xy 182.050595 -407.992997) (xy 182.091784 -407.957306) (xy 182.137632 -407.927841)
			(xy 182.187207 -407.9052) (xy 182.2395 -407.889845) (xy 182.293446 -407.882089) (xy 182.347946 -407.882088)
			(xy 182.401892 -407.889844) (xy 182.454185 -407.905197) (xy 182.503761 -407.927837) (xy 182.54961 -407.957301)
			(xy 182.590799 -407.992991) (xy 182.62649 -408.034179) (xy 182.655956 -408.080027) (xy 182.678598 -408.129602)
			(xy 182.693953 -408.181894) (xy 182.701711 -408.23584) (xy 182.7022 -408.26309) (xy 182.701968 -408.281109)
			(xy 182.698537 -408.316983) (xy 182.695342 -408.334718) (xy 182.693056 -408.347418) (xy 182.700676 -408.371802)
			(xy 182.781448 -408.448764) (xy 182.805832 -408.455622) (xy 182.818786 -408.452574) (xy 182.840495 -408.447707)
			(xy 182.884679 -408.442485) (xy 182.906924 -408.44216) (xy 182.934175 -408.442647) (xy 182.988122 -408.450407)
			(xy 183.040416 -408.465763) (xy 183.089992 -408.488405) (xy 183.135841 -408.517872) (xy 183.177031 -408.553563)
			(xy 183.212723 -408.594752) (xy 183.242191 -408.640601) (xy 183.264834 -408.690177) (xy 183.280192 -408.74247)
			(xy 183.287952 -408.796417) (xy 183.288432 -408.823668) (xy 183.28767 -408.845766) (xy 183.286908 -408.859482)
			(xy 183.299354 -408.883866) (xy 183.396382 -408.946858) (xy 183.42356 -408.948382) (xy 183.435752 -408.942032)
			(xy 183.462924 -408.92867) (xy 183.520445 -408.909763) (xy 183.58023 -408.900182) (xy 183.610504 -408.899614)
			(xy 183.636614 -408.900035) (xy 183.688347 -408.907142) (xy 183.738628 -408.921238) (xy 183.786517 -408.942059)
			(xy 183.83112 -408.969215) (xy 183.871603 -409.002199) (xy 183.90721 -409.040396) (xy 183.937276 -409.083092)
			(xy 183.949594 -409.106116) (xy 183.956198 -409.118816) (xy 183.980074 -409.133548) (xy 184.018174 -409.133548)
			(xy 184.028237 -409.13311) (xy 184.046817 -409.125371) (xy 184.054242 -409.118562) (xy 184.214008 -408.958796)
			(xy 184.220853 -408.951397) (xy 184.228585 -408.932799) (xy 184.228994 -408.922728) (xy 184.228994 -408.203908)
			(xy 184.22909 -408.19889) (xy 184.231017 -408.189041) (xy 184.232804 -408.18435) (xy 184.24017 -408.167078)
			(xy 184.241967 -408.162391) (xy 184.243882 -408.152539) (xy 184.24398 -408.14752) (xy 184.24398 -406.498044)
			(xy 184.243914 -406.494036) (xy 184.242642 -406.486121) (xy 184.24144 -406.482296) (xy 184.234328 -406.460452)
			(xy 184.230264 -406.454356) (xy 184.214211 -406.430277) (xy 184.188783 -406.378293) (xy 184.171499 -406.323066)
			(xy 184.162755 -406.265861) (xy 184.162751 -406.207992) (xy 184.171487 -406.150786) (xy 184.188764 -406.095555)
			(xy 184.214184 -406.043568) (xy 184.230264 -406.019508) (xy 184.234328 -406.013412) (xy 184.24144 -405.991568)
			(xy 184.242598 -405.987733) (xy 184.243869 -405.979825) (xy 184.24398 -405.97582) (xy 184.24398 -405.544528)
			(xy 184.243528 -405.534389) (xy 184.235679 -405.515689) (xy 184.221225 -405.501464) (xy 184.211976 -405.497284)
			(xy 184.109868 -405.456644) (xy 184.079388 -405.463248) (xy 184.06872 -405.474678) (xy 184.05063 -405.493107)
			(xy 184.010346 -405.525416) (xy 183.966072 -405.551997) (xy 183.918618 -405.572364) (xy 183.868851 -405.586147)
			(xy 183.81768 -405.593092) (xy 183.79186 -405.59355) (xy 183.764608 -405.593061) (xy 183.710658 -405.585299)
			(xy 183.658363 -405.569939) (xy 183.608785 -405.547293) (xy 183.562935 -405.517823) (xy 183.521745 -405.482127)
			(xy 183.486053 -405.440933) (xy 183.456588 -405.39508) (xy 183.433947 -405.3455) (xy 183.418592 -405.293203)
			(xy 183.410836 -405.239252) (xy 183.410836 -405.184748) (xy 183.418592 -405.130797) (xy 183.433947 -405.0785)
			(xy 183.456588 -405.02892) (xy 183.486053 -404.983067) (xy 183.521745 -404.941873) (xy 183.562935 -404.906177)
			(xy 183.608785 -404.876707) (xy 183.658363 -404.854061) (xy 183.710658 -404.838701) (xy 183.764608 -404.830939)
			(xy 183.79186 -404.830534) (xy 183.81768 -404.830964) (xy 183.868848 -404.83793) (xy 183.918611 -404.851725)
			(xy 183.966061 -404.8721) (xy 184.010334 -404.898681) (xy 184.050622 -404.930985) (xy 184.06872 -404.949406)
			(xy 184.079388 -404.960836) (xy 184.109868 -404.96744) (xy 184.211976 -404.9268) (xy 184.221242 -404.922643)
			(xy 184.235722 -404.908426) (xy 184.243547 -404.889703) (xy 184.24398 -404.879556) (xy 184.24398 -402.326348)
			(xy 184.243568 -402.316322) (xy 184.235906 -402.297792) (xy 184.221731 -402.28361) (xy 184.203206 -402.275937)
			(xy 184.19318 -402.275548) (xy 182.65521 -402.275548) (xy 182.627238 -402.27505) (xy 182.571979 -402.266335)
			(xy 182.518767 -402.249072) (xy 182.468916 -402.223686) (xy 182.423657 -402.190805) (xy 182.403496 -402.171408)
			(xy 181.748684 -401.516596) (xy 181.729308 -401.49642) (xy 181.696453 -401.45115) (xy 181.671079 -401.401301)
			(xy 181.653809 -401.348098) (xy 181.645068 -401.29285) (xy 181.644544 -401.264882) (xy 181.644544 -400.312382)
			(xy 181.645044 -400.284411) (xy 181.653763 -400.229154) (xy 181.671029 -400.175944) (xy 181.696417 -400.126096)
			(xy 181.729299 -400.08084) (xy 181.748684 -400.060668) (xy 182.12689 -399.682462) (xy 182.133696 -399.675115)
			(xy 182.141416 -399.656653) (xy 182.141876 -399.646648) (xy 182.141876 -396.259304) (xy 182.141339 -396.249317)
			(xy 182.133624 -396.230886) (xy 182.12689 -396.22349) (xy 181.938168 -396.034768) (xy 181.931056 -396.027402)
			(xy 181.91226 -396.019782) (xy 180.480462 -396.019782) (xy 180.470477 -396.020326) (xy 180.452053 -396.028047)
			(xy 180.444648 -396.034768) (xy 180.421534 -396.057628) (xy 180.403183 -396.075388) (xy 180.362392 -396.106112)
			(xy 180.340254 -396.118842) (xy 180.332221 -396.1238) (xy 180.320108 -396.138259) (xy 180.316632 -396.147036)
			(xy 180.306726 -396.176754) (xy 180.304014 -396.185834) (xy 180.304805 -396.204755) (xy 180.30825 -396.213584)
			(xy 180.318425 -396.237867) (xy 180.332768 -396.288527) (xy 180.340029 -396.340675) (xy 180.340508 -396.367)
			(xy 180.340022 -396.394251) (xy 180.332266 -396.448199) (xy 180.316911 -396.500494) (xy 180.294269 -396.550071)
			(xy 180.264803 -396.595921) (xy 180.229112 -396.637112) (xy 180.187921 -396.672803) (xy 180.142071 -396.702269)
			(xy 180.092494 -396.724911) (xy 180.040199 -396.740266) (xy 179.986251 -396.748022) (xy 179.931749 -396.748022)
			(xy 179.877801 -396.740266) (xy 179.825506 -396.724911) (xy 179.775929 -396.702269) (xy 179.730079 -396.672803)
			(xy 179.688888 -396.637112) (xy 179.653197 -396.595921) (xy 179.623731 -396.550071) (xy 179.601089 -396.500494)
			(xy 179.585734 -396.448199) (xy 179.577978 -396.394251) (xy 179.577492 -396.367) (xy 179.578213 -396.33271)
			(xy 179.590479 -396.265236) (xy 179.601876 -396.232888) (xy 179.605178 -396.224252) (xy 179.605178 -396.215108)
			(xy 179.604759 -396.205087) (xy 179.59709 -396.186572) (xy 179.582917 -396.172402) (xy 179.564399 -396.164738)
			(xy 179.554378 -396.164308) (xy 179.552854 -396.164308) (xy 179.542821 -396.164745) (xy 179.524245 -396.172318)
			(xy 179.516786 -396.17904) (xy 177.44821 -398.24787) (xy 177.440844 -398.262856) (xy 177.439828 -398.271492)
			(xy 177.435983 -398.298638) (xy 177.421519 -398.351522) (xy 177.400081 -398.400778) (xy 179.702458 -398.400778)
			(xy 179.706529 -398.345156) (xy 179.718655 -398.290719) (xy 179.738578 -398.238628) (xy 179.765874 -398.189993)
			(xy 179.79996 -398.14585) (xy 179.840109 -398.107141) (xy 179.885467 -398.07469) (xy 179.935067 -398.049189)
			(xy 179.987851 -398.031182) (xy 180.042694 -398.021052) (xy 180.098428 -398.019015) (xy 180.153865 -398.025115)
			(xy 180.207822 -398.039221) (xy 180.259151 -398.061033) (xy 180.306757 -398.090087) (xy 180.349625 -398.125762)
			(xy 180.386842 -398.167299) (xy 180.417615 -398.213812) (xy 180.441287 -398.264309) (xy 180.457355 -398.317716)
			(xy 180.465475 -398.372892) (xy 180.465984 -398.400778) (xy 180.465475 -398.428664) (xy 180.457355 -398.48384)
			(xy 180.441287 -398.537247) (xy 180.417615 -398.587744) (xy 180.386842 -398.634257) (xy 180.349625 -398.675794)
			(xy 180.306757 -398.711469) (xy 180.259151 -398.740523) (xy 180.207822 -398.762335) (xy 180.153865 -398.776441)
			(xy 180.098428 -398.782541) (xy 180.042694 -398.780504) (xy 179.987851 -398.770374) (xy 179.935067 -398.752367)
			(xy 179.885467 -398.726866) (xy 179.840109 -398.694415) (xy 179.79996 -398.655706) (xy 179.765874 -398.611563)
			(xy 179.738578 -398.562928) (xy 179.718655 -398.510837) (xy 179.706529 -398.4564) (xy 179.702458 -398.400778)
			(xy 177.400081 -398.400778) (xy 177.399639 -398.401793) (xy 177.370791 -398.448416) (xy 177.33557 -398.490433)
			(xy 177.2947 -398.526979) (xy 177.249022 -398.557301) (xy 177.224436 -398.569434) (xy 177.210974 -398.576038)
			(xy 177.19548 -398.600676) (xy 177.19548 -399.420842) (xy 179.602382 -399.420842) (xy 179.606453 -399.36522)
			(xy 179.618579 -399.310783) (xy 179.638502 -399.258692) (xy 179.665798 -399.210057) (xy 179.699884 -399.165914)
			(xy 179.740033 -399.127205) (xy 179.785391 -399.094754) (xy 179.834991 -399.069253) (xy 179.887775 -399.051246)
			(xy 179.942618 -399.041116) (xy 179.998352 -399.039079) (xy 180.053789 -399.045179) (xy 180.107746 -399.059285)
			(xy 180.159075 -399.081097) (xy 180.195524 -399.103342) (xy 181.202582 -399.103342) (xy 181.206653 -399.04772)
			(xy 181.218779 -398.993283) (xy 181.238702 -398.941192) (xy 181.265998 -398.892557) (xy 181.300084 -398.848414)
			(xy 181.340233 -398.809705) (xy 181.385591 -398.777254) (xy 181.435191 -398.751753) (xy 181.487975 -398.733746)
			(xy 181.542818 -398.723616) (xy 181.598552 -398.721579) (xy 181.653989 -398.727679) (xy 181.707946 -398.741785)
			(xy 181.759275 -398.763597) (xy 181.806881 -398.792651) (xy 181.849749 -398.828326) (xy 181.886966 -398.869863)
			(xy 181.917739 -398.916376) (xy 181.941411 -398.966873) (xy 181.957479 -399.02028) (xy 181.965599 -399.075456)
			(xy 181.966108 -399.103342) (xy 181.965599 -399.131228) (xy 181.957479 -399.186404) (xy 181.941411 -399.239811)
			(xy 181.917739 -399.290308) (xy 181.886966 -399.336821) (xy 181.849749 -399.378358) (xy 181.806881 -399.414033)
			(xy 181.759275 -399.443087) (xy 181.707946 -399.464899) (xy 181.653989 -399.479005) (xy 181.598552 -399.485105)
			(xy 181.542818 -399.483068) (xy 181.487975 -399.472938) (xy 181.435191 -399.454931) (xy 181.385591 -399.42943)
			(xy 181.340233 -399.396979) (xy 181.300084 -399.35827) (xy 181.265998 -399.314127) (xy 181.238702 -399.265492)
			(xy 181.218779 -399.213401) (xy 181.206653 -399.158964) (xy 181.202582 -399.103342) (xy 180.195524 -399.103342)
			(xy 180.206681 -399.110151) (xy 180.249549 -399.145826) (xy 180.286766 -399.187363) (xy 180.317539 -399.233876)
			(xy 180.341211 -399.284373) (xy 180.357279 -399.33778) (xy 180.365399 -399.392956) (xy 180.365908 -399.420842)
			(xy 180.365399 -399.448728) (xy 180.357279 -399.503904) (xy 180.341211 -399.557311) (xy 180.317539 -399.607808)
			(xy 180.286766 -399.654321) (xy 180.249549 -399.695858) (xy 180.206681 -399.731533) (xy 180.159075 -399.760587)
			(xy 180.107746 -399.782399) (xy 180.053789 -399.796505) (xy 179.998352 -399.802605) (xy 179.942618 -399.800568)
			(xy 179.887775 -399.790438) (xy 179.834991 -399.772431) (xy 179.785391 -399.74693) (xy 179.740033 -399.714479)
			(xy 179.699884 -399.67577) (xy 179.665798 -399.631627) (xy 179.638502 -399.582992) (xy 179.618579 -399.530901)
			(xy 179.606453 -399.476464) (xy 179.602382 -399.420842) (xy 177.19548 -399.420842) (xy 177.19548 -400.436842)
			(xy 180.097682 -400.436842) (xy 180.101753 -400.38122) (xy 180.113879 -400.326783) (xy 180.133802 -400.274692)
			(xy 180.161098 -400.226057) (xy 180.195184 -400.181914) (xy 180.235333 -400.143205) (xy 180.280691 -400.110754)
			(xy 180.330291 -400.085253) (xy 180.383075 -400.067246) (xy 180.437918 -400.057116) (xy 180.493652 -400.055079)
			(xy 180.549089 -400.061179) (xy 180.603046 -400.075285) (xy 180.654375 -400.097097) (xy 180.701981 -400.126151)
			(xy 180.744849 -400.161826) (xy 180.782066 -400.203363) (xy 180.812839 -400.249876) (xy 180.836511 -400.300373)
			(xy 180.852579 -400.35378) (xy 180.860699 -400.408956) (xy 180.861208 -400.436842) (xy 180.860699 -400.464728)
			(xy 180.852579 -400.519904) (xy 180.836511 -400.573311) (xy 180.812839 -400.623808) (xy 180.782066 -400.670321)
			(xy 180.744849 -400.711858) (xy 180.701981 -400.747533) (xy 180.654375 -400.776587) (xy 180.603046 -400.798399)
			(xy 180.549089 -400.812505) (xy 180.493652 -400.818605) (xy 180.437918 -400.816568) (xy 180.383075 -400.806438)
			(xy 180.330291 -400.788431) (xy 180.280691 -400.76293) (xy 180.235333 -400.730479) (xy 180.195184 -400.69177)
			(xy 180.161098 -400.647627) (xy 180.133802 -400.598992) (xy 180.113879 -400.546901) (xy 180.101753 -400.492464)
			(xy 180.097682 -400.436842) (xy 177.19548 -400.436842) (xy 177.19548 -401.452842) (xy 177.318922 -401.452842)
			(xy 177.322993 -401.39722) (xy 177.335119 -401.342783) (xy 177.355042 -401.290692) (xy 177.382338 -401.242057)
			(xy 177.416424 -401.197914) (xy 177.456573 -401.159205) (xy 177.501931 -401.126754) (xy 177.551531 -401.101253)
			(xy 177.604315 -401.083246) (xy 177.659158 -401.073116) (xy 177.714892 -401.071079) (xy 177.770329 -401.077179)
			(xy 177.824286 -401.091285) (xy 177.875615 -401.113097) (xy 177.923221 -401.142151) (xy 177.966089 -401.177826)
			(xy 178.003306 -401.219363) (xy 178.034079 -401.265876) (xy 178.057751 -401.316373) (xy 178.073819 -401.36978)
			(xy 178.081939 -401.424956) (xy 178.082448 -401.452842) (xy 178.081939 -401.480728) (xy 178.073819 -401.535904)
			(xy 178.057751 -401.589311) (xy 178.034079 -401.639808) (xy 178.003306 -401.686321) (xy 177.966089 -401.727858)
			(xy 177.942508 -401.747482) (xy 179.978302 -401.747482) (xy 179.982373 -401.69186) (xy 179.994499 -401.637423)
			(xy 180.014422 -401.585332) (xy 180.041718 -401.536697) (xy 180.075804 -401.492554) (xy 180.115953 -401.453845)
			(xy 180.161311 -401.421394) (xy 180.210911 -401.395893) (xy 180.263695 -401.377886) (xy 180.318538 -401.367756)
			(xy 180.374272 -401.365719) (xy 180.429709 -401.371819) (xy 180.483666 -401.385925) (xy 180.534995 -401.407737)
			(xy 180.582601 -401.436791) (xy 180.625469 -401.472466) (xy 180.662686 -401.514003) (xy 180.693459 -401.560516)
			(xy 180.717131 -401.611013) (xy 180.733199 -401.66442) (xy 180.741319 -401.719596) (xy 180.741828 -401.747482)
			(xy 180.741319 -401.775368) (xy 180.733199 -401.830544) (xy 180.717131 -401.883951) (xy 180.693459 -401.934448)
			(xy 180.662686 -401.980961) (xy 180.625469 -402.022498) (xy 180.582601 -402.058173) (xy 180.534995 -402.087227)
			(xy 180.483666 -402.109039) (xy 180.429709 -402.123145) (xy 180.374272 -402.129245) (xy 180.318538 -402.127208)
			(xy 180.263695 -402.117078) (xy 180.210911 -402.099071) (xy 180.161311 -402.07357) (xy 180.115953 -402.041119)
			(xy 180.075804 -402.00241) (xy 180.041718 -401.958267) (xy 180.014422 -401.909632) (xy 179.994499 -401.857541)
			(xy 179.982373 -401.803104) (xy 179.978302 -401.747482) (xy 177.942508 -401.747482) (xy 177.923221 -401.763533)
			(xy 177.875615 -401.792587) (xy 177.824286 -401.814399) (xy 177.770329 -401.828505) (xy 177.714892 -401.834605)
			(xy 177.659158 -401.832568) (xy 177.604315 -401.822438) (xy 177.551531 -401.804431) (xy 177.501931 -401.77893)
			(xy 177.456573 -401.746479) (xy 177.416424 -401.70777) (xy 177.382338 -401.663627) (xy 177.355042 -401.614992)
			(xy 177.335119 -401.562901) (xy 177.322993 -401.508464) (xy 177.318922 -401.452842) (xy 177.19548 -401.452842)
			(xy 177.19548 -402.633942) (xy 180.064662 -402.633942) (xy 180.068733 -402.57832) (xy 180.080859 -402.523883)
			(xy 180.100782 -402.471792) (xy 180.128078 -402.423157) (xy 180.162164 -402.379014) (xy 180.202313 -402.340305)
			(xy 180.247671 -402.307854) (xy 180.297271 -402.282353) (xy 180.350055 -402.264346) (xy 180.404898 -402.254216)
			(xy 180.460632 -402.252179) (xy 180.516069 -402.258279) (xy 180.570026 -402.272385) (xy 180.621355 -402.294197)
			(xy 180.668961 -402.323251) (xy 180.711829 -402.358926) (xy 180.749046 -402.400463) (xy 180.779819 -402.446976)
			(xy 180.803491 -402.497473) (xy 180.819559 -402.55088) (xy 180.827679 -402.606056) (xy 180.828188 -402.633942)
			(xy 180.827679 -402.661828) (xy 180.819559 -402.717004) (xy 180.803491 -402.770411) (xy 180.779819 -402.820908)
			(xy 180.749046 -402.867421) (xy 180.711829 -402.908958) (xy 180.668961 -402.944633) (xy 180.621355 -402.973687)
			(xy 180.570026 -402.995499) (xy 180.516069 -403.009605) (xy 180.460632 -403.015705) (xy 180.404898 -403.013668)
			(xy 180.350055 -403.003538) (xy 180.297271 -402.985531) (xy 180.247671 -402.96003) (xy 180.202313 -402.927579)
			(xy 180.162164 -402.88887) (xy 180.128078 -402.844727) (xy 180.100782 -402.796092) (xy 180.080859 -402.744001)
			(xy 180.068733 -402.689564) (xy 180.064662 -402.633942) (xy 177.19548 -402.633942) (xy 177.19548 -403.175724)
			(xy 177.195925 -403.186213) (xy 177.204207 -403.205479) (xy 177.219531 -403.219794) (xy 177.229262 -403.22373)
			(xy 177.334926 -403.261068) (xy 177.36566 -403.252178) (xy 177.376074 -403.239478) (xy 177.394293 -403.217722)
			(xy 177.436068 -403.17932) (xy 177.48307 -403.147528) (xy 177.53426 -403.123045) (xy 177.588512 -403.106412)
			(xy 177.644628 -403.097995) (xy 177.673 -403.097492) (xy 177.700251 -403.097978) (xy 177.754199 -403.105734)
			(xy 177.806494 -403.121089) (xy 177.856071 -403.143731) (xy 177.901921 -403.173197) (xy 177.943112 -403.208888)
			(xy 177.978803 -403.250079) (xy 178.008269 -403.295929) (xy 178.030911 -403.345506) (xy 178.046266 -403.397801)
			(xy 178.054022 -403.451749) (xy 178.054022 -403.506251) (xy 178.046266 -403.560199) (xy 178.030911 -403.612494)
			(xy 178.008269 -403.662071) (xy 177.995986 -403.681184) (xy 180.049422 -403.681184) (xy 180.053493 -403.625562)
			(xy 180.065619 -403.571125) (xy 180.085542 -403.519034) (xy 180.112838 -403.470399) (xy 180.146924 -403.426256)
			(xy 180.187073 -403.387547) (xy 180.232431 -403.355096) (xy 180.282031 -403.329595) (xy 180.334815 -403.311588)
			(xy 180.389658 -403.301458) (xy 180.445392 -403.299421) (xy 180.500829 -403.305521) (xy 180.554786 -403.319627)
			(xy 180.606115 -403.341439) (xy 180.653721 -403.370493) (xy 180.696589 -403.406168) (xy 180.733806 -403.447705)
			(xy 180.764579 -403.494218) (xy 180.788251 -403.544715) (xy 180.804319 -403.598122) (xy 180.812439 -403.653298)
			(xy 180.812948 -403.681184) (xy 180.812439 -403.70907) (xy 180.804319 -403.764246) (xy 180.788251 -403.817653)
			(xy 180.764579 -403.86815) (xy 180.733806 -403.914663) (xy 180.696589 -403.9562) (xy 180.653721 -403.991875)
			(xy 180.606115 -404.020929) (xy 180.554786 -404.042741) (xy 180.500829 -404.056847) (xy 180.445392 -404.062947)
			(xy 180.389658 -404.06091) (xy 180.334815 -404.05078) (xy 180.282031 -404.032773) (xy 180.232431 -404.007272)
			(xy 180.187073 -403.974821) (xy 180.146924 -403.936112) (xy 180.112838 -403.891969) (xy 180.085542 -403.843334)
			(xy 180.065619 -403.791243) (xy 180.053493 -403.736806) (xy 180.049422 -403.681184) (xy 177.995986 -403.681184)
			(xy 177.978803 -403.707921) (xy 177.943112 -403.749112) (xy 177.901921 -403.784803) (xy 177.856071 -403.814269)
			(xy 177.806494 -403.836911) (xy 177.754199 -403.852266) (xy 177.700251 -403.860022) (xy 177.673 -403.860508)
			(xy 177.644629 -403.859987) (xy 177.588512 -403.851581) (xy 177.53426 -403.834953) (xy 177.48307 -403.810471)
			(xy 177.436073 -403.778676) (xy 177.394304 -403.740268) (xy 177.376074 -403.718522) (xy 177.36566 -403.705822)
			(xy 177.334926 -403.696932) (xy 177.229262 -403.73427) (xy 177.219579 -403.73828) (xy 177.204305 -403.752599)
			(xy 177.195978 -403.771808) (xy 177.19548 -403.782276) (xy 177.19548 -405.059134) (xy 179.916326 -405.059134)
			(xy 179.920397 -405.003512) (xy 179.932523 -404.949075) (xy 179.952446 -404.896984) (xy 179.979742 -404.848349)
			(xy 180.013828 -404.804206) (xy 180.053977 -404.765497) (xy 180.099335 -404.733046) (xy 180.148935 -404.707545)
			(xy 180.201719 -404.689538) (xy 180.256562 -404.679408) (xy 180.312296 -404.677371) (xy 180.367733 -404.683471)
			(xy 180.42169 -404.697577) (xy 180.473019 -404.719389) (xy 180.520625 -404.748443) (xy 180.563493 -404.784118)
			(xy 180.60071 -404.825655) (xy 180.631483 -404.872168) (xy 180.655155 -404.922665) (xy 180.671223 -404.976072)
			(xy 180.679343 -405.031248) (xy 180.679657 -405.048466) (xy 181.06847 -405.048466) (xy 181.072541 -404.992844)
			(xy 181.084667 -404.938407) (xy 181.10459 -404.886316) (xy 181.131886 -404.837681) (xy 181.165972 -404.793538)
			(xy 181.206121 -404.754829) (xy 181.251479 -404.722378) (xy 181.301079 -404.696877) (xy 181.353863 -404.67887)
			(xy 181.408706 -404.66874) (xy 181.46444 -404.666703) (xy 181.519877 -404.672803) (xy 181.573834 -404.686909)
			(xy 181.625163 -404.708721) (xy 181.672769 -404.737775) (xy 181.715637 -404.77345) (xy 181.752854 -404.814987)
			(xy 181.783627 -404.8615) (xy 181.807299 -404.911997) (xy 181.823367 -404.965404) (xy 181.831487 -405.02058)
			(xy 181.831996 -405.048466) (xy 181.831487 -405.076352) (xy 181.823367 -405.131528) (xy 181.807299 -405.184935)
			(xy 181.783627 -405.235432) (xy 181.752854 -405.281945) (xy 181.715637 -405.323482) (xy 181.672769 -405.359157)
			(xy 181.625163 -405.388211) (xy 181.573834 -405.410023) (xy 181.519877 -405.424129) (xy 181.46444 -405.430229)
			(xy 181.408706 -405.428192) (xy 181.353863 -405.418062) (xy 181.301079 -405.400055) (xy 181.251479 -405.374554)
			(xy 181.206121 -405.342103) (xy 181.165972 -405.303394) (xy 181.131886 -405.259251) (xy 181.10459 -405.210616)
			(xy 181.084667 -405.158525) (xy 181.072541 -405.104088) (xy 181.06847 -405.048466) (xy 180.679657 -405.048466)
			(xy 180.679852 -405.059134) (xy 180.679343 -405.08702) (xy 180.671223 -405.142196) (xy 180.655155 -405.195603)
			(xy 180.631483 -405.2461) (xy 180.60071 -405.292613) (xy 180.563493 -405.33415) (xy 180.520625 -405.369825)
			(xy 180.473019 -405.398879) (xy 180.42169 -405.420691) (xy 180.367733 -405.434797) (xy 180.312296 -405.440897)
			(xy 180.256562 -405.43886) (xy 180.201719 -405.42873) (xy 180.148935 -405.410723) (xy 180.099335 -405.385222)
			(xy 180.053977 -405.352771) (xy 180.013828 -405.314062) (xy 179.979742 -405.269919) (xy 179.952446 -405.221284)
			(xy 179.932523 -405.169193) (xy 179.920397 -405.114756) (xy 179.916326 -405.059134) (xy 177.19548 -405.059134)
			(xy 177.19548 -405.676608) (xy 182.21655 -405.676608) (xy 182.220621 -405.620986) (xy 182.232747 -405.566549)
			(xy 182.25267 -405.514458) (xy 182.279966 -405.465823) (xy 182.314052 -405.42168) (xy 182.354201 -405.382971)
			(xy 182.399559 -405.35052) (xy 182.449159 -405.325019) (xy 182.501943 -405.307012) (xy 182.556786 -405.296882)
			(xy 182.61252 -405.294845) (xy 182.667957 -405.300945) (xy 182.721914 -405.315051) (xy 182.773243 -405.336863)
			(xy 182.820849 -405.365917) (xy 182.863717 -405.401592) (xy 182.900934 -405.443129) (xy 182.931707 -405.489642)
			(xy 182.955379 -405.540139) (xy 182.971447 -405.593546) (xy 182.979567 -405.648722) (xy 182.980076 -405.676608)
			(xy 182.979567 -405.704494) (xy 182.971447 -405.75967) (xy 182.955379 -405.813077) (xy 182.931707 -405.863574)
			(xy 182.900934 -405.910087) (xy 182.863717 -405.951624) (xy 182.820849 -405.987299) (xy 182.773243 -406.016353)
			(xy 182.721914 -406.038165) (xy 182.667957 -406.052271) (xy 182.61252 -406.058371) (xy 182.556786 -406.056334)
			(xy 182.501943 -406.046204) (xy 182.449159 -406.028197) (xy 182.399559 -406.002696) (xy 182.354201 -405.970245)
			(xy 182.314052 -405.931536) (xy 182.279966 -405.887393) (xy 182.25267 -405.838758) (xy 182.232747 -405.786667)
			(xy 182.220621 -405.73223) (xy 182.21655 -405.676608) (xy 177.19548 -405.676608) (xy 177.19548 -405.969724)
			(xy 177.195925 -405.980213) (xy 177.204207 -405.999479) (xy 177.219531 -406.013794) (xy 177.229262 -406.01773)
			(xy 177.334926 -406.055068) (xy 177.36566 -406.046178) (xy 177.376074 -406.033478) (xy 177.394293 -406.011722)
			(xy 177.436068 -405.97332) (xy 177.48307 -405.941528) (xy 177.53426 -405.917045) (xy 177.588512 -405.900412)
			(xy 177.644628 -405.891995) (xy 177.673 -405.891492) (xy 177.700251 -405.891978) (xy 177.754199 -405.899734)
			(xy 177.806494 -405.915089) (xy 177.856071 -405.937731) (xy 177.901921 -405.967197) (xy 177.943112 -406.002888)
			(xy 177.978803 -406.044079) (xy 178.008269 -406.089929) (xy 178.030911 -406.139506) (xy 178.046266 -406.191801)
			(xy 178.054022 -406.245749) (xy 178.054508 -406.273) (xy 178.054035 -406.299966) (xy 178.046423 -406.353359)
			(xy 178.031366 -406.405147) (xy 178.009164 -406.454297) (xy 177.980259 -406.49983) (xy 177.945228 -406.540837)
			(xy 177.90477 -406.5765) (xy 177.859691 -406.606108) (xy 177.810891 -406.62907) (xy 177.785268 -406.63749)
			(xy 177.772568 -406.641554) (xy 177.75428 -406.660858) (xy 177.742781 -406.70734) (xy 179.80101 -406.70734)
			(xy 179.805081 -406.651718) (xy 179.817207 -406.597281) (xy 179.83713 -406.54519) (xy 179.864426 -406.496555)
			(xy 179.898512 -406.452412) (xy 179.938661 -406.413703) (xy 179.984019 -406.381252) (xy 180.033619 -406.355751)
			(xy 180.086403 -406.337744) (xy 180.141246 -406.327614) (xy 180.19698 -406.325577) (xy 180.252417 -406.331677)
			(xy 180.306374 -406.345783) (xy 180.357703 -406.367595) (xy 180.405309 -406.396649) (xy 180.448177 -406.432324)
			(xy 180.485394 -406.473861) (xy 180.516167 -406.520374) (xy 180.539839 -406.570871) (xy 180.555907 -406.624278)
			(xy 180.564027 -406.679454) (xy 180.564536 -406.70734) (xy 180.564027 -406.735226) (xy 180.555907 -406.790402)
			(xy 180.539839 -406.843809) (xy 180.516167 -406.894306) (xy 180.485394 -406.940819) (xy 180.448177 -406.982356)
			(xy 180.405309 -407.018031) (xy 180.357703 -407.047085) (xy 180.306374 -407.068897) (xy 180.252417 -407.083003)
			(xy 180.19698 -407.089103) (xy 180.141246 -407.087066) (xy 180.086403 -407.076936) (xy 180.033619 -407.058929)
			(xy 179.984019 -407.033428) (xy 179.938661 -407.000977) (xy 179.898512 -406.962268) (xy 179.864426 -406.918125)
			(xy 179.83713 -406.86949) (xy 179.817207 -406.817399) (xy 179.805081 -406.762962) (xy 179.80101 -406.70734)
			(xy 177.742781 -406.70734) (xy 177.73015 -406.758394) (xy 177.728407 -406.76692) (xy 177.730113 -406.784226)
			(xy 177.73749 -406.799974) (xy 177.743358 -406.8064) (xy 179.56276 -408.625802) (xy 179.569075 -408.631607)
			(xy 179.584541 -408.638998) (xy 179.60158 -408.640877) (xy 179.610004 -408.639264) (xy 179.706778 -408.616912)
			(xy 179.726082 -408.599386) (xy 179.7304 -408.58694) (xy 179.739409 -408.562281) (xy 179.763236 -408.515499)
			(xy 179.793247 -408.472423) (xy 179.828877 -408.433865) (xy 179.869452 -408.400551) (xy 179.914209 -408.373109)
			(xy 179.962303 -408.352058) (xy 180.012828 -408.337793) (xy 180.06483 -408.330585) (xy 180.09108 -408.330146)
			(xy 180.118333 -408.33063) (xy 180.172286 -408.338384) (xy 180.224586 -408.353737) (xy 180.274168 -408.376377)
			(xy 180.320024 -408.405842) (xy 180.361221 -408.441532) (xy 180.396919 -408.482723) (xy 180.426392 -408.528574)
			(xy 180.44904 -408.578153) (xy 180.464402 -408.63045) (xy 180.472165 -408.684401) (xy 180.472588 -408.711654)
			(xy 180.47209 -408.739327) (xy 180.464082 -408.794092) (xy 180.448242 -408.847124) (xy 180.424903 -408.89731)
			(xy 180.394555 -408.943595) (xy 180.376576 -408.964638) (xy 180.36667 -408.975814) (xy 180.362098 -409.005278)
			(xy 180.406294 -409.103576) (xy 180.410694 -409.112325) (xy 180.42481 -409.125873) (xy 180.44299 -409.133107)
			(xy 180.452776 -409.133548)
		)
		(stroke
			(width 0)
			(type solid)
		)
		(fill yes)
		(layer "In15.Cu")
		(net "AGND_HSC")
	)
	(gr_poly
		(pts
			(xy 251.944886 -52.876958) (xy 251.954759 -52.876487) (xy 251.973045 -52.869033) (xy 251.980446 -52.86248)
			(xy 251.9807 -52.862226) (xy 252.546358 -52.296568) (xy 252.546866 -52.29606) (xy 252.553449 -52.288679)
			(xy 252.560902 -52.27038) (xy 252.561344 -52.2605) (xy 252.561344 -47.194978) (xy 252.560874 -47.18467)
			(xy 252.55276 -47.165721) (xy 252.53782 -47.151518) (xy 252.528324 -47.14748) (xy 252.424438 -47.108364)
			(xy 252.393958 -47.115984) (xy 252.38329 -47.127922) (xy 252.3651 -47.147961) (xy 252.324036 -47.183211)
			(xy 252.278401 -47.212301) (xy 252.229111 -47.234646) (xy 252.177157 -47.249799) (xy 252.123583 -47.257454)
			(xy 252.096524 -47.25797) (xy 252.069273 -47.257508) (xy 252.015325 -47.249755) (xy 251.963029 -47.234403)
			(xy 251.913451 -47.211764) (xy 251.867599 -47.182299) (xy 251.826408 -47.146609) (xy 251.790715 -47.10542)
			(xy 251.761248 -47.05957) (xy 251.738606 -47.009993) (xy 251.72325 -46.957699) (xy 251.715493 -46.903751)
			(xy 251.715493 -46.849249) (xy 251.72325 -46.795301) (xy 251.738606 -46.743007) (xy 251.761248 -46.69343)
			(xy 251.790715 -46.64758) (xy 251.826408 -46.606391) (xy 251.867599 -46.570701) (xy 251.913451 -46.541236)
			(xy 251.963029 -46.518597) (xy 252.015325 -46.503245) (xy 252.069273 -46.495492) (xy 252.096524 -46.494954)
			(xy 252.123584 -46.495429) (xy 252.17716 -46.503088) (xy 252.229114 -46.518249) (xy 252.278401 -46.540607)
			(xy 252.324029 -46.569711) (xy 252.365082 -46.604977) (xy 252.38329 -46.625002) (xy 252.393958 -46.63694)
			(xy 252.424438 -46.64456) (xy 252.528324 -46.605444) (xy 252.537793 -46.601378) (xy 252.55268 -46.587157)
			(xy 252.560803 -46.568239) (xy 252.561344 -46.557946) (xy 252.561344 -45.671486) (xy 252.560697 -45.658934)
			(xy 252.548832 -45.636812) (xy 252.538738 -45.629322) (xy 252.457712 -45.57522) (xy 252.43282 -45.57268)
			(xy 252.420882 -45.57776) (xy 252.397568 -45.587007) (xy 252.349127 -45.60001) (xy 252.299402 -45.606569)
			(xy 252.274324 -45.60697) (xy 252.269752 -45.60697) (xy 252.242582 -45.606159) (xy 252.188875 -45.597793)
			(xy 252.136897 -45.581893) (xy 252.087701 -45.558781) (xy 252.042281 -45.528922) (xy 252.001556 -45.492923)
			(xy 251.96635 -45.45151) (xy 251.937375 -45.405522) (xy 251.925836 -45.38091) (xy 251.921518 -45.371004)
			(xy 251.906024 -45.357034) (xy 251.814838 -45.326046) (xy 251.79401 -45.327824) (xy 251.784612 -45.333158)
			(xy 251.745416 -45.353829) (xy 251.663729 -45.388187) (xy 251.57903 -45.414255) (xy 251.492161 -45.431773)
			(xy 251.403979 -45.44057) (xy 251.35967 -45.441108) (xy 251.317834 -45.440631) (xy 251.234532 -45.432779)
			(xy 251.152336 -45.417136) (xy 251.071972 -45.393843) (xy 250.994152 -45.363103) (xy 250.919563 -45.325191)
			(xy 250.848865 -45.280439) (xy 250.782683 -45.229245) (xy 250.721602 -45.172061) (xy 250.666162 -45.109393)
			(xy 250.616854 -45.041794) (xy 250.574113 -44.969863) (xy 250.538318 -44.894235) (xy 250.509785 -44.815579)
			(xy 250.488765 -44.734591) (xy 250.475446 -44.651986) (xy 250.472194 -44.610274) (xy 250.471221 -44.600884)
			(xy 250.463272 -44.583776) (xy 250.4567 -44.577) (xy 250.434856 -44.556172) (xy 250.427792 -44.549953)
			(xy 250.41046 -44.542658) (xy 250.401074 -44.541948) (xy 250.358152 -44.540314) (xy 250.272897 -44.529813)
			(xy 250.189052 -44.511141) (xy 250.107397 -44.484473) (xy 250.028694 -44.450057) (xy 249.953675 -44.408214)
			(xy 249.883039 -44.359333) (xy 249.817445 -44.30387) (xy 249.757504 -44.242342) (xy 249.703773 -44.175322)
			(xy 249.656754 -44.103434) (xy 249.616884 -44.027348) (xy 249.584536 -43.947772) (xy 249.56001 -43.865448)
			(xy 249.543534 -43.781144) (xy 249.535263 -43.695644) (xy 249.53468 -43.652694) (xy 249.535183 -43.610457)
			(xy 249.543203 -43.526364) (xy 249.55916 -43.44341) (xy 249.58291 -43.362343) (xy 249.61424 -43.283893)
			(xy 249.652867 -43.208767) (xy 249.698443 -43.137642) (xy 249.750558 -43.071159) (xy 249.808741 -43.009917)
			(xy 249.872469 -42.954467) (xy 249.941168 -42.905309) (xy 250.014218 -42.862887) (xy 250.090961 -42.827582)
			(xy 250.170706 -42.799713) (xy 250.21159 -42.789094) (xy 250.220743 -42.78637) (xy 250.236274 -42.775281)
			(xy 250.241816 -42.767504) (xy 250.25858 -42.742104) (xy 250.26334 -42.733862) (xy 250.267126 -42.715226)
			(xy 250.265946 -42.705782) (xy 250.259966 -42.668479) (xy 250.253609 -42.593192) (xy 250.253246 -42.555414)
			(xy 250.25375 -42.513066) (xy 250.261801 -42.428752) (xy 250.27783 -42.345586) (xy 250.301691 -42.264319)
			(xy 250.33317 -42.185689) (xy 250.371981 -42.110408) (xy 250.417771 -42.039156) (xy 250.470127 -41.97258)
			(xy 250.528575 -41.911282) (xy 250.592585 -41.855817) (xy 250.661577 -41.806688) (xy 250.734927 -41.764339)
			(xy 250.81197 -41.729155) (xy 250.892009 -41.701453) (xy 250.974318 -41.681485) (xy 251.058153 -41.669432)
			(xy 251.142754 -41.665402) (xy 251.227355 -41.669432) (xy 251.31119 -41.681485) (xy 251.393499 -41.701453)
			(xy 251.473538 -41.729155) (xy 251.550581 -41.764339) (xy 251.623931 -41.806688) (xy 251.692923 -41.855817)
			(xy 251.756933 -41.911282) (xy 251.815381 -41.97258) (xy 251.867737 -42.039156) (xy 251.913527 -42.110408)
			(xy 251.952338 -42.185689) (xy 251.983817 -42.264319) (xy 252.007678 -42.345586) (xy 252.023707 -42.428752)
			(xy 252.031758 -42.513066) (xy 252.032262 -42.555414) (xy 252.031763 -42.597654) (xy 252.023751 -42.681754)
			(xy 252.007801 -42.764715) (xy 251.984057 -42.845791) (xy 251.952733 -42.924249) (xy 251.91411 -42.999384)
			(xy 251.868537 -43.070518) (xy 251.816424 -43.137011) (xy 251.758242 -43.198262) (xy 251.694513 -43.253721)
			(xy 251.625814 -43.302888) (xy 251.552762 -43.345319) (xy 251.476016 -43.380632) (xy 251.396267 -43.408509)
			(xy 251.355352 -43.419014) (xy 251.346195 -43.421732) (xy 251.330655 -43.432816) (xy 251.325126 -43.440604)
			(xy 251.308362 -43.466004) (xy 251.303608 -43.474248) (xy 251.299829 -43.492881) (xy 251.300996 -43.502326)
			(xy 251.304708 -43.525116) (xy 251.310044 -43.570987) (xy 251.311664 -43.59402) (xy 251.312655 -43.603401)
			(xy 251.320632 -43.62048) (xy 251.327158 -43.627294) (xy 251.349002 -43.648122) (xy 251.356064 -43.654348)
			(xy 251.373395 -43.661658) (xy 251.382784 -43.662346) (xy 251.425576 -43.663968) (xy 251.510576 -43.674407)
			(xy 251.594179 -43.692967) (xy 251.675612 -43.719476) (xy 251.75412 -43.753688) (xy 251.828976 -43.795286)
			(xy 251.899489 -43.843886) (xy 251.965005 -43.899038) (xy 252.024916 -43.96023) (xy 252.07867 -44.026898)
			(xy 252.10262 -44.062396) (xy 252.109407 -44.071715) (xy 252.129182 -44.083522) (xy 252.152123 -44.085557)
			(xy 252.163072 -44.081954) (xy 252.184948 -44.073917) (xy 252.230165 -44.062618) (xy 252.276421 -44.056915)
			(xy 252.299724 -44.056554) (xy 252.331977 -44.05723) (xy 252.395564 -44.068084) (xy 252.426216 -44.078144)
			(xy 252.4379 -44.082208) (xy 252.46203 -44.078906) (xy 252.539754 -44.023788) (xy 252.545264 -44.019693)
			(xy 252.554031 -44.009136) (xy 252.557026 -44.00296) (xy 252.561344 -43.9928) (xy 252.561344 -42.283634)
			(xy 252.561781 -42.27357) (xy 252.569517 -42.254987) (xy 252.57633 -42.247566) (xy 253.49581 -41.328086)
			(xy 253.503205 -41.321232) (xy 253.521804 -41.313487) (xy 253.531878 -41.3131) (xy 253.96444 -41.3131)
			(xy 253.975685 -41.312527) (xy 253.996011 -41.302912) (xy 254.003556 -41.294558) (xy 254.031663 -41.261131)
			(xy 254.093426 -41.199377) (xy 254.160945 -41.143975) (xy 254.23357 -41.095458) (xy 254.310602 -41.054294)
			(xy 254.391297 -41.020879) (xy 254.474879 -40.995536) (xy 254.560543 -40.978508) (xy 254.647464 -40.969959)
			(xy 254.691134 -40.969438) (xy 254.734931 -40.969956) (xy 254.8221 -40.978559) (xy 254.908 -40.995697)
			(xy 254.991797 -41.021204) (xy 255.072677 -41.054833) (xy 255.111504 -41.075102) (xy 255.12297 -41.08052)
			(xy 255.148298 -41.08052) (xy 255.159764 -41.075102) (xy 255.193705 -41.057353) (xy 255.264074 -41.02709)
			(xy 255.336785 -41.002995) (xy 255.411301 -40.985246) (xy 255.487067 -40.973976) (xy 255.52527 -40.971216)
			(xy 255.534668 -40.970454) (xy 255.551686 -40.962834) (xy 255.648714 -40.865806) (xy 255.649222 -40.865298)
			(xy 255.6558 -40.857916) (xy 255.663238 -40.839616) (xy 255.6637 -40.829738) (xy 255.6637 -39.251382)
			(xy 255.663273 -39.241313) (xy 255.655554 -39.222714) (xy 255.648714 -39.215314) (xy 255.336294 -38.902894)
			(xy 255.328895 -38.896049) (xy 255.310297 -38.888318) (xy 255.300226 -38.887908) (xy 254.81915 -38.887908)
			(xy 254.806727 -38.888515) (xy 254.78474 -38.900086) (xy 254.77724 -38.910006) (xy 254.72263 -38.989254)
			(xy 254.719582 -39.013892) (xy 254.724154 -39.02583) (xy 254.738237 -39.063904) (xy 254.760211 -39.142059)
			(xy 254.774969 -39.221892) (xy 254.782386 -39.302737) (xy 254.782828 -39.34333) (xy 254.782203 -39.390758)
			(xy 254.772074 -39.485073) (xy 254.751958 -39.577772) (xy 254.737616 -39.622984) (xy 254.734314 -39.63289)
			(xy 254.736092 -39.652956) (xy 254.779272 -39.736268) (xy 254.794766 -39.749222) (xy 254.804926 -39.75227)
			(xy 254.83074 -39.760541) (xy 254.879907 -39.78336) (xy 254.92535 -39.812909) (xy 254.966153 -39.848592)
			(xy 255.001496 -39.88969) (xy 255.030666 -39.935377) (xy 255.053076 -39.984732) (xy 255.068275 -40.036762)
			(xy 255.075958 -40.09042) (xy 255.076452 -40.117522) (xy 255.075965 -40.144773) (xy 255.068206 -40.198721)
			(xy 255.052849 -40.251016) (xy 255.030208 -40.300593) (xy 255.000741 -40.346444) (xy 254.965051 -40.387635)
			(xy 254.923861 -40.423328) (xy 254.878012 -40.452797) (xy 254.828436 -40.475442) (xy 254.776143 -40.490801)
			(xy 254.722195 -40.498563) (xy 254.694944 -40.49903) (xy 254.66603 -40.498492) (xy 254.608865 -40.489756)
			(xy 254.553673 -40.472494) (xy 254.501719 -40.4471) (xy 254.454191 -40.414157) (xy 254.41218 -40.374418)
			(xy 254.393954 -40.351964) (xy 254.387672 -40.344577) (xy 254.370957 -40.334779) (xy 254.361442 -40.332914)
			(xy 254.353822 -40.332406) (xy 254.274066 -40.332406) (xy 254.266446 -40.332914) (xy 254.256925 -40.334774)
			(xy 254.240191 -40.344553) (xy 254.233934 -40.351964) (xy 254.215744 -40.374449) (xy 254.173728 -40.41419)
			(xy 254.126194 -40.447133) (xy 254.074232 -40.472522) (xy 254.019032 -40.489775) (xy 253.961861 -40.498498)
			(xy 253.932944 -40.49903) (xy 253.903619 -40.498495) (xy 253.845659 -40.489519) (xy 253.789757 -40.471772)
			(xy 253.737233 -40.445673) (xy 253.71298 -40.42918) (xy 253.703836 -40.42283) (xy 253.6825 -40.418766)
			(xy 253.586488 -40.44188) (xy 253.56947 -40.455342) (xy 253.56439 -40.464994) (xy 253.543515 -40.503793)
			(xy 253.495196 -40.577472) (xy 253.439828 -40.646012) (xy 253.377953 -40.70874) (xy 253.310178 -40.765043)
			(xy 253.237169 -40.814368) (xy 253.159639 -40.856231) (xy 253.07835 -40.890222) (xy 252.994097 -40.916008)
			(xy 252.907708 -40.933336) (xy 252.820029 -40.942037) (xy 252.775974 -40.942514) (xy 252.733356 -40.942012)
			(xy 252.64851 -40.933855) (xy 252.564833 -40.917618) (xy 252.483094 -40.89345) (xy 252.404042 -40.861574)
			(xy 252.328402 -40.822281) (xy 252.256868 -40.775931) (xy 252.190097 -40.722951) (xy 252.1287 -40.663826)
			(xy 252.073242 -40.599098) (xy 252.02423 -40.529361) (xy 251.982115 -40.455255) (xy 251.947282 -40.37746)
			(xy 251.933202 -40.337232) (xy 251.929714 -40.328191) (xy 251.917175 -40.313436) (xy 251.908818 -40.30853)
			(xy 251.881894 -40.294306) (xy 251.873171 -40.290148) (xy 251.853974 -40.288072) (xy 251.844556 -40.290242)
			(xy 251.805819 -40.300519) (xy 251.726967 -40.31488) (xy 251.647141 -40.322075) (xy 251.607066 -40.3225)
			(xy 251.581866 -40.322352) (xy 251.531544 -40.319555) (xy 251.506482 -40.316912) (xy 251.497134 -40.316192)
			(xy 251.478995 -40.320884) (xy 251.471176 -40.326056) (xy 251.446792 -40.343582) (xy 251.439356 -40.349308)
			(xy 251.429033 -40.364966) (xy 251.426726 -40.374062) (xy 251.417072 -40.41608) (xy 251.39069 -40.498164)
			(xy 251.356491 -40.577311) (xy 251.314794 -40.652777) (xy 251.26599 -40.723855) (xy 251.210539 -40.789877)
			(xy 251.14896 -40.850224) (xy 251.081831 -40.90433) (xy 251.009782 -40.951688) (xy 250.933488 -40.991851)
			(xy 250.853667 -41.024445) (xy 250.771067 -41.049163) (xy 250.686462 -41.065772) (xy 250.600648 -41.074118)
			(xy 250.557538 -41.074594) (xy 250.515188 -41.074108) (xy 250.430872 -41.06606) (xy 250.347703 -41.050034)
			(xy 250.266433 -41.026174) (xy 250.1878 -40.994697) (xy 250.112515 -40.955887) (xy 250.04126 -40.910097)
			(xy 249.97468 -40.857741) (xy 249.913379 -40.799293) (xy 249.857912 -40.735283) (xy 249.80878 -40.66629)
			(xy 249.766429 -40.592938) (xy 249.731243 -40.515893) (xy 249.70354 -40.435853) (xy 249.683571 -40.353541)
			(xy 249.671516 -40.269704) (xy 249.667486 -40.1851) (xy 249.671516 -40.100496) (xy 249.683571 -40.016659)
			(xy 249.70354 -39.934347) (xy 249.731243 -39.854307) (xy 249.766429 -39.777262) (xy 249.80878 -39.70391)
			(xy 249.857912 -39.634917) (xy 249.913379 -39.570907) (xy 249.97468 -39.512459) (xy 250.04126 -39.460103)
			(xy 250.112515 -39.414313) (xy 250.1878 -39.375503) (xy 250.266433 -39.344026) (xy 250.347703 -39.320166)
			(xy 250.430872 -39.30414) (xy 250.515188 -39.296092) (xy 250.557538 -39.295578) (xy 250.582738 -39.295726)
			(xy 250.63306 -39.298523) (xy 250.658122 -39.301166) (xy 250.667466 -39.301829) (xy 250.685588 -39.297147)
			(xy 250.693428 -39.292022) (xy 250.717812 -39.274496) (xy 250.725245 -39.268768) (xy 250.73556 -39.253109)
			(xy 250.737878 -39.244016) (xy 250.746108 -39.207898) (xy 250.767795 -39.137059) (xy 250.795304 -39.068272)
			(xy 250.811538 -39.034974) (xy 250.817634 -39.023036) (xy 250.816364 -38.996874) (xy 250.76404 -38.912038)
			(xy 250.759178 -38.904846) (xy 250.745652 -38.893982) (xy 250.729281 -38.888239) (xy 250.720606 -38.887908)
			(xy 248.294398 -38.887908) (xy 248.282863 -38.888451) (xy 248.262094 -38.898496) (xy 248.25452 -38.907212)
			(xy 248.205244 -38.969696) (xy 248.198508 -38.979125) (xy 248.19363 -39.001753) (xy 248.195846 -39.01313)
			(xy 248.195846 -39.013384) (xy 248.200814 -39.035338) (xy 248.206157 -39.080032) (xy 248.206514 -39.102538)
			(xy 248.206514 -39.1033) (xy 248.20598 -39.132217) (xy 248.197253 -39.189388) (xy 248.18 -39.244588)
			(xy 248.154614 -39.296553) (xy 248.121678 -39.344092) (xy 248.081946 -39.386117) (xy 248.059448 -39.40429)
			(xy 248.052056 -39.41057) (xy 248.042243 -39.427281) (xy 248.040398 -39.436802) (xy 248.03989 -39.444422)
			(xy 248.03989 -39.524178) (xy 248.040398 -39.531798) (xy 248.042268 -39.541311) (xy 248.052067 -39.558022)
			(xy 248.059448 -39.56431) (xy 248.081937 -39.582498) (xy 248.121686 -39.624511) (xy 248.154637 -39.672044)
			(xy 248.180035 -39.724006) (xy 248.197297 -39.779207) (xy 248.206028 -39.836381) (xy 248.206514 -39.8653)
			(xy 248.206028 -39.892551) (xy 248.198272 -39.946499) (xy 248.182917 -39.998794) (xy 248.160275 -40.048371)
			(xy 248.130809 -40.094221) (xy 248.095118 -40.135412) (xy 248.053927 -40.171103) (xy 248.008077 -40.200569)
			(xy 247.9585 -40.223211) (xy 247.906205 -40.238566) (xy 247.852257 -40.246322) (xy 247.797755 -40.246322)
			(xy 247.743807 -40.238566) (xy 247.691512 -40.223211) (xy 247.641935 -40.200569) (xy 247.596085 -40.171103)
			(xy 247.554894 -40.135412) (xy 247.519203 -40.094221) (xy 247.489737 -40.048371) (xy 247.467095 -39.998794)
			(xy 247.45174 -39.946499) (xy 247.443984 -39.892551) (xy 247.443498 -39.8653) (xy 247.444032 -39.836383)
			(xy 247.452759 -39.779212) (xy 247.470013 -39.724012) (xy 247.495399 -39.672048) (xy 247.528335 -39.62451)
			(xy 247.568068 -39.582486) (xy 247.590564 -39.56431) (xy 247.597954 -39.558029) (xy 247.607766 -39.541317)
			(xy 247.609614 -39.531798) (xy 247.610122 -39.524178) (xy 247.610122 -39.444422) (xy 247.609614 -39.436802)
			(xy 247.608077 -39.428709) (xy 247.60057 -39.414058) (xy 247.594882 -39.4081) (xy 247.581674 -39.397178)
			(xy 247.561672 -39.380043) (xy 247.526112 -39.341193) (xy 247.496238 -39.297817) (xy 247.472619 -39.250743)
			(xy 247.455703 -39.200865) (xy 247.445815 -39.149134) (xy 247.444006 -39.122858) (xy 247.443244 -39.107618)
			(xy 247.425718 -39.083488) (xy 247.32488 -39.044626) (xy 247.315593 -39.041515) (xy 247.296028 -39.041822)
			(xy 247.278008 -39.049449) (xy 247.270778 -39.056056) (xy 244.735096 -41.591738) (xy 244.729192 -41.598195)
			(xy 244.721769 -41.614025) (xy 244.720113 -41.631429) (xy 244.721888 -41.639998) (xy 244.746272 -41.737534)
			(xy 244.76456 -41.756838) (xy 244.777514 -41.760648) (xy 244.819134 -41.77385) (xy 244.899796 -41.807295)
			(xy 244.976793 -41.848484) (xy 245.049382 -41.89702) (xy 245.116866 -41.952435) (xy 245.178594 -42.014198)
			(xy 245.233973 -42.081712) (xy 245.282469 -42.154328) (xy 245.323615 -42.231348) (xy 245.357016 -42.312028)
			(xy 245.382349 -42.395594) (xy 245.399371 -42.48124) (xy 245.407919 -42.568141) (xy 245.40845 -42.611802)
			(xy 245.408039 -42.650091) (xy 245.40143 -42.726385) (xy 245.388279 -42.801826) (xy 245.368684 -42.875856)
			(xy 245.356126 -42.91203) (xy 245.353483 -42.920468) (xy 245.353484 -42.938136) (xy 245.356126 -42.946574)
			(xy 245.368669 -42.982752) (xy 245.388243 -43.056784) (xy 245.401388 -43.132224) (xy 245.408006 -43.208514)
			(xy 245.40845 -43.246802) (xy 245.407946 -43.28915) (xy 245.399895 -43.373464) (xy 245.383866 -43.45663)
			(xy 245.360005 -43.537897) (xy 245.328526 -43.616527) (xy 245.289715 -43.691808) (xy 245.243925 -43.76306)
			(xy 245.191569 -43.829636) (xy 245.133121 -43.890934) (xy 245.069111 -43.946399) (xy 245.000119 -43.995528)
			(xy 244.926769 -44.037877) (xy 244.849726 -44.073061) (xy 244.769687 -44.100763) (xy 244.687378 -44.120731)
			(xy 244.603543 -44.132784) (xy 244.518942 -44.136815) (xy 244.434341 -44.132784) (xy 244.350506 -44.120731)
			(xy 244.268197 -44.100763) (xy 244.188158 -44.073061) (xy 244.111115 -44.037877) (xy 244.037765 -43.995528)
			(xy 243.968773 -43.946399) (xy 243.904763 -43.890934) (xy 243.846315 -43.829636) (xy 243.793959 -43.76306)
			(xy 243.748169 -43.691808) (xy 243.709358 -43.616527) (xy 243.677879 -43.537897) (xy 243.654018 -43.45663)
			(xy 243.637989 -43.373464) (xy 243.629938 -43.28915) (xy 243.629434 -43.246802) (xy 243.629845 -43.208512)
			(xy 243.636453 -43.132219) (xy 243.649603 -43.056777) (xy 243.669198 -42.982747) (xy 243.681758 -42.946574)
			(xy 243.684401 -42.938136) (xy 243.684402 -42.920468) (xy 243.681758 -42.91203) (xy 243.667788 -42.870374)
			(xy 243.663978 -42.85742) (xy 243.644674 -42.839132) (xy 243.547138 -42.814748) (xy 243.538574 -42.812957)
			(xy 243.521171 -42.81463) (xy 243.505346 -42.822062) (xy 243.498878 -42.827956) (xy 242.39855 -43.928284)
			(xy 242.391711 -43.935684) (xy 242.383999 -43.954283) (xy 242.383564 -43.964352) (xy 242.383564 -45.726153)
			(xy 244.028673 -45.726153) (xy 244.028673 -45.671647) (xy 244.036431 -45.617697) (xy 244.051787 -45.5654)
			(xy 244.07443 -45.515821) (xy 244.103899 -45.469969) (xy 244.139593 -45.428777) (xy 244.180786 -45.393085)
			(xy 244.22664 -45.363619) (xy 244.276221 -45.340979) (xy 244.328519 -45.325626) (xy 244.382469 -45.317872)
			(xy 244.409722 -45.31741) (xy 244.41912 -45.31741) (xy 244.432582 -45.317918) (xy 244.45595 -45.305218)
			(xy 244.51691 -45.208444) (xy 244.51818 -45.182028) (xy 244.512084 -45.169836) (xy 244.499055 -45.142926)
			(xy 244.480598 -45.086061) (xy 244.471261 -45.027009) (xy 244.470682 -44.997116) (xy 244.471168 -44.969865)
			(xy 244.478924 -44.915917) (xy 244.494279 -44.863622) (xy 244.516921 -44.814045) (xy 244.546387 -44.768195)
			(xy 244.582078 -44.727004) (xy 244.623269 -44.691313) (xy 244.669119 -44.661847) (xy 244.718696 -44.639205)
			(xy 244.770991 -44.62385) (xy 244.824939 -44.616094) (xy 244.879441 -44.616094) (xy 244.933389 -44.62385)
			(xy 244.985684 -44.639205) (xy 245.035261 -44.661847) (xy 245.081111 -44.691313) (xy 245.122302 -44.727004)
			(xy 245.157993 -44.768195) (xy 245.187459 -44.814045) (xy 245.210101 -44.863622) (xy 245.225456 -44.915917)
			(xy 245.233212 -44.969865) (xy 245.233698 -44.997116) (xy 245.233189 -45.025048) (xy 245.225048 -45.080314)
			(xy 245.208941 -45.133805) (xy 245.185214 -45.184379) (xy 245.170198 -45.207936) (xy 245.164102 -45.21708)
			(xy 245.160546 -45.23867) (xy 245.186708 -45.33392) (xy 245.200678 -45.350684) (xy 245.210838 -45.35551)
			(xy 245.234703 -45.367543) (xy 245.279101 -45.397298) (xy 245.31891 -45.43296) (xy 245.353352 -45.47383)
			(xy 245.38175 -45.519108) (xy 245.40355 -45.567907) (xy 245.418323 -45.619271) (xy 245.425782 -45.672195)
			(xy 245.42623 -45.698918) (xy 245.425739 -45.726169) (xy 245.417981 -45.780115) (xy 245.402624 -45.832408)
			(xy 245.379983 -45.881984) (xy 245.350517 -45.927833) (xy 245.314826 -45.969023) (xy 245.273637 -46.004714)
			(xy 245.227788 -46.034181) (xy 245.178212 -46.056823) (xy 245.125919 -46.07218) (xy 245.071973 -46.079939)
			(xy 245.044722 -46.080426) (xy 245.017351 -46.079965) (xy 244.963171 -46.072149) (xy 244.910667 -46.056659)
			(xy 244.860921 -46.033816) (xy 244.814955 -46.004089) (xy 244.794024 -45.986446) (xy 244.786912 -45.98035)
			(xy 244.769894 -45.974) (xy 244.68455 -45.974) (xy 244.667532 -45.98035) (xy 244.66042 -45.986446)
			(xy 244.639484 -46.004081) (xy 244.593513 -46.033795) (xy 244.543767 -46.056633) (xy 244.491267 -46.072125)
			(xy 244.437091 -46.079953) (xy 244.409722 -46.080426) (xy 244.382469 -46.079928) (xy 244.328519 -46.072174)
			(xy 244.276221 -46.056821) (xy 244.22664 -46.034181) (xy 244.180786 -46.004715) (xy 244.139593 -45.969023)
			(xy 244.103899 -45.927831) (xy 244.07443 -45.881979) (xy 244.051787 -45.8324) (xy 244.036431 -45.780103)
			(xy 244.028673 -45.726153) (xy 242.383564 -45.726153) (xy 242.383564 -47.116054) (xy 248.905961 -47.116054)
			(xy 248.905961 -47.061546) (xy 248.913719 -47.007594) (xy 248.929076 -46.955294) (xy 248.951721 -46.905713)
			(xy 248.981191 -46.859859) (xy 249.016887 -46.818666) (xy 249.058083 -46.782973) (xy 249.103939 -46.753506)
			(xy 249.153522 -46.730866) (xy 249.205823 -46.715513) (xy 249.259776 -46.707759) (xy 249.28703 -46.707298)
			(xy 249.319753 -46.707953) (xy 249.384248 -46.719055) (xy 249.4153 -46.729396) (xy 249.423986 -46.732171)
			(xy 249.442209 -46.732028) (xy 249.45086 -46.729142) (xy 249.479308 -46.717966) (xy 249.487869 -46.714156)
			(xy 249.501684 -46.701521) (xy 249.506232 -46.693328) (xy 249.524985 -46.656696) (xy 249.568231 -46.586674)
			(xy 249.61776 -46.520945) (xy 249.673148 -46.460073) (xy 249.733922 -46.404576) (xy 249.799562 -46.35493)
			(xy 249.869507 -46.311559) (xy 249.943158 -46.274833) (xy 250.019887 -46.245067) (xy 250.099037 -46.222516)
			(xy 250.179932 -46.207371) (xy 250.26188 -46.199763) (xy 250.30303 -46.199298) (xy 250.344133 -46.199738)
			(xy 250.425989 -46.207326) (xy 250.506795 -46.222434) (xy 250.585862 -46.244933) (xy 250.662517 -46.274631)
			(xy 250.736104 -46.311276) (xy 250.805996 -46.354553) (xy 250.871597 -46.404095) (xy 250.932347 -46.459479)
			(xy 250.987728 -46.520231) (xy 251.037267 -46.585834) (xy 251.080542 -46.655728) (xy 251.117183 -46.729316)
			(xy 251.146879 -46.805972) (xy 251.169375 -46.88504) (xy 251.184479 -46.965847) (xy 251.192064 -47.047703)
			(xy 251.192538 -47.088806) (xy 251.192049 -47.13012) (xy 251.184383 -47.212393) (xy 251.16912 -47.293599)
			(xy 251.146389 -47.37304) (xy 251.116387 -47.450029) (xy 251.079373 -47.523904) (xy 251.057918 -47.559214)
			(xy 251.050806 -47.570644) (xy 251.04979 -47.596552) (xy 251.10059 -47.698152) (xy 251.12218 -47.712884)
			(xy 251.135388 -47.714154) (xy 251.163573 -47.717102) (xy 251.218695 -47.730247) (xy 251.271265 -47.751405)
			(xy 251.320124 -47.780109) (xy 251.364198 -47.815727) (xy 251.402516 -47.857476) (xy 251.434233 -47.904436)
			(xy 251.458652 -47.955573) (xy 251.475234 -48.00976) (xy 251.483615 -48.065804) (xy 251.48413 -48.094138)
			(xy 251.483644 -48.121389) (xy 251.475888 -48.175337) (xy 251.460533 -48.227632) (xy 251.437891 -48.277209)
			(xy 251.408425 -48.323059) (xy 251.372734 -48.36425) (xy 251.331543 -48.399941) (xy 251.285693 -48.429407)
			(xy 251.236116 -48.452049) (xy 251.183821 -48.467404) (xy 251.129873 -48.47516) (xy 251.075371 -48.47516)
			(xy 251.021423 -48.467404) (xy 250.969128 -48.452049) (xy 250.919551 -48.429407) (xy 250.873701 -48.399941)
			(xy 250.83251 -48.36425) (xy 250.796819 -48.323059) (xy 250.767353 -48.277209) (xy 250.744711 -48.227632)
			(xy 250.729356 -48.175337) (xy 250.7216 -48.121389) (xy 250.721114 -48.094138) (xy 250.721234 -48.080693)
			(xy 250.72314 -48.053871) (xy 250.724924 -48.040544) (xy 250.726702 -48.027336) (xy 250.717304 -48.002952)
			(xy 250.629928 -47.930562) (xy 250.60402 -47.92599) (xy 250.59132 -47.930308) (xy 250.544796 -47.945523)
			(xy 250.449269 -47.966891) (xy 250.351974 -47.977642) (xy 250.30303 -47.978314) (xy 250.261878 -47.97783)
			(xy 250.179925 -47.970238) (xy 250.099025 -47.955107) (xy 250.019868 -47.932566) (xy 249.943132 -47.902808)
			(xy 249.869474 -47.866088) (xy 249.799524 -47.82272) (xy 249.733879 -47.773075) (xy 249.673102 -47.717576)
			(xy 249.617713 -47.656701) (xy 249.568184 -47.590968) (xy 249.524941 -47.52094) (xy 249.506232 -47.484284)
			(xy 249.501673 -47.476099) (xy 249.487865 -47.46346) (xy 249.479308 -47.459646) (xy 249.45086 -47.44847)
			(xy 249.442209 -47.445577) (xy 249.423985 -47.445432) (xy 249.4153 -47.448216) (xy 249.384244 -47.458544)
			(xy 249.319752 -47.469658) (xy 249.28703 -47.470314) (xy 249.259776 -47.469841) (xy 249.205823 -47.462087)
			(xy 249.153522 -47.446734) (xy 249.103939 -47.424094) (xy 249.058083 -47.394627) (xy 249.016887 -47.358934)
			(xy 248.981191 -47.317741) (xy 248.951721 -47.271887) (xy 248.929076 -47.222306) (xy 248.913719 -47.170006)
			(xy 248.905961 -47.116054) (xy 242.383564 -47.116054) (xy 242.383564 -47.23765) (xy 242.387374 -47.250858)
			(xy 242.39093 -47.256954) (xy 242.394436 -47.263059) (xy 242.398309 -47.276589) (xy 242.39855 -47.283624)
			(xy 242.39855 -52.008532) (xy 242.39898 -52.018598) (xy 242.406709 -52.03719) (xy 242.413536 -52.0446)
			(xy 242.497883 -52.128947) (xy 243.816428 -52.128947) (xy 243.816428 -52.074453) (xy 243.824183 -52.020515)
			(xy 243.839535 -51.968229) (xy 243.862172 -51.918659) (xy 243.891632 -51.872816) (xy 243.927316 -51.831632)
			(xy 243.968498 -51.795945) (xy 244.01434 -51.766482) (xy 244.063908 -51.743843) (xy 244.116193 -51.728488)
			(xy 244.170131 -51.72073) (xy 244.197378 -51.720242) (xy 244.223757 -51.720681) (xy 244.276014 -51.727943)
			(xy 244.326772 -51.742331) (xy 244.375066 -51.763572) (xy 244.419975 -51.79126) (xy 244.460644 -51.824869)
			(xy 244.496297 -51.863757) (xy 244.526255 -51.907184) (xy 244.5385 -51.930554) (xy 244.545202 -51.942913)
			(xy 244.564177 -51.963641) (xy 244.588091 -51.978403) (xy 244.615127 -51.986075) (xy 244.643229 -51.986075)
			(xy 244.670265 -51.978403) (xy 244.694179 -51.963641) (xy 244.713154 -51.942913) (xy 244.719856 -51.930554)
			(xy 244.732095 -51.907182) (xy 244.762059 -51.86376) (xy 244.797716 -51.824876) (xy 244.838386 -51.791271)
			(xy 244.883295 -51.763585) (xy 244.931588 -51.742344) (xy 244.982345 -51.727954) (xy 245.034599 -51.720689)
			(xy 245.060978 -51.720242) (xy 245.088235 -51.720603) (xy 245.142196 -51.728359) (xy 245.194503 -51.743715)
			(xy 245.244093 -51.766359) (xy 245.289955 -51.795831) (xy 245.331155 -51.831529) (xy 245.366856 -51.872728)
			(xy 245.39633 -51.918588) (xy 245.418977 -51.968176) (xy 245.434336 -52.020483) (xy 245.442095 -52.074443)
			(xy 245.442095 -52.128957) (xy 245.434336 -52.182917) (xy 245.418977 -52.235224) (xy 245.39633 -52.284812)
			(xy 245.366856 -52.330672) (xy 245.331155 -52.371871) (xy 245.289955 -52.407569) (xy 245.244093 -52.437041)
			(xy 245.194503 -52.459685) (xy 245.142196 -52.475041) (xy 245.088235 -52.482797) (xy 245.060978 -52.483258)
			(xy 245.0346 -52.482773) (xy 244.982346 -52.475519) (xy 244.931588 -52.461138) (xy 244.883295 -52.439904)
			(xy 244.838386 -52.412222) (xy 244.797716 -52.378619) (xy 244.762062 -52.339736) (xy 244.732101 -52.296313)
			(xy 244.719856 -52.272946) (xy 244.713154 -52.260587) (xy 244.694179 -52.239859) (xy 244.670265 -52.225097)
			(xy 244.643229 -52.217425) (xy 244.615127 -52.217425) (xy 244.588091 -52.225097) (xy 244.564177 -52.239859)
			(xy 244.545202 -52.260587) (xy 244.5385 -52.272946) (xy 244.526294 -52.296336) (xy 244.496326 -52.339759)
			(xy 244.460664 -52.378643) (xy 244.41999 -52.412247) (xy 244.375076 -52.439931) (xy 244.326778 -52.461168)
			(xy 244.276017 -52.475554) (xy 244.223758 -52.482814) (xy 244.197378 -52.483258) (xy 244.170131 -52.48267)
			(xy 244.116193 -52.474912) (xy 244.063908 -52.459557) (xy 244.01434 -52.436918) (xy 243.968498 -52.407455)
			(xy 243.927316 -52.371768) (xy 243.891632 -52.330584) (xy 243.862172 -52.284741) (xy 243.839535 -52.235171)
			(xy 243.824183 -52.182885) (xy 243.816428 -52.128947) (xy 242.497883 -52.128947) (xy 243.230908 -52.861972)
			(xy 243.238306 -52.86882) (xy 243.256904 -52.876556) (xy 243.266976 -52.876958)
		)
		(stroke
			(width 0)
			(type solid)
		)
		(fill yes)
		(layer "In15.Cu")
		(net "P12V_E1S_0")
	)
	(gr_poly
		(pts
			(xy 230.599234 -55.063644) (xy 230.604314 -55.047642) (xy 230.613489 -55.020924) (xy 230.638602 -54.970325)
			(xy 230.670904 -54.923983) (xy 230.709686 -54.882911) (xy 230.754101 -54.848007) (xy 230.803178 -54.820035)
			(xy 230.855844 -54.799606) (xy 230.910946 -54.787168) (xy 230.96728 -54.782991) (xy 231.023614 -54.787168)
			(xy 231.078716 -54.799606) (xy 231.131382 -54.820035) (xy 231.180459 -54.848007) (xy 231.224874 -54.882911)
			(xy 231.263656 -54.923983) (xy 231.295958 -54.970325) (xy 231.321071 -55.020924) (xy 231.330246 -55.047642)
			(xy 231.335326 -55.063644) (xy 231.361996 -55.082948) (xy 237.221522 -55.082948) (xy 237.248192 -55.063644)
			(xy 237.253272 -55.047642) (xy 237.262447 -55.020924) (xy 237.28756 -54.970325) (xy 237.319862 -54.923983)
			(xy 237.358644 -54.882911) (xy 237.403059 -54.848007) (xy 237.452136 -54.820035) (xy 237.504802 -54.799606)
			(xy 237.559904 -54.787168) (xy 237.616238 -54.782991) (xy 237.672572 -54.787168) (xy 237.727674 -54.799606)
			(xy 237.78034 -54.820035) (xy 237.829417 -54.848007) (xy 237.873832 -54.882911) (xy 237.912614 -54.923983)
			(xy 237.944916 -54.970325) (xy 237.970029 -55.020924) (xy 237.979204 -55.047642) (xy 237.984284 -55.063644)
			(xy 238.010954 -55.082948) (xy 240.780316 -55.082948) (xy 240.790384 -55.08252) (xy 240.808979 -55.074796)
			(xy 240.816384 -55.067962) (xy 241.042444 -54.841902) (xy 241.049297 -54.834506) (xy 241.057041 -54.815908)
			(xy 241.05743 -54.805834) (xy 241.05743 -47.339758) (xy 241.057 -47.329691) (xy 241.049278 -47.311094)
			(xy 241.042444 -47.30369) (xy 240.708688 -46.969934) (xy 240.70129 -46.963086) (xy 240.682692 -46.95535)
			(xy 240.67262 -46.954948) (xy 238.200184 -46.954948) (xy 238.188567 -46.95553) (xy 238.167691 -46.965731)
			(xy 238.160052 -46.974506) (xy 238.143299 -46.99525) (xy 238.104961 -47.032308) (xy 238.061835 -47.063666)
			(xy 238.014763 -47.088712) (xy 237.964661 -47.10696) (xy 237.912507 -47.118052) (xy 237.859316 -47.121774)
			(xy 237.806125 -47.118052) (xy 237.753971 -47.10696) (xy 237.703869 -47.088712) (xy 237.656797 -47.063666)
			(xy 237.613671 -47.032308) (xy 237.575333 -46.99525) (xy 237.55858 -46.974506) (xy 237.550994 -46.965665)
			(xy 237.530084 -46.955457) (xy 237.518448 -46.954948) (xy 233.375454 -46.954948) (xy 233.362833 -46.955544)
			(xy 233.340564 -46.967408) (xy 233.333036 -46.977554) (xy 233.317781 -46.999478) (xy 233.282119 -47.039241)
			(xy 233.241259 -47.073639) (xy 233.196 -47.102002) (xy 233.147227 -47.123774) (xy 233.095893 -47.13853)
			(xy 233.043004 -47.14598) (xy 232.989592 -47.14598) (xy 232.936703 -47.13853) (xy 232.885369 -47.123774)
			(xy 232.836596 -47.102002) (xy 232.791337 -47.073639) (xy 232.750477 -47.039241) (xy 232.714815 -46.999478)
			(xy 232.69956 -46.977554) (xy 232.691993 -46.967456) (xy 232.669745 -46.955613) (xy 232.657142 -46.954948)
			(xy 227.478082 -46.954948) (xy 227.468014 -46.95452) (xy 227.44942 -46.946795) (xy 227.442014 -46.939962)
			(xy 226.201986 -45.699934) (xy 226.195141 -45.692536) (xy 226.187417 -45.673937) (xy 226.187 -45.663866)
			(xy 226.187 -41.64203) (xy 226.186564 -41.631965) (xy 226.178832 -41.61338) (xy 226.172014 -41.605962)
			(xy 225.566986 -41.000934) (xy 225.559874 -40.993568) (xy 225.541078 -40.985948) (xy 220.493082 -40.985948)
			(xy 220.483014 -40.986376) (xy 220.464419 -40.9941) (xy 220.457014 -41.000934) (xy 219.837 -41.620948)
			(xy 221.688912 -41.620948) (xy 221.692983 -41.565326) (xy 221.705109 -41.510889) (xy 221.725032 -41.458798)
			(xy 221.752328 -41.410163) (xy 221.786414 -41.36602) (xy 221.826563 -41.327311) (xy 221.871921 -41.29486)
			(xy 221.921521 -41.269359) (xy 221.974305 -41.251352) (xy 222.029148 -41.241222) (xy 222.084882 -41.239185)
			(xy 222.140319 -41.245285) (xy 222.194276 -41.259391) (xy 222.245605 -41.281203) (xy 222.293211 -41.310257)
			(xy 222.336079 -41.345932) (xy 222.373296 -41.387469) (xy 222.404069 -41.433982) (xy 222.427741 -41.484479)
			(xy 222.443809 -41.537886) (xy 222.451929 -41.593062) (xy 222.452438 -41.620948) (xy 222.451929 -41.648834)
			(xy 222.443809 -41.70401) (xy 222.427741 -41.757417) (xy 222.404069 -41.807914) (xy 222.373296 -41.854427)
			(xy 222.336079 -41.895964) (xy 222.293211 -41.931639) (xy 222.245605 -41.960693) (xy 222.194276 -41.982505)
			(xy 222.140319 -41.996611) (xy 222.084882 -42.002711) (xy 222.029148 -42.000674) (xy 221.974305 -41.990544)
			(xy 221.921521 -41.972537) (xy 221.871921 -41.947036) (xy 221.826563 -41.914585) (xy 221.786414 -41.875876)
			(xy 221.752328 -41.831733) (xy 221.725032 -41.783098) (xy 221.705109 -41.731007) (xy 221.692983 -41.67657)
			(xy 221.688912 -41.620948) (xy 219.837 -41.620948) (xy 219.724986 -41.732962) (xy 219.71762 -41.740074)
			(xy 219.71 -41.75887) (xy 219.71 -43.525948) (xy 225.048316 -43.525948) (xy 225.052387 -43.470326)
			(xy 225.064513 -43.415889) (xy 225.084436 -43.363798) (xy 225.111732 -43.315163) (xy 225.145818 -43.27102)
			(xy 225.185967 -43.232311) (xy 225.231325 -43.19986) (xy 225.280925 -43.174359) (xy 225.333709 -43.156352)
			(xy 225.388552 -43.146222) (xy 225.444286 -43.144185) (xy 225.499723 -43.150285) (xy 225.55368 -43.164391)
			(xy 225.605009 -43.186203) (xy 225.652615 -43.215257) (xy 225.695483 -43.250932) (xy 225.7327 -43.292469)
			(xy 225.763473 -43.338982) (xy 225.787145 -43.389479) (xy 225.803213 -43.442886) (xy 225.811333 -43.498062)
			(xy 225.811842 -43.525948) (xy 225.811333 -43.553834) (xy 225.803213 -43.60901) (xy 225.787145 -43.662417)
			(xy 225.763473 -43.712914) (xy 225.7327 -43.759427) (xy 225.695483 -43.800964) (xy 225.652615 -43.836639)
			(xy 225.605009 -43.865693) (xy 225.55368 -43.887505) (xy 225.499723 -43.901611) (xy 225.444286 -43.907711)
			(xy 225.388552 -43.905674) (xy 225.333709 -43.895544) (xy 225.280925 -43.877537) (xy 225.231325 -43.852036)
			(xy 225.185967 -43.819585) (xy 225.145818 -43.780876) (xy 225.111732 -43.736733) (xy 225.084436 -43.688098)
			(xy 225.064513 -43.636007) (xy 225.052387 -43.58157) (xy 225.048316 -43.525948) (xy 219.71 -43.525948)
			(xy 219.71 -44.922948) (xy 225.048316 -44.922948) (xy 225.052387 -44.867326) (xy 225.064513 -44.812889)
			(xy 225.084436 -44.760798) (xy 225.111732 -44.712163) (xy 225.145818 -44.66802) (xy 225.185967 -44.629311)
			(xy 225.231325 -44.59686) (xy 225.280925 -44.571359) (xy 225.333709 -44.553352) (xy 225.388552 -44.543222)
			(xy 225.444286 -44.541185) (xy 225.499723 -44.547285) (xy 225.55368 -44.561391) (xy 225.605009 -44.583203)
			(xy 225.652615 -44.612257) (xy 225.695483 -44.647932) (xy 225.7327 -44.689469) (xy 225.763473 -44.735982)
			(xy 225.787145 -44.786479) (xy 225.803213 -44.839886) (xy 225.811333 -44.895062) (xy 225.811842 -44.922948)
			(xy 225.811333 -44.950834) (xy 225.803213 -45.00601) (xy 225.787145 -45.059417) (xy 225.763473 -45.109914)
			(xy 225.7327 -45.156427) (xy 225.695483 -45.197964) (xy 225.652615 -45.233639) (xy 225.605009 -45.262693)
			(xy 225.55368 -45.284505) (xy 225.499723 -45.298611) (xy 225.444286 -45.304711) (xy 225.388552 -45.302674)
			(xy 225.333709 -45.292544) (xy 225.280925 -45.274537) (xy 225.231325 -45.249036) (xy 225.185967 -45.216585)
			(xy 225.145818 -45.177876) (xy 225.111732 -45.133733) (xy 225.084436 -45.085098) (xy 225.064513 -45.033007)
			(xy 225.052387 -44.97857) (xy 225.048316 -44.922948) (xy 219.71 -44.922948) (xy 219.71 -46.524926)
			(xy 224.949002 -46.524926) (xy 224.953073 -46.469304) (xy 224.965199 -46.414867) (xy 224.985122 -46.362776)
			(xy 225.012418 -46.314141) (xy 225.046504 -46.269998) (xy 225.086653 -46.231289) (xy 225.132011 -46.198838)
			(xy 225.181611 -46.173337) (xy 225.234395 -46.15533) (xy 225.289238 -46.1452) (xy 225.344972 -46.143163)
			(xy 225.400409 -46.149263) (xy 225.454366 -46.163369) (xy 225.505695 -46.185181) (xy 225.553301 -46.214235)
			(xy 225.596169 -46.24991) (xy 225.633386 -46.291447) (xy 225.664159 -46.33796) (xy 225.687831 -46.388457)
			(xy 225.703899 -46.441864) (xy 225.712019 -46.49704) (xy 225.712528 -46.524926) (xy 225.712019 -46.552812)
			(xy 225.703899 -46.607988) (xy 225.687831 -46.661395) (xy 225.664159 -46.711892) (xy 225.633386 -46.758405)
			(xy 225.596169 -46.799942) (xy 225.553301 -46.835617) (xy 225.505695 -46.864671) (xy 225.454366 -46.886483)
			(xy 225.400409 -46.900589) (xy 225.344972 -46.906689) (xy 225.289238 -46.904652) (xy 225.234395 -46.894522)
			(xy 225.181611 -46.876515) (xy 225.132011 -46.851014) (xy 225.086653 -46.818563) (xy 225.046504 -46.779854)
			(xy 225.012418 -46.735711) (xy 224.985122 -46.687076) (xy 224.965199 -46.634985) (xy 224.953073 -46.580548)
			(xy 224.949002 -46.524926) (xy 219.71 -46.524926) (xy 219.71 -47.018702) (xy 221.911162 -47.018702)
			(xy 221.915233 -46.96308) (xy 221.927359 -46.908643) (xy 221.947282 -46.856552) (xy 221.974578 -46.807917)
			(xy 222.008664 -46.763774) (xy 222.048813 -46.725065) (xy 222.094171 -46.692614) (xy 222.143771 -46.667113)
			(xy 222.196555 -46.649106) (xy 222.251398 -46.638976) (xy 222.307132 -46.636939) (xy 222.362569 -46.643039)
			(xy 222.416526 -46.657145) (xy 222.467855 -46.678957) (xy 222.515461 -46.708011) (xy 222.558329 -46.743686)
			(xy 222.595546 -46.785223) (xy 222.626319 -46.831736) (xy 222.649991 -46.882233) (xy 222.666059 -46.93564)
			(xy 222.674179 -46.990816) (xy 222.674688 -47.018702) (xy 222.674179 -47.046588) (xy 222.666059 -47.101764)
			(xy 222.649991 -47.155171) (xy 222.626319 -47.205668) (xy 222.595546 -47.252181) (xy 222.558329 -47.293718)
			(xy 222.515461 -47.329393) (xy 222.467855 -47.358447) (xy 222.416526 -47.380259) (xy 222.362569 -47.394365)
			(xy 222.307132 -47.400465) (xy 222.251398 -47.398428) (xy 222.196555 -47.388298) (xy 222.143771 -47.370291)
			(xy 222.094171 -47.34479) (xy 222.048813 -47.312339) (xy 222.008664 -47.27363) (xy 221.974578 -47.229487)
			(xy 221.947282 -47.180852) (xy 221.927359 -47.128761) (xy 221.915233 -47.074324) (xy 221.911162 -47.018702)
			(xy 219.71 -47.018702) (xy 219.71 -47.980346) (xy 230.407716 -47.980346) (xy 230.411787 -47.924724)
			(xy 230.423913 -47.870287) (xy 230.443836 -47.818196) (xy 230.471132 -47.769561) (xy 230.505218 -47.725418)
			(xy 230.545367 -47.686709) (xy 230.590725 -47.654258) (xy 230.640325 -47.628757) (xy 230.693109 -47.61075)
			(xy 230.747952 -47.60062) (xy 230.803686 -47.598583) (xy 230.859123 -47.604683) (xy 230.91308 -47.618789)
			(xy 230.964409 -47.640601) (xy 231.012015 -47.669655) (xy 231.054883 -47.70533) (xy 231.0921 -47.746867)
			(xy 231.122873 -47.79338) (xy 231.146545 -47.843877) (xy 231.162613 -47.897284) (xy 231.170733 -47.95246)
			(xy 231.171242 -47.980346) (xy 231.170733 -48.008232) (xy 231.162613 -48.063408) (xy 231.150387 -48.104044)
			(xy 235.110018 -48.104044) (xy 235.114089 -48.048422) (xy 235.126215 -47.993985) (xy 235.146138 -47.941894)
			(xy 235.173434 -47.893259) (xy 235.20752 -47.849116) (xy 235.247669 -47.810407) (xy 235.293027 -47.777956)
			(xy 235.342627 -47.752455) (xy 235.395411 -47.734448) (xy 235.450254 -47.724318) (xy 235.505988 -47.722281)
			(xy 235.561425 -47.728381) (xy 235.615382 -47.742487) (xy 235.666711 -47.764299) (xy 235.714317 -47.793353)
			(xy 235.757185 -47.829028) (xy 235.794402 -47.870565) (xy 235.825175 -47.917078) (xy 235.848847 -47.967575)
			(xy 235.861172 -48.00854) (xy 237.6838 -48.00854) (xy 237.687871 -47.952918) (xy 237.699997 -47.898481)
			(xy 237.71992 -47.84639) (xy 237.747216 -47.797755) (xy 237.781302 -47.753612) (xy 237.821451 -47.714903)
			(xy 237.866809 -47.682452) (xy 237.916409 -47.656951) (xy 237.969193 -47.638944) (xy 238.024036 -47.628814)
			(xy 238.07977 -47.626777) (xy 238.135207 -47.632877) (xy 238.189164 -47.646983) (xy 238.240493 -47.668795)
			(xy 238.288099 -47.697849) (xy 238.330967 -47.733524) (xy 238.368184 -47.775061) (xy 238.398957 -47.821574)
			(xy 238.422629 -47.872071) (xy 238.438697 -47.925478) (xy 238.446817 -47.980654) (xy 238.447326 -48.00854)
			(xy 238.446817 -48.036426) (xy 238.438697 -48.091602) (xy 238.422629 -48.145009) (xy 238.398957 -48.195506)
			(xy 238.368184 -48.242019) (xy 238.330967 -48.283556) (xy 238.288099 -48.319231) (xy 238.240493 -48.348285)
			(xy 238.189164 -48.370097) (xy 238.135207 -48.384203) (xy 238.07977 -48.390303) (xy 238.024036 -48.388266)
			(xy 237.969193 -48.378136) (xy 237.916409 -48.360129) (xy 237.866809 -48.334628) (xy 237.821451 -48.302177)
			(xy 237.781302 -48.263468) (xy 237.747216 -48.219325) (xy 237.71992 -48.17069) (xy 237.699997 -48.118599)
			(xy 237.687871 -48.064162) (xy 237.6838 -48.00854) (xy 235.861172 -48.00854) (xy 235.864915 -48.020982)
			(xy 235.873035 -48.076158) (xy 235.873544 -48.104044) (xy 235.873035 -48.13193) (xy 235.864915 -48.187106)
			(xy 235.848847 -48.240513) (xy 235.825175 -48.29101) (xy 235.794402 -48.337523) (xy 235.757185 -48.37906)
			(xy 235.714317 -48.414735) (xy 235.666711 -48.443789) (xy 235.615382 -48.465601) (xy 235.561425 -48.479707)
			(xy 235.505988 -48.485807) (xy 235.450254 -48.48377) (xy 235.395411 -48.47364) (xy 235.342627 -48.455633)
			(xy 235.293027 -48.430132) (xy 235.247669 -48.397681) (xy 235.20752 -48.358972) (xy 235.173434 -48.314829)
			(xy 235.146138 -48.266194) (xy 235.126215 -48.214103) (xy 235.114089 -48.159666) (xy 235.110018 -48.104044)
			(xy 231.150387 -48.104044) (xy 231.146545 -48.116815) (xy 231.122873 -48.167312) (xy 231.0921 -48.213825)
			(xy 231.054883 -48.255362) (xy 231.012015 -48.291037) (xy 230.964409 -48.320091) (xy 230.91308 -48.341903)
			(xy 230.859123 -48.356009) (xy 230.803686 -48.362109) (xy 230.747952 -48.360072) (xy 230.693109 -48.349942)
			(xy 230.640325 -48.331935) (xy 230.590725 -48.306434) (xy 230.545367 -48.273983) (xy 230.505218 -48.235274)
			(xy 230.471132 -48.191131) (xy 230.443836 -48.142496) (xy 230.423913 -48.090405) (xy 230.411787 -48.035968)
			(xy 230.407716 -47.980346) (xy 219.71 -47.980346) (xy 219.71 -48.78197) (xy 222.686116 -48.78197)
			(xy 222.690187 -48.726348) (xy 222.702313 -48.671911) (xy 222.722236 -48.61982) (xy 222.749532 -48.571185)
			(xy 222.783618 -48.527042) (xy 222.823767 -48.488333) (xy 222.869125 -48.455882) (xy 222.918725 -48.430381)
			(xy 222.971509 -48.412374) (xy 223.026352 -48.402244) (xy 223.082086 -48.400207) (xy 223.137523 -48.406307)
			(xy 223.19148 -48.420413) (xy 223.242809 -48.442225) (xy 223.290415 -48.471279) (xy 223.333283 -48.506954)
			(xy 223.3705 -48.548491) (xy 223.401273 -48.595004) (xy 223.424945 -48.645501) (xy 223.441013 -48.698908)
			(xy 223.449133 -48.754084) (xy 223.449642 -48.78197) (xy 223.449133 -48.809856) (xy 223.441013 -48.865032)
			(xy 223.424945 -48.918439) (xy 223.401273 -48.968936) (xy 223.3705 -49.015449) (xy 223.333283 -49.056986)
			(xy 223.290415 -49.092661) (xy 223.242809 -49.121715) (xy 223.19148 -49.143527) (xy 223.137523 -49.157633)
			(xy 223.082086 -49.163733) (xy 223.026352 -49.161696) (xy 222.971509 -49.151566) (xy 222.918725 -49.133559)
			(xy 222.869125 -49.108058) (xy 222.823767 -49.075607) (xy 222.783618 -49.036898) (xy 222.749532 -48.992755)
			(xy 222.722236 -48.94412) (xy 222.702313 -48.892029) (xy 222.690187 -48.837592) (xy 222.686116 -48.78197)
			(xy 219.71 -48.78197) (xy 219.71 -49.165002) (xy 234.158026 -49.165002) (xy 234.162097 -49.10938)
			(xy 234.174223 -49.054943) (xy 234.194146 -49.002852) (xy 234.221442 -48.954217) (xy 234.255528 -48.910074)
			(xy 234.295677 -48.871365) (xy 234.341035 -48.838914) (xy 234.390635 -48.813413) (xy 234.443419 -48.795406)
			(xy 234.498262 -48.785276) (xy 234.553996 -48.783239) (xy 234.609433 -48.789339) (xy 234.66339 -48.803445)
			(xy 234.714719 -48.825257) (xy 234.762325 -48.854311) (xy 234.805193 -48.889986) (xy 234.84241 -48.931523)
			(xy 234.873183 -48.978036) (xy 234.896855 -49.028533) (xy 234.912923 -49.08194) (xy 234.91397 -49.089056)
			(xy 239.678462 -49.089056) (xy 239.682533 -49.033434) (xy 239.694659 -48.978997) (xy 239.714582 -48.926906)
			(xy 239.741878 -48.878271) (xy 239.775964 -48.834128) (xy 239.816113 -48.795419) (xy 239.861471 -48.762968)
			(xy 239.911071 -48.737467) (xy 239.963855 -48.71946) (xy 240.018698 -48.70933) (xy 240.074432 -48.707293)
			(xy 240.129869 -48.713393) (xy 240.183826 -48.727499) (xy 240.235155 -48.749311) (xy 240.282761 -48.778365)
			(xy 240.325629 -48.81404) (xy 240.362846 -48.855577) (xy 240.393619 -48.90209) (xy 240.417291 -48.952587)
			(xy 240.433359 -49.005994) (xy 240.441479 -49.06117) (xy 240.441988 -49.089056) (xy 240.441479 -49.116942)
			(xy 240.433359 -49.172118) (xy 240.417291 -49.225525) (xy 240.393619 -49.276022) (xy 240.362846 -49.322535)
			(xy 240.325629 -49.364072) (xy 240.282761 -49.399747) (xy 240.235155 -49.428801) (xy 240.183826 -49.450613)
			(xy 240.129869 -49.464719) (xy 240.074432 -49.470819) (xy 240.018698 -49.468782) (xy 239.963855 -49.458652)
			(xy 239.911071 -49.440645) (xy 239.861471 -49.415144) (xy 239.816113 -49.382693) (xy 239.775964 -49.343984)
			(xy 239.741878 -49.299841) (xy 239.714582 -49.251206) (xy 239.694659 -49.199115) (xy 239.682533 -49.144678)
			(xy 239.678462 -49.089056) (xy 234.91397 -49.089056) (xy 234.921043 -49.137116) (xy 234.921552 -49.165002)
			(xy 234.921043 -49.192888) (xy 234.912923 -49.248064) (xy 234.896855 -49.301471) (xy 234.873183 -49.351968)
			(xy 234.84241 -49.398481) (xy 234.805193 -49.440018) (xy 234.762325 -49.475693) (xy 234.714719 -49.504747)
			(xy 234.66339 -49.526559) (xy 234.609433 -49.540665) (xy 234.553996 -49.546765) (xy 234.498262 -49.544728)
			(xy 234.443419 -49.534598) (xy 234.390635 -49.516591) (xy 234.341035 -49.49109) (xy 234.295677 -49.458639)
			(xy 234.255528 -49.41993) (xy 234.221442 -49.375787) (xy 234.194146 -49.327152) (xy 234.174223 -49.275061)
			(xy 234.162097 -49.220624) (xy 234.158026 -49.165002) (xy 219.71 -49.165002) (xy 219.71 -49.654206)
			(xy 225.513136 -49.654206) (xy 225.517207 -49.598584) (xy 225.529333 -49.544147) (xy 225.549256 -49.492056)
			(xy 225.576552 -49.443421) (xy 225.610638 -49.399278) (xy 225.650787 -49.360569) (xy 225.696145 -49.328118)
			(xy 225.745745 -49.302617) (xy 225.798529 -49.28461) (xy 225.853372 -49.27448) (xy 225.909106 -49.272443)
			(xy 225.964543 -49.278543) (xy 226.0185 -49.292649) (xy 226.069829 -49.314461) (xy 226.117435 -49.343515)
			(xy 226.160303 -49.37919) (xy 226.19752 -49.420727) (xy 226.228293 -49.46724) (xy 226.251965 -49.517737)
			(xy 226.268033 -49.571144) (xy 226.276153 -49.62632) (xy 226.276662 -49.654206) (xy 226.276153 -49.682092)
			(xy 226.268033 -49.737268) (xy 226.259705 -49.76495) (xy 230.579674 -49.76495) (xy 230.583745 -49.709328)
			(xy 230.595871 -49.654891) (xy 230.615794 -49.6028) (xy 230.64309 -49.554165) (xy 230.677176 -49.510022)
			(xy 230.717325 -49.471313) (xy 230.762683 -49.438862) (xy 230.812283 -49.413361) (xy 230.865067 -49.395354)
			(xy 230.91991 -49.385224) (xy 230.975644 -49.383187) (xy 231.031081 -49.389287) (xy 231.085038 -49.403393)
			(xy 231.136367 -49.425205) (xy 231.183973 -49.454259) (xy 231.226841 -49.489934) (xy 231.264058 -49.531471)
			(xy 231.294831 -49.577984) (xy 231.318503 -49.628481) (xy 231.334571 -49.681888) (xy 231.342691 -49.737064)
			(xy 231.3432 -49.76495) (xy 237.23422 -49.76495) (xy 237.238291 -49.709328) (xy 237.250417 -49.654891)
			(xy 237.27034 -49.6028) (xy 237.297636 -49.554165) (xy 237.331722 -49.510022) (xy 237.371871 -49.471313)
			(xy 237.417229 -49.438862) (xy 237.466829 -49.413361) (xy 237.519613 -49.395354) (xy 237.574456 -49.385224)
			(xy 237.63019 -49.383187) (xy 237.685627 -49.389287) (xy 237.739584 -49.403393) (xy 237.790913 -49.425205)
			(xy 237.838519 -49.454259) (xy 237.881387 -49.489934) (xy 237.918604 -49.531471) (xy 237.949377 -49.577984)
			(xy 237.973049 -49.628481) (xy 237.989117 -49.681888) (xy 237.997237 -49.737064) (xy 237.997746 -49.76495)
			(xy 237.997237 -49.792836) (xy 237.989117 -49.848012) (xy 237.973049 -49.901419) (xy 237.949377 -49.951916)
			(xy 237.918604 -49.998429) (xy 237.881387 -50.039966) (xy 237.838519 -50.075641) (xy 237.790913 -50.104695)
			(xy 237.739584 -50.126507) (xy 237.685627 -50.140613) (xy 237.63019 -50.146713) (xy 237.574456 -50.144676)
			(xy 237.519613 -50.134546) (xy 237.466829 -50.116539) (xy 237.417229 -50.091038) (xy 237.371871 -50.058587)
			(xy 237.331722 -50.019878) (xy 237.297636 -49.975735) (xy 237.27034 -49.9271) (xy 237.250417 -49.875009)
			(xy 237.238291 -49.820572) (xy 237.23422 -49.76495) (xy 231.3432 -49.76495) (xy 231.342691 -49.792836)
			(xy 231.334571 -49.848012) (xy 231.318503 -49.901419) (xy 231.294831 -49.951916) (xy 231.264058 -49.998429)
			(xy 231.226841 -50.039966) (xy 231.183973 -50.075641) (xy 231.136367 -50.104695) (xy 231.085038 -50.126507)
			(xy 231.031081 -50.140613) (xy 230.975644 -50.146713) (xy 230.91991 -50.144676) (xy 230.865067 -50.134546)
			(xy 230.812283 -50.116539) (xy 230.762683 -50.091038) (xy 230.717325 -50.058587) (xy 230.677176 -50.019878)
			(xy 230.64309 -49.975735) (xy 230.615794 -49.9271) (xy 230.595871 -49.875009) (xy 230.583745 -49.820572)
			(xy 230.579674 -49.76495) (xy 226.259705 -49.76495) (xy 226.251965 -49.790675) (xy 226.228293 -49.841172)
			(xy 226.19752 -49.887685) (xy 226.160303 -49.929222) (xy 226.117435 -49.964897) (xy 226.069829 -49.993951)
			(xy 226.0185 -50.015763) (xy 225.964543 -50.029869) (xy 225.909106 -50.035969) (xy 225.853372 -50.033932)
			(xy 225.798529 -50.023802) (xy 225.745745 -50.005795) (xy 225.696145 -49.980294) (xy 225.650787 -49.947843)
			(xy 225.610638 -49.909134) (xy 225.576552 -49.864991) (xy 225.549256 -49.816356) (xy 225.529333 -49.764265)
			(xy 225.517207 -49.709828) (xy 225.513136 -49.654206) (xy 219.71 -49.654206) (xy 219.71 -50.534527)
			(xy 224.278438 -50.534527) (xy 224.278438 -50.470605) (xy 224.286449 -50.407187) (xy 224.302346 -50.345273)
			(xy 224.325878 -50.28584) (xy 224.356672 -50.229825) (xy 224.394245 -50.17811) (xy 224.438002 -50.131513)
			(xy 224.487255 -50.090768) (xy 224.541226 -50.056517) (xy 224.599065 -50.0293) (xy 224.659858 -50.009547)
			(xy 224.722648 -49.997569) (xy 224.786444 -49.993556) (xy 224.85024 -49.997569) (xy 224.91303 -50.009547)
			(xy 224.973823 -50.0293) (xy 225.031662 -50.056517) (xy 225.085633 -50.090768) (xy 225.134886 -50.131513)
			(xy 225.178643 -50.17811) (xy 225.216216 -50.229825) (xy 225.24701 -50.28584) (xy 225.270542 -50.345273)
			(xy 225.286439 -50.407187) (xy 225.29445 -50.470605) (xy 225.294952 -50.502566) (xy 225.29445 -50.534527)
			(xy 225.286439 -50.597945) (xy 225.270542 -50.659859) (xy 225.24701 -50.719292) (xy 225.216216 -50.775307)
			(xy 225.178643 -50.827022) (xy 225.134886 -50.873619) (xy 225.085633 -50.914364) (xy 225.031662 -50.948615)
			(xy 224.973823 -50.975832) (xy 224.91303 -50.995585) (xy 224.85024 -51.007563) (xy 224.786444 -51.011577)
			(xy 224.722648 -51.007563) (xy 224.659858 -50.995585) (xy 224.599065 -50.975832) (xy 224.541226 -50.948615)
			(xy 224.487255 -50.914364) (xy 224.438002 -50.873619) (xy 224.394245 -50.827022) (xy 224.356672 -50.775307)
			(xy 224.325878 -50.719292) (xy 224.302346 -50.659859) (xy 224.286449 -50.597945) (xy 224.278438 -50.534527)
			(xy 219.71 -50.534527) (xy 219.71 -51.124866) (xy 219.710435 -51.134931) (xy 219.718167 -51.153518)
			(xy 219.724986 -51.160934) (xy 220.1291 -51.565048) (xy 230.544876 -51.565048) (xy 230.548947 -51.509426)
			(xy 230.561073 -51.454989) (xy 230.580996 -51.402898) (xy 230.608292 -51.354263) (xy 230.642378 -51.31012)
			(xy 230.682527 -51.271411) (xy 230.727885 -51.23896) (xy 230.777485 -51.213459) (xy 230.830269 -51.195452)
			(xy 230.885112 -51.185322) (xy 230.940846 -51.183285) (xy 230.996283 -51.189385) (xy 231.05024 -51.203491)
			(xy 231.101569 -51.225303) (xy 231.149175 -51.254357) (xy 231.192043 -51.290032) (xy 231.22926 -51.331569)
			(xy 231.260033 -51.378082) (xy 231.283705 -51.428579) (xy 231.299773 -51.481986) (xy 231.307893 -51.537162)
			(xy 231.308402 -51.565048) (xy 231.307893 -51.592934) (xy 231.299773 -51.64811) (xy 231.295189 -51.663346)
			(xy 234.649516 -51.663346) (xy 234.653587 -51.607724) (xy 234.665713 -51.553287) (xy 234.685636 -51.501196)
			(xy 234.712932 -51.452561) (xy 234.747018 -51.408418) (xy 234.787167 -51.369709) (xy 234.832525 -51.337258)
			(xy 234.882125 -51.311757) (xy 234.934909 -51.29375) (xy 234.989752 -51.28362) (xy 235.045486 -51.281583)
			(xy 235.100923 -51.287683) (xy 235.15488 -51.301789) (xy 235.206209 -51.323601) (xy 235.253815 -51.352655)
			(xy 235.296683 -51.38833) (xy 235.3339 -51.429867) (xy 235.364673 -51.47638) (xy 235.388345 -51.526877)
			(xy 235.399829 -51.565048) (xy 237.23422 -51.565048) (xy 237.238291 -51.509426) (xy 237.250417 -51.454989)
			(xy 237.27034 -51.402898) (xy 237.297636 -51.354263) (xy 237.331722 -51.31012) (xy 237.371871 -51.271411)
			(xy 237.417229 -51.23896) (xy 237.466829 -51.213459) (xy 237.519613 -51.195452) (xy 237.574456 -51.185322)
			(xy 237.63019 -51.183285) (xy 237.685627 -51.189385) (xy 237.739584 -51.203491) (xy 237.790913 -51.225303)
			(xy 237.838519 -51.254357) (xy 237.881387 -51.290032) (xy 237.918604 -51.331569) (xy 237.949377 -51.378082)
			(xy 237.973049 -51.428579) (xy 237.989117 -51.481986) (xy 237.997237 -51.537162) (xy 237.997746 -51.565048)
			(xy 237.997237 -51.592934) (xy 237.989117 -51.64811) (xy 237.973049 -51.701517) (xy 237.949377 -51.752014)
			(xy 237.918604 -51.798527) (xy 237.881387 -51.840064) (xy 237.838519 -51.875739) (xy 237.790913 -51.904793)
			(xy 237.739584 -51.926605) (xy 237.685627 -51.940711) (xy 237.63019 -51.946811) (xy 237.574456 -51.944774)
			(xy 237.519613 -51.934644) (xy 237.466829 -51.916637) (xy 237.417229 -51.891136) (xy 237.371871 -51.858685)
			(xy 237.331722 -51.819976) (xy 237.297636 -51.775833) (xy 237.27034 -51.727198) (xy 237.250417 -51.675107)
			(xy 237.238291 -51.62067) (xy 237.23422 -51.565048) (xy 235.399829 -51.565048) (xy 235.404413 -51.580284)
			(xy 235.412533 -51.63546) (xy 235.413042 -51.663346) (xy 235.412533 -51.691232) (xy 235.404413 -51.746408)
			(xy 235.388345 -51.799815) (xy 235.364673 -51.850312) (xy 235.3339 -51.896825) (xy 235.296683 -51.938362)
			(xy 235.253815 -51.974037) (xy 235.206209 -52.003091) (xy 235.15488 -52.024903) (xy 235.100923 -52.039009)
			(xy 235.045486 -52.045109) (xy 234.989752 -52.043072) (xy 234.934909 -52.032942) (xy 234.882125 -52.014935)
			(xy 234.832525 -51.989434) (xy 234.787167 -51.956983) (xy 234.747018 -51.918274) (xy 234.712932 -51.874131)
			(xy 234.685636 -51.825496) (xy 234.665713 -51.773405) (xy 234.653587 -51.718968) (xy 234.649516 -51.663346)
			(xy 231.295189 -51.663346) (xy 231.283705 -51.701517) (xy 231.260033 -51.752014) (xy 231.22926 -51.798527)
			(xy 231.192043 -51.840064) (xy 231.149175 -51.875739) (xy 231.101569 -51.904793) (xy 231.05024 -51.926605)
			(xy 230.996283 -51.940711) (xy 230.940846 -51.946811) (xy 230.885112 -51.944774) (xy 230.830269 -51.934644)
			(xy 230.777485 -51.916637) (xy 230.727885 -51.891136) (xy 230.682527 -51.858685) (xy 230.642378 -51.819976)
			(xy 230.608292 -51.775833) (xy 230.580996 -51.727198) (xy 230.561073 -51.675107) (xy 230.548947 -51.62067)
			(xy 230.544876 -51.565048) (xy 220.1291 -51.565048) (xy 221.928944 -53.364892) (xy 230.585262 -53.364892)
			(xy 230.589333 -53.30927) (xy 230.601459 -53.254833) (xy 230.621382 -53.202742) (xy 230.648678 -53.154107)
			(xy 230.682764 -53.109964) (xy 230.722913 -53.071255) (xy 230.768271 -53.038804) (xy 230.817871 -53.013303)
			(xy 230.870655 -52.995296) (xy 230.925498 -52.985166) (xy 230.981232 -52.983129) (xy 231.036669 -52.989229)
			(xy 231.090626 -53.003335) (xy 231.141955 -53.025147) (xy 231.189561 -53.054201) (xy 231.232429 -53.089876)
			(xy 231.269646 -53.131413) (xy 231.300419 -53.177926) (xy 231.324091 -53.228423) (xy 231.340159 -53.28183)
			(xy 231.348279 -53.337006) (xy 231.348788 -53.364892) (xy 237.23422 -53.364892) (xy 237.238291 -53.30927)
			(xy 237.250417 -53.254833) (xy 237.27034 -53.202742) (xy 237.297636 -53.154107) (xy 237.331722 -53.109964)
			(xy 237.371871 -53.071255) (xy 237.417229 -53.038804) (xy 237.466829 -53.013303) (xy 237.519613 -52.995296)
			(xy 237.574456 -52.985166) (xy 237.63019 -52.983129) (xy 237.685627 -52.989229) (xy 237.739584 -53.003335)
			(xy 237.790913 -53.025147) (xy 237.838519 -53.054201) (xy 237.881387 -53.089876) (xy 237.918604 -53.131413)
			(xy 237.949377 -53.177926) (xy 237.973049 -53.228423) (xy 237.989117 -53.28183) (xy 237.997237 -53.337006)
			(xy 237.997746 -53.364892) (xy 237.997237 -53.392778) (xy 237.989117 -53.447954) (xy 237.973049 -53.501361)
			(xy 237.949377 -53.551858) (xy 237.918604 -53.598371) (xy 237.881387 -53.639908) (xy 237.838519 -53.675583)
			(xy 237.790913 -53.704637) (xy 237.739584 -53.726449) (xy 237.685627 -53.740555) (xy 237.63019 -53.746655)
			(xy 237.574456 -53.744618) (xy 237.519613 -53.734488) (xy 237.466829 -53.716481) (xy 237.417229 -53.69098)
			(xy 237.371871 -53.658529) (xy 237.331722 -53.61982) (xy 237.297636 -53.575677) (xy 237.27034 -53.527042)
			(xy 237.250417 -53.474951) (xy 237.238291 -53.420514) (xy 237.23422 -53.364892) (xy 231.348788 -53.364892)
			(xy 231.348279 -53.392778) (xy 231.340159 -53.447954) (xy 231.324091 -53.501361) (xy 231.300419 -53.551858)
			(xy 231.269646 -53.598371) (xy 231.232429 -53.639908) (xy 231.189561 -53.675583) (xy 231.141955 -53.704637)
			(xy 231.090626 -53.726449) (xy 231.036669 -53.740555) (xy 230.981232 -53.746655) (xy 230.925498 -53.744618)
			(xy 230.870655 -53.734488) (xy 230.817871 -53.716481) (xy 230.768271 -53.69098) (xy 230.722913 -53.658529)
			(xy 230.682764 -53.61982) (xy 230.648678 -53.575677) (xy 230.621382 -53.527042) (xy 230.601459 -53.474951)
			(xy 230.589333 -53.420514) (xy 230.585262 -53.364892) (xy 221.928944 -53.364892) (xy 223.632014 -55.067962)
			(xy 223.639411 -55.07481) (xy 223.65801 -55.082546) (xy 223.668082 -55.082948) (xy 230.572564 -55.082948)
		)
		(stroke
			(width 0)
			(type solid)
		)
		(fill yes)
		(layer "In15.Cu")
		(net "P3V3_E1S_0")
	)
	(gr_poly
		(pts
			(xy 155.75534 -83.59902) (xy 155.765325 -83.598476) (xy 155.783748 -83.590755) (xy 155.791154 -83.584034)
			(xy 156.250894 -83.124294) (xy 156.257704 -83.116949) (xy 156.265435 -83.098486) (xy 156.26588 -83.08848)
			(xy 156.26588 -72.304656) (xy 156.265448 -72.29459) (xy 156.25772 -72.275999) (xy 156.250894 -72.268588)
			(xy 156.121354 -72.139048) (xy 156.114242 -72.131682) (xy 156.095446 -72.124062) (xy 138.213084 -72.124062)
			(xy 138.203099 -72.124604) (xy 138.184677 -72.132328) (xy 138.17727 -72.139048) (xy 136.694365 -73.621953)
			(xy 137.238177 -73.621953) (xy 137.238177 -73.567447) (xy 137.245935 -73.513497) (xy 137.261291 -73.461199)
			(xy 137.283935 -73.41162) (xy 137.313404 -73.365768) (xy 137.349099 -73.324577) (xy 137.390293 -73.288885)
			(xy 137.436148 -73.25942) (xy 137.485729 -73.23678) (xy 137.538028 -73.221428) (xy 137.591979 -73.213675)
			(xy 137.619232 -73.213214) (xy 137.650162 -73.213794) (xy 137.711216 -73.223731) (xy 137.769868 -73.243389)
			(xy 137.824579 -73.272252) (xy 137.84961 -73.29043) (xy 137.858246 -73.297288) (xy 137.88009 -73.302114)
			(xy 137.977118 -73.281032) (xy 137.994898 -73.267824) (xy 138.000232 -73.257918) (xy 138.014686 -73.232456)
			(xy 138.050123 -73.185852) (xy 138.092266 -73.14521) (xy 138.140124 -73.111485) (xy 138.192573 -73.08547)
			(xy 138.248382 -73.067774) (xy 138.306239 -73.058814) (xy 138.335512 -73.058274) (xy 138.362763 -73.058767)
			(xy 138.416709 -73.066524) (xy 138.469003 -73.08188) (xy 138.518579 -73.104521) (xy 138.564428 -73.133987)
			(xy 138.605618 -73.169678) (xy 138.641309 -73.210867) (xy 138.670776 -73.256716) (xy 138.693418 -73.306292)
			(xy 138.708774 -73.358585) (xy 138.716533 -73.412531) (xy 138.71702 -73.439782) (xy 138.716563 -73.467153)
			(xy 138.708746 -73.521333) (xy 138.693256 -73.573837) (xy 138.673733 -73.616352) (xy 152.964589 -73.616352)
			(xy 152.964589 -73.561848) (xy 152.972347 -73.507898) (xy 152.987704 -73.455601) (xy 153.010347 -73.406023)
			(xy 153.039816 -73.360172) (xy 153.075511 -73.318982) (xy 153.116705 -73.283291) (xy 153.16256 -73.253827)
			(xy 153.212141 -73.231189) (xy 153.264439 -73.215838) (xy 153.31839 -73.208086) (xy 153.345642 -73.207626)
			(xy 153.373352 -73.208112) (xy 153.428187 -73.216142) (xy 153.481282 -73.232025) (xy 153.531518 -73.255427)
			(xy 153.577837 -73.285856) (xy 153.59888 -73.303892) (xy 153.605992 -73.309988) (xy 153.623264 -73.316592)
			(xy 153.70937 -73.316592) (xy 153.726642 -73.309988) (xy 153.733754 -73.303892) (xy 153.754797 -73.285858)
			(xy 153.801117 -73.255432) (xy 153.851353 -73.232034) (xy 153.904448 -73.216156) (xy 153.959283 -73.208132)
			(xy 154.014701 -73.208132) (xy 154.069536 -73.216156) (xy 154.122631 -73.232034) (xy 154.172867 -73.255432)
			(xy 154.219187 -73.285858) (xy 154.24023 -73.303892) (xy 154.247342 -73.309988) (xy 154.264614 -73.316592)
			(xy 154.35072 -73.316592) (xy 154.367992 -73.309988) (xy 154.375104 -73.303892) (xy 154.396136 -73.285844)
			(xy 154.442457 -73.255416) (xy 154.492696 -73.232017) (xy 154.545794 -73.21614) (xy 154.600632 -73.20812)
			(xy 154.628342 -73.207626) (xy 154.655594 -73.208047) (xy 154.709542 -73.215809) (xy 154.761836 -73.231169)
			(xy 154.811412 -73.253814) (xy 154.857262 -73.283285) (xy 154.898451 -73.318979) (xy 154.934141 -73.360172)
			(xy 154.963606 -73.406024) (xy 154.986246 -73.455603) (xy 155.0016 -73.507899) (xy 155.009356 -73.561848)
			(xy 155.009356 -73.616352) (xy 155.0016 -73.670301) (xy 154.986246 -73.722597) (xy 154.963606 -73.772176)
			(xy 154.934141 -73.818028) (xy 154.898451 -73.859221) (xy 154.857262 -73.894915) (xy 154.811412 -73.924386)
			(xy 154.761836 -73.947031) (xy 154.709542 -73.962391) (xy 154.655594 -73.970153) (xy 154.628342 -73.970642)
			(xy 154.600633 -73.970148) (xy 154.545799 -73.962118) (xy 154.492704 -73.946236) (xy 154.442468 -73.922835)
			(xy 154.396148 -73.89241) (xy 154.375104 -73.874376) (xy 154.367992 -73.86828) (xy 154.35072 -73.861676)
			(xy 154.264614 -73.861676) (xy 154.247342 -73.86828) (xy 154.24023 -73.874376) (xy 154.219187 -73.89241)
			(xy 154.172867 -73.922836) (xy 154.122631 -73.946234) (xy 154.069536 -73.962112) (xy 154.014701 -73.970136)
			(xy 153.959283 -73.970136) (xy 153.904448 -73.962112) (xy 153.851353 -73.946234) (xy 153.801117 -73.922836)
			(xy 153.754797 -73.89241) (xy 153.733754 -73.874376) (xy 153.726642 -73.86828) (xy 153.70937 -73.861676)
			(xy 153.623264 -73.861676) (xy 153.605992 -73.86828) (xy 153.59888 -73.874376) (xy 153.577849 -73.892427)
			(xy 153.531529 -73.922855) (xy 153.481289 -73.946254) (xy 153.428191 -73.96213) (xy 153.373353 -73.970148)
			(xy 153.345642 -73.970642) (xy 153.31839 -73.970114) (xy 153.264439 -73.962362) (xy 153.212141 -73.947011)
			(xy 153.16256 -73.924373) (xy 153.116705 -73.894909) (xy 153.075511 -73.859218) (xy 153.039816 -73.818028)
			(xy 153.010347 -73.772177) (xy 152.987704 -73.722599) (xy 152.972347 -73.670302) (xy 152.964589 -73.616352)
			(xy 138.673733 -73.616352) (xy 138.670412 -73.623584) (xy 138.640683 -73.669549) (xy 138.62304 -73.69048)
			(xy 138.616944 -73.697592) (xy 138.610594 -73.71461) (xy 138.610594 -73.799954) (xy 138.616944 -73.816972)
			(xy 138.62304 -73.824084) (xy 138.640692 -73.845006) (xy 138.6704 -73.890982) (xy 138.693233 -73.940732)
			(xy 138.708722 -73.993235) (xy 138.716548 -74.047412) (xy 138.71702 -74.074782) (xy 138.716585 -74.101067)
			(xy 138.709381 -74.153142) (xy 138.695094 -74.203734) (xy 138.673994 -74.251885) (xy 138.646482 -74.296681)
			(xy 138.613077 -74.337274) (xy 138.574415 -74.372896) (xy 138.531227 -74.40287) (xy 138.507978 -74.415142)
			(xy 138.498834 -74.419714) (xy 138.48588 -74.4347) (xy 138.45667 -74.521822) (xy 138.458194 -74.54138)
			(xy 138.462512 -74.550524) (xy 138.474828 -74.576829) (xy 138.492268 -74.632227) (xy 138.501085 -74.689633)
			(xy 138.501628 -74.718672) (xy 138.501142 -74.745923) (xy 138.493386 -74.799871) (xy 138.478073 -74.852022)
			(xy 141.157704 -74.852022) (xy 141.161775 -74.7964) (xy 141.173901 -74.741963) (xy 141.193824 -74.689872)
			(xy 141.22112 -74.641237) (xy 141.255206 -74.597094) (xy 141.295355 -74.558385) (xy 141.340713 -74.525934)
			(xy 141.390313 -74.500433) (xy 141.443097 -74.482426) (xy 141.49794 -74.472296) (xy 141.553674 -74.470259)
			(xy 141.609111 -74.476359) (xy 141.663068 -74.490465) (xy 141.714397 -74.512277) (xy 141.762003 -74.541331)
			(xy 141.804871 -74.577006) (xy 141.842088 -74.618543) (xy 141.872861 -74.665056) (xy 141.896533 -74.715553)
			(xy 141.912601 -74.76896) (xy 141.920721 -74.824136) (xy 141.92123 -74.852022) (xy 141.920721 -74.879908)
			(xy 141.917349 -74.902822) (xy 144.607024 -74.902822) (xy 144.611095 -74.8472) (xy 144.623221 -74.792763)
			(xy 144.643144 -74.740672) (xy 144.67044 -74.692037) (xy 144.704526 -74.647894) (xy 144.744675 -74.609185)
			(xy 144.790033 -74.576734) (xy 144.839633 -74.551233) (xy 144.892417 -74.533226) (xy 144.94726 -74.523096)
			(xy 145.002994 -74.521059) (xy 145.058431 -74.527159) (xy 145.112388 -74.541265) (xy 145.163717 -74.563077)
			(xy 145.211323 -74.592131) (xy 145.254191 -74.627806) (xy 145.291408 -74.669343) (xy 145.322181 -74.715856)
			(xy 145.345853 -74.766353) (xy 145.361921 -74.81976) (xy 145.370041 -74.874936) (xy 145.37055 -74.902822)
			(xy 145.370041 -74.930708) (xy 145.361921 -74.985884) (xy 145.345853 -75.039291) (xy 145.322181 -75.089788)
			(xy 145.291408 -75.136301) (xy 145.254191 -75.177838) (xy 145.211323 -75.213513) (xy 145.163717 -75.242567)
			(xy 145.112388 -75.264379) (xy 145.058431 -75.278485) (xy 145.002994 -75.284585) (xy 144.94726 -75.282548)
			(xy 144.892417 -75.272418) (xy 144.839633 -75.254411) (xy 144.790033 -75.22891) (xy 144.744675 -75.196459)
			(xy 144.704526 -75.15775) (xy 144.67044 -75.113607) (xy 144.643144 -75.064972) (xy 144.623221 -75.012881)
			(xy 144.611095 -74.958444) (xy 144.607024 -74.902822) (xy 141.917349 -74.902822) (xy 141.912601 -74.935084)
			(xy 141.896533 -74.988491) (xy 141.872861 -75.038988) (xy 141.842088 -75.085501) (xy 141.804871 -75.127038)
			(xy 141.762003 -75.162713) (xy 141.714397 -75.191767) (xy 141.663068 -75.213579) (xy 141.609111 -75.227685)
			(xy 141.553674 -75.233785) (xy 141.49794 -75.231748) (xy 141.443097 -75.221618) (xy 141.390313 -75.203611)
			(xy 141.340713 -75.17811) (xy 141.295355 -75.145659) (xy 141.255206 -75.10695) (xy 141.22112 -75.062807)
			(xy 141.193824 -75.014172) (xy 141.173901 -74.962081) (xy 141.161775 -74.907644) (xy 141.157704 -74.852022)
			(xy 138.478073 -74.852022) (xy 138.478031 -74.852166) (xy 138.455389 -74.901743) (xy 138.425923 -74.947593)
			(xy 138.390232 -74.988784) (xy 138.349041 -75.024475) (xy 138.303191 -75.053941) (xy 138.253614 -75.076583)
			(xy 138.201319 -75.091938) (xy 138.147371 -75.099694) (xy 138.092869 -75.099694) (xy 138.038921 -75.091938)
			(xy 137.986626 -75.076583) (xy 137.937049 -75.053941) (xy 137.891199 -75.024475) (xy 137.850008 -74.988784)
			(xy 137.814317 -74.947593) (xy 137.784851 -74.901743) (xy 137.762209 -74.852166) (xy 137.746854 -74.799871)
			(xy 137.739098 -74.745923) (xy 137.738612 -74.718672) (xy 137.739074 -74.692387) (xy 137.746271 -74.640313)
			(xy 137.760553 -74.589721) (xy 137.781648 -74.54157) (xy 137.809157 -74.496773) (xy 137.842558 -74.456179)
			(xy 137.881219 -74.420557) (xy 137.924406 -74.390584) (xy 137.947654 -74.378312) (xy 137.956798 -74.37374)
			(xy 137.969752 -74.358754) (xy 137.998962 -74.271632) (xy 137.997438 -74.252074) (xy 137.99312 -74.24293)
			(xy 137.980784 -74.216634) (xy 137.963352 -74.161231) (xy 137.954543 -74.103823) (xy 137.954004 -74.074782)
			(xy 137.954086 -74.063132) (xy 137.955484 -74.039875) (xy 137.956798 -74.0283) (xy 137.958576 -74.013822)
			(xy 137.946638 -73.987914) (xy 137.847324 -73.921366) (xy 137.818876 -73.920096) (xy 137.806176 -73.927208)
			(xy 137.784693 -73.93885) (xy 137.73939 -73.957162) (xy 137.692124 -73.969554) (xy 137.643664 -73.975822)
			(xy 137.619232 -73.97623) (xy 137.591979 -73.975725) (xy 137.538028 -73.967972) (xy 137.485729 -73.95262)
			(xy 137.436148 -73.92998) (xy 137.390293 -73.900515) (xy 137.349099 -73.864823) (xy 137.313404 -73.823632)
			(xy 137.283935 -73.77778) (xy 137.261291 -73.728201) (xy 137.245935 -73.675903) (xy 137.238177 -73.621953)
			(xy 136.694365 -73.621953) (xy 136.658858 -73.65746) (xy 136.65205 -73.664806) (xy 136.644331 -73.683269)
			(xy 136.643872 -73.693274) (xy 136.643872 -76.324968) (xy 142.317214 -76.324968) (xy 142.321285 -76.269346)
			(xy 142.333411 -76.214909) (xy 142.353334 -76.162818) (xy 142.38063 -76.114183) (xy 142.414716 -76.07004)
			(xy 142.454865 -76.031331) (xy 142.500223 -75.99888) (xy 142.549823 -75.973379) (xy 142.602607 -75.955372)
			(xy 142.65745 -75.945242) (xy 142.713184 -75.943205) (xy 142.768621 -75.949305) (xy 142.822578 -75.963411)
			(xy 142.873907 -75.985223) (xy 142.921513 -76.014277) (xy 142.964381 -76.049952) (xy 143.001598 -76.091489)
			(xy 143.032371 -76.138002) (xy 143.056043 -76.188499) (xy 143.072111 -76.241906) (xy 143.080231 -76.297082)
			(xy 143.080314 -76.301652) (xy 144.371777 -76.301652) (xy 144.371777 -76.247148) (xy 144.379534 -76.193198)
			(xy 144.394891 -76.140901) (xy 144.417533 -76.091323) (xy 144.447002 -76.045471) (xy 144.482696 -76.00428)
			(xy 144.523889 -75.968589) (xy 144.569742 -75.939123) (xy 144.619322 -75.916483) (xy 144.67162 -75.90113)
			(xy 144.72557 -75.893376) (xy 144.752822 -75.892914) (xy 144.782807 -75.893527) (xy 144.842034 -75.902939)
			(xy 144.899066 -75.921482) (xy 144.92605 -75.93457) (xy 144.935194 -75.939142) (xy 144.954752 -75.940666)
			(xy 145.042636 -75.912472) (xy 145.057622 -75.899772) (xy 145.062448 -75.890628) (xy 145.074767 -75.867592)
			(xy 145.104805 -75.824853) (xy 145.140395 -75.786612) (xy 145.18087 -75.753587) (xy 145.225474 -75.726394)
			(xy 145.273372 -75.705542) (xy 145.323667 -75.691422) (xy 145.375418 -75.684298) (xy 145.401538 -75.683872)
			(xy 145.428786 -75.684401) (xy 145.482727 -75.692161) (xy 145.535014 -75.707519) (xy 145.580194 -75.728156)
			(xy 152.583545 -75.728156) (xy 152.583545 -75.673644) (xy 152.591303 -75.619688) (xy 152.606662 -75.567386)
			(xy 152.629308 -75.517801) (xy 152.658781 -75.471945) (xy 152.69448 -75.43075) (xy 152.735679 -75.395056)
			(xy 152.781538 -75.365588) (xy 152.831125 -75.342947) (xy 152.883429 -75.327594) (xy 152.937386 -75.319842)
			(xy 152.964642 -75.319382) (xy 152.992351 -75.319879) (xy 153.047186 -75.327908) (xy 153.10028 -75.343789)
			(xy 153.150516 -75.367189) (xy 153.196836 -75.397614) (xy 153.21788 -75.415648) (xy 153.224992 -75.421744)
			(xy 153.242264 -75.428348) (xy 153.32837 -75.428348) (xy 153.345642 -75.421744) (xy 153.352754 -75.415648)
			(xy 153.373797 -75.397614) (xy 153.420117 -75.367188) (xy 153.470353 -75.34379) (xy 153.523448 -75.327912)
			(xy 153.578283 -75.319888) (xy 153.633701 -75.319888) (xy 153.688536 -75.327912) (xy 153.741631 -75.34379)
			(xy 153.791867 -75.367188) (xy 153.838187 -75.397614) (xy 153.85923 -75.415648) (xy 153.866342 -75.421744)
			(xy 153.883614 -75.428348) (xy 153.96972 -75.428348) (xy 153.986992 -75.421744) (xy 153.994104 -75.415648)
			(xy 154.015147 -75.397614) (xy 154.061467 -75.367188) (xy 154.111703 -75.34379) (xy 154.164798 -75.327912)
			(xy 154.219633 -75.319888) (xy 154.275051 -75.319888) (xy 154.329886 -75.327912) (xy 154.382981 -75.34379)
			(xy 154.433217 -75.367188) (xy 154.479537 -75.397614) (xy 154.50058 -75.415648) (xy 154.507692 -75.421744)
			(xy 154.524964 -75.428348) (xy 154.61107 -75.428348) (xy 154.628342 -75.421744) (xy 154.635454 -75.415648)
			(xy 154.6565 -75.397616) (xy 154.702817 -75.367187) (xy 154.753053 -75.343786) (xy 154.806148 -75.327905)
			(xy 154.860983 -75.31988) (xy 154.888692 -75.319382) (xy 154.915945 -75.319865) (xy 154.969895 -75.327621)
			(xy 155.022192 -75.342976) (xy 155.071772 -75.365617) (xy 155.117625 -75.395084) (xy 155.158818 -75.430777)
			(xy 155.194511 -75.471969) (xy 155.223979 -75.517821) (xy 155.246622 -75.5674) (xy 155.261978 -75.619697)
			(xy 155.269735 -75.673647) (xy 155.269735 -75.728153) (xy 155.261978 -75.782103) (xy 155.246622 -75.8344)
			(xy 155.223979 -75.883979) (xy 155.194511 -75.929831) (xy 155.158818 -75.971023) (xy 155.117625 -76.006716)
			(xy 155.071772 -76.036183) (xy 155.022192 -76.058824) (xy 154.969895 -76.074179) (xy 154.915945 -76.081935)
			(xy 154.888692 -76.082398) (xy 154.860983 -76.081886) (xy 154.806149 -76.073862) (xy 154.753055 -76.057984)
			(xy 154.702818 -76.034588) (xy 154.656498 -76.004165) (xy 154.635454 -75.986132) (xy 154.628342 -75.980036)
			(xy 154.61107 -75.973432) (xy 154.524964 -75.973432) (xy 154.507692 -75.980036) (xy 154.50058 -75.986132)
			(xy 154.479537 -76.004166) (xy 154.433217 -76.034592) (xy 154.382981 -76.05799) (xy 154.329886 -76.073868)
			(xy 154.275051 -76.081892) (xy 154.219633 -76.081892) (xy 154.164798 -76.073868) (xy 154.111703 -76.05799)
			(xy 154.061467 -76.034592) (xy 154.015147 -76.004166) (xy 153.994104 -75.986132) (xy 153.986992 -75.980036)
			(xy 153.96972 -75.973432) (xy 153.883614 -75.973432) (xy 153.866342 -75.980036) (xy 153.85923 -75.986132)
			(xy 153.838187 -76.004166) (xy 153.791867 -76.034592) (xy 153.741631 -76.05799) (xy 153.688536 -76.073868)
			(xy 153.633701 -76.081892) (xy 153.578283 -76.081892) (xy 153.523448 -76.073868) (xy 153.470353 -76.05799)
			(xy 153.420117 -76.034592) (xy 153.373797 -76.004166) (xy 153.352754 -75.986132) (xy 153.345642 -75.980036)
			(xy 153.32837 -75.973432) (xy 153.242264 -75.973432) (xy 153.224992 -75.980036) (xy 153.21788 -75.986132)
			(xy 153.196857 -76.004192) (xy 153.150533 -76.034617) (xy 153.100292 -76.058013) (xy 153.047192 -76.073888)
			(xy 152.992353 -76.081905) (xy 152.964642 -76.082398) (xy 152.937386 -76.081958) (xy 152.883429 -76.074206)
			(xy 152.831125 -76.058853) (xy 152.781538 -76.036212) (xy 152.735679 -76.006744) (xy 152.69448 -75.97105)
			(xy 152.658781 -75.929855) (xy 152.629308 -75.883999) (xy 152.606662 -75.834414) (xy 152.591303 -75.782112)
			(xy 152.583545 -75.728156) (xy 145.580194 -75.728156) (xy 145.584584 -75.730161) (xy 145.630427 -75.759627)
			(xy 145.671611 -75.795316) (xy 145.707296 -75.836503) (xy 145.736757 -75.882349) (xy 145.759394 -75.931922)
			(xy 145.774747 -75.98421) (xy 145.782502 -76.038152) (xy 145.782502 -76.092648) (xy 145.774747 -76.14659)
			(xy 145.759394 -76.198878) (xy 145.736757 -76.248451) (xy 145.707296 -76.294297) (xy 145.671611 -76.335484)
			(xy 145.630427 -76.371173) (xy 145.584584 -76.400639) (xy 145.535014 -76.423281) (xy 145.482727 -76.438639)
			(xy 145.428786 -76.446399) (xy 145.401538 -76.446888) (xy 145.371553 -76.446289) (xy 145.312325 -76.436871)
			(xy 145.255294 -76.418323) (xy 145.22831 -76.405232) (xy 145.219166 -76.40066) (xy 145.199608 -76.399136)
			(xy 145.111724 -76.42733) (xy 145.096738 -76.44003) (xy 145.091912 -76.449174) (xy 145.079623 -76.472227)
			(xy 145.049581 -76.514967) (xy 145.013987 -76.553207) (xy 144.973507 -76.586232) (xy 144.928899 -76.613423)
			(xy 144.880997 -76.634271) (xy 144.830698 -76.648387) (xy 144.778943 -76.655506) (xy 144.752822 -76.65593)
			(xy 144.72557 -76.655424) (xy 144.671619 -76.64767) (xy 144.619322 -76.632317) (xy 144.569742 -76.609677)
			(xy 144.523889 -76.580211) (xy 144.482696 -76.54452) (xy 144.447002 -76.503329) (xy 144.417533 -76.457477)
			(xy 144.394891 -76.407899) (xy 144.379534 -76.355602) (xy 144.371777 -76.301652) (xy 143.080314 -76.301652)
			(xy 143.08074 -76.324968) (xy 143.080231 -76.352854) (xy 143.072111 -76.40803) (xy 143.056043 -76.461437)
			(xy 143.032371 -76.511934) (xy 143.001598 -76.558447) (xy 142.964381 -76.599984) (xy 142.921513 -76.635659)
			(xy 142.873907 -76.664713) (xy 142.822578 -76.686525) (xy 142.768621 -76.700631) (xy 142.713184 -76.706731)
			(xy 142.65745 -76.704694) (xy 142.602607 -76.694564) (xy 142.549823 -76.676557) (xy 142.500223 -76.651056)
			(xy 142.454865 -76.618605) (xy 142.414716 -76.579896) (xy 142.38063 -76.535753) (xy 142.353334 -76.487118)
			(xy 142.333411 -76.435027) (xy 142.321285 -76.38059) (xy 142.317214 -76.324968) (xy 136.643872 -76.324968)
			(xy 136.643872 -80.302862) (xy 143.832324 -80.302862) (xy 143.836395 -80.24724) (xy 143.848521 -80.192803)
			(xy 143.868444 -80.140712) (xy 143.89574 -80.092077) (xy 143.929826 -80.047934) (xy 143.969975 -80.009225)
			(xy 144.015333 -79.976774) (xy 144.064933 -79.951273) (xy 144.117717 -79.933266) (xy 144.17256 -79.923136)
			(xy 144.228294 -79.921099) (xy 144.272162 -79.925926) (xy 144.667984 -79.925926) (xy 144.672055 -79.870304)
			(xy 144.684181 -79.815867) (xy 144.704104 -79.763776) (xy 144.7314 -79.715141) (xy 144.765486 -79.670998)
			(xy 144.805635 -79.632289) (xy 144.850993 -79.599838) (xy 144.900593 -79.574337) (xy 144.953377 -79.55633)
			(xy 145.00822 -79.5462) (xy 145.063954 -79.544163) (xy 145.119391 -79.550263) (xy 145.173348 -79.564369)
			(xy 145.224677 -79.586181) (xy 145.272283 -79.615235) (xy 145.315151 -79.65091) (xy 145.352368 -79.692447)
			(xy 145.383141 -79.73896) (xy 145.406813 -79.789457) (xy 145.416018 -79.820053) (xy 152.583585 -79.820053)
			(xy 152.583585 -79.765547) (xy 152.591343 -79.711597) (xy 152.6067 -79.6593) (xy 152.629344 -79.609721)
			(xy 152.658813 -79.563869) (xy 152.694509 -79.522679) (xy 152.735703 -79.486988) (xy 152.781558 -79.457523)
			(xy 152.831139 -79.434885) (xy 152.883438 -79.419534) (xy 152.937389 -79.411782) (xy 152.964642 -79.411322)
			(xy 152.992352 -79.411809) (xy 153.047187 -79.419838) (xy 153.100282 -79.435722) (xy 153.150518 -79.459124)
			(xy 153.196837 -79.489553) (xy 153.21788 -79.507588) (xy 153.224992 -79.513684) (xy 153.242264 -79.520288)
			(xy 153.32837 -79.520288) (xy 153.345642 -79.513684) (xy 153.352754 -79.507588) (xy 153.373797 -79.489554)
			(xy 153.420117 -79.459128) (xy 153.470353 -79.43573) (xy 153.523448 -79.419852) (xy 153.578283 -79.411828)
			(xy 153.633701 -79.411828) (xy 153.688536 -79.419852) (xy 153.741631 -79.43573) (xy 153.791867 -79.459128)
			(xy 153.838187 -79.489554) (xy 153.85923 -79.507588) (xy 153.866342 -79.513684) (xy 153.883614 -79.520288)
			(xy 153.96972 -79.520288) (xy 153.986992 -79.513684) (xy 153.994104 -79.507588) (xy 154.015147 -79.489554)
			(xy 154.061467 -79.459128) (xy 154.111703 -79.43573) (xy 154.164798 -79.419852) (xy 154.219633 -79.411828)
			(xy 154.275051 -79.411828) (xy 154.329886 -79.419852) (xy 154.382981 -79.43573) (xy 154.433217 -79.459128)
			(xy 154.479537 -79.489554) (xy 154.50058 -79.507588) (xy 154.507692 -79.513684) (xy 154.524964 -79.520288)
			(xy 154.61107 -79.520288) (xy 154.628342 -79.513684) (xy 154.635454 -79.507588) (xy 154.656505 -79.489562)
			(xy 154.702821 -79.459131) (xy 154.753055 -79.435728) (xy 154.806149 -79.419846) (xy 154.860983 -79.41182)
			(xy 154.888692 -79.411322) (xy 154.915947 -79.411724) (xy 154.969903 -79.419481) (xy 155.022206 -79.434838)
			(xy 155.071792 -79.457481) (xy 155.117649 -79.486952) (xy 155.158846 -79.522648) (xy 155.194544 -79.563844)
			(xy 155.224015 -79.609701) (xy 155.24666 -79.659286) (xy 155.262017 -79.711589) (xy 155.269775 -79.765545)
			(xy 155.269775 -79.820055) (xy 155.262017 -79.874011) (xy 155.24666 -79.926314) (xy 155.224015 -79.975899)
			(xy 155.194544 -80.021756) (xy 155.158846 -80.062952) (xy 155.117649 -80.098648) (xy 155.071792 -80.128119)
			(xy 155.022206 -80.150762) (xy 154.969903 -80.166119) (xy 154.915947 -80.173876) (xy 154.888692 -80.174338)
			(xy 154.860984 -80.173816) (xy 154.806151 -80.165793) (xy 154.753057 -80.149917) (xy 154.70282 -80.126523)
			(xy 154.656499 -80.096103) (xy 154.635454 -80.078072) (xy 154.628342 -80.071976) (xy 154.61107 -80.065372)
			(xy 154.524964 -80.065372) (xy 154.507692 -80.071976) (xy 154.50058 -80.078072) (xy 154.479537 -80.096106)
			(xy 154.433217 -80.126532) (xy 154.382981 -80.14993) (xy 154.329886 -80.165808) (xy 154.275051 -80.173832)
			(xy 154.219633 -80.173832) (xy 154.164798 -80.165808) (xy 154.111703 -80.14993) (xy 154.061467 -80.126532)
			(xy 154.015147 -80.096106) (xy 153.994104 -80.078072) (xy 153.986992 -80.071976) (xy 153.96972 -80.065372)
			(xy 153.883614 -80.065372) (xy 153.866342 -80.071976) (xy 153.85923 -80.078072) (xy 153.838187 -80.096106)
			(xy 153.791867 -80.126532) (xy 153.741631 -80.14993) (xy 153.688536 -80.165808) (xy 153.633701 -80.173832)
			(xy 153.578283 -80.173832) (xy 153.523448 -80.165808) (xy 153.470353 -80.14993) (xy 153.420117 -80.126532)
			(xy 153.373797 -80.096106) (xy 153.352754 -80.078072) (xy 153.345642 -80.071976) (xy 153.32837 -80.065372)
			(xy 153.242264 -80.065372) (xy 153.224992 -80.071976) (xy 153.21788 -80.078072) (xy 153.196849 -80.096122)
			(xy 153.150528 -80.126551) (xy 153.100289 -80.14995) (xy 153.047191 -80.165826) (xy 152.992353 -80.173844)
			(xy 152.964642 -80.174338) (xy 152.937389 -80.173818) (xy 152.883438 -80.166066) (xy 152.831139 -80.150715)
			(xy 152.781558 -80.128077) (xy 152.735703 -80.098612) (xy 152.694509 -80.062921) (xy 152.658813 -80.021731)
			(xy 152.629344 -79.975879) (xy 152.6067 -79.9263) (xy 152.591343 -79.874003) (xy 152.583585 -79.820053)
			(xy 145.416018 -79.820053) (xy 145.422881 -79.842864) (xy 145.431001 -79.89804) (xy 145.43151 -79.925926)
			(xy 145.431001 -79.953812) (xy 145.422881 -80.008988) (xy 145.406813 -80.062395) (xy 145.383141 -80.112892)
			(xy 145.352368 -80.159405) (xy 145.315151 -80.200942) (xy 145.272283 -80.236617) (xy 145.224677 -80.265671)
			(xy 145.173348 -80.287483) (xy 145.119391 -80.301589) (xy 145.063954 -80.307689) (xy 145.00822 -80.305652)
			(xy 144.953377 -80.295522) (xy 144.900593 -80.277515) (xy 144.850993 -80.252014) (xy 144.805635 -80.219563)
			(xy 144.765486 -80.180854) (xy 144.7314 -80.136711) (xy 144.704104 -80.088076) (xy 144.684181 -80.035985)
			(xy 144.672055 -79.981548) (xy 144.667984 -79.925926) (xy 144.272162 -79.925926) (xy 144.283731 -79.927199)
			(xy 144.337688 -79.941305) (xy 144.389017 -79.963117) (xy 144.436623 -79.992171) (xy 144.479491 -80.027846)
			(xy 144.516708 -80.069383) (xy 144.547481 -80.115896) (xy 144.571153 -80.166393) (xy 144.587221 -80.2198)
			(xy 144.595341 -80.274976) (xy 144.59585 -80.302862) (xy 144.595341 -80.330748) (xy 144.587221 -80.385924)
			(xy 144.571153 -80.439331) (xy 144.547481 -80.489828) (xy 144.516708 -80.536341) (xy 144.479491 -80.577878)
			(xy 144.436623 -80.613553) (xy 144.389017 -80.642607) (xy 144.337688 -80.664419) (xy 144.283731 -80.678525)
			(xy 144.228294 -80.684625) (xy 144.17256 -80.682588) (xy 144.117717 -80.672458) (xy 144.064933 -80.654451)
			(xy 144.015333 -80.62895) (xy 143.969975 -80.596499) (xy 143.929826 -80.55779) (xy 143.89574 -80.513647)
			(xy 143.868444 -80.465012) (xy 143.848521 -80.412921) (xy 143.836395 -80.358484) (xy 143.832324 -80.302862)
			(xy 136.643872 -80.302862) (xy 136.643872 -81.866055) (xy 152.583555 -81.866055) (xy 152.583555 -81.811545)
			(xy 152.591314 -81.757591) (xy 152.606672 -81.705289) (xy 152.629317 -81.655707) (xy 152.658789 -81.609851)
			(xy 152.694487 -81.568658) (xy 152.735685 -81.532964) (xy 152.781543 -81.503497) (xy 152.831129 -81.480857)
			(xy 152.883432 -81.465505) (xy 152.937387 -81.457752) (xy 152.964642 -81.457292) (xy 152.992351 -81.457787)
			(xy 153.047186 -81.465815) (xy 153.10028 -81.481697) (xy 153.150517 -81.505098) (xy 153.196836 -81.535524)
			(xy 153.21788 -81.553558) (xy 153.224992 -81.559654) (xy 153.242264 -81.566258) (xy 153.32837 -81.566258)
			(xy 153.345642 -81.559654) (xy 153.352754 -81.553558) (xy 153.373797 -81.535524) (xy 153.420117 -81.505098)
			(xy 153.470353 -81.4817) (xy 153.523448 -81.465822) (xy 153.578283 -81.457798) (xy 153.633701 -81.457798)
			(xy 153.688536 -81.465822) (xy 153.741631 -81.4817) (xy 153.791867 -81.505098) (xy 153.838187 -81.535524)
			(xy 153.85923 -81.553558) (xy 153.866342 -81.559654) (xy 153.883614 -81.566258) (xy 153.96972 -81.566258)
			(xy 153.986992 -81.559654) (xy 153.994104 -81.553558) (xy 154.015147 -81.535524) (xy 154.061467 -81.505098)
			(xy 154.111703 -81.4817) (xy 154.164798 -81.465822) (xy 154.219633 -81.457798) (xy 154.275051 -81.457798)
			(xy 154.329886 -81.465822) (xy 154.382981 -81.4817) (xy 154.433217 -81.505098) (xy 154.479537 -81.535524)
			(xy 154.50058 -81.553558) (xy 154.507692 -81.559654) (xy 154.524964 -81.566258) (xy 154.61107 -81.566258)
			(xy 154.628342 -81.559654) (xy 154.635454 -81.553558) (xy 154.656501 -81.535528) (xy 154.702818 -81.505098)
			(xy 154.753054 -81.481697) (xy 154.806148 -81.465815) (xy 154.860983 -81.45779) (xy 154.888692 -81.457292)
			(xy 154.915945 -81.457755) (xy 154.969897 -81.465511) (xy 155.022196 -81.480866) (xy 155.071777 -81.503508)
			(xy 155.117631 -81.532976) (xy 155.158825 -81.56867) (xy 155.194519 -81.609863) (xy 155.223988 -81.655716)
			(xy 155.246631 -81.705297) (xy 155.261987 -81.757595) (xy 155.269745 -81.811547) (xy 155.269745 -81.866053)
			(xy 155.261987 -81.920005) (xy 155.246631 -81.972303) (xy 155.223988 -82.021884) (xy 155.194519 -82.067737)
			(xy 155.158825 -82.10893) (xy 155.117631 -82.144624) (xy 155.071777 -82.174092) (xy 155.022196 -82.196734)
			(xy 154.969897 -82.212089) (xy 154.915945 -82.219845) (xy 154.888692 -82.220308) (xy 154.860983 -82.219793)
			(xy 154.80615 -82.21177) (xy 154.753055 -82.195892) (xy 154.702819 -82.172496) (xy 154.656498 -82.142074)
			(xy 154.635454 -82.124042) (xy 154.628342 -82.117946) (xy 154.61107 -82.111342) (xy 154.524964 -82.111342)
			(xy 154.507692 -82.117946) (xy 154.50058 -82.124042) (xy 154.479537 -82.142076) (xy 154.433217 -82.172502)
			(xy 154.382981 -82.1959) (xy 154.329886 -82.211778) (xy 154.275051 -82.219802) (xy 154.219633 -82.219802)
			(xy 154.164798 -82.211778) (xy 154.111703 -82.1959) (xy 154.061467 -82.172502) (xy 154.015147 -82.142076)
			(xy 153.994104 -82.124042) (xy 153.986992 -82.117946) (xy 153.96972 -82.111342) (xy 153.883614 -82.111342)
			(xy 153.866342 -82.117946) (xy 153.85923 -82.124042) (xy 153.838187 -82.142076) (xy 153.791867 -82.172502)
			(xy 153.741631 -82.1959) (xy 153.688536 -82.211778) (xy 153.633701 -82.219802) (xy 153.578283 -82.219802)
			(xy 153.523448 -82.211778) (xy 153.470353 -82.1959) (xy 153.420117 -82.172502) (xy 153.373797 -82.142076)
			(xy 153.352754 -82.124042) (xy 153.345642 -82.117946) (xy 153.32837 -82.111342) (xy 153.242264 -82.111342)
			(xy 153.224992 -82.117946) (xy 153.21788 -82.124042) (xy 153.196859 -82.142103) (xy 153.150534 -82.172528)
			(xy 153.100292 -82.195924) (xy 153.047192 -82.211798) (xy 152.992353 -82.219815) (xy 152.964642 -82.220308)
			(xy 152.937387 -82.219848) (xy 152.883432 -82.212095) (xy 152.831129 -82.196743) (xy 152.781543 -82.174103)
			(xy 152.735685 -82.144636) (xy 152.694487 -82.108942) (xy 152.658789 -82.067749) (xy 152.629317 -82.021893)
			(xy 152.606672 -81.972311) (xy 152.591314 -81.920009) (xy 152.583555 -81.866055) (xy 136.643872 -81.866055)
			(xy 136.643872 -82.423508) (xy 143.419574 -82.423508) (xy 143.423645 -82.367886) (xy 143.435771 -82.313449)
			(xy 143.455694 -82.261358) (xy 143.48299 -82.212723) (xy 143.517076 -82.16858) (xy 143.557225 -82.129871)
			(xy 143.602583 -82.09742) (xy 143.652183 -82.071919) (xy 143.704967 -82.053912) (xy 143.75981 -82.043782)
			(xy 143.815544 -82.041745) (xy 143.870981 -82.047845) (xy 143.924938 -82.061951) (xy 143.976267 -82.083763)
			(xy 144.023873 -82.112817) (xy 144.066741 -82.148492) (xy 144.103958 -82.190029) (xy 144.134731 -82.236542)
			(xy 144.158403 -82.287039) (xy 144.174471 -82.340446) (xy 144.182591 -82.395622) (xy 144.1831 -82.423508)
			(xy 144.182591 -82.451394) (xy 144.174471 -82.50657) (xy 144.158403 -82.559977) (xy 144.134731 -82.610474)
			(xy 144.103958 -82.656987) (xy 144.066741 -82.698524) (xy 144.023873 -82.734199) (xy 143.976267 -82.763253)
			(xy 143.924938 -82.785065) (xy 143.870981 -82.799171) (xy 143.815544 -82.805271) (xy 143.75981 -82.803234)
			(xy 143.704967 -82.793104) (xy 143.652183 -82.775097) (xy 143.602583 -82.749596) (xy 143.557225 -82.717145)
			(xy 143.517076 -82.678436) (xy 143.48299 -82.634293) (xy 143.455694 -82.585658) (xy 143.435771 -82.533567)
			(xy 143.423645 -82.47913) (xy 143.419574 -82.423508) (xy 136.643872 -82.423508) (xy 136.643872 -83.551776)
			(xy 136.644989 -83.561291) (xy 136.653289 -83.578543) (xy 136.667301 -83.591589) (xy 136.685101 -83.598639)
			(xy 136.694672 -83.59902)
		)
		(stroke
			(width 0)
			(type solid)
		)
		(fill yes)
		(layer "In15.Cu")
		(net "GND")
	)
	(gr_poly
		(pts
			(xy 71.780908 -26.081482) (xy 71.786142 -26.081327) (xy 71.796384 -26.079153) (xy 71.801228 -26.077164)
			(xy 71.828406 -26.065226) (xy 71.835518 -26.05786) (xy 71.86345 -26.029197) (xy 71.923659 -25.976458)
			(xy 71.988359 -25.92934) (xy 72.05703 -25.888221) (xy 72.129115 -25.853434) (xy 72.204033 -25.825261)
			(xy 72.281177 -25.803928) (xy 72.359926 -25.789609) (xy 72.439642 -25.782418) (xy 72.479662 -25.782016)
			(xy 72.518874 -25.78246) (xy 72.596992 -25.78939) (xy 72.674197 -25.803166) (xy 72.74989 -25.823681)
			(xy 72.823486 -25.850774) (xy 72.859138 -25.867106) (xy 72.864218 -25.869392) (xy 72.874886 -25.871678)
			(xy 72.880422 -25.87277) (xy 72.891702 -25.87277) (xy 72.897238 -25.871678) (xy 72.907906 -25.869392)
			(xy 72.912986 -25.867106) (xy 72.948629 -25.850752) (xy 73.022223 -25.823645) (xy 73.097918 -25.803128)
			(xy 73.175127 -25.78936) (xy 73.253249 -25.782447) (xy 73.292462 -25.782016) (xy 73.332482 -25.782453)
			(xy 73.412198 -25.789636) (xy 73.490947 -25.803949) (xy 73.568092 -25.825276) (xy 73.643011 -25.853443)
			(xy 73.715098 -25.888225) (xy 73.783771 -25.929338) (xy 73.848474 -25.976453) (xy 73.908685 -26.029187)
			(xy 73.936606 -26.05786) (xy 73.943718 -26.065226) (xy 73.970896 -26.077164) (xy 73.975737 -26.079163)
			(xy 73.98598 -26.081332) (xy 73.991216 -26.081482) (xy 79.464154 -26.081482) (xy 79.474219 -26.081049)
			(xy 79.492808 -26.073318) (xy 79.500222 -26.066496) (xy 80.367632 -25.199086) (xy 80.374483 -25.19169)
			(xy 80.382224 -25.173091) (xy 80.382618 -25.163018) (xy 80.382618 -23.511002) (xy 80.359758 -23.483062)
			(xy 80.341724 -23.479506) (xy 80.301756 -23.471173) (xy 80.223424 -23.448136) (xy 80.147535 -23.418012)
			(xy 80.074728 -23.381057) (xy 80.005616 -23.337582) (xy 79.972916 -23.313136) (xy 79.963565 -23.306701)
			(xy 79.941401 -23.301947) (xy 79.919353 -23.307218) (xy 79.910178 -23.313898) (xy 79.876298 -23.340539)
			(xy 79.80426 -23.387868) (xy 79.727983 -23.428008) (xy 79.648182 -23.460584) (xy 79.565605 -23.485291)
			(xy 79.481026 -23.501896) (xy 79.395237 -23.510245) (xy 79.35214 -23.510748) (xy 79.309788 -23.510262)
			(xy 79.225466 -23.502214) (xy 79.142292 -23.486186) (xy 79.061017 -23.462325) (xy 78.982379 -23.430846)
			(xy 78.907089 -23.392035) (xy 78.83583 -23.346242) (xy 78.769246 -23.293883) (xy 78.707941 -23.235431)
			(xy 78.65247 -23.171417) (xy 78.603335 -23.102419) (xy 78.560982 -23.029064) (xy 78.525793 -22.952014)
			(xy 78.498088 -22.871968) (xy 78.478118 -22.789651) (xy 78.466063 -22.705809) (xy 78.462032 -22.6212)
			(xy 78.466063 -22.536591) (xy 78.478118 -22.452749) (xy 78.498088 -22.370432) (xy 78.525793 -22.290386)
			(xy 78.560982 -22.213336) (xy 78.603335 -22.139981) (xy 78.65247 -22.070983) (xy 78.707941 -22.006969)
			(xy 78.769246 -21.948517) (xy 78.83583 -21.896158) (xy 78.907089 -21.850365) (xy 78.982379 -21.811554)
			(xy 79.061017 -21.780075) (xy 79.142292 -21.756214) (xy 79.225466 -21.740186) (xy 79.309788 -21.732138)
			(xy 79.35214 -21.731732) (xy 79.393647 -21.732209) (xy 79.476299 -21.739941) (xy 79.55787 -21.755343)
			(xy 79.637651 -21.778281) (xy 79.714947 -21.808555) (xy 79.789084 -21.845902) (xy 79.859418 -21.889997)
			(xy 79.892652 -21.914866) (xy 79.902002 -21.921285) (xy 79.924153 -21.926011) (xy 79.946176 -21.920722)
			(xy 79.95539 -21.914104) (xy 79.989233 -21.887488) (xy 80.061191 -21.840202) (xy 80.137383 -21.800092)
			(xy 80.217095 -21.767535) (xy 80.299581 -21.742834) (xy 80.341724 -21.734018) (xy 80.359758 -21.730462)
			(xy 80.382618 -21.702522) (xy 80.382618 -17.18818) (xy 80.382192 -17.178111) (xy 80.374474 -17.15951)
			(xy 80.367632 -17.152112) (xy 79.008224 -15.792704) (xy 79.001112 -15.785338) (xy 78.982316 -15.777718)
			(xy 71.662544 -15.777718) (xy 71.652478 -15.777285) (xy 71.633886 -15.769559) (xy 71.626476 -15.762732)
			(xy 68.450968 -12.587224) (xy 68.444095 -12.580986) (xy 68.427148 -12.573452) (xy 68.408632 -12.572396)
			(xy 68.39966 -12.574778) (xy 68.300092 -12.606274) (xy 68.28155 -12.62761) (xy 68.27901 -12.641834)
			(xy 68.271656 -12.681474) (xy 68.250705 -12.759333) (xy 68.222793 -12.834977) (xy 68.18815 -12.907783)
			(xy 68.147059 -12.977156) (xy 68.099859 -13.042524) (xy 68.046935 -13.103352) (xy 67.988724 -13.159141)
			(xy 67.925702 -13.209432) (xy 67.858387 -13.253812) (xy 67.82308 -13.273278) (xy 67.813809 -13.278728)
			(xy 67.800642 -13.295706) (xy 67.79768 -13.306044) (xy 67.787278 -13.347142) (xy 67.759673 -13.427305)
			(xy 67.724562 -13.504477) (xy 67.682265 -13.577955) (xy 67.633164 -13.647073) (xy 67.577707 -13.711203)
			(xy 67.516397 -13.769762) (xy 67.44979 -13.822219) (xy 67.378493 -13.868097) (xy 67.303152 -13.90698)
			(xy 67.224451 -13.938514) (xy 67.143106 -13.962413) (xy 67.059856 -13.978459) (xy 66.975456 -13.986508)
			(xy 66.933064 -13.987018) (xy 66.894774 -13.98661) (xy 66.818479 -13.980007) (xy 66.743036 -13.96686)
			(xy 66.669004 -13.947269) (xy 66.632836 -13.934694) (xy 66.624398 -13.932052) (xy 66.60673 -13.932052)
			(xy 66.598292 -13.934694) (xy 66.562114 -13.947239) (xy 66.488082 -13.966817) (xy 66.412643 -13.979967)
			(xy 66.336352 -13.98659) (xy 66.298064 -13.987018) (xy 66.254268 -13.9865) (xy 66.167098 -13.977897)
			(xy 66.081199 -13.960757) (xy 65.997403 -13.935249) (xy 65.916523 -13.901618) (xy 65.877694 -13.881354)
			(xy 65.866228 -13.875936) (xy 65.8409 -13.875936) (xy 65.829434 -13.881354) (xy 65.79059 -13.901586)
			(xy 65.709706 -13.935193) (xy 65.625912 -13.960696) (xy 65.54002 -13.977848) (xy 65.452858 -13.986484)
			(xy 65.409064 -13.987018) (xy 65.365268 -13.9865) (xy 65.278098 -13.977897) (xy 65.192199 -13.960757)
			(xy 65.108403 -13.935249) (xy 65.027523 -13.901618) (xy 64.988694 -13.881354) (xy 64.977228 -13.875936)
			(xy 64.9519 -13.875936) (xy 64.940434 -13.881354) (xy 64.90159 -13.901586) (xy 64.820706 -13.935193)
			(xy 64.736912 -13.960696) (xy 64.65102 -13.977848) (xy 64.563858 -13.986484) (xy 64.520064 -13.987018)
			(xy 64.476268 -13.9865) (xy 64.389098 -13.977897) (xy 64.303199 -13.960757) (xy 64.219403 -13.935249)
			(xy 64.138523 -13.901618) (xy 64.099694 -13.881354) (xy 64.088228 -13.875936) (xy 64.0629 -13.875936)
			(xy 64.051434 -13.881354) (xy 64.01259 -13.901586) (xy 63.931706 -13.935193) (xy 63.847912 -13.960696)
			(xy 63.76202 -13.977848) (xy 63.674858 -13.986484) (xy 63.631064 -13.987018) (xy 63.588528 -13.986519)
			(xy 63.503844 -13.978395) (xy 63.420322 -13.962223) (xy 63.338726 -13.938151) (xy 63.2598 -13.906401)
			(xy 63.184266 -13.86726) (xy 63.112813 -13.821088) (xy 63.046094 -13.768305) (xy 62.984719 -13.709395)
			(xy 62.929248 -13.644894) (xy 62.880188 -13.575392) (xy 62.85865 -13.538708) (xy 62.850014 -13.523468)
			(xy 62.818518 -13.51026) (xy 62.706758 -13.539978) (xy 62.696083 -13.543401) (xy 62.67891 -13.557767)
			(xy 62.669442 -13.578058) (xy 62.668912 -13.589254) (xy 62.668912 -14.801342) (xy 62.669343 -14.811409)
			(xy 62.67707 -14.830001) (xy 62.683898 -14.83741) (xy 64.70904 -16.862552) (xy 64.715885 -16.86995)
			(xy 64.72361 -16.888549) (xy 64.724026 -16.89862) (xy 64.724026 -18.518562) (xy 67.655436 -18.518562)
			(xy 67.655436 -18.433866) (xy 67.663487 -18.349552) (xy 67.679516 -18.266386) (xy 67.703377 -18.185119)
			(xy 67.734856 -18.106489) (xy 67.773667 -18.031208) (xy 67.819457 -17.959956) (xy 67.871813 -17.89338)
			(xy 67.930261 -17.832082) (xy 67.994271 -17.776617) (xy 68.063263 -17.727488) (xy 68.136613 -17.685139)
			(xy 68.213656 -17.649955) (xy 68.293695 -17.622253) (xy 68.376004 -17.602285) (xy 68.459839 -17.590232)
			(xy 68.54444 -17.586202) (xy 68.629041 -17.590232) (xy 68.712876 -17.602285) (xy 68.795185 -17.622253)
			(xy 68.875224 -17.649955) (xy 68.952267 -17.685139) (xy 69.025617 -17.727488) (xy 69.094609 -17.776617)
			(xy 69.158619 -17.832082) (xy 69.217067 -17.89338) (xy 69.269423 -17.959956) (xy 69.315213 -18.031208)
			(xy 69.354024 -18.106489) (xy 69.385503 -18.185119) (xy 69.409364 -18.266386) (xy 69.425393 -18.349552)
			(xy 69.433444 -18.433866) (xy 69.433948 -18.476214) (xy 69.43377 -18.4912) (xy 74.232262 -18.4912)
			(xy 74.232808 -18.448529) (xy 74.240982 -18.363579) (xy 74.257255 -18.279803) (xy 74.281476 -18.19797)
			(xy 74.313425 -18.118833) (xy 74.352806 -18.043121) (xy 74.399257 -17.971528) (xy 74.452352 -17.904713)
			(xy 74.511602 -17.843291) (xy 74.576463 -17.787826) (xy 74.646338 -17.738828) (xy 74.720585 -17.696748)
			(xy 74.79852 -17.661973) (xy 74.838814 -17.64792) (xy 74.849466 -17.643697) (xy 74.865885 -17.627756)
			(xy 74.873802 -17.606285) (xy 74.873358 -17.594834) (xy 74.87158 -17.558512) (xy 74.872066 -17.531261)
			(xy 74.879822 -17.477313) (xy 74.895177 -17.425018) (xy 74.917819 -17.375441) (xy 74.947285 -17.329591)
			(xy 74.982976 -17.2884) (xy 75.024167 -17.252709) (xy 75.070017 -17.223243) (xy 75.119594 -17.200601)
			(xy 75.171889 -17.185246) (xy 75.225837 -17.17749) (xy 75.280339 -17.17749) (xy 75.334287 -17.185246)
			(xy 75.386582 -17.200601) (xy 75.436159 -17.223243) (xy 75.482009 -17.252709) (xy 75.5232 -17.2884)
			(xy 75.558891 -17.329591) (xy 75.588357 -17.375441) (xy 75.610999 -17.425018) (xy 75.626354 -17.477313)
			(xy 75.63411 -17.531261) (xy 75.634596 -17.558512) (xy 75.634245 -17.582355) (xy 75.628321 -17.629672)
			(xy 75.616553 -17.675884) (xy 75.60818 -17.698212) (xy 75.604528 -17.709037) (xy 75.606167 -17.731801)
			(xy 75.617456 -17.751637) (xy 75.626468 -17.758664) (xy 75.661973 -17.783798) (xy 75.728437 -17.83993)
			(xy 75.789106 -17.90228) (xy 75.843402 -17.970251) (xy 75.890807 -18.043196) (xy 75.930868 -18.120419)
			(xy 75.963203 -18.201182) (xy 75.987504 -18.284714) (xy 75.996038 -18.32737) (xy 75.99807 -18.3388)
			(xy 76.011786 -18.357088) (xy 76.101702 -18.405602) (xy 76.124816 -18.406618) (xy 76.135484 -18.402046)
			(xy 76.176588 -18.385277) (xy 76.261424 -18.359109) (xy 76.348446 -18.341529) (xy 76.436788 -18.332715)
			(xy 76.481178 -18.332196) (xy 76.519228 -18.332603) (xy 76.59505 -18.339103) (xy 76.67004 -18.352057)
			(xy 76.743648 -18.371371) (xy 76.779628 -18.383758) (xy 76.788671 -18.386584) (xy 76.807592 -18.386078)
			(xy 76.816458 -18.382742) (xy 76.844144 -18.371058) (xy 76.852714 -18.367033) (xy 76.866288 -18.353853)
			(xy 76.87056 -18.345404) (xy 76.888685 -18.307284) (xy 76.931153 -18.234331) (xy 76.980341 -18.165729)
			(xy 77.035806 -18.102094) (xy 77.09705 -18.044001) (xy 77.163522 -17.99197) (xy 77.234624 -17.94647)
			(xy 77.309716 -17.907911) (xy 77.388123 -17.876638) (xy 77.469141 -17.852933) (xy 77.552039 -17.83701)
			(xy 77.636073 -17.829012) (xy 77.67828 -17.828514) (xy 77.718904 -17.829005) (xy 77.799814 -17.836411)
			(xy 77.879712 -17.851162) (xy 77.957932 -17.873137) (xy 78.033822 -17.902151) (xy 78.106752 -17.937964)
			(xy 78.176112 -17.980277) (xy 78.241326 -18.028738) (xy 78.30185 -18.082942) (xy 78.35718 -18.142438)
			(xy 78.406855 -18.206732) (xy 78.450461 -18.275286) (xy 78.487636 -18.347531) (xy 78.503272 -18.385028)
			(xy 78.507191 -18.393638) (xy 78.5201 -18.407444) (xy 78.528418 -18.411952) (xy 78.555596 -18.424906)
			(xy 78.564331 -18.428603) (xy 78.58323 -18.430026) (xy 78.592426 -18.4277) (xy 78.635129 -18.415046)
			(xy 78.722415 -18.39731) (xy 78.811035 -18.388381) (xy 78.85557 -18.387822) (xy 78.897922 -18.388249)
			(xy 78.982241 -18.396298) (xy 79.065414 -18.412325) (xy 79.146687 -18.436187) (xy 79.225324 -18.467666)
			(xy 79.300612 -18.506477) (xy 79.371869 -18.55227) (xy 79.438452 -18.604628) (xy 79.499755 -18.663079)
			(xy 79.555225 -18.727093) (xy 79.604359 -18.796089) (xy 79.646711 -18.869444) (xy 79.681899 -18.946492)
			(xy 79.709603 -19.026536) (xy 79.729573 -19.108852) (xy 79.741628 -19.192693) (xy 79.745658 -19.2773)
			(xy 79.741628 -19.361907) (xy 79.729573 -19.445748) (xy 79.709603 -19.528064) (xy 79.681899 -19.608108)
			(xy 79.646711 -19.685156) (xy 79.604359 -19.758511) (xy 79.555225 -19.827507) (xy 79.499755 -19.891521)
			(xy 79.438452 -19.949972) (xy 79.371869 -20.00233) (xy 79.300612 -20.048123) (xy 79.225324 -20.086934)
			(xy 79.146687 -20.118413) (xy 79.065414 -20.142275) (xy 78.982241 -20.158302) (xy 78.897922 -20.166351)
			(xy 78.85557 -20.166838) (xy 78.814944 -20.166421) (xy 78.734031 -20.15901) (xy 78.654131 -20.144254)
			(xy 78.575909 -20.122273) (xy 78.500016 -20.093253) (xy 78.427086 -20.057434) (xy 78.357725 -20.015115)
			(xy 78.292512 -19.966648) (xy 78.231988 -19.912437) (xy 78.17666 -19.852935) (xy 78.126987 -19.788635)
			(xy 78.083383 -19.720074) (xy 78.046212 -19.647824) (xy 78.030578 -19.610324) (xy 78.026625 -19.601733)
			(xy 78.01374 -19.587916) (xy 78.005432 -19.5834) (xy 77.978254 -19.570446) (xy 77.96951 -19.566775)
			(xy 77.950619 -19.565336) (xy 77.941424 -19.567652) (xy 77.898725 -19.58032) (xy 77.811437 -19.59805)
			(xy 77.722815 -19.606974) (xy 77.67828 -19.60753) (xy 77.64023 -19.607134) (xy 77.564407 -19.60063)
			(xy 77.489418 -19.587673) (xy 77.415809 -19.568357) (xy 77.37983 -19.555968) (xy 77.370793 -19.553118)
			(xy 77.351866 -19.553639) (xy 77.343 -19.556984) (xy 77.315314 -19.568668) (xy 77.306749 -19.572702)
			(xy 77.293171 -19.585874) (xy 77.288898 -19.594322) (xy 77.27115 -19.631643) (xy 77.229678 -19.703133)
			(xy 77.206094 -19.73707) (xy 77.200506 -19.744944) (xy 77.195934 -19.763232) (xy 77.206348 -19.8501)
			(xy 77.215238 -19.86661) (xy 77.22235 -19.87296) (xy 77.242703 -19.891142) (xy 77.278503 -19.932337)
			(xy 77.308061 -19.978215) (xy 77.330776 -20.02784) (xy 77.346182 -20.080197) (xy 77.353964 -20.134216)
			(xy 77.35443 -20.161504) (xy 77.353892 -20.19005) (xy 77.345374 -20.246504) (xy 77.328542 -20.301059)
			(xy 77.303773 -20.352499) (xy 77.288136 -20.376388) (xy 77.282126 -20.386323) (xy 77.27881 -20.409277)
			(xy 77.285868 -20.431368) (xy 77.29347 -20.440142) (xy 77.322601 -20.471192) (xy 77.375459 -20.537945)
			(xy 77.421699 -20.609442) (xy 77.460897 -20.685029) (xy 77.492695 -20.764015) (xy 77.516801 -20.845678)
			(xy 77.532995 -20.92927) (xy 77.541129 -21.014027) (xy 77.541628 -21.0566) (xy 77.54111 -21.09857)
			(xy 77.53322 -21.182138) (xy 77.517492 -21.26459) (xy 77.494064 -21.345194) (xy 77.463146 -21.423232)
			(xy 77.425013 -21.49801) (xy 77.380004 -21.568862) (xy 77.32852 -21.635158) (xy 77.271018 -21.696309)
			(xy 77.20801 -21.751769) (xy 77.140057 -21.801046) (xy 77.067763 -21.843701) (xy 76.991772 -21.879355)
			(xy 76.91276 -21.907691) (xy 76.831429 -21.928455) (xy 76.790042 -21.93544) (xy 76.777342 -21.937218)
			(xy 76.75753 -21.952204) (xy 76.710286 -22.050502) (xy 76.711302 -22.075394) (xy 76.717652 -22.086316)
			(xy 76.740279 -22.12687) (xy 76.777909 -22.211777) (xy 76.806498 -22.30014) (xy 76.825735 -22.390997)
			(xy 76.835411 -22.483364) (xy 76.836016 -22.5298) (xy 76.835585 -22.571119) (xy 76.827906 -22.6534)
			(xy 76.812632 -22.734614) (xy 76.789894 -22.814063) (xy 76.75989 -22.891061) (xy 76.722876 -22.964947)
			(xy 76.679172 -23.035083) (xy 76.629155 -23.100865) (xy 76.573254 -23.161728) (xy 76.511952 -23.217146)
			(xy 76.479146 -23.24227) (xy 76.472222 -23.247833) (xy 76.46247 -23.262667) (xy 76.460096 -23.271226)
			(xy 76.453238 -23.300182) (xy 76.451608 -23.308584) (xy 76.453418 -23.325592) (xy 76.456794 -23.333456)
			(xy 76.468356 -23.359066) (xy 76.484643 -23.412845) (xy 76.492874 -23.468429) (xy 76.49337 -23.496524)
			(xy 76.492884 -23.523775) (xy 76.485128 -23.577723) (xy 76.469773 -23.630018) (xy 76.447131 -23.679595)
			(xy 76.417665 -23.725445) (xy 76.381974 -23.766636) (xy 76.340783 -23.802327) (xy 76.294933 -23.831793)
			(xy 76.245356 -23.854435) (xy 76.193061 -23.86979) (xy 76.139113 -23.877546) (xy 76.084611 -23.877546)
			(xy 76.030663 -23.86979) (xy 75.978368 -23.854435) (xy 75.928791 -23.831793) (xy 75.882941 -23.802327)
			(xy 75.84175 -23.766636) (xy 75.806059 -23.725445) (xy 75.776593 -23.679595) (xy 75.753951 -23.630018)
			(xy 75.738596 -23.577723) (xy 75.73084 -23.523775) (xy 75.730354 -23.496524) (xy 75.730421 -23.486727)
			(xy 75.731436 -23.467159) (xy 75.732386 -23.457408) (xy 75.732877 -23.448872) (xy 75.728853 -23.432263)
			(xy 75.724512 -23.424896) (xy 75.70851 -23.39975) (xy 75.703416 -23.392507) (xy 75.68939 -23.381721)
			(xy 75.681078 -23.378668) (xy 75.63985 -23.365172) (xy 75.559959 -23.331355) (xy 75.483741 -23.289919)
			(xy 75.411919 -23.241259) (xy 75.345176 -23.185838) (xy 75.284147 -23.124181) (xy 75.229411 -23.056875)
			(xy 75.181488 -22.984559) (xy 75.140834 -22.90792) (xy 75.107836 -22.827688) (xy 75.082806 -22.744624)
			(xy 75.065983 -22.659517) (xy 75.057526 -22.573177) (xy 75.057 -22.5298) (xy 75.057494 -22.487829)
			(xy 75.065384 -22.40426) (xy 75.081114 -22.321806) (xy 75.104542 -22.241201) (xy 75.135461 -22.163162)
			(xy 75.173596 -22.088383) (xy 75.218606 -22.017531) (xy 75.270093 -21.951234) (xy 75.327597 -21.890084)
			(xy 75.390607 -21.834624) (xy 75.458562 -21.785347) (xy 75.530858 -21.742693) (xy 75.606851 -21.70704)
			(xy 75.685865 -21.678706) (xy 75.767198 -21.657943) (xy 75.808586 -21.65096) (xy 75.821286 -21.649182)
			(xy 75.841098 -21.634196) (xy 75.888342 -21.535898) (xy 75.887326 -21.511006) (xy 75.880976 -21.500084)
			(xy 75.858351 -21.459528) (xy 75.82072 -21.374622) (xy 75.792131 -21.28626) (xy 75.772893 -21.195402)
			(xy 75.763217 -21.103036) (xy 75.762612 -21.0566) (xy 75.763054 -21.015482) (xy 75.770647 -20.933596)
			(xy 75.785769 -20.852761) (xy 75.80829 -20.773668) (xy 75.838018 -20.696992) (xy 75.874698 -20.623388)
			(xy 75.918018 -20.553486) (xy 75.942444 -20.520406) (xy 75.947966 -20.51244) (xy 75.953053 -20.493752)
			(xy 75.95235 -20.484084) (xy 75.948794 -20.453604) (xy 75.947355 -20.444381) (xy 75.938741 -20.427836)
			(xy 75.93203 -20.421346) (xy 75.912273 -20.40315) (xy 75.877544 -20.362178) (xy 75.8489 -20.316742)
			(xy 75.826908 -20.26774) (xy 75.812 -20.21614) (xy 75.804471 -20.162959) (xy 75.804014 -20.136104)
			(xy 75.8045 -20.108014) (xy 75.812745 -20.052443) (xy 75.829057 -19.998683) (xy 75.853083 -19.9479)
			(xy 75.868276 -19.924268) (xy 75.874278 -19.914104) (xy 75.877174 -19.890704) (xy 75.869411 -19.868439)
			(xy 75.861418 -19.859752) (xy 75.829118 -19.827595) (xy 75.770579 -19.757729) (xy 75.719492 -19.682242)
			(xy 75.676392 -19.601927) (xy 75.64173 -19.517626) (xy 75.61587 -19.430223) (xy 75.60691 -19.385534)
			(xy 75.604878 -19.374104) (xy 75.591162 -19.355816) (xy 75.501246 -19.307302) (xy 75.478132 -19.306286)
			(xy 75.467464 -19.310858) (xy 75.426354 -19.327612) (xy 75.34152 -19.353784) (xy 75.2545 -19.371368)
			(xy 75.16616 -19.380187) (xy 75.12177 -19.380708) (xy 75.080667 -19.380262) (xy 74.998812 -19.372674)
			(xy 74.918006 -19.357567) (xy 74.838939 -19.335068) (xy 74.762285 -19.30537) (xy 74.688698 -19.268725)
			(xy 74.618806 -19.225448) (xy 74.553205 -19.175907) (xy 74.492455 -19.120524) (xy 74.437074 -19.059772)
			(xy 74.387535 -18.994169) (xy 74.34426 -18.924276) (xy 74.307618 -18.850688) (xy 74.277923 -18.774033)
			(xy 74.255426 -18.694965) (xy 74.240321 -18.614158) (xy 74.232737 -18.532303) (xy 74.232262 -18.4912)
			(xy 69.43377 -18.4912) (xy 69.433444 -18.518562) (xy 69.425393 -18.602876) (xy 69.409364 -18.686042)
			(xy 69.385503 -18.767309) (xy 69.354024 -18.845939) (xy 69.315213 -18.92122) (xy 69.269423 -18.992472)
			(xy 69.217067 -19.059048) (xy 69.158619 -19.120346) (xy 69.094609 -19.175811) (xy 69.025617 -19.22494)
			(xy 68.952267 -19.267289) (xy 68.875224 -19.302473) (xy 68.795185 -19.330175) (xy 68.712876 -19.350143)
			(xy 68.629041 -19.362196) (xy 68.54444 -19.366227) (xy 68.459839 -19.362196) (xy 68.376004 -19.350143)
			(xy 68.293695 -19.330175) (xy 68.213656 -19.302473) (xy 68.136613 -19.267289) (xy 68.063263 -19.22494)
			(xy 67.994271 -19.175811) (xy 67.930261 -19.120346) (xy 67.871813 -19.059048) (xy 67.819457 -18.992472)
			(xy 67.773667 -18.92122) (xy 67.734856 -18.845939) (xy 67.703377 -18.767309) (xy 67.679516 -18.686042)
			(xy 67.663487 -18.602876) (xy 67.655436 -18.518562) (xy 64.724026 -18.518562) (xy 64.724026 -19.958304)
			(xy 74.152504 -19.958304) (xy 74.156575 -19.902682) (xy 74.168701 -19.848245) (xy 74.188624 -19.796154)
			(xy 74.21592 -19.747519) (xy 74.250006 -19.703376) (xy 74.290155 -19.664667) (xy 74.335513 -19.632216)
			(xy 74.385113 -19.606715) (xy 74.437897 -19.588708) (xy 74.49274 -19.578578) (xy 74.548474 -19.576541)
			(xy 74.603911 -19.582641) (xy 74.657868 -19.596747) (xy 74.709197 -19.618559) (xy 74.756803 -19.647613)
			(xy 74.799671 -19.683288) (xy 74.836888 -19.724825) (xy 74.867661 -19.771338) (xy 74.891333 -19.821835)
			(xy 74.907401 -19.875242) (xy 74.915521 -19.930418) (xy 74.91603 -19.958304) (xy 74.915521 -19.98619)
			(xy 74.907401 -20.041366) (xy 74.891333 -20.094773) (xy 74.867661 -20.14527) (xy 74.836888 -20.191783)
			(xy 74.799671 -20.23332) (xy 74.756803 -20.268995) (xy 74.709197 -20.298049) (xy 74.657868 -20.319861)
			(xy 74.603911 -20.333967) (xy 74.548474 -20.340067) (xy 74.49274 -20.33803) (xy 74.437897 -20.3279)
			(xy 74.385113 -20.309893) (xy 74.335513 -20.284392) (xy 74.290155 -20.251941) (xy 74.250006 -20.213232)
			(xy 74.21592 -20.169089) (xy 74.188624 -20.120454) (xy 74.168701 -20.068363) (xy 74.156575 -20.013926)
			(xy 74.152504 -19.958304) (xy 64.724026 -19.958304) (xy 64.724026 -21.0881) (xy 69.020483 -21.0881)
			(xy 69.024513 -21.003501) (xy 69.036566 -20.919669) (xy 69.056533 -20.837362) (xy 69.084233 -20.757325)
			(xy 69.119415 -20.680284) (xy 69.161761 -20.606935) (xy 69.210887 -20.537944) (xy 69.266349 -20.473935)
			(xy 69.327643 -20.415488) (xy 69.394216 -20.363131) (xy 69.465464 -20.317339) (xy 69.540742 -20.278527)
			(xy 69.619368 -20.247046) (xy 69.700631 -20.223181) (xy 69.783794 -20.207149) (xy 69.868105 -20.199094)
			(xy 69.910452 -20.198588) (xy 69.952896 -20.19906) (xy 70.037397 -20.207152) (xy 70.120743 -20.223257)
			(xy 70.202175 -20.247229) (xy 70.280954 -20.278849) (xy 70.318884 -20.297902) (xy 70.330048 -20.302883)
			(xy 70.354456 -20.302883) (xy 70.36562 -20.297902) (xy 70.403559 -20.278868) (xy 70.482336 -20.247249)
			(xy 70.563766 -20.223278) (xy 70.64711 -20.207174) (xy 70.731609 -20.199083) (xy 70.774052 -20.198588)
			(xy 70.816403 -20.199082) (xy 70.90072 -20.207129) (xy 70.983892 -20.223155) (xy 71.065163 -20.247014)
			(xy 71.143798 -20.278491) (xy 71.219084 -20.317301) (xy 71.290341 -20.363091) (xy 71.356922 -20.415448)
			(xy 71.418225 -20.473896) (xy 71.473694 -20.537908) (xy 71.522826 -20.606902) (xy 71.565178 -20.680254)
			(xy 71.600365 -20.757301) (xy 71.628069 -20.837343) (xy 71.648039 -20.919656) (xy 71.65261 -20.951444)
			(xy 74.153774 -20.951444) (xy 74.157845 -20.895822) (xy 74.169971 -20.841385) (xy 74.189894 -20.789294)
			(xy 74.21719 -20.740659) (xy 74.251276 -20.696516) (xy 74.291425 -20.657807) (xy 74.336783 -20.625356)
			(xy 74.386383 -20.599855) (xy 74.439167 -20.581848) (xy 74.49401 -20.571718) (xy 74.549744 -20.569681)
			(xy 74.605181 -20.575781) (xy 74.659138 -20.589887) (xy 74.710467 -20.611699) (xy 74.758073 -20.640753)
			(xy 74.800941 -20.676428) (xy 74.838158 -20.717965) (xy 74.868931 -20.764478) (xy 74.892603 -20.814975)
			(xy 74.908671 -20.868382) (xy 74.916791 -20.923558) (xy 74.9173 -20.951444) (xy 74.916791 -20.97933)
			(xy 74.908671 -21.034506) (xy 74.892603 -21.087913) (xy 74.868931 -21.13841) (xy 74.838158 -21.184923)
			(xy 74.800941 -21.22646) (xy 74.758073 -21.262135) (xy 74.710467 -21.291189) (xy 74.659138 -21.313001)
			(xy 74.605181 -21.327107) (xy 74.549744 -21.333207) (xy 74.49401 -21.33117) (xy 74.439167 -21.32104)
			(xy 74.386383 -21.303033) (xy 74.336783 -21.277532) (xy 74.291425 -21.245081) (xy 74.251276 -21.206372)
			(xy 74.21719 -21.162229) (xy 74.189894 -21.113594) (xy 74.169971 -21.061503) (xy 74.157845 -21.007066)
			(xy 74.153774 -20.951444) (xy 71.65261 -20.951444) (xy 71.660094 -21.003495) (xy 71.664124 -21.0881)
			(xy 71.660094 -21.172705) (xy 71.648039 -21.256544) (xy 71.628069 -21.338857) (xy 71.600365 -21.418899)
			(xy 71.565178 -21.495946) (xy 71.522826 -21.569298) (xy 71.473694 -21.638292) (xy 71.418225 -21.702304)
			(xy 71.356922 -21.760752) (xy 71.290341 -21.813109) (xy 71.247803 -21.840444) (xy 74.153774 -21.840444)
			(xy 74.157845 -21.784822) (xy 74.169971 -21.730385) (xy 74.189894 -21.678294) (xy 74.21719 -21.629659)
			(xy 74.251276 -21.585516) (xy 74.291425 -21.546807) (xy 74.336783 -21.514356) (xy 74.386383 -21.488855)
			(xy 74.439167 -21.470848) (xy 74.49401 -21.460718) (xy 74.549744 -21.458681) (xy 74.605181 -21.464781)
			(xy 74.659138 -21.478887) (xy 74.710467 -21.500699) (xy 74.758073 -21.529753) (xy 74.800941 -21.565428)
			(xy 74.838158 -21.606965) (xy 74.868931 -21.653478) (xy 74.892603 -21.703975) (xy 74.908671 -21.757382)
			(xy 74.916791 -21.812558) (xy 74.9173 -21.840444) (xy 74.916791 -21.86833) (xy 74.908671 -21.923506)
			(xy 74.892603 -21.976913) (xy 74.868931 -22.02741) (xy 74.838158 -22.073923) (xy 74.800941 -22.11546)
			(xy 74.758073 -22.151135) (xy 74.710467 -22.180189) (xy 74.659138 -22.202001) (xy 74.605181 -22.216107)
			(xy 74.549744 -22.222207) (xy 74.49401 -22.22017) (xy 74.439167 -22.21004) (xy 74.386383 -22.192033)
			(xy 74.336783 -22.166532) (xy 74.291425 -22.134081) (xy 74.251276 -22.095372) (xy 74.21719 -22.051229)
			(xy 74.189894 -22.002594) (xy 74.169971 -21.950503) (xy 74.157845 -21.896066) (xy 74.153774 -21.840444)
			(xy 71.247803 -21.840444) (xy 71.219084 -21.858899) (xy 71.143798 -21.897709) (xy 71.065163 -21.929186)
			(xy 70.983892 -21.953045) (xy 70.90072 -21.969071) (xy 70.816403 -21.977118) (xy 70.774052 -21.977604)
			(xy 70.731608 -21.977131) (xy 70.647107 -21.969039) (xy 70.563761 -21.952935) (xy 70.482329 -21.928963)
			(xy 70.40355 -21.897343) (xy 70.36562 -21.87829) (xy 70.354456 -21.873309) (xy 70.330048 -21.873309)
			(xy 70.318884 -21.87829) (xy 70.280962 -21.897359) (xy 70.20218 -21.928972) (xy 70.120745 -21.952935)
			(xy 70.037398 -21.969031) (xy 69.952896 -21.977114) (xy 69.910452 -21.977604) (xy 69.868105 -21.977106)
			(xy 69.783794 -21.969051) (xy 69.700631 -21.953019) (xy 69.619368 -21.929154) (xy 69.540742 -21.897673)
			(xy 69.465464 -21.858861) (xy 69.394216 -21.813069) (xy 69.327643 -21.760712) (xy 69.266349 -21.702265)
			(xy 69.210887 -21.638256) (xy 69.161761 -21.569265) (xy 69.119415 -21.495916) (xy 69.084233 -21.418875)
			(xy 69.056533 -21.338838) (xy 69.036566 -21.256531) (xy 69.024513 -21.172699) (xy 69.020483 -21.0881)
			(xy 64.724026 -21.0881) (xy 64.724026 -24.357006) (xy 77.29626 -24.357006) (xy 77.29626 -24.27231)
			(xy 77.304311 -24.187996) (xy 77.32034 -24.10483) (xy 77.344201 -24.023563) (xy 77.37568 -23.944933)
			(xy 77.414491 -23.869652) (xy 77.460281 -23.7984) (xy 77.512637 -23.731824) (xy 77.571085 -23.670526)
			(xy 77.635095 -23.615061) (xy 77.704087 -23.565932) (xy 77.777437 -23.523583) (xy 77.85448 -23.488399)
			(xy 77.934519 -23.460697) (xy 78.016828 -23.440729) (xy 78.100663 -23.428676) (xy 78.185264 -23.424646)
			(xy 78.269865 -23.428676) (xy 78.3537 -23.440729) (xy 78.436009 -23.460697) (xy 78.516048 -23.488399)
			(xy 78.593091 -23.523583) (xy 78.666441 -23.565932) (xy 78.735433 -23.615061) (xy 78.799443 -23.670526)
			(xy 78.857891 -23.731824) (xy 78.910247 -23.7984) (xy 78.956037 -23.869652) (xy 78.994848 -23.944933)
			(xy 79.026327 -24.023563) (xy 79.050188 -24.10483) (xy 79.066217 -24.187996) (xy 79.074268 -24.27231)
			(xy 79.074772 -24.314658) (xy 79.074268 -24.357006) (xy 79.066217 -24.44132) (xy 79.050188 -24.524486)
			(xy 79.026327 -24.605753) (xy 78.994848 -24.684383) (xy 78.956037 -24.759664) (xy 78.910247 -24.830916)
			(xy 78.857891 -24.897492) (xy 78.799443 -24.95879) (xy 78.735433 -25.014255) (xy 78.666441 -25.063384)
			(xy 78.593091 -25.105733) (xy 78.516048 -25.140917) (xy 78.436009 -25.168619) (xy 78.3537 -25.188587)
			(xy 78.269865 -25.20064) (xy 78.185264 -25.204671) (xy 78.100663 -25.20064) (xy 78.016828 -25.188587)
			(xy 77.934519 -25.168619) (xy 77.85448 -25.140917) (xy 77.777437 -25.105733) (xy 77.704087 -25.063384)
			(xy 77.635095 -25.014255) (xy 77.571085 -24.95879) (xy 77.512637 -24.897492) (xy 77.460281 -24.830916)
			(xy 77.414491 -24.759664) (xy 77.37568 -24.684383) (xy 77.344201 -24.605753) (xy 77.32034 -24.524486)
			(xy 77.304311 -24.44132) (xy 77.29626 -24.357006) (xy 64.724026 -24.357006) (xy 64.724026 -25.193244)
			(xy 70.553324 -25.193244) (xy 70.557395 -25.137622) (xy 70.569521 -25.083185) (xy 70.589444 -25.031094)
			(xy 70.61674 -24.982459) (xy 70.650826 -24.938316) (xy 70.690975 -24.899607) (xy 70.736333 -24.867156)
			(xy 70.785933 -24.841655) (xy 70.838717 -24.823648) (xy 70.89356 -24.813518) (xy 70.949294 -24.811481)
			(xy 71.004731 -24.817581) (xy 71.058688 -24.831687) (xy 71.110017 -24.853499) (xy 71.157623 -24.882553)
			(xy 71.200491 -24.918228) (xy 71.237708 -24.959765) (xy 71.268481 -25.006278) (xy 71.292153 -25.056775)
			(xy 71.308221 -25.110182) (xy 71.316341 -25.165358) (xy 71.31685 -25.193244) (xy 71.316341 -25.22113)
			(xy 71.308221 -25.276306) (xy 71.292153 -25.329713) (xy 71.268481 -25.38021) (xy 71.237708 -25.426723)
			(xy 71.200491 -25.46826) (xy 71.157623 -25.503935) (xy 71.110017 -25.532989) (xy 71.058688 -25.554801)
			(xy 71.004731 -25.568907) (xy 70.949294 -25.575007) (xy 70.89356 -25.57297) (xy 70.838717 -25.56284)
			(xy 70.785933 -25.544833) (xy 70.736333 -25.519332) (xy 70.690975 -25.486881) (xy 70.650826 -25.448172)
			(xy 70.61674 -25.404029) (xy 70.589444 -25.355394) (xy 70.569521 -25.303303) (xy 70.557395 -25.248866)
			(xy 70.553324 -25.193244) (xy 64.724026 -25.193244) (xy 64.724026 -25.828752) (xy 64.724459 -25.838817)
			(xy 64.73219 -25.857406) (xy 64.739012 -25.86482) (xy 64.940688 -26.066496) (xy 64.948086 -26.073345)
			(xy 64.966684 -26.081084) (xy 64.976756 -26.081482)
		)
		(stroke
			(width 0)
			(type solid)
		)
		(fill yes)
		(layer "In15.Cu")
		(net "P12V_OCP_V3_2")
	)
	(gr_poly
		(pts
			(xy 222.515938 -79.892652) (xy 222.525815 -79.89219) (xy 222.544113 -79.884747) (xy 222.551498 -79.878174)
			(xy 222.551752 -79.87792) (xy 225.83902 -76.590652) (xy 225.839528 -76.590144) (xy 225.846113 -76.582764)
			(xy 225.853566 -76.564465) (xy 225.854006 -76.554584) (xy 225.854006 -74.861674) (xy 225.853739 -74.853141)
			(xy 225.848219 -74.836996) (xy 225.837674 -74.823582) (xy 225.830638 -74.818748) (xy 225.747834 -74.765662)
			(xy 225.72218 -74.76363) (xy 225.710242 -74.769218) (xy 225.68528 -74.780042) (xy 225.63306 -74.795312)
			(xy 225.579203 -74.803026) (xy 225.552 -74.803508) (xy 225.524749 -74.803022) (xy 225.470801 -74.795266)
			(xy 225.418506 -74.779911) (xy 225.368929 -74.757269) (xy 225.323079 -74.727803) (xy 225.281888 -74.692112)
			(xy 225.246197 -74.650921) (xy 225.216731 -74.605071) (xy 225.194089 -74.555494) (xy 225.178734 -74.503199)
			(xy 225.170978 -74.449251) (xy 225.170978 -74.394749) (xy 225.178734 -74.340801) (xy 225.194089 -74.288506)
			(xy 225.216731 -74.238929) (xy 225.246197 -74.193079) (xy 225.281888 -74.151888) (xy 225.323079 -74.116197)
			(xy 225.368929 -74.086731) (xy 225.418506 -74.064089) (xy 225.470801 -74.048734) (xy 225.524749 -74.040978)
			(xy 225.552 -74.040492) (xy 225.579206 -74.040934) (xy 225.63307 -74.048638) (xy 225.685289 -74.063932)
			(xy 225.710242 -74.074782) (xy 225.72218 -74.08037) (xy 225.747834 -74.078338) (xy 225.830638 -74.025252)
			(xy 225.837626 -74.020367) (xy 225.848138 -74.006957) (xy 225.853686 -73.990846) (xy 225.854006 -73.982326)
			(xy 225.854006 -68.060316) (xy 225.853568 -68.050252) (xy 225.845833 -68.031669) (xy 225.83902 -68.024248)
			(xy 223.917764 -66.102992) (xy 223.910652 -66.095626) (xy 223.891856 -66.088006) (xy 217.179652 -66.088006)
			(xy 217.169247 -66.088496) (xy 217.150144 -66.096748) (xy 217.135895 -66.111914) (xy 217.1319 -66.121534)
			(xy 217.094054 -66.226944) (xy 217.10269 -66.257678) (xy 217.115136 -66.268092) (xy 217.136476 -66.286293)
			(xy 217.174098 -66.32789) (xy 217.205217 -66.374552) (xy 217.229161 -66.425271) (xy 217.245413 -66.478952)
			(xy 217.253621 -66.534435) (xy 217.254074 -66.562478) (xy 217.253588 -66.589729) (xy 217.245832 -66.643677)
			(xy 217.230477 -66.695972) (xy 217.207835 -66.745549) (xy 217.178369 -66.791399) (xy 217.142678 -66.83259)
			(xy 217.101487 -66.868281) (xy 217.055637 -66.897747) (xy 217.00606 -66.920389) (xy 216.953765 -66.935744)
			(xy 216.899817 -66.9435) (xy 216.845315 -66.9435) (xy 216.791367 -66.935744) (xy 216.739072 -66.920389)
			(xy 216.689495 -66.897747) (xy 216.643645 -66.868281) (xy 216.602454 -66.83259) (xy 216.566763 -66.791399)
			(xy 216.537297 -66.745549) (xy 216.514655 -66.695972) (xy 216.4993 -66.643677) (xy 216.491544 -66.589729)
			(xy 216.491058 -66.562478) (xy 216.491555 -66.534437) (xy 216.49977 -66.47896) (xy 216.51602 -66.425284)
			(xy 216.539953 -66.374566) (xy 216.571056 -66.327899) (xy 216.608656 -66.286289) (xy 216.629996 -66.268092)
			(xy 216.642442 -66.257678) (xy 216.651078 -66.226944) (xy 216.613232 -66.121534) (xy 216.609232 -66.111913)
			(xy 216.594983 -66.096741) (xy 216.575887 -66.08846) (xy 216.56548 -66.088006) (xy 213.679786 -66.088006)
			(xy 213.669717 -66.088432) (xy 213.651117 -66.096151) (xy 213.643718 -66.102992) (xy 211.792312 -67.954398)
			(xy 211.78472 -67.96293) (xy 211.7772 -67.984463) (xy 211.77969 -68.007134) (xy 211.7852 -68.017136)
			(xy 211.7852 -68.01739) (xy 211.79881 -68.040106) (xy 211.820311 -68.088497) (xy 211.834913 -68.139397)
			(xy 211.842333 -68.191828) (xy 211.842858 -68.218304) (xy 211.842858 -68.225416) (xy 211.842689 -68.230496)
			(xy 212.039452 -68.230496) (xy 212.043523 -68.174874) (xy 212.055649 -68.120437) (xy 212.075572 -68.068346)
			(xy 212.102868 -68.019711) (xy 212.136954 -67.975568) (xy 212.177103 -67.936859) (xy 212.222461 -67.904408)
			(xy 212.272061 -67.878907) (xy 212.324845 -67.8609) (xy 212.379688 -67.85077) (xy 212.435422 -67.848733)
			(xy 212.490859 -67.854833) (xy 212.544816 -67.868939) (xy 212.596145 -67.890751) (xy 212.643751 -67.919805)
			(xy 212.685319 -67.954398) (xy 220.014036 -67.954398) (xy 220.018107 -67.898776) (xy 220.030233 -67.844339)
			(xy 220.050156 -67.792248) (xy 220.077452 -67.743613) (xy 220.111538 -67.69947) (xy 220.151687 -67.660761)
			(xy 220.197045 -67.62831) (xy 220.246645 -67.602809) (xy 220.299429 -67.584802) (xy 220.354272 -67.574672)
			(xy 220.410006 -67.572635) (xy 220.465443 -67.578735) (xy 220.5194 -67.592841) (xy 220.570729 -67.614653)
			(xy 220.618335 -67.643707) (xy 220.661203 -67.679382) (xy 220.69842 -67.720919) (xy 220.729193 -67.767432)
			(xy 220.752865 -67.817929) (xy 220.768933 -67.871336) (xy 220.776297 -67.921378) (xy 223.481898 -67.921378)
			(xy 223.485969 -67.865756) (xy 223.498095 -67.811319) (xy 223.518018 -67.759228) (xy 223.545314 -67.710593)
			(xy 223.5794 -67.66645) (xy 223.619549 -67.627741) (xy 223.664907 -67.59529) (xy 223.714507 -67.569789)
			(xy 223.767291 -67.551782) (xy 223.822134 -67.541652) (xy 223.877868 -67.539615) (xy 223.933305 -67.545715)
			(xy 223.987262 -67.559821) (xy 224.038591 -67.581633) (xy 224.086197 -67.610687) (xy 224.129065 -67.646362)
			(xy 224.166282 -67.687899) (xy 224.197055 -67.734412) (xy 224.220727 -67.784909) (xy 224.236795 -67.838316)
			(xy 224.244915 -67.893492) (xy 224.245424 -67.921378) (xy 224.244915 -67.949264) (xy 224.236795 -68.00444)
			(xy 224.220727 -68.057847) (xy 224.197055 -68.108344) (xy 224.166282 -68.154857) (xy 224.129065 -68.196394)
			(xy 224.086197 -68.232069) (xy 224.038591 -68.261123) (xy 223.987262 -68.282935) (xy 223.933305 -68.297041)
			(xy 223.877868 -68.303141) (xy 223.822134 -68.301104) (xy 223.767291 -68.290974) (xy 223.714507 -68.272967)
			(xy 223.664907 -68.247466) (xy 223.619549 -68.215015) (xy 223.5794 -68.176306) (xy 223.545314 -68.132163)
			(xy 223.518018 -68.083528) (xy 223.498095 -68.031437) (xy 223.485969 -67.977) (xy 223.481898 -67.921378)
			(xy 220.776297 -67.921378) (xy 220.777053 -67.926512) (xy 220.777562 -67.954398) (xy 220.777053 -67.982284)
			(xy 220.768933 -68.03746) (xy 220.752865 -68.090867) (xy 220.729193 -68.141364) (xy 220.69842 -68.187877)
			(xy 220.661203 -68.229414) (xy 220.618335 -68.265089) (xy 220.570729 -68.294143) (xy 220.5194 -68.315955)
			(xy 220.465443 -68.330061) (xy 220.410006 -68.336161) (xy 220.354272 -68.334124) (xy 220.299429 -68.323994)
			(xy 220.246645 -68.305987) (xy 220.197045 -68.280486) (xy 220.151687 -68.248035) (xy 220.111538 -68.209326)
			(xy 220.077452 -68.165183) (xy 220.050156 -68.116548) (xy 220.030233 -68.064457) (xy 220.018107 -68.01002)
			(xy 220.014036 -67.954398) (xy 212.685319 -67.954398) (xy 212.686619 -67.95548) (xy 212.723836 -67.997017)
			(xy 212.754609 -68.04353) (xy 212.778281 -68.094027) (xy 212.794349 -68.147434) (xy 212.802469 -68.20261)
			(xy 212.802978 -68.230496) (xy 212.802469 -68.258382) (xy 212.794349 -68.313558) (xy 212.78625 -68.340478)
			(xy 216.437716 -68.340478) (xy 216.441787 -68.284856) (xy 216.453913 -68.230419) (xy 216.473836 -68.178328)
			(xy 216.501132 -68.129693) (xy 216.535218 -68.08555) (xy 216.575367 -68.046841) (xy 216.620725 -68.01439)
			(xy 216.670325 -67.988889) (xy 216.723109 -67.970882) (xy 216.777952 -67.960752) (xy 216.833686 -67.958715)
			(xy 216.889123 -67.964815) (xy 216.94308 -67.978921) (xy 216.994409 -68.000733) (xy 217.042015 -68.029787)
			(xy 217.084883 -68.065462) (xy 217.1221 -68.106999) (xy 217.152873 -68.153512) (xy 217.176545 -68.204009)
			(xy 217.192613 -68.257416) (xy 217.200733 -68.312592) (xy 217.201242 -68.340478) (xy 217.200733 -68.368364)
			(xy 217.192613 -68.42354) (xy 217.176545 -68.476947) (xy 217.152873 -68.527444) (xy 217.1221 -68.573957)
			(xy 217.084883 -68.615494) (xy 217.042015 -68.651169) (xy 216.994409 -68.680223) (xy 216.94308 -68.702035)
			(xy 216.889123 -68.716141) (xy 216.833686 -68.722241) (xy 216.777952 -68.720204) (xy 216.723109 -68.710074)
			(xy 216.670325 -68.692067) (xy 216.620725 -68.666566) (xy 216.575367 -68.634115) (xy 216.535218 -68.595406)
			(xy 216.501132 -68.551263) (xy 216.473836 -68.502628) (xy 216.453913 -68.450537) (xy 216.441787 -68.3961)
			(xy 216.437716 -68.340478) (xy 212.78625 -68.340478) (xy 212.778281 -68.366965) (xy 212.754609 -68.417462)
			(xy 212.723836 -68.463975) (xy 212.686619 -68.505512) (xy 212.643751 -68.541187) (xy 212.596145 -68.570241)
			(xy 212.544816 -68.592053) (xy 212.490859 -68.606159) (xy 212.435422 -68.612259) (xy 212.379688 -68.610222)
			(xy 212.324845 -68.600092) (xy 212.272061 -68.582085) (xy 212.222461 -68.556584) (xy 212.177103 -68.524133)
			(xy 212.136954 -68.485424) (xy 212.102868 -68.441281) (xy 212.075572 -68.392646) (xy 212.055649 -68.340555)
			(xy 212.043523 -68.286118) (xy 212.039452 -68.230496) (xy 211.842689 -68.230496) (xy 211.841971 -68.252086)
			(xy 211.833664 -68.304798) (xy 211.818093 -68.355838) (xy 211.795564 -68.404211) (xy 211.766516 -68.448974)
			(xy 211.731514 -68.489254) (xy 211.691243 -68.524264) (xy 211.646486 -68.553323) (xy 211.598118 -68.575863)
			(xy 211.547081 -68.591444) (xy 211.494371 -68.599764) (xy 211.4677 -68.600574) (xy 211.461096 -68.600574)
			(xy 211.434556 -68.600096) (xy 211.381995 -68.592697) (xy 211.330966 -68.578084) (xy 211.282455 -68.55654)
			(xy 211.259674 -68.542916) (xy 211.25942 -68.542916) (xy 211.24941 -68.537402) (xy 211.226729 -68.534869)
			(xy 211.205183 -68.542394) (xy 211.196682 -68.550028) (xy 210.378548 -69.368162) (xy 218.846398 -69.368162)
			(xy 218.850469 -69.31254) (xy 218.862595 -69.258103) (xy 218.882518 -69.206012) (xy 218.909814 -69.157377)
			(xy 218.9439 -69.113234) (xy 218.984049 -69.074525) (xy 219.029407 -69.042074) (xy 219.079007 -69.016573)
			(xy 219.131791 -68.998566) (xy 219.186634 -68.988436) (xy 219.242368 -68.986399) (xy 219.297805 -68.992499)
			(xy 219.351762 -69.006605) (xy 219.403091 -69.028417) (xy 219.450697 -69.057471) (xy 219.493565 -69.093146)
			(xy 219.530782 -69.134683) (xy 219.561555 -69.181196) (xy 219.585227 -69.231693) (xy 219.601295 -69.2851)
			(xy 219.609415 -69.340276) (xy 219.609924 -69.368162) (xy 220.116398 -69.368162) (xy 220.120469 -69.31254)
			(xy 220.132595 -69.258103) (xy 220.152518 -69.206012) (xy 220.179814 -69.157377) (xy 220.2139 -69.113234)
			(xy 220.254049 -69.074525) (xy 220.299407 -69.042074) (xy 220.349007 -69.016573) (xy 220.401791 -68.998566)
			(xy 220.456634 -68.988436) (xy 220.512368 -68.986399) (xy 220.567805 -68.992499) (xy 220.621762 -69.006605)
			(xy 220.673091 -69.028417) (xy 220.720697 -69.057471) (xy 220.763565 -69.093146) (xy 220.800782 -69.134683)
			(xy 220.831555 -69.181196) (xy 220.855227 -69.231693) (xy 220.871295 -69.2851) (xy 220.879415 -69.340276)
			(xy 220.879924 -69.368162) (xy 220.879415 -69.396048) (xy 220.871295 -69.451224) (xy 220.855227 -69.504631)
			(xy 220.831555 -69.555128) (xy 220.800782 -69.601641) (xy 220.763565 -69.643178) (xy 220.720697 -69.678853)
			(xy 220.673091 -69.707907) (xy 220.648332 -69.718428) (xy 224.155508 -69.718428) (xy 224.155975 -69.691825)
			(xy 224.163353 -69.639132) (xy 224.177984 -69.587977) (xy 224.199583 -69.539352) (xy 224.227732 -69.494201)
			(xy 224.261884 -69.453402) (xy 224.301375 -69.417745) (xy 224.323148 -69.402452) (xy 224.334654 -69.394148)
			(xy 224.352868 -69.372401) (xy 224.36439 -69.346479) (xy 224.36833 -69.318388) (xy 224.364383 -69.290297)
			(xy 224.352855 -69.264378) (xy 224.334636 -69.242635) (xy 224.323148 -69.234304) (xy 224.301373 -69.219016)
			(xy 224.261893 -69.183349) (xy 224.22775 -69.142544) (xy 224.199605 -69.097393) (xy 224.178003 -69.048771)
			(xy 224.163364 -68.997619) (xy 224.155971 -68.94493) (xy 224.155508 -68.918328) (xy 224.155994 -68.891077)
			(xy 224.16375 -68.837129) (xy 224.179105 -68.784834) (xy 224.201747 -68.735257) (xy 224.231213 -68.689407)
			(xy 224.266904 -68.648216) (xy 224.308095 -68.612525) (xy 224.353945 -68.583059) (xy 224.403522 -68.560417)
			(xy 224.455817 -68.545062) (xy 224.509765 -68.537306) (xy 224.564267 -68.537306) (xy 224.618215 -68.545062)
			(xy 224.67051 -68.560417) (xy 224.720087 -68.583059) (xy 224.765937 -68.612525) (xy 224.807128 -68.648216)
			(xy 224.842819 -68.689407) (xy 224.872285 -68.735257) (xy 224.894927 -68.784834) (xy 224.910282 -68.837129)
			(xy 224.918038 -68.891077) (xy 224.918524 -68.918328) (xy 224.918054 -68.944932) (xy 224.91068 -68.997625)
			(xy 224.896052 -69.048782) (xy 224.874454 -69.097408) (xy 224.846305 -69.142559) (xy 224.812152 -69.183358)
			(xy 224.772658 -69.219012) (xy 224.750884 -69.234304) (xy 224.739427 -69.242667) (xy 224.721227 -69.264405)
			(xy 224.709711 -69.290312) (xy 224.705769 -69.318388) (xy 224.709704 -69.346464) (xy 224.721214 -69.372374)
			(xy 224.739408 -69.394117) (xy 224.750884 -69.402452) (xy 224.772646 -69.417758) (xy 224.812124 -69.453423)
			(xy 224.846267 -69.494225) (xy 224.874413 -69.539373) (xy 224.896017 -69.587992) (xy 224.91066 -69.639141)
			(xy 224.918058 -69.691827) (xy 224.918524 -69.718428) (xy 224.918038 -69.745679) (xy 224.910282 -69.799627)
			(xy 224.894927 -69.851922) (xy 224.872285 -69.901499) (xy 224.842819 -69.947349) (xy 224.807128 -69.98854)
			(xy 224.765937 -70.024231) (xy 224.720087 -70.053697) (xy 224.67051 -70.076339) (xy 224.618215 -70.091694)
			(xy 224.564267 -70.09945) (xy 224.509765 -70.09945) (xy 224.455817 -70.091694) (xy 224.403522 -70.076339)
			(xy 224.353945 -70.053697) (xy 224.308095 -70.024231) (xy 224.266904 -69.98854) (xy 224.231213 -69.947349)
			(xy 224.201747 -69.901499) (xy 224.179105 -69.851922) (xy 224.16375 -69.799627) (xy 224.155994 -69.745679)
			(xy 224.155508 -69.718428) (xy 220.648332 -69.718428) (xy 220.621762 -69.729719) (xy 220.567805 -69.743825)
			(xy 220.512368 -69.749925) (xy 220.456634 -69.747888) (xy 220.401791 -69.737758) (xy 220.349007 -69.719751)
			(xy 220.299407 -69.69425) (xy 220.254049 -69.661799) (xy 220.2139 -69.62309) (xy 220.179814 -69.578947)
			(xy 220.152518 -69.530312) (xy 220.132595 -69.478221) (xy 220.120469 -69.423784) (xy 220.116398 -69.368162)
			(xy 219.609924 -69.368162) (xy 219.609415 -69.396048) (xy 219.601295 -69.451224) (xy 219.585227 -69.504631)
			(xy 219.561555 -69.555128) (xy 219.530782 -69.601641) (xy 219.493565 -69.643178) (xy 219.450697 -69.678853)
			(xy 219.403091 -69.707907) (xy 219.351762 -69.729719) (xy 219.297805 -69.743825) (xy 219.242368 -69.749925)
			(xy 219.186634 -69.747888) (xy 219.131791 -69.737758) (xy 219.079007 -69.719751) (xy 219.029407 -69.69425)
			(xy 218.984049 -69.661799) (xy 218.9439 -69.62309) (xy 218.909814 -69.578947) (xy 218.882518 -69.530312)
			(xy 218.862595 -69.478221) (xy 218.850469 -69.423784) (xy 218.846398 -69.368162) (xy 210.378548 -69.368162)
			(xy 210.112864 -69.633846) (xy 210.105498 -69.640958) (xy 210.097878 -69.659754) (xy 210.097878 -70.024244)
			(xy 212.007956 -70.024244) (xy 212.012027 -69.968622) (xy 212.024153 -69.914185) (xy 212.044076 -69.862094)
			(xy 212.071372 -69.813459) (xy 212.105458 -69.769316) (xy 212.145607 -69.730607) (xy 212.190965 -69.698156)
			(xy 212.240565 -69.672655) (xy 212.293349 -69.654648) (xy 212.348192 -69.644518) (xy 212.403926 -69.642481)
			(xy 212.459363 -69.648581) (xy 212.51332 -69.662687) (xy 212.564649 -69.684499) (xy 212.612255 -69.713553)
			(xy 212.655123 -69.749228) (xy 212.69234 -69.790765) (xy 212.723113 -69.837278) (xy 212.746785 -69.887775)
			(xy 212.762853 -69.941182) (xy 212.770973 -69.996358) (xy 212.771482 -70.024244) (xy 212.770973 -70.05213)
			(xy 212.762853 -70.107306) (xy 212.746785 -70.160713) (xy 212.723113 -70.21121) (xy 212.69234 -70.257723)
			(xy 212.655123 -70.29926) (xy 212.612255 -70.334935) (xy 212.564649 -70.363989) (xy 212.51332 -70.385801)
			(xy 212.459363 -70.399907) (xy 212.403926 -70.406007) (xy 212.348192 -70.40397) (xy 212.293349 -70.39384)
			(xy 212.240565 -70.375833) (xy 212.190965 -70.350332) (xy 212.145607 -70.317881) (xy 212.105458 -70.279172)
			(xy 212.071372 -70.235029) (xy 212.044076 -70.186394) (xy 212.024153 -70.134303) (xy 212.012027 -70.079866)
			(xy 212.007956 -70.024244) (xy 210.097878 -70.024244) (xy 210.097878 -71.480426) (xy 214.549988 -71.480426)
			(xy 214.554059 -71.424804) (xy 214.566185 -71.370367) (xy 214.586108 -71.318276) (xy 214.613404 -71.269641)
			(xy 214.64749 -71.225498) (xy 214.687639 -71.186789) (xy 214.732997 -71.154338) (xy 214.782597 -71.128837)
			(xy 214.835381 -71.11083) (xy 214.890224 -71.1007) (xy 214.945958 -71.098663) (xy 215.001395 -71.104763)
			(xy 215.055352 -71.118869) (xy 215.058611 -71.120254) (xy 218.878402 -71.120254) (xy 218.882473 -71.064632)
			(xy 218.894599 -71.010195) (xy 218.914522 -70.958104) (xy 218.941818 -70.909469) (xy 218.975904 -70.865326)
			(xy 219.016053 -70.826617) (xy 219.061411 -70.794166) (xy 219.111011 -70.768665) (xy 219.163795 -70.750658)
			(xy 219.218638 -70.740528) (xy 219.274372 -70.738491) (xy 219.329809 -70.744591) (xy 219.383766 -70.758697)
			(xy 219.435095 -70.780509) (xy 219.455313 -70.792848) (xy 224.154998 -70.792848) (xy 224.159069 -70.737226)
			(xy 224.171195 -70.682789) (xy 224.191118 -70.630698) (xy 224.218414 -70.582063) (xy 224.2525 -70.53792)
			(xy 224.292649 -70.499211) (xy 224.338007 -70.46676) (xy 224.387607 -70.441259) (xy 224.440391 -70.423252)
			(xy 224.495234 -70.413122) (xy 224.550968 -70.411085) (xy 224.606405 -70.417185) (xy 224.660362 -70.431291)
			(xy 224.711691 -70.453103) (xy 224.759297 -70.482157) (xy 224.802165 -70.517832) (xy 224.839382 -70.559369)
			(xy 224.870155 -70.605882) (xy 224.893827 -70.656379) (xy 224.909895 -70.709786) (xy 224.918015 -70.764962)
			(xy 224.918524 -70.792848) (xy 224.918015 -70.820734) (xy 224.909895 -70.87591) (xy 224.893827 -70.929317)
			(xy 224.870155 -70.979814) (xy 224.839382 -71.026327) (xy 224.802165 -71.067864) (xy 224.759297 -71.103539)
			(xy 224.711691 -71.132593) (xy 224.660362 -71.154405) (xy 224.606405 -71.168511) (xy 224.550968 -71.174611)
			(xy 224.495234 -71.172574) (xy 224.440391 -71.162444) (xy 224.387607 -71.144437) (xy 224.338007 -71.118936)
			(xy 224.292649 -71.086485) (xy 224.2525 -71.047776) (xy 224.218414 -71.003633) (xy 224.191118 -70.954998)
			(xy 224.171195 -70.902907) (xy 224.159069 -70.84847) (xy 224.154998 -70.792848) (xy 219.455313 -70.792848)
			(xy 219.482701 -70.809563) (xy 219.525569 -70.845238) (xy 219.562786 -70.886775) (xy 219.593559 -70.933288)
			(xy 219.617231 -70.983785) (xy 219.633299 -71.037192) (xy 219.641419 -71.092368) (xy 219.641928 -71.120254)
			(xy 219.641419 -71.14814) (xy 219.633299 -71.203316) (xy 219.617231 -71.256723) (xy 219.593559 -71.30722)
			(xy 219.562786 -71.353733) (xy 219.525569 -71.39527) (xy 219.482701 -71.430945) (xy 219.435095 -71.459999)
			(xy 219.383766 -71.481811) (xy 219.329809 -71.495917) (xy 219.274372 -71.502017) (xy 219.218638 -71.49998)
			(xy 219.163795 -71.48985) (xy 219.111011 -71.471843) (xy 219.061411 -71.446342) (xy 219.016053 -71.413891)
			(xy 218.975904 -71.375182) (xy 218.941818 -71.331039) (xy 218.914522 -71.282404) (xy 218.894599 -71.230313)
			(xy 218.882473 -71.175876) (xy 218.878402 -71.120254) (xy 215.058611 -71.120254) (xy 215.106681 -71.140681)
			(xy 215.154287 -71.169735) (xy 215.197155 -71.20541) (xy 215.234372 -71.246947) (xy 215.265145 -71.29346)
			(xy 215.288817 -71.343957) (xy 215.304885 -71.397364) (xy 215.313005 -71.45254) (xy 215.313514 -71.480426)
			(xy 215.313005 -71.508312) (xy 215.304885 -71.563488) (xy 215.288817 -71.616895) (xy 215.265145 -71.667392)
			(xy 215.234372 -71.713905) (xy 215.197155 -71.755442) (xy 215.154287 -71.791117) (xy 215.106681 -71.820171)
			(xy 215.055352 -71.841983) (xy 215.001395 -71.856089) (xy 214.945958 -71.862189) (xy 214.890224 -71.860152)
			(xy 214.835381 -71.850022) (xy 214.782597 -71.832015) (xy 214.732997 -71.806514) (xy 214.687639 -71.774063)
			(xy 214.64749 -71.735354) (xy 214.613404 -71.691211) (xy 214.586108 -71.642576) (xy 214.566185 -71.590485)
			(xy 214.554059 -71.536048) (xy 214.549988 -71.480426) (xy 210.097878 -71.480426) (xy 210.097878 -72.34555)
			(xy 222.489774 -72.34555) (xy 222.493845 -72.289928) (xy 222.505971 -72.235491) (xy 222.525894 -72.1834)
			(xy 222.55319 -72.134765) (xy 222.587276 -72.090622) (xy 222.627425 -72.051913) (xy 222.672783 -72.019462)
			(xy 222.722383 -71.993961) (xy 222.775167 -71.975954) (xy 222.83001 -71.965824) (xy 222.885744 -71.963787)
			(xy 222.941181 -71.969887) (xy 222.995138 -71.983993) (xy 223.046467 -72.005805) (xy 223.094073 -72.034859)
			(xy 223.136941 -72.070534) (xy 223.174158 -72.112071) (xy 223.204931 -72.158584) (xy 223.228603 -72.209081)
			(xy 223.234203 -72.227694) (xy 224.602038 -72.227694) (xy 224.606109 -72.172072) (xy 224.618235 -72.117635)
			(xy 224.638158 -72.065544) (xy 224.665454 -72.016909) (xy 224.69954 -71.972766) (xy 224.739689 -71.934057)
			(xy 224.785047 -71.901606) (xy 224.834647 -71.876105) (xy 224.887431 -71.858098) (xy 224.942274 -71.847968)
			(xy 224.998008 -71.845931) (xy 225.053445 -71.852031) (xy 225.107402 -71.866137) (xy 225.158731 -71.887949)
			(xy 225.206337 -71.917003) (xy 225.249205 -71.952678) (xy 225.286422 -71.994215) (xy 225.317195 -72.040728)
			(xy 225.340867 -72.091225) (xy 225.356935 -72.144632) (xy 225.365055 -72.199808) (xy 225.365564 -72.227694)
			(xy 225.365055 -72.25558) (xy 225.356935 -72.310756) (xy 225.340867 -72.364163) (xy 225.317195 -72.41466)
			(xy 225.286422 -72.461173) (xy 225.249205 -72.50271) (xy 225.206337 -72.538385) (xy 225.158731 -72.567439)
			(xy 225.107402 -72.589251) (xy 225.053445 -72.603357) (xy 224.998008 -72.609457) (xy 224.942274 -72.60742)
			(xy 224.887431 -72.59729) (xy 224.834647 -72.579283) (xy 224.785047 -72.553782) (xy 224.739689 -72.521331)
			(xy 224.69954 -72.482622) (xy 224.665454 -72.438479) (xy 224.638158 -72.389844) (xy 224.618235 -72.337753)
			(xy 224.606109 -72.283316) (xy 224.602038 -72.227694) (xy 223.234203 -72.227694) (xy 223.244671 -72.262488)
			(xy 223.252791 -72.317664) (xy 223.2533 -72.34555) (xy 223.252791 -72.373436) (xy 223.244671 -72.428612)
			(xy 223.228603 -72.482019) (xy 223.204931 -72.532516) (xy 223.174158 -72.579029) (xy 223.136941 -72.620566)
			(xy 223.094073 -72.656241) (xy 223.046467 -72.685295) (xy 222.995138 -72.707107) (xy 222.941181 -72.721213)
			(xy 222.885744 -72.727313) (xy 222.83001 -72.725276) (xy 222.775167 -72.715146) (xy 222.722383 -72.697139)
			(xy 222.672783 -72.671638) (xy 222.627425 -72.639187) (xy 222.587276 -72.600478) (xy 222.55319 -72.556335)
			(xy 222.525894 -72.5077) (xy 222.505971 -72.455609) (xy 222.493845 -72.401172) (xy 222.489774 -72.34555)
			(xy 210.097878 -72.34555) (xy 210.097878 -73.050908) (xy 213.867998 -73.050908) (xy 213.872069 -72.995286)
			(xy 213.884195 -72.940849) (xy 213.904118 -72.888758) (xy 213.931414 -72.840123) (xy 213.9655 -72.79598)
			(xy 214.005649 -72.757271) (xy 214.051007 -72.72482) (xy 214.100607 -72.699319) (xy 214.153391 -72.681312)
			(xy 214.208234 -72.671182) (xy 214.263968 -72.669145) (xy 214.319405 -72.675245) (xy 214.373362 -72.689351)
			(xy 214.424691 -72.711163) (xy 214.472297 -72.740217) (xy 214.49311 -72.757538) (xy 217.103958 -72.757538)
			(xy 217.108029 -72.701916) (xy 217.120155 -72.647479) (xy 217.140078 -72.595388) (xy 217.167374 -72.546753)
			(xy 217.20146 -72.50261) (xy 217.241609 -72.463901) (xy 217.286967 -72.43145) (xy 217.336567 -72.405949)
			(xy 217.389351 -72.387942) (xy 217.444194 -72.377812) (xy 217.499928 -72.375775) (xy 217.555365 -72.381875)
			(xy 217.609322 -72.395981) (xy 217.660651 -72.417793) (xy 217.708257 -72.446847) (xy 217.751125 -72.482522)
			(xy 217.788342 -72.524059) (xy 217.819115 -72.570572) (xy 217.842787 -72.621069) (xy 217.858855 -72.674476)
			(xy 217.866975 -72.729652) (xy 217.867484 -72.757538) (xy 217.866975 -72.785424) (xy 217.858855 -72.8406)
			(xy 217.856793 -72.847454) (xy 219.739208 -72.847454) (xy 219.743279 -72.791832) (xy 219.755405 -72.737395)
			(xy 219.775328 -72.685304) (xy 219.802624 -72.636669) (xy 219.83671 -72.592526) (xy 219.876859 -72.553817)
			(xy 219.922217 -72.521366) (xy 219.971817 -72.495865) (xy 220.024601 -72.477858) (xy 220.079444 -72.467728)
			(xy 220.135178 -72.465691) (xy 220.190615 -72.471791) (xy 220.244572 -72.485897) (xy 220.295901 -72.507709)
			(xy 220.343507 -72.536763) (xy 220.386375 -72.572438) (xy 220.423592 -72.613975) (xy 220.454365 -72.660488)
			(xy 220.478037 -72.710985) (xy 220.494105 -72.764392) (xy 220.502225 -72.819568) (xy 220.502734 -72.847454)
			(xy 220.502225 -72.87534) (xy 220.497133 -72.909938) (xy 221.675958 -72.909938) (xy 221.680029 -72.854316)
			(xy 221.692155 -72.799879) (xy 221.712078 -72.747788) (xy 221.739374 -72.699153) (xy 221.77346 -72.65501)
			(xy 221.813609 -72.616301) (xy 221.858967 -72.58385) (xy 221.908567 -72.558349) (xy 221.961351 -72.540342)
			(xy 222.016194 -72.530212) (xy 222.071928 -72.528175) (xy 222.127365 -72.534275) (xy 222.181322 -72.548381)
			(xy 222.232651 -72.570193) (xy 222.280257 -72.599247) (xy 222.323125 -72.634922) (xy 222.360342 -72.676459)
			(xy 222.391115 -72.722972) (xy 222.414787 -72.773469) (xy 222.430855 -72.826876) (xy 222.438975 -72.882052)
			(xy 222.439484 -72.909938) (xy 222.438975 -72.937824) (xy 222.430855 -72.993) (xy 222.414787 -73.046407)
			(xy 222.391115 -73.096904) (xy 222.360342 -73.143417) (xy 222.323125 -73.184954) (xy 222.280257 -73.220629)
			(xy 222.232651 -73.249683) (xy 222.181322 -73.271495) (xy 222.127365 -73.285601) (xy 222.071928 -73.291701)
			(xy 222.016194 -73.289664) (xy 221.961351 -73.279534) (xy 221.908567 -73.261527) (xy 221.858967 -73.236026)
			(xy 221.813609 -73.203575) (xy 221.77346 -73.164866) (xy 221.739374 -73.120723) (xy 221.712078 -73.072088)
			(xy 221.692155 -73.019997) (xy 221.680029 -72.96556) (xy 221.675958 -72.909938) (xy 220.497133 -72.909938)
			(xy 220.494105 -72.930516) (xy 220.478037 -72.983923) (xy 220.454365 -73.03442) (xy 220.423592 -73.080933)
			(xy 220.386375 -73.12247) (xy 220.343507 -73.158145) (xy 220.295901 -73.187199) (xy 220.244572 -73.209011)
			(xy 220.190615 -73.223117) (xy 220.135178 -73.229217) (xy 220.079444 -73.22718) (xy 220.024601 -73.21705)
			(xy 219.971817 -73.199043) (xy 219.922217 -73.173542) (xy 219.876859 -73.141091) (xy 219.83671 -73.102382)
			(xy 219.802624 -73.058239) (xy 219.775328 -73.009604) (xy 219.755405 -72.957513) (xy 219.743279 -72.903076)
			(xy 219.739208 -72.847454) (xy 217.856793 -72.847454) (xy 217.842787 -72.894007) (xy 217.819115 -72.944504)
			(xy 217.788342 -72.991017) (xy 217.751125 -73.032554) (xy 217.708257 -73.068229) (xy 217.660651 -73.097283)
			(xy 217.609322 -73.119095) (xy 217.555365 -73.133201) (xy 217.499928 -73.139301) (xy 217.444194 -73.137264)
			(xy 217.389351 -73.127134) (xy 217.336567 -73.109127) (xy 217.286967 -73.083626) (xy 217.241609 -73.051175)
			(xy 217.20146 -73.012466) (xy 217.167374 -72.968323) (xy 217.140078 -72.919688) (xy 217.120155 -72.867597)
			(xy 217.108029 -72.81316) (xy 217.103958 -72.757538) (xy 214.49311 -72.757538) (xy 214.515165 -72.775892)
			(xy 214.552382 -72.817429) (xy 214.583155 -72.863942) (xy 214.606827 -72.914439) (xy 214.622895 -72.967846)
			(xy 214.631015 -73.023022) (xy 214.631524 -73.050908) (xy 214.631015 -73.078794) (xy 214.622895 -73.13397)
			(xy 214.606827 -73.187377) (xy 214.583155 -73.237874) (xy 214.552382 -73.284387) (xy 214.515165 -73.325924)
			(xy 214.472297 -73.361599) (xy 214.424691 -73.390653) (xy 214.373362 -73.412465) (xy 214.319405 -73.426571)
			(xy 214.263968 -73.432671) (xy 214.208234 -73.430634) (xy 214.153391 -73.420504) (xy 214.100607 -73.402497)
			(xy 214.051007 -73.376996) (xy 214.005649 -73.344545) (xy 213.9655 -73.305836) (xy 213.931414 -73.261693)
			(xy 213.904118 -73.213058) (xy 213.884195 -73.160967) (xy 213.872069 -73.10653) (xy 213.867998 -73.050908)
			(xy 210.097878 -73.050908) (xy 210.097878 -75.080451) (xy 220.769668 -75.080451) (xy 220.769668 -75.025949)
			(xy 220.777424 -74.972) (xy 220.792779 -74.919705) (xy 220.81542 -74.870128) (xy 220.844886 -74.824277)
			(xy 220.880577 -74.783086) (xy 220.921767 -74.747393) (xy 220.967617 -74.717926) (xy 221.017194 -74.695283)
			(xy 221.069489 -74.679927) (xy 221.123437 -74.672169) (xy 221.150688 -74.671682) (xy 221.178059 -74.672135)
			(xy 221.232239 -74.679953) (xy 221.284743 -74.695444) (xy 221.33449 -74.718289) (xy 221.380456 -74.748018)
			(xy 221.401386 -74.765662) (xy 221.408498 -74.771758) (xy 221.425516 -74.778108) (xy 221.51086 -74.778108)
			(xy 221.527878 -74.771758) (xy 221.53499 -74.765662) (xy 221.55591 -74.748008) (xy 221.601887 -74.718299)
			(xy 221.651637 -74.695467) (xy 221.70414 -74.679979) (xy 221.758318 -74.672154) (xy 221.785688 -74.671682)
			(xy 221.812941 -74.672164) (xy 221.866892 -74.67992) (xy 221.919189 -74.695274) (xy 221.96877 -74.717916)
			(xy 222.014623 -74.747383) (xy 222.055816 -74.783075) (xy 222.09151 -74.824267) (xy 222.120979 -74.87012)
			(xy 222.143621 -74.919699) (xy 222.158978 -74.971997) (xy 222.166735 -75.025947) (xy 222.166735 -75.080453)
			(xy 222.158978 -75.134403) (xy 222.143621 -75.186701) (xy 222.120979 -75.23628) (xy 222.09151 -75.282133)
			(xy 222.055816 -75.323325) (xy 222.014623 -75.359017) (xy 221.96877 -75.388484) (xy 221.919189 -75.411126)
			(xy 221.866892 -75.42648) (xy 221.812941 -75.434236) (xy 221.785688 -75.434698) (xy 221.758317 -75.434239)
			(xy 221.704138 -75.42642) (xy 221.651635 -75.410929) (xy 221.601888 -75.388086) (xy 221.555922 -75.35836)
			(xy 221.53499 -75.340718) (xy 221.527878 -75.334622) (xy 221.51086 -75.328272) (xy 221.425516 -75.328272)
			(xy 221.408498 -75.334622) (xy 221.401386 -75.340718) (xy 221.380435 -75.358333) (xy 221.334467 -75.388048)
			(xy 221.284724 -75.410888) (xy 221.232228 -75.426385) (xy 221.178056 -75.43422) (xy 221.150688 -75.434698)
			(xy 221.123437 -75.434231) (xy 221.069489 -75.426473) (xy 221.017194 -75.411117) (xy 220.967617 -75.388474)
			(xy 220.921767 -75.359007) (xy 220.880577 -75.323314) (xy 220.844886 -75.282123) (xy 220.81542 -75.236272)
			(xy 220.792779 -75.186695) (xy 220.777424 -75.1344) (xy 220.769668 -75.080451) (xy 210.097878 -75.080451)
			(xy 210.097878 -76.121768) (xy 216.910156 -76.121768) (xy 216.914227 -76.066146) (xy 216.926353 -76.011709)
			(xy 216.946276 -75.959618) (xy 216.973572 -75.910983) (xy 217.007658 -75.86684) (xy 217.047807 -75.828131)
			(xy 217.093165 -75.79568) (xy 217.142765 -75.770179) (xy 217.195549 -75.752172) (xy 217.250392 -75.742042)
			(xy 217.306126 -75.740005) (xy 217.361563 -75.746105) (xy 217.41552 -75.760211) (xy 217.466849 -75.782023)
			(xy 217.514455 -75.811077) (xy 217.557323 -75.846752) (xy 217.59454 -75.888289) (xy 217.625313 -75.934802)
			(xy 217.648985 -75.985299) (xy 217.665053 -76.038706) (xy 217.673173 -76.093882) (xy 217.673682 -76.121768)
			(xy 217.673173 -76.149654) (xy 217.665053 -76.20483) (xy 217.648985 -76.258237) (xy 217.625313 -76.308734)
			(xy 217.59454 -76.355247) (xy 217.557323 -76.396784) (xy 217.514455 -76.432459) (xy 217.466849 -76.461513)
			(xy 217.41552 -76.483325) (xy 217.361563 -76.497431) (xy 217.306126 -76.503531) (xy 217.250392 -76.501494)
			(xy 217.195549 -76.491364) (xy 217.142765 -76.473357) (xy 217.093165 -76.447856) (xy 217.047807 -76.415405)
			(xy 217.007658 -76.376696) (xy 216.973572 -76.332553) (xy 216.946276 -76.283918) (xy 216.926353 -76.231827)
			(xy 216.914227 -76.17739) (xy 216.910156 -76.121768) (xy 210.097878 -76.121768) (xy 210.097878 -76.469494)
			(xy 210.098354 -76.479735) (xy 210.106359 -76.498589) (xy 210.113372 -76.50607) (xy 210.16595 -76.55687)
			(xy 210.16971 -76.560303) (xy 210.178284 -76.565793) (xy 210.182968 -76.567792) (xy 210.19262 -76.571348)
			(xy 210.199986 -76.571094) (xy 210.215734 -76.57084) (xy 210.242984 -76.571306) (xy 210.296929 -76.579067)
			(xy 210.34922 -76.594426) (xy 210.398793 -76.617071) (xy 210.444638 -76.646541) (xy 210.485823 -76.682235)
			(xy 210.521508 -76.723428) (xy 210.550968 -76.76928) (xy 210.567071 -76.804551) (xy 220.600997 -76.804551)
			(xy 220.600997 -76.750049) (xy 220.608754 -76.696101) (xy 220.62411 -76.643806) (xy 220.646753 -76.594229)
			(xy 220.67622 -76.54838) (xy 220.711914 -76.507191) (xy 220.753105 -76.471501) (xy 220.798958 -76.442037)
			(xy 220.848536 -76.419399) (xy 220.900832 -76.404047) (xy 220.954781 -76.396295) (xy 220.982032 -76.395834)
			(xy 221.009403 -76.396273) (xy 221.063584 -76.404096) (xy 221.116088 -76.419591) (xy 221.165834 -76.442439)
			(xy 221.211799 -76.47217) (xy 221.23273 -76.489814) (xy 221.239842 -76.49591) (xy 221.25686 -76.50226)
			(xy 221.342204 -76.50226) (xy 221.359222 -76.49591) (xy 221.366334 -76.489814) (xy 221.387282 -76.472195)
			(xy 221.43325 -76.442479) (xy 221.482994 -76.419639) (xy 221.535491 -76.404144) (xy 221.589664 -76.396311)
			(xy 221.617032 -76.395834) (xy 221.644285 -76.396238) (xy 221.698235 -76.403999) (xy 221.750532 -76.419359)
			(xy 221.80011 -76.442004) (xy 221.845962 -76.471475) (xy 221.887153 -76.50717) (xy 221.922845 -76.548364)
			(xy 221.952311 -76.594218) (xy 221.974952 -76.643798) (xy 221.990308 -76.696096) (xy 221.998064 -76.750047)
			(xy 221.998064 -76.804553) (xy 221.990308 -76.858504) (xy 221.974952 -76.910802) (xy 221.952311 -76.960382)
			(xy 221.922845 -77.006236) (xy 221.887153 -77.04743) (xy 221.845962 -77.083125) (xy 221.80011 -77.112596)
			(xy 221.750532 -77.135241) (xy 221.698235 -77.150601) (xy 221.644285 -77.158362) (xy 221.617032 -77.15885)
			(xy 221.589662 -77.158377) (xy 221.535483 -77.150563) (xy 221.482979 -77.135076) (xy 221.433232 -77.112236)
			(xy 221.387265 -77.082511) (xy 221.366334 -77.06487) (xy 221.359222 -77.058774) (xy 221.342204 -77.052424)
			(xy 221.25686 -77.052424) (xy 221.239842 -77.058774) (xy 221.23273 -77.06487) (xy 221.211794 -77.082504)
			(xy 221.165822 -77.112217) (xy 221.116076 -77.135055) (xy 221.063576 -77.150547) (xy 221.009401 -77.158376)
			(xy 220.982032 -77.15885) (xy 220.954781 -77.158305) (xy 220.900832 -77.150553) (xy 220.848536 -77.135201)
			(xy 220.798958 -77.112563) (xy 220.753105 -77.083099) (xy 220.711914 -77.047409) (xy 220.67622 -77.00622)
			(xy 220.646753 -76.960371) (xy 220.62411 -76.910794) (xy 220.608754 -76.858499) (xy 220.600997 -76.804551)
			(xy 210.567071 -76.804551) (xy 210.573602 -76.818857) (xy 210.588951 -76.871152) (xy 210.5967 -76.925098)
			(xy 210.597242 -76.952348) (xy 210.596759 -76.979517) (xy 210.589043 -77.033305) (xy 210.573773 -77.085454)
			(xy 210.55126 -77.134909) (xy 210.521958 -77.18067) (xy 210.486459 -77.22181) (xy 210.445483 -77.257499)
			(xy 210.399859 -77.287012) (xy 210.350508 -77.309754) (xy 210.29843 -77.325264) (xy 210.244679 -77.333229)
			(xy 210.217512 -77.333856) (xy 210.21548 -77.333856) (xy 210.200687 -77.333713) (xy 210.17119 -77.331425)
			(xy 210.156552 -77.329284) (xy 210.152742 -77.328522) (xy 210.148678 -77.328522) (xy 210.138675 -77.329014)
			(xy 210.120194 -77.336678) (xy 210.106054 -77.350831) (xy 210.098405 -77.369318) (xy 210.097878 -77.379322)
			(xy 210.097878 -77.4319) (xy 218.076016 -77.4319) (xy 218.080087 -77.376278) (xy 218.092213 -77.321841)
			(xy 218.112136 -77.26975) (xy 218.139432 -77.221115) (xy 218.173518 -77.176972) (xy 218.213667 -77.138263)
			(xy 218.259025 -77.105812) (xy 218.308625 -77.080311) (xy 218.361409 -77.062304) (xy 218.416252 -77.052174)
			(xy 218.471986 -77.050137) (xy 218.527423 -77.056237) (xy 218.58138 -77.070343) (xy 218.632709 -77.092155)
			(xy 218.680315 -77.121209) (xy 218.723183 -77.156884) (xy 218.7604 -77.198421) (xy 218.791173 -77.244934)
			(xy 218.814845 -77.295431) (xy 218.830913 -77.348838) (xy 218.839033 -77.404014) (xy 218.839542 -77.4319)
			(xy 218.839033 -77.459786) (xy 218.830913 -77.514962) (xy 218.814845 -77.568369) (xy 218.791173 -77.618866)
			(xy 218.7604 -77.665379) (xy 218.723183 -77.706916) (xy 218.680315 -77.742591) (xy 218.632709 -77.771645)
			(xy 218.58138 -77.793457) (xy 218.527423 -77.807563) (xy 218.471986 -77.813663) (xy 218.416252 -77.811626)
			(xy 218.361409 -77.801496) (xy 218.308625 -77.783489) (xy 218.259025 -77.757988) (xy 218.213667 -77.725537)
			(xy 218.173518 -77.686828) (xy 218.139432 -77.642685) (xy 218.112136 -77.59405) (xy 218.092213 -77.541959)
			(xy 218.080087 -77.487522) (xy 218.076016 -77.4319) (xy 210.097878 -77.4319) (xy 210.097878 -77.432662)
			(xy 210.098345 -77.442536) (xy 210.105797 -77.460825) (xy 210.112356 -77.468222) (xy 210.11261 -77.468476)
			(xy 212.5218 -79.877666) (xy 212.522308 -79.878174) (xy 212.529688 -79.884761) (xy 212.547986 -79.892225)
			(xy 212.557868 -79.892652)
		)
		(stroke
			(width 0)
			(type solid)
		)
		(fill yes)
		(layer "In15.Cu")
		(net "GND")
	)
	(gr_poly
		(pts
			(xy 446.916302 -112.658398) (xy 446.926372 -112.657974) (xy 446.944976 -112.650259) (xy 446.95237 -112.643412)
			(xy 450.614542 -108.98124) (xy 450.621385 -108.973841) (xy 450.629107 -108.955242) (xy 450.629528 -108.945172)
			(xy 450.629528 -92.566998) (xy 450.629105 -92.556927) (xy 450.621394 -92.538321) (xy 450.614542 -92.53093)
			(xy 448.31254 -90.228928) (xy 448.30514 -90.222088) (xy 448.286541 -90.214371) (xy 448.276472 -90.213942)
			(xy 444.231014 -90.213942) (xy 444.221019 -90.214437) (xy 444.202543 -90.222073) (xy 444.18836 -90.236164)
			(xy 444.184024 -90.245184) (xy 444.178182 -90.259662) (xy 444.184024 -90.289634) (xy 444.852044 -90.9574)
			(xy 444.869091 -90.975114) (xy 444.897961 -91.014904) (xy 444.920246 -91.058724) (xy 444.935397 -91.105491)
			(xy 444.943041 -91.154053) (xy 444.943484 -91.178634) (xy 444.943484 -92.468192) (xy 445.845182 -92.468192)
			(xy 445.849253 -92.41257) (xy 445.861379 -92.358133) (xy 445.881302 -92.306042) (xy 445.908598 -92.257407)
			(xy 445.942684 -92.213264) (xy 445.982833 -92.174555) (xy 446.028191 -92.142104) (xy 446.077791 -92.116603)
			(xy 446.130575 -92.098596) (xy 446.185418 -92.088466) (xy 446.241152 -92.086429) (xy 446.296589 -92.092529)
			(xy 446.350546 -92.106635) (xy 446.401875 -92.128447) (xy 446.449481 -92.157501) (xy 446.492349 -92.193176)
			(xy 446.529566 -92.234713) (xy 446.560339 -92.281226) (xy 446.584011 -92.331723) (xy 446.600079 -92.38513)
			(xy 446.608199 -92.440306) (xy 446.608708 -92.468192) (xy 446.608199 -92.496078) (xy 446.600079 -92.551254)
			(xy 446.584011 -92.604661) (xy 446.560339 -92.655158) (xy 446.529566 -92.701671) (xy 446.492349 -92.743208)
			(xy 446.449481 -92.778883) (xy 446.401875 -92.807937) (xy 446.350546 -92.829749) (xy 446.296589 -92.843855)
			(xy 446.241152 -92.849955) (xy 446.185418 -92.847918) (xy 446.130575 -92.837788) (xy 446.077791 -92.819781)
			(xy 446.028191 -92.79428) (xy 445.982833 -92.761829) (xy 445.942684 -92.72312) (xy 445.908598 -92.678977)
			(xy 445.881302 -92.630342) (xy 445.861379 -92.578251) (xy 445.849253 -92.523814) (xy 445.845182 -92.468192)
			(xy 444.943484 -92.468192) (xy 444.943484 -93.219778) (xy 444.944017 -93.229768) (xy 444.951723 -93.248207)
			(xy 444.95847 -93.255592) (xy 445.18707 -93.484192) (xy 445.845182 -93.484192) (xy 445.849253 -93.42857)
			(xy 445.861379 -93.374133) (xy 445.881302 -93.322042) (xy 445.908598 -93.273407) (xy 445.942684 -93.229264)
			(xy 445.982833 -93.190555) (xy 446.028191 -93.158104) (xy 446.077791 -93.132603) (xy 446.130575 -93.114596)
			(xy 446.185418 -93.104466) (xy 446.241152 -93.102429) (xy 446.296589 -93.108529) (xy 446.350546 -93.122635)
			(xy 446.401875 -93.144447) (xy 446.449481 -93.173501) (xy 446.492349 -93.209176) (xy 446.529566 -93.250713)
			(xy 446.560339 -93.297226) (xy 446.584011 -93.347723) (xy 446.600079 -93.40113) (xy 446.608199 -93.456306)
			(xy 446.608708 -93.484192) (xy 446.608199 -93.512078) (xy 446.600079 -93.567254) (xy 446.584011 -93.620661)
			(xy 446.560339 -93.671158) (xy 446.529566 -93.717671) (xy 446.492349 -93.759208) (xy 446.449481 -93.794883)
			(xy 446.401875 -93.823937) (xy 446.350546 -93.845749) (xy 446.296589 -93.859855) (xy 446.241152 -93.865955)
			(xy 446.185418 -93.863918) (xy 446.130575 -93.853788) (xy 446.077791 -93.835781) (xy 446.028191 -93.81028)
			(xy 445.982833 -93.777829) (xy 445.942684 -93.73912) (xy 445.908598 -93.694977) (xy 445.881302 -93.646342)
			(xy 445.861379 -93.594251) (xy 445.849253 -93.539814) (xy 445.845182 -93.484192) (xy 445.18707 -93.484192)
			(xy 445.978026 -94.275148) (xy 445.985439 -94.281823) (xy 446.003875 -94.289388) (xy 446.01384 -94.28988)
			(xy 446.034668 -94.28988) (xy 446.04813 -94.28607) (xy 446.054734 -94.282006) (xy 446.077903 -94.267641)
			(xy 446.127475 -94.244958) (xy 446.17977 -94.229563) (xy 446.233725 -94.221771) (xy 446.260982 -94.2213)
			(xy 446.288235 -94.221762) (xy 446.342187 -94.229517) (xy 446.394486 -94.244871) (xy 446.444067 -94.267512)
			(xy 446.489922 -94.296979) (xy 446.531115 -94.332672) (xy 446.56681 -94.373864) (xy 446.596279 -94.419717)
			(xy 446.618923 -94.469297) (xy 446.634279 -94.521596) (xy 446.642037 -94.575547) (xy 446.642037 -94.602808)
			(xy 449.269102 -94.602808) (xy 449.273173 -94.547186) (xy 449.285299 -94.492749) (xy 449.305222 -94.440658)
			(xy 449.332518 -94.392023) (xy 449.366604 -94.34788) (xy 449.406753 -94.309171) (xy 449.452111 -94.27672)
			(xy 449.501711 -94.251219) (xy 449.554495 -94.233212) (xy 449.609338 -94.223082) (xy 449.665072 -94.221045)
			(xy 449.720509 -94.227145) (xy 449.774466 -94.241251) (xy 449.825795 -94.263063) (xy 449.873401 -94.292117)
			(xy 449.916269 -94.327792) (xy 449.953486 -94.369329) (xy 449.984259 -94.415842) (xy 450.007931 -94.466339)
			(xy 450.023999 -94.519746) (xy 450.032119 -94.574922) (xy 450.032628 -94.602808) (xy 450.032119 -94.630694)
			(xy 450.023999 -94.68587) (xy 450.007931 -94.739277) (xy 449.984259 -94.789774) (xy 449.953486 -94.836287)
			(xy 449.916269 -94.877824) (xy 449.873401 -94.913499) (xy 449.825795 -94.942553) (xy 449.774466 -94.964365)
			(xy 449.720509 -94.978471) (xy 449.665072 -94.984571) (xy 449.609338 -94.982534) (xy 449.554495 -94.972404)
			(xy 449.501711 -94.954397) (xy 449.452111 -94.928896) (xy 449.406753 -94.896445) (xy 449.366604 -94.857736)
			(xy 449.332518 -94.813593) (xy 449.305222 -94.764958) (xy 449.285299 -94.712867) (xy 449.273173 -94.65843)
			(xy 449.269102 -94.602808) (xy 446.642037 -94.602808) (xy 446.642037 -94.630053) (xy 446.634279 -94.684004)
			(xy 446.618923 -94.736303) (xy 446.596279 -94.785883) (xy 446.56681 -94.831736) (xy 446.531115 -94.872928)
			(xy 446.489922 -94.908621) (xy 446.444067 -94.938088) (xy 446.394486 -94.960729) (xy 446.342187 -94.976083)
			(xy 446.288235 -94.983838) (xy 446.260982 -94.984316) (xy 446.233729 -94.983808) (xy 446.179782 -94.976007)
			(xy 446.127494 -94.960609) (xy 446.077929 -94.937929) (xy 446.054734 -94.92361) (xy 446.048427 -94.919904)
			(xy 446.034361 -94.915911) (xy 446.027048 -94.915736) (xy 445.863218 -94.915736) (xy 445.838626 -94.91528)
			(xy 445.790048 -94.907587) (xy 445.743272 -94.892386) (xy 445.699451 -94.870054) (xy 445.659664 -94.84114)
			(xy 445.641984 -94.824042) (xy 444.409576 -93.591634) (xy 444.392526 -93.573921) (xy 444.36365 -93.534132)
			(xy 444.341359 -93.490314) (xy 444.326202 -93.443546) (xy 444.318552 -93.394982) (xy 444.318136 -93.3704)
			(xy 444.318136 -91.329256) (xy 444.31761 -91.319263) (xy 444.309914 -91.300813) (xy 444.30315 -91.293442)
			(xy 443.238636 -90.228928) (xy 443.231289 -90.222124) (xy 443.212826 -90.214411) (xy 443.202822 -90.213942)
			(xy 417.129468 -90.213942) (xy 417.119401 -90.214372) (xy 417.100809 -90.2221) (xy 417.0934 -90.228928)
			(xy 416.051492 -91.270836) (xy 437.855358 -91.270836) (xy 437.859429 -91.215214) (xy 437.871555 -91.160777)
			(xy 437.891478 -91.108686) (xy 437.918774 -91.060051) (xy 437.95286 -91.015908) (xy 437.993009 -90.977199)
			(xy 438.038367 -90.944748) (xy 438.087967 -90.919247) (xy 438.140751 -90.90124) (xy 438.195594 -90.89111)
			(xy 438.251328 -90.889073) (xy 438.306765 -90.895173) (xy 438.360722 -90.909279) (xy 438.412051 -90.931091)
			(xy 438.459657 -90.960145) (xy 438.502525 -90.99582) (xy 438.539742 -91.037357) (xy 438.570515 -91.08387)
			(xy 438.594187 -91.134367) (xy 438.610255 -91.187774) (xy 438.618375 -91.24295) (xy 438.618884 -91.270836)
			(xy 438.618375 -91.298722) (xy 438.610255 -91.353898) (xy 438.594187 -91.407305) (xy 438.570515 -91.457802)
			(xy 438.539742 -91.504315) (xy 438.502525 -91.545852) (xy 438.459657 -91.581527) (xy 438.412051 -91.610581)
			(xy 438.360722 -91.632393) (xy 438.306765 -91.646499) (xy 438.251328 -91.652599) (xy 438.195594 -91.650562)
			(xy 438.140751 -91.640432) (xy 438.087967 -91.622425) (xy 438.038367 -91.596924) (xy 437.993009 -91.564473)
			(xy 437.95286 -91.525764) (xy 437.918774 -91.481621) (xy 437.891478 -91.432986) (xy 437.871555 -91.380895)
			(xy 437.859429 -91.326458) (xy 437.855358 -91.270836) (xy 416.051492 -91.270836) (xy 414.014158 -93.30817)
			(xy 414.007316 -93.315569) (xy 413.999598 -93.334168) (xy 413.999172 -93.344238) (xy 413.999172 -93.891608)
			(xy 430.965862 -93.891608) (xy 430.969933 -93.835986) (xy 430.982059 -93.781549) (xy 431.001982 -93.729458)
			(xy 431.029278 -93.680823) (xy 431.063364 -93.63668) (xy 431.103513 -93.597971) (xy 431.148871 -93.56552)
			(xy 431.198471 -93.540019) (xy 431.251255 -93.522012) (xy 431.306098 -93.511882) (xy 431.361832 -93.509845)
			(xy 431.417269 -93.515945) (xy 431.471226 -93.530051) (xy 431.522555 -93.551863) (xy 431.570161 -93.580917)
			(xy 431.613029 -93.616592) (xy 431.650246 -93.658129) (xy 431.681019 -93.704642) (xy 431.704691 -93.755139)
			(xy 431.720759 -93.808546) (xy 431.728879 -93.863722) (xy 431.729388 -93.891608) (xy 431.728879 -93.919494)
			(xy 431.720759 -93.97467) (xy 431.704691 -94.028077) (xy 431.681019 -94.078574) (xy 431.650246 -94.125087)
			(xy 431.613029 -94.166624) (xy 431.570161 -94.202299) (xy 431.522555 -94.231353) (xy 431.471226 -94.253165)
			(xy 431.417269 -94.267271) (xy 431.361832 -94.273371) (xy 431.306098 -94.271334) (xy 431.251255 -94.261204)
			(xy 431.198471 -94.243197) (xy 431.148871 -94.217696) (xy 431.103513 -94.185245) (xy 431.063364 -94.146536)
			(xy 431.029278 -94.102393) (xy 431.001982 -94.053758) (xy 430.982059 -94.001667) (xy 430.969933 -93.94723)
			(xy 430.965862 -93.891608) (xy 413.999172 -93.891608) (xy 413.999172 -94.275148) (xy 436.294782 -94.275148)
			(xy 436.298853 -94.219526) (xy 436.310979 -94.165089) (xy 436.330902 -94.112998) (xy 436.358198 -94.064363)
			(xy 436.392284 -94.02022) (xy 436.432433 -93.981511) (xy 436.477791 -93.94906) (xy 436.527391 -93.923559)
			(xy 436.580175 -93.905552) (xy 436.635018 -93.895422) (xy 436.690752 -93.893385) (xy 436.746189 -93.899485)
			(xy 436.800146 -93.913591) (xy 436.851475 -93.935403) (xy 436.899081 -93.964457) (xy 436.941949 -94.000132)
			(xy 436.979166 -94.041669) (xy 437.009939 -94.088182) (xy 437.033611 -94.138679) (xy 437.049679 -94.192086)
			(xy 437.057799 -94.247262) (xy 437.058308 -94.275148) (xy 437.057799 -94.303034) (xy 437.049679 -94.35821)
			(xy 437.033611 -94.411617) (xy 437.009939 -94.462114) (xy 436.979166 -94.508627) (xy 436.941949 -94.550164)
			(xy 436.899081 -94.585839) (xy 436.851475 -94.614893) (xy 436.800146 -94.636705) (xy 436.746189 -94.650811)
			(xy 436.690752 -94.656911) (xy 436.635018 -94.654874) (xy 436.580175 -94.644744) (xy 436.527391 -94.626737)
			(xy 436.477791 -94.601236) (xy 436.432433 -94.568785) (xy 436.392284 -94.530076) (xy 436.358198 -94.485933)
			(xy 436.330902 -94.437298) (xy 436.310979 -94.385207) (xy 436.298853 -94.33077) (xy 436.294782 -94.275148)
			(xy 413.999172 -94.275148) (xy 413.999172 -95.957898) (xy 438.606182 -95.957898) (xy 438.610253 -95.902276)
			(xy 438.622379 -95.847839) (xy 438.642302 -95.795748) (xy 438.669598 -95.747113) (xy 438.703684 -95.70297)
			(xy 438.743833 -95.664261) (xy 438.789191 -95.63181) (xy 438.838791 -95.606309) (xy 438.891575 -95.588302)
			(xy 438.946418 -95.578172) (xy 439.002152 -95.576135) (xy 439.057589 -95.582235) (xy 439.111546 -95.596341)
			(xy 439.162875 -95.618153) (xy 439.210481 -95.647207) (xy 439.253349 -95.682882) (xy 439.290566 -95.724419)
			(xy 439.321339 -95.770932) (xy 439.345011 -95.821429) (xy 439.360469 -95.872808) (xy 442.723522 -95.872808)
			(xy 442.727593 -95.817186) (xy 442.739719 -95.762749) (xy 442.759642 -95.710658) (xy 442.786938 -95.662023)
			(xy 442.821024 -95.61788) (xy 442.861173 -95.579171) (xy 442.906531 -95.54672) (xy 442.956131 -95.521219)
			(xy 443.008915 -95.503212) (xy 443.063758 -95.493082) (xy 443.119492 -95.491045) (xy 443.174929 -95.497145)
			(xy 443.228886 -95.511251) (xy 443.280215 -95.533063) (xy 443.327821 -95.562117) (xy 443.370689 -95.597792)
			(xy 443.407906 -95.639329) (xy 443.438679 -95.685842) (xy 443.462351 -95.736339) (xy 443.478419 -95.789746)
			(xy 443.486539 -95.844922) (xy 443.487048 -95.872808) (xy 449.253862 -95.872808) (xy 449.257933 -95.817186)
			(xy 449.270059 -95.762749) (xy 449.289982 -95.710658) (xy 449.317278 -95.662023) (xy 449.351364 -95.61788)
			(xy 449.391513 -95.579171) (xy 449.436871 -95.54672) (xy 449.486471 -95.521219) (xy 449.539255 -95.503212)
			(xy 449.594098 -95.493082) (xy 449.649832 -95.491045) (xy 449.705269 -95.497145) (xy 449.759226 -95.511251)
			(xy 449.810555 -95.533063) (xy 449.858161 -95.562117) (xy 449.901029 -95.597792) (xy 449.938246 -95.639329)
			(xy 449.969019 -95.685842) (xy 449.992691 -95.736339) (xy 450.008759 -95.789746) (xy 450.016879 -95.844922)
			(xy 450.017388 -95.872808) (xy 450.016879 -95.900694) (xy 450.008759 -95.95587) (xy 449.992691 -96.009277)
			(xy 449.969019 -96.059774) (xy 449.938246 -96.106287) (xy 449.901029 -96.147824) (xy 449.858161 -96.183499)
			(xy 449.810555 -96.212553) (xy 449.759226 -96.234365) (xy 449.705269 -96.248471) (xy 449.649832 -96.254571)
			(xy 449.594098 -96.252534) (xy 449.539255 -96.242404) (xy 449.486471 -96.224397) (xy 449.436871 -96.198896)
			(xy 449.391513 -96.166445) (xy 449.351364 -96.127736) (xy 449.317278 -96.083593) (xy 449.289982 -96.034958)
			(xy 449.270059 -95.982867) (xy 449.257933 -95.92843) (xy 449.253862 -95.872808) (xy 443.487048 -95.872808)
			(xy 443.486539 -95.900694) (xy 443.478419 -95.95587) (xy 443.462351 -96.009277) (xy 443.438679 -96.059774)
			(xy 443.407906 -96.106287) (xy 443.370689 -96.147824) (xy 443.327821 -96.183499) (xy 443.280215 -96.212553)
			(xy 443.228886 -96.234365) (xy 443.174929 -96.248471) (xy 443.119492 -96.254571) (xy 443.063758 -96.252534)
			(xy 443.008915 -96.242404) (xy 442.956131 -96.224397) (xy 442.906531 -96.198896) (xy 442.861173 -96.166445)
			(xy 442.821024 -96.127736) (xy 442.786938 -96.083593) (xy 442.759642 -96.034958) (xy 442.739719 -95.982867)
			(xy 442.727593 -95.92843) (xy 442.723522 -95.872808) (xy 439.360469 -95.872808) (xy 439.361079 -95.874836)
			(xy 439.369199 -95.930012) (xy 439.369708 -95.957898) (xy 439.369199 -95.985784) (xy 439.361079 -96.04096)
			(xy 439.345011 -96.094367) (xy 439.321339 -96.144864) (xy 439.290566 -96.191377) (xy 439.253349 -96.232914)
			(xy 439.210481 -96.268589) (xy 439.162875 -96.297643) (xy 439.111546 -96.319455) (xy 439.057589 -96.333561)
			(xy 439.002152 -96.339661) (xy 438.946418 -96.337624) (xy 438.891575 -96.327494) (xy 438.838791 -96.309487)
			(xy 438.789191 -96.283986) (xy 438.743833 -96.251535) (xy 438.703684 -96.212826) (xy 438.669598 -96.168683)
			(xy 438.642302 -96.120048) (xy 438.622379 -96.067957) (xy 438.610253 -96.01352) (xy 438.606182 -95.957898)
			(xy 413.999172 -95.957898) (xy 413.999172 -96.812608) (xy 434.902862 -96.812608) (xy 434.906933 -96.756986)
			(xy 434.919059 -96.702549) (xy 434.938982 -96.650458) (xy 434.966278 -96.601823) (xy 435.000364 -96.55768)
			(xy 435.040513 -96.518971) (xy 435.085871 -96.48652) (xy 435.135471 -96.461019) (xy 435.188255 -96.443012)
			(xy 435.243098 -96.432882) (xy 435.298832 -96.430845) (xy 435.354269 -96.436945) (xy 435.408226 -96.451051)
			(xy 435.459555 -96.472863) (xy 435.507161 -96.501917) (xy 435.550029 -96.537592) (xy 435.587246 -96.579129)
			(xy 435.618019 -96.625642) (xy 435.641691 -96.676139) (xy 435.657759 -96.729546) (xy 435.665879 -96.784722)
			(xy 435.666388 -96.812608) (xy 435.791862 -96.812608) (xy 435.795933 -96.756986) (xy 435.808059 -96.702549)
			(xy 435.827982 -96.650458) (xy 435.855278 -96.601823) (xy 435.889364 -96.55768) (xy 435.929513 -96.518971)
			(xy 435.974871 -96.48652) (xy 436.024471 -96.461019) (xy 436.077255 -96.443012) (xy 436.132098 -96.432882)
			(xy 436.187832 -96.430845) (xy 436.243269 -96.436945) (xy 436.297226 -96.451051) (xy 436.348555 -96.472863)
			(xy 436.396161 -96.501917) (xy 436.439029 -96.537592) (xy 436.476246 -96.579129) (xy 436.507019 -96.625642)
			(xy 436.530691 -96.676139) (xy 436.546759 -96.729546) (xy 436.554879 -96.784722) (xy 436.555388 -96.812608)
			(xy 436.554879 -96.840494) (xy 436.546759 -96.89567) (xy 436.530691 -96.949077) (xy 436.507019 -96.999574)
			(xy 436.476246 -97.046087) (xy 436.439029 -97.087624) (xy 436.396161 -97.123299) (xy 436.348555 -97.152353)
			(xy 436.297226 -97.174165) (xy 436.243269 -97.188271) (xy 436.187832 -97.194371) (xy 436.132098 -97.192334)
			(xy 436.077255 -97.182204) (xy 436.024471 -97.164197) (xy 435.974871 -97.138696) (xy 435.929513 -97.106245)
			(xy 435.889364 -97.067536) (xy 435.855278 -97.023393) (xy 435.827982 -96.974758) (xy 435.808059 -96.922667)
			(xy 435.795933 -96.86823) (xy 435.791862 -96.812608) (xy 435.666388 -96.812608) (xy 435.665879 -96.840494)
			(xy 435.657759 -96.89567) (xy 435.641691 -96.949077) (xy 435.618019 -96.999574) (xy 435.587246 -97.046087)
			(xy 435.550029 -97.087624) (xy 435.507161 -97.123299) (xy 435.459555 -97.152353) (xy 435.408226 -97.174165)
			(xy 435.354269 -97.188271) (xy 435.298832 -97.194371) (xy 435.243098 -97.192334) (xy 435.188255 -97.182204)
			(xy 435.135471 -97.164197) (xy 435.085871 -97.138696) (xy 435.040513 -97.106245) (xy 435.000364 -97.067536)
			(xy 434.966278 -97.023393) (xy 434.938982 -96.974758) (xy 434.919059 -96.922667) (xy 434.906933 -96.86823)
			(xy 434.902862 -96.812608) (xy 413.999172 -96.812608) (xy 413.999172 -97.254568) (xy 442.690502 -97.254568)
			(xy 442.694573 -97.198946) (xy 442.706699 -97.144509) (xy 442.726622 -97.092418) (xy 442.753918 -97.043783)
			(xy 442.788004 -96.99964) (xy 442.828153 -96.960931) (xy 442.873511 -96.92848) (xy 442.923111 -96.902979)
			(xy 442.975895 -96.884972) (xy 443.030738 -96.874842) (xy 443.086472 -96.872805) (xy 443.141909 -96.878905)
			(xy 443.195866 -96.893011) (xy 443.247195 -96.914823) (xy 443.294801 -96.943877) (xy 443.337669 -96.979552)
			(xy 443.374886 -97.021089) (xy 443.405659 -97.067602) (xy 443.429331 -97.118099) (xy 443.445399 -97.171506)
			(xy 443.453519 -97.226682) (xy 443.454028 -97.254568) (xy 443.45375 -97.269808) (xy 449.253862 -97.269808)
			(xy 449.257933 -97.214186) (xy 449.270059 -97.159749) (xy 449.289982 -97.107658) (xy 449.317278 -97.059023)
			(xy 449.351364 -97.01488) (xy 449.391513 -96.976171) (xy 449.436871 -96.94372) (xy 449.486471 -96.918219)
			(xy 449.539255 -96.900212) (xy 449.594098 -96.890082) (xy 449.649832 -96.888045) (xy 449.705269 -96.894145)
			(xy 449.759226 -96.908251) (xy 449.810555 -96.930063) (xy 449.858161 -96.959117) (xy 449.901029 -96.994792)
			(xy 449.938246 -97.036329) (xy 449.969019 -97.082842) (xy 449.992691 -97.133339) (xy 450.008759 -97.186746)
			(xy 450.016879 -97.241922) (xy 450.017388 -97.269808) (xy 450.016879 -97.297694) (xy 450.008759 -97.35287)
			(xy 449.992691 -97.406277) (xy 449.969019 -97.456774) (xy 449.938246 -97.503287) (xy 449.901029 -97.544824)
			(xy 449.858161 -97.580499) (xy 449.810555 -97.609553) (xy 449.759226 -97.631365) (xy 449.705269 -97.645471)
			(xy 449.649832 -97.651571) (xy 449.594098 -97.649534) (xy 449.539255 -97.639404) (xy 449.486471 -97.621397)
			(xy 449.436871 -97.595896) (xy 449.391513 -97.563445) (xy 449.351364 -97.524736) (xy 449.317278 -97.480593)
			(xy 449.289982 -97.431958) (xy 449.270059 -97.379867) (xy 449.257933 -97.32543) (xy 449.253862 -97.269808)
			(xy 443.45375 -97.269808) (xy 443.453519 -97.282454) (xy 443.445399 -97.33763) (xy 443.429331 -97.391037)
			(xy 443.405659 -97.441534) (xy 443.374886 -97.488047) (xy 443.337669 -97.529584) (xy 443.294801 -97.565259)
			(xy 443.247195 -97.594313) (xy 443.195866 -97.616125) (xy 443.141909 -97.630231) (xy 443.086472 -97.636331)
			(xy 443.030738 -97.634294) (xy 442.975895 -97.624164) (xy 442.923111 -97.606157) (xy 442.873511 -97.580656)
			(xy 442.828153 -97.548205) (xy 442.788004 -97.509496) (xy 442.753918 -97.465353) (xy 442.726622 -97.416718)
			(xy 442.706699 -97.364627) (xy 442.694573 -97.31019) (xy 442.690502 -97.254568) (xy 413.999172 -97.254568)
			(xy 413.999172 -97.701608) (xy 434.902862 -97.701608) (xy 434.906933 -97.645986) (xy 434.919059 -97.591549)
			(xy 434.938982 -97.539458) (xy 434.966278 -97.490823) (xy 435.000364 -97.44668) (xy 435.040513 -97.407971)
			(xy 435.085871 -97.37552) (xy 435.135471 -97.350019) (xy 435.188255 -97.332012) (xy 435.243098 -97.321882)
			(xy 435.298832 -97.319845) (xy 435.354269 -97.325945) (xy 435.408226 -97.340051) (xy 435.459555 -97.361863)
			(xy 435.507161 -97.390917) (xy 435.550029 -97.426592) (xy 435.587246 -97.468129) (xy 435.618019 -97.514642)
			(xy 435.641691 -97.565139) (xy 435.657759 -97.618546) (xy 435.665879 -97.673722) (xy 435.666388 -97.701608)
			(xy 435.791862 -97.701608) (xy 435.795933 -97.645986) (xy 435.808059 -97.591549) (xy 435.827982 -97.539458)
			(xy 435.855278 -97.490823) (xy 435.889364 -97.44668) (xy 435.929513 -97.407971) (xy 435.974871 -97.37552)
			(xy 436.024471 -97.350019) (xy 436.077255 -97.332012) (xy 436.132098 -97.321882) (xy 436.187832 -97.319845)
			(xy 436.243269 -97.325945) (xy 436.297226 -97.340051) (xy 436.348555 -97.361863) (xy 436.396161 -97.390917)
			(xy 436.439029 -97.426592) (xy 436.476246 -97.468129) (xy 436.507019 -97.514642) (xy 436.530691 -97.565139)
			(xy 436.546759 -97.618546) (xy 436.554879 -97.673722) (xy 436.555388 -97.701608) (xy 436.554879 -97.729494)
			(xy 436.546759 -97.78467) (xy 436.530691 -97.838077) (xy 436.507019 -97.888574) (xy 436.476246 -97.935087)
			(xy 436.439029 -97.976624) (xy 436.396161 -98.012299) (xy 436.348555 -98.041353) (xy 436.297226 -98.063165)
			(xy 436.243269 -98.077271) (xy 436.187832 -98.083371) (xy 436.132098 -98.081334) (xy 436.077255 -98.071204)
			(xy 436.024471 -98.053197) (xy 435.974871 -98.027696) (xy 435.929513 -97.995245) (xy 435.889364 -97.956536)
			(xy 435.855278 -97.912393) (xy 435.827982 -97.863758) (xy 435.808059 -97.811667) (xy 435.795933 -97.75723)
			(xy 435.791862 -97.701608) (xy 435.666388 -97.701608) (xy 435.665879 -97.729494) (xy 435.657759 -97.78467)
			(xy 435.641691 -97.838077) (xy 435.618019 -97.888574) (xy 435.587246 -97.935087) (xy 435.550029 -97.976624)
			(xy 435.507161 -98.012299) (xy 435.459555 -98.041353) (xy 435.408226 -98.063165) (xy 435.354269 -98.077271)
			(xy 435.298832 -98.083371) (xy 435.243098 -98.081334) (xy 435.188255 -98.071204) (xy 435.135471 -98.053197)
			(xy 435.085871 -98.027696) (xy 435.040513 -97.995245) (xy 435.000364 -97.956536) (xy 434.966278 -97.912393)
			(xy 434.938982 -97.863758) (xy 434.919059 -97.811667) (xy 434.906933 -97.75723) (xy 434.902862 -97.701608)
			(xy 413.999172 -97.701608) (xy 413.999172 -98.590608) (xy 434.902862 -98.590608) (xy 434.906933 -98.534986)
			(xy 434.919059 -98.480549) (xy 434.938982 -98.428458) (xy 434.966278 -98.379823) (xy 435.000364 -98.33568)
			(xy 435.040513 -98.296971) (xy 435.085871 -98.26452) (xy 435.135471 -98.239019) (xy 435.188255 -98.221012)
			(xy 435.243098 -98.210882) (xy 435.298832 -98.208845) (xy 435.354269 -98.214945) (xy 435.408226 -98.229051)
			(xy 435.459555 -98.250863) (xy 435.507161 -98.279917) (xy 435.550029 -98.315592) (xy 435.587246 -98.357129)
			(xy 435.618019 -98.403642) (xy 435.641691 -98.454139) (xy 435.657759 -98.507546) (xy 435.665879 -98.562722)
			(xy 435.666388 -98.590608) (xy 435.791862 -98.590608) (xy 435.795933 -98.534986) (xy 435.808059 -98.480549)
			(xy 435.827982 -98.428458) (xy 435.855278 -98.379823) (xy 435.889364 -98.33568) (xy 435.929513 -98.296971)
			(xy 435.974871 -98.26452) (xy 436.024471 -98.239019) (xy 436.077255 -98.221012) (xy 436.132098 -98.210882)
			(xy 436.187832 -98.208845) (xy 436.243269 -98.214945) (xy 436.297226 -98.229051) (xy 436.348555 -98.250863)
			(xy 436.396161 -98.279917) (xy 436.439029 -98.315592) (xy 436.476246 -98.357129) (xy 436.507019 -98.403642)
			(xy 436.530691 -98.454139) (xy 436.546759 -98.507546) (xy 436.554879 -98.562722) (xy 436.555388 -98.590608)
			(xy 436.554879 -98.618494) (xy 436.546759 -98.67367) (xy 436.530691 -98.727077) (xy 436.507019 -98.777574)
			(xy 436.476246 -98.824087) (xy 436.439029 -98.865624) (xy 436.396161 -98.901299) (xy 436.348555 -98.930353)
			(xy 436.297226 -98.952165) (xy 436.243269 -98.966271) (xy 436.187832 -98.972371) (xy 436.132098 -98.970334)
			(xy 436.077255 -98.960204) (xy 436.024471 -98.942197) (xy 435.974871 -98.916696) (xy 435.929513 -98.884245)
			(xy 435.889364 -98.845536) (xy 435.855278 -98.801393) (xy 435.827982 -98.752758) (xy 435.808059 -98.700667)
			(xy 435.795933 -98.64623) (xy 435.791862 -98.590608) (xy 435.666388 -98.590608) (xy 435.665879 -98.618494)
			(xy 435.657759 -98.67367) (xy 435.641691 -98.727077) (xy 435.618019 -98.777574) (xy 435.587246 -98.824087)
			(xy 435.550029 -98.865624) (xy 435.507161 -98.901299) (xy 435.459555 -98.930353) (xy 435.408226 -98.952165)
			(xy 435.354269 -98.966271) (xy 435.298832 -98.972371) (xy 435.243098 -98.970334) (xy 435.188255 -98.960204)
			(xy 435.135471 -98.942197) (xy 435.085871 -98.916696) (xy 435.040513 -98.884245) (xy 435.000364 -98.845536)
			(xy 434.966278 -98.801393) (xy 434.938982 -98.752758) (xy 434.919059 -98.700667) (xy 434.906933 -98.64623)
			(xy 434.902862 -98.590608) (xy 413.999172 -98.590608) (xy 413.999172 -99.459796) (xy 413.999667 -99.469793)
			(xy 414.0073 -99.488275) (xy 414.021383 -99.502471) (xy 414.030414 -99.506786) (xy 414.131252 -99.548696)
			(xy 414.161224 -99.542854) (xy 414.1724 -99.531932) (xy 414.193974 -99.511369) (xy 414.242321 -99.476519)
			(xy 414.295496 -99.449607) (xy 414.352209 -99.431287) (xy 414.411079 -99.422005) (xy 414.440878 -99.421442)
			(xy 414.468128 -99.421904) (xy 414.522075 -99.429657) (xy 414.574368 -99.445009) (xy 414.623945 -99.467648)
			(xy 414.642557 -99.479608) (xy 434.902862 -99.479608) (xy 434.906933 -99.423986) (xy 434.919059 -99.369549)
			(xy 434.938982 -99.317458) (xy 434.966278 -99.268823) (xy 435.000364 -99.22468) (xy 435.040513 -99.185971)
			(xy 435.085871 -99.15352) (xy 435.135471 -99.128019) (xy 435.188255 -99.110012) (xy 435.243098 -99.099882)
			(xy 435.298832 -99.097845) (xy 435.354269 -99.103945) (xy 435.408226 -99.118051) (xy 435.459555 -99.139863)
			(xy 435.507161 -99.168917) (xy 435.550029 -99.204592) (xy 435.587246 -99.246129) (xy 435.618019 -99.292642)
			(xy 435.641691 -99.343139) (xy 435.657759 -99.396546) (xy 435.665879 -99.451722) (xy 435.666388 -99.479608)
			(xy 435.791862 -99.479608) (xy 435.795933 -99.423986) (xy 435.808059 -99.369549) (xy 435.827982 -99.317458)
			(xy 435.855278 -99.268823) (xy 435.889364 -99.22468) (xy 435.929513 -99.185971) (xy 435.974871 -99.15352)
			(xy 436.024471 -99.128019) (xy 436.077255 -99.110012) (xy 436.132098 -99.099882) (xy 436.187832 -99.097845)
			(xy 436.243269 -99.103945) (xy 436.297226 -99.118051) (xy 436.348555 -99.139863) (xy 436.396161 -99.168917)
			(xy 436.439029 -99.204592) (xy 436.476246 -99.246129) (xy 436.507019 -99.292642) (xy 436.530691 -99.343139)
			(xy 436.546759 -99.396546) (xy 436.554879 -99.451722) (xy 436.555388 -99.479608) (xy 436.554879 -99.507494)
			(xy 436.546759 -99.56267) (xy 436.530691 -99.616077) (xy 436.507019 -99.666574) (xy 436.476246 -99.713087)
			(xy 436.439029 -99.754624) (xy 436.396161 -99.790299) (xy 436.348555 -99.819353) (xy 436.297226 -99.841165)
			(xy 436.243269 -99.855271) (xy 436.187832 -99.861371) (xy 436.132098 -99.859334) (xy 436.077255 -99.849204)
			(xy 436.024471 -99.831197) (xy 435.974871 -99.805696) (xy 435.929513 -99.773245) (xy 435.889364 -99.734536)
			(xy 435.855278 -99.690393) (xy 435.827982 -99.641758) (xy 435.808059 -99.589667) (xy 435.795933 -99.53523)
			(xy 435.791862 -99.479608) (xy 435.666388 -99.479608) (xy 435.665879 -99.507494) (xy 435.657759 -99.56267)
			(xy 435.641691 -99.616077) (xy 435.618019 -99.666574) (xy 435.587246 -99.713087) (xy 435.550029 -99.754624)
			(xy 435.507161 -99.790299) (xy 435.459555 -99.819353) (xy 435.408226 -99.841165) (xy 435.354269 -99.855271)
			(xy 435.298832 -99.861371) (xy 435.243098 -99.859334) (xy 435.188255 -99.849204) (xy 435.135471 -99.831197)
			(xy 435.085871 -99.805696) (xy 435.040513 -99.773245) (xy 435.000364 -99.734536) (xy 434.966278 -99.690393)
			(xy 434.938982 -99.641758) (xy 434.919059 -99.589667) (xy 434.906933 -99.53523) (xy 434.902862 -99.479608)
			(xy 414.642557 -99.479608) (xy 414.669794 -99.497111) (xy 414.710984 -99.5328) (xy 414.746676 -99.573988)
			(xy 414.776142 -99.619836) (xy 414.798783 -99.669411) (xy 414.814138 -99.721704) (xy 414.821895 -99.77565)
			(xy 414.821895 -99.83015) (xy 414.814138 -99.884096) (xy 414.798783 -99.936389) (xy 414.776142 -99.985964)
			(xy 414.746676 -100.031812) (xy 414.710984 -100.073) (xy 414.669794 -100.108689) (xy 414.623945 -100.138152)
			(xy 414.574368 -100.160791) (xy 414.522075 -100.176143) (xy 414.468128 -100.183896) (xy 414.440878 -100.184458)
			(xy 414.411077 -100.183889) (xy 414.352199 -100.174629) (xy 414.295479 -100.156322) (xy 414.242297 -100.129414)
			(xy 414.193949 -100.094559) (xy 414.1724 -100.073968) (xy 414.161224 -100.063046) (xy 414.131252 -100.057204)
			(xy 414.030414 -100.099114) (xy 414.021317 -100.103343) (xy 414.007162 -100.117538) (xy 413.999542 -100.136079)
			(xy 413.999172 -100.146104) (xy 413.999172 -102.63945) (xy 429.495968 -102.63945) (xy 429.495968 -102.58495)
			(xy 429.503724 -102.531003) (xy 429.519077 -102.47871) (xy 429.541717 -102.429134) (xy 429.57118 -102.383284)
			(xy 429.606869 -102.342093) (xy 429.648057 -102.306401) (xy 429.693904 -102.276933) (xy 429.743478 -102.254289)
			(xy 429.79577 -102.238931) (xy 429.849716 -102.23117) (xy 429.876966 -102.230682) (xy 429.903569 -102.231164)
			(xy 429.95626 -102.238541) (xy 430.007415 -102.25317) (xy 430.056039 -102.274767) (xy 430.10119 -102.302914)
			(xy 430.14199 -102.337062) (xy 430.177648 -102.376551) (xy 430.192942 -102.398322) (xy 430.200458 -102.408259)
			(xy 430.222413 -102.419979) (xy 430.234852 -102.420674) (xy 430.31918 -102.420674) (xy 430.331635 -102.420036)
			(xy 430.353613 -102.408305) (xy 430.36109 -102.398322) (xy 430.376374 -102.376544) (xy 430.412042 -102.337065)
			(xy 430.452848 -102.302923) (xy 430.498 -102.274779) (xy 430.546623 -102.253178) (xy 430.597775 -102.238539)
			(xy 430.650463 -102.231145) (xy 430.677066 -102.230682) (xy 430.704318 -102.231187) (xy 430.758266 -102.238939)
			(xy 430.810563 -102.25429) (xy 430.860142 -102.276928) (xy 430.905995 -102.306392) (xy 430.947188 -102.342081)
			(xy 430.982882 -102.38327) (xy 431.012351 -102.429119) (xy 431.034994 -102.478696) (xy 431.050352 -102.53099)
			(xy 431.05811 -102.584938) (xy 431.058574 -102.61219) (xy 431.058169 -102.636998) (xy 431.057848 -102.639451)
			(xy 431.370468 -102.639451) (xy 431.370468 -102.584949) (xy 431.378224 -102.531001) (xy 431.393579 -102.478706)
			(xy 431.41622 -102.429128) (xy 431.445685 -102.383277) (xy 431.481376 -102.342086) (xy 431.522566 -102.306394)
			(xy 431.568416 -102.276926) (xy 431.617993 -102.254284) (xy 431.670287 -102.238927) (xy 431.724235 -102.231169)
			(xy 431.751486 -102.230682) (xy 431.780451 -102.231233) (xy 431.837715 -102.240002) (xy 431.892995 -102.257325)
			(xy 431.945022 -102.282805) (xy 431.9926 -102.315856) (xy 432.034635 -102.355719) (xy 432.070163 -102.401477)
			(xy 432.084734 -102.426516) (xy 432.092088 -102.438728) (xy 432.112316 -102.458797) (xy 432.137304 -102.472494)
			(xy 432.165104 -102.47875) (xy 432.19355 -102.47708) (xy 432.220426 -102.467612) (xy 432.243639 -102.451085)
			(xy 432.252882 -102.440232) (xy 432.271098 -102.418176) (xy 432.313 -102.379236) (xy 432.360242 -102.346983)
			(xy 432.411768 -102.322139) (xy 432.466423 -102.30526) (xy 432.522985 -102.296724) (xy 432.551586 -102.296214)
			(xy 432.578841 -102.296632) (xy 432.632797 -102.304388) (xy 432.685099 -102.319743) (xy 432.734684 -102.342386)
			(xy 432.780542 -102.371856) (xy 432.821738 -102.407552) (xy 432.857436 -102.448747) (xy 432.886907 -102.494604)
			(xy 432.909552 -102.544188) (xy 432.924909 -102.59649) (xy 432.932667 -102.650445) (xy 432.932667 -102.704955)
			(xy 432.924909 -102.75891) (xy 432.909552 -102.811212) (xy 432.886907 -102.860796) (xy 432.857436 -102.906653)
			(xy 432.821738 -102.947848) (xy 432.780542 -102.983544) (xy 432.734684 -103.013014) (xy 432.685099 -103.035657)
			(xy 432.632797 -103.051012) (xy 432.578841 -103.058768) (xy 432.551586 -103.05923) (xy 432.522618 -103.058746)
			(xy 432.465349 -103.049971) (xy 432.410065 -103.032639) (xy 432.358036 -103.007149) (xy 432.310459 -102.974086)
			(xy 432.268427 -102.934212) (xy 432.232905 -102.888441) (xy 432.218338 -102.863396) (xy 432.211021 -102.851159)
			(xy 432.190786 -102.831086) (xy 432.16579 -102.817388) (xy 432.137982 -102.811133) (xy 432.109529 -102.812809)
			(xy 432.082648 -102.822285) (xy 432.059433 -102.838822) (xy 432.05019 -102.84968) (xy 432.031993 -102.871752)
			(xy 431.990086 -102.91069) (xy 431.94284 -102.942941) (xy 431.891311 -102.967782) (xy 431.836652 -102.984658)
			(xy 431.780088 -102.99319) (xy 431.751486 -102.993698) (xy 431.724235 -102.993231) (xy 431.670287 -102.985473)
			(xy 431.617993 -102.970116) (xy 431.568416 -102.947474) (xy 431.522566 -102.918006) (xy 431.481376 -102.882314)
			(xy 431.445685 -102.841123) (xy 431.41622 -102.795272) (xy 431.393579 -102.745694) (xy 431.378224 -102.693399)
			(xy 431.370468 -102.639451) (xy 431.057848 -102.639451) (xy 431.051732 -102.686194) (xy 431.038953 -102.734135)
			(xy 431.029872 -102.757224) (xy 431.0253 -102.7684) (xy 431.027078 -102.79253) (xy 431.081942 -102.883208)
			(xy 431.102262 -102.895908) (xy 431.114454 -102.897178) (xy 431.142478 -102.90029) (xy 431.197232 -102.913751)
			(xy 431.249408 -102.935124) (xy 431.29787 -102.963943) (xy 431.341562 -102.999582) (xy 431.379534 -103.041264)
			(xy 431.410956 -103.08808) (xy 431.435146 -103.139011) (xy 431.451576 -103.192948) (xy 431.459889 -103.248716)
			(xy 431.460402 -103.276908) (xy 431.459916 -103.304159) (xy 431.45216 -103.358107) (xy 431.436805 -103.410402)
			(xy 431.414163 -103.459979) (xy 431.384697 -103.505829) (xy 431.349006 -103.54702) (xy 431.307815 -103.582711)
			(xy 431.261965 -103.612177) (xy 431.212388 -103.634819) (xy 431.160093 -103.650174) (xy 431.106145 -103.65793)
			(xy 431.051643 -103.65793) (xy 430.997695 -103.650174) (xy 430.9454 -103.634819) (xy 430.895823 -103.612177)
			(xy 430.849973 -103.582711) (xy 430.808782 -103.54702) (xy 430.773091 -103.505829) (xy 430.743625 -103.459979)
			(xy 430.720983 -103.410402) (xy 430.705628 -103.358107) (xy 430.697872 -103.304159) (xy 430.697386 -103.276908)
			(xy 430.697793 -103.2521) (xy 430.704229 -103.202905) (xy 430.717007 -103.154963) (xy 430.726088 -103.131874)
			(xy 430.73066 -103.120698) (xy 430.728882 -103.096568) (xy 430.674018 -103.00589) (xy 430.653698 -102.99319)
			(xy 430.641506 -102.99192) (xy 430.613609 -102.988818) (xy 430.559087 -102.975477) (xy 430.50711 -102.95429)
			(xy 430.458798 -102.925714) (xy 430.415195 -102.890368) (xy 430.377243 -102.849014) (xy 430.36109 -102.826058)
			(xy 430.353611 -102.816087) (xy 430.331628 -102.804386) (xy 430.31918 -102.803706) (xy 430.234852 -102.803706)
			(xy 430.222401 -102.804371) (xy 430.200423 -102.816084) (xy 430.192942 -102.826058) (xy 430.177632 -102.847817)
			(xy 430.141968 -102.887297) (xy 430.101167 -102.921441) (xy 430.05602 -102.949588) (xy 430.007401 -102.971192)
			(xy 429.956253 -102.985835) (xy 429.903567 -102.993232) (xy 429.876966 -102.993698) (xy 429.849716 -102.99323)
			(xy 429.79577 -102.985469) (xy 429.743478 -102.970111) (xy 429.693904 -102.947467) (xy 429.648057 -102.917999)
			(xy 429.606869 -102.882307) (xy 429.57118 -102.841116) (xy 429.541717 -102.795266) (xy 429.519077 -102.74569)
			(xy 429.503724 -102.693397) (xy 429.495968 -102.63945) (xy 413.999172 -102.63945) (xy 413.999172 -104.501188)
			(xy 418.035232 -104.501188) (xy 418.035683 -104.473817) (xy 418.043503 -104.419637) (xy 418.058996 -104.367134)
			(xy 418.081841 -104.317387) (xy 418.111569 -104.271421) (xy 418.129212 -104.25049) (xy 418.135308 -104.243378)
			(xy 418.141658 -104.22636) (xy 418.141658 -104.141016) (xy 418.135308 -104.123998) (xy 418.129212 -104.116886)
			(xy 418.111602 -104.095931) (xy 418.081885 -104.049965) (xy 418.059043 -104.000223) (xy 418.043546 -103.947727)
			(xy 418.03571 -103.893556) (xy 418.035232 -103.866188) (xy 418.035644 -103.838933) (xy 418.043403 -103.784978)
			(xy 418.058763 -103.732677) (xy 418.08141 -103.683094) (xy 418.110883 -103.637239) (xy 418.146582 -103.596045)
			(xy 418.187781 -103.560352) (xy 418.23364 -103.530885) (xy 418.283226 -103.508245) (xy 418.335529 -103.492892)
			(xy 418.389485 -103.48514) (xy 418.41674 -103.48468) (xy 418.442319 -103.485084) (xy 418.493018 -103.491932)
			(xy 418.542348 -103.505486) (xy 418.589428 -103.525504) (xy 418.633414 -103.551628) (xy 418.673519 -103.583389)
			(xy 418.691568 -103.60152) (xy 418.69868 -103.608886) (xy 418.717222 -103.617014) (xy 418.810186 -103.61803)
			(xy 418.828982 -103.61041) (xy 418.836348 -103.603044) (xy 418.857913 -103.582417) (xy 418.906289 -103.547481)
			(xy 418.959517 -103.520507) (xy 419.016298 -103.502155) (xy 419.075244 -103.492872) (xy 419.10508 -103.4923)
			(xy 419.132333 -103.492774) (xy 419.186284 -103.500528) (xy 419.238582 -103.515882) (xy 419.288162 -103.538523)
			(xy 419.334016 -103.56799) (xy 419.375209 -103.603682) (xy 419.410903 -103.644874) (xy 419.440371 -103.690727)
			(xy 419.463013 -103.740307) (xy 419.478369 -103.792605) (xy 419.486125 -103.846555) (xy 419.486588 -103.873808)
			(xy 419.48613 -103.901179) (xy 419.47831 -103.955358) (xy 419.46282 -104.007861) (xy 419.439976 -104.057608)
			(xy 419.41025 -104.103575) (xy 419.392608 -104.124506) (xy 419.386512 -104.131618) (xy 419.380162 -104.148636)
			(xy 419.380162 -104.23398) (xy 419.386512 -104.250998) (xy 419.392608 -104.25811) (xy 419.410266 -104.279026)
			(xy 419.439975 -104.325004) (xy 419.462807 -104.374755) (xy 419.478294 -104.427259) (xy 419.486117 -104.481438)
			(xy 419.486588 -104.508808) (xy 419.486152 -104.536062) (xy 419.478393 -104.590015) (xy 419.463035 -104.642314)
			(xy 419.440391 -104.691896) (xy 419.41092 -104.73775) (xy 419.375223 -104.778943) (xy 419.334028 -104.814637)
			(xy 419.288171 -104.844104) (xy 419.238588 -104.866745) (xy 419.186287 -104.882099) (xy 419.132334 -104.889854)
			(xy 419.10508 -104.890316) (xy 419.079501 -104.8899) (xy 419.028803 -104.883055) (xy 418.979473 -104.869503)
			(xy 418.932393 -104.849487) (xy 418.888407 -104.823365) (xy 418.848301 -104.791606) (xy 418.830252 -104.773476)
			(xy 418.82314 -104.76611) (xy 418.804598 -104.757982) (xy 418.711634 -104.756966) (xy 418.692838 -104.764586)
			(xy 418.685472 -104.771952) (xy 418.663898 -104.792569) (xy 418.615524 -104.827506) (xy 418.562298 -104.854482)
			(xy 418.50552 -104.872837) (xy 418.446576 -104.882123) (xy 418.41674 -104.882696) (xy 418.389488 -104.882207)
			(xy 418.335537 -104.874456) (xy 418.283239 -104.859104) (xy 418.233658 -104.836465) (xy 418.187804 -104.807)
			(xy 418.146611 -104.771309) (xy 418.110916 -104.730118) (xy 418.081448 -104.684267) (xy 418.058806 -104.634687)
			(xy 418.04345 -104.58239) (xy 418.035695 -104.52844) (xy 418.035232 -104.501188) (xy 413.999172 -104.501188)
			(xy 413.999172 -105.827322) (xy 429.906682 -105.827322) (xy 429.910753 -105.7717) (xy 429.922879 -105.717263)
			(xy 429.942802 -105.665172) (xy 429.970098 -105.616537) (xy 430.004184 -105.572394) (xy 430.044333 -105.533685)
			(xy 430.089691 -105.501234) (xy 430.139291 -105.475733) (xy 430.192075 -105.457726) (xy 430.246918 -105.447596)
			(xy 430.302652 -105.445559) (xy 430.358089 -105.451659) (xy 430.412046 -105.465765) (xy 430.463375 -105.487577)
			(xy 430.510981 -105.516631) (xy 430.553849 -105.552306) (xy 430.591066 -105.593843) (xy 430.614291 -105.628948)
			(xy 433.069492 -105.628948) (xy 433.069988 -105.601579) (xy 433.077799 -105.547401) (xy 433.093281 -105.494898)
			(xy 433.116116 -105.445151) (xy 433.145834 -105.399183) (xy 433.163472 -105.37825) (xy 433.169568 -105.371138)
			(xy 433.175918 -105.35412) (xy 433.175918 -105.268776) (xy 433.169568 -105.251758) (xy 433.163472 -105.244646)
			(xy 433.145837 -105.223711) (xy 433.116125 -105.177739) (xy 433.093289 -105.127992) (xy 433.077797 -105.075492)
			(xy 433.069967 -105.021317) (xy 433.069492 -104.993948) (xy 433.069991 -104.965775) (xy 433.078298 -104.910045)
			(xy 433.094709 -104.856142) (xy 433.118868 -104.805238) (xy 433.150249 -104.75844) (xy 433.188171 -104.716765)
			(xy 433.231808 -104.681118) (xy 433.280212 -104.652276) (xy 433.332331 -104.630864) (xy 433.35956 -104.623616)
			(xy 433.370482 -104.620822) (xy 433.388008 -104.606598) (xy 433.432204 -104.516174) (xy 433.432458 -104.493822)
			(xy 433.427886 -104.483408) (xy 433.417375 -104.458766) (xy 433.402561 -104.407283) (xy 433.395071 -104.354238)
			(xy 433.394612 -104.327452) (xy 433.395098 -104.300201) (xy 433.402854 -104.246253) (xy 433.418209 -104.193958)
			(xy 433.440851 -104.144381) (xy 433.470317 -104.098531) (xy 433.506008 -104.05734) (xy 433.547199 -104.021649)
			(xy 433.593049 -103.992183) (xy 433.642626 -103.969541) (xy 433.694921 -103.954186) (xy 433.748869 -103.94643)
			(xy 433.803371 -103.94643) (xy 433.857319 -103.954186) (xy 433.909614 -103.969541) (xy 433.959191 -103.992183)
			(xy 434.005041 -104.021649) (xy 434.046232 -104.05734) (xy 434.081923 -104.098531) (xy 434.111389 -104.144381)
			(xy 434.134031 -104.193958) (xy 434.149386 -104.246253) (xy 434.157142 -104.300201) (xy 434.157628 -104.327452)
			(xy 434.157175 -104.354753) (xy 434.149421 -104.4088) (xy 434.134021 -104.461184) (xy 434.123084 -104.486202)
			(xy 434.118258 -104.496362) (xy 434.118512 -104.51846) (xy 434.160422 -104.609138) (xy 434.17744 -104.623362)
			(xy 434.188108 -104.62641) (xy 434.214542 -104.634228) (xy 434.264983 -104.656465) (xy 434.311697 -104.685732)
			(xy 434.353711 -104.721419) (xy 434.390149 -104.762783) (xy 434.420254 -104.808961) (xy 434.443397 -104.858992)
			(xy 434.459097 -104.911834) (xy 434.467026 -104.966386) (xy 434.467508 -104.993948) (xy 434.467009 -105.021317)
			(xy 434.459199 -105.075495) (xy 434.443718 -105.127997) (xy 434.420883 -105.177745) (xy 434.391166 -105.223713)
			(xy 434.373528 -105.244646) (xy 434.367432 -105.251758) (xy 434.361082 -105.268776) (xy 434.361082 -105.35412)
			(xy 434.367432 -105.371138) (xy 434.373528 -105.37825) (xy 434.391161 -105.399187) (xy 434.420873 -105.445159)
			(xy 434.44371 -105.494905) (xy 434.459202 -105.547404) (xy 434.467033 -105.601579) (xy 434.467508 -105.628948)
			(xy 434.467067 -105.6562) (xy 434.459304 -105.71015) (xy 434.443943 -105.762445) (xy 434.421296 -105.812023)
			(xy 434.391825 -105.857873) (xy 434.356129 -105.899063) (xy 434.314934 -105.934753) (xy 434.269081 -105.964219)
			(xy 434.2195 -105.986859) (xy 434.167203 -106.002214) (xy 434.113252 -106.00997) (xy 434.086 -106.010456)
			(xy 434.058629 -106.010001) (xy 434.004449 -106.002182) (xy 433.951946 -105.986691) (xy 433.902199 -105.963847)
			(xy 433.856233 -105.934119) (xy 433.835302 -105.916476) (xy 433.82819 -105.91038) (xy 433.811172 -105.90403)
			(xy 433.725828 -105.90403) (xy 433.70881 -105.91038) (xy 433.701698 -105.916476) (xy 433.680774 -105.934126)
			(xy 433.6348 -105.963837) (xy 433.58505 -105.986671) (xy 433.532547 -106.00216) (xy 433.47837 -106.009984)
			(xy 433.451 -106.010456) (xy 433.423751 -106.009922) (xy 433.369807 -106.002167) (xy 433.317516 -105.986814)
			(xy 433.267942 -105.964177) (xy 433.222094 -105.934715) (xy 433.180905 -105.899029) (xy 433.145214 -105.857844)
			(xy 433.115746 -105.812) (xy 433.093102 -105.762429) (xy 433.077743 -105.71014) (xy 433.069981 -105.656197)
			(xy 433.069492 -105.628948) (xy 430.614291 -105.628948) (xy 430.621839 -105.640356) (xy 430.645511 -105.690853)
			(xy 430.661579 -105.74426) (xy 430.669699 -105.799436) (xy 430.670208 -105.827322) (xy 430.669699 -105.855208)
			(xy 430.661579 -105.910384) (xy 430.645511 -105.963791) (xy 430.621839 -106.014288) (xy 430.591066 -106.060801)
			(xy 430.553849 -106.102338) (xy 430.510981 -106.138013) (xy 430.463375 -106.167067) (xy 430.412046 -106.188879)
			(xy 430.358089 -106.202985) (xy 430.302652 -106.209085) (xy 430.246918 -106.207048) (xy 430.192075 -106.196918)
			(xy 430.139291 -106.178911) (xy 430.089691 -106.15341) (xy 430.044333 -106.120959) (xy 430.004184 -106.08225)
			(xy 429.970098 -106.038107) (xy 429.942802 -105.989472) (xy 429.922879 -105.937381) (xy 429.910753 -105.882944)
			(xy 429.906682 -105.827322) (xy 413.999172 -105.827322) (xy 413.999172 -107.15117) (xy 428.930814 -107.15117)
			(xy 428.934885 -107.095548) (xy 428.947011 -107.041111) (xy 428.966934 -106.98902) (xy 428.99423 -106.940385)
			(xy 429.028316 -106.896242) (xy 429.068465 -106.857533) (xy 429.113823 -106.825082) (xy 429.163423 -106.799581)
			(xy 429.216207 -106.781574) (xy 429.27105 -106.771444) (xy 429.326784 -106.769407) (xy 429.368344 -106.77398)
			(xy 433.340254 -106.77398) (xy 433.344325 -106.718358) (xy 433.356451 -106.663921) (xy 433.376374 -106.61183)
			(xy 433.40367 -106.563195) (xy 433.437756 -106.519052) (xy 433.477905 -106.480343) (xy 433.523263 -106.447892)
			(xy 433.572863 -106.422391) (xy 433.625647 -106.404384) (xy 433.68049 -106.394254) (xy 433.736224 -106.392217)
			(xy 433.791661 -106.398317) (xy 433.845618 -106.412423) (xy 433.896947 -106.434235) (xy 433.944553 -106.463289)
			(xy 433.987421 -106.498964) (xy 434.024638 -106.540501) (xy 434.055411 -106.587014) (xy 434.079083 -106.637511)
			(xy 434.095151 -106.690918) (xy 434.103271 -106.746094) (xy 434.10378 -106.77398) (xy 434.103271 -106.801866)
			(xy 434.095151 -106.857042) (xy 434.079083 -106.910449) (xy 434.055411 -106.960946) (xy 434.024638 -107.007459)
			(xy 433.987421 -107.048996) (xy 433.944553 -107.084671) (xy 433.896947 -107.113725) (xy 433.845618 -107.135537)
			(xy 433.791661 -107.149643) (xy 433.736224 -107.155743) (xy 433.68049 -107.153706) (xy 433.625647 -107.143576)
			(xy 433.572863 -107.125569) (xy 433.523263 -107.100068) (xy 433.477905 -107.067617) (xy 433.437756 -107.028908)
			(xy 433.40367 -106.984765) (xy 433.376374 -106.93613) (xy 433.356451 -106.884039) (xy 433.344325 -106.829602)
			(xy 433.340254 -106.77398) (xy 429.368344 -106.77398) (xy 429.382221 -106.775507) (xy 429.436178 -106.789613)
			(xy 429.487507 -106.811425) (xy 429.535113 -106.840479) (xy 429.577981 -106.876154) (xy 429.615198 -106.917691)
			(xy 429.645971 -106.964204) (xy 429.669643 -107.014701) (xy 429.685711 -107.068108) (xy 429.693831 -107.123284)
			(xy 429.69434 -107.15117) (xy 429.693831 -107.179056) (xy 429.685711 -107.234232) (xy 429.677688 -107.260898)
			(xy 430.263552 -107.260898) (xy 430.267623 -107.205276) (xy 430.279749 -107.150839) (xy 430.299672 -107.098748)
			(xy 430.326968 -107.050113) (xy 430.361054 -107.00597) (xy 430.401203 -106.967261) (xy 430.446561 -106.93481)
			(xy 430.496161 -106.909309) (xy 430.548945 -106.891302) (xy 430.603788 -106.881172) (xy 430.659522 -106.879135)
			(xy 430.714959 -106.885235) (xy 430.768916 -106.899341) (xy 430.820245 -106.921153) (xy 430.867851 -106.950207)
			(xy 430.910719 -106.985882) (xy 430.947936 -107.027419) (xy 430.978709 -107.073932) (xy 431.002381 -107.124429)
			(xy 431.018449 -107.177836) (xy 431.026569 -107.233012) (xy 431.027078 -107.260898) (xy 431.026569 -107.288784)
			(xy 431.018449 -107.34396) (xy 431.002381 -107.397367) (xy 430.978709 -107.447864) (xy 430.947936 -107.494377)
			(xy 430.910719 -107.535914) (xy 430.867851 -107.571589) (xy 430.820245 -107.600643) (xy 430.768916 -107.622455)
			(xy 430.714959 -107.636561) (xy 430.659522 -107.642661) (xy 430.603788 -107.640624) (xy 430.548945 -107.630494)
			(xy 430.496161 -107.612487) (xy 430.446561 -107.586986) (xy 430.401203 -107.554535) (xy 430.361054 -107.515826)
			(xy 430.326968 -107.471683) (xy 430.299672 -107.423048) (xy 430.279749 -107.370957) (xy 430.267623 -107.31652)
			(xy 430.263552 -107.260898) (xy 429.677688 -107.260898) (xy 429.669643 -107.287639) (xy 429.645971 -107.338136)
			(xy 429.615198 -107.384649) (xy 429.577981 -107.426186) (xy 429.535113 -107.461861) (xy 429.487507 -107.490915)
			(xy 429.436178 -107.512727) (xy 429.382221 -107.526833) (xy 429.326784 -107.532933) (xy 429.27105 -107.530896)
			(xy 429.216207 -107.520766) (xy 429.163423 -107.502759) (xy 429.113823 -107.477258) (xy 429.068465 -107.444807)
			(xy 429.028316 -107.406098) (xy 428.99423 -107.361955) (xy 428.966934 -107.31332) (xy 428.947011 -107.261229)
			(xy 428.934885 -107.206792) (xy 428.930814 -107.15117) (xy 413.999172 -107.15117) (xy 413.999172 -107.645708)
			(xy 431.703478 -107.645708) (xy 431.707549 -107.590086) (xy 431.719675 -107.535649) (xy 431.739598 -107.483558)
			(xy 431.766894 -107.434923) (xy 431.80098 -107.39078) (xy 431.841129 -107.352071) (xy 431.886487 -107.31962)
			(xy 431.936087 -107.294119) (xy 431.988871 -107.276112) (xy 432.043714 -107.265982) (xy 432.099448 -107.263945)
			(xy 432.154885 -107.270045) (xy 432.208842 -107.284151) (xy 432.260171 -107.305963) (xy 432.307777 -107.335017)
			(xy 432.350645 -107.370692) (xy 432.387862 -107.412229) (xy 432.418635 -107.458742) (xy 432.442307 -107.509239)
			(xy 432.458375 -107.562646) (xy 432.466495 -107.617822) (xy 432.467004 -107.645708) (xy 432.466495 -107.673594)
			(xy 432.458375 -107.72877) (xy 432.442307 -107.782177) (xy 432.418635 -107.832674) (xy 432.387862 -107.879187)
			(xy 432.350645 -107.920724) (xy 432.307777 -107.956399) (xy 432.260171 -107.985453) (xy 432.208842 -108.007265)
			(xy 432.154885 -108.021371) (xy 432.099448 -108.027471) (xy 432.043714 -108.025434) (xy 431.988871 -108.015304)
			(xy 431.936087 -107.997297) (xy 431.886487 -107.971796) (xy 431.841129 -107.939345) (xy 431.80098 -107.900636)
			(xy 431.766894 -107.856493) (xy 431.739598 -107.807858) (xy 431.719675 -107.755767) (xy 431.707549 -107.70133)
			(xy 431.703478 -107.645708) (xy 413.999172 -107.645708) (xy 413.999172 -109.66323) (xy 433.334158 -109.66323)
			(xy 433.338229 -109.607608) (xy 433.350355 -109.553171) (xy 433.370278 -109.50108) (xy 433.397574 -109.452445)
			(xy 433.43166 -109.408302) (xy 433.471809 -109.369593) (xy 433.517167 -109.337142) (xy 433.566767 -109.311641)
			(xy 433.619551 -109.293634) (xy 433.674394 -109.283504) (xy 433.730128 -109.281467) (xy 433.785565 -109.287567)
			(xy 433.839522 -109.301673) (xy 433.890851 -109.323485) (xy 433.938457 -109.352539) (xy 433.981325 -109.388214)
			(xy 434.018542 -109.429751) (xy 434.049315 -109.476264) (xy 434.072987 -109.526761) (xy 434.089055 -109.580168)
			(xy 434.097175 -109.635344) (xy 434.097684 -109.66323) (xy 434.097175 -109.691116) (xy 434.089055 -109.746292)
			(xy 434.072987 -109.799699) (xy 434.049315 -109.850196) (xy 434.018542 -109.896709) (xy 433.981325 -109.938246)
			(xy 433.938457 -109.973921) (xy 433.890851 -110.002975) (xy 433.839522 -110.024787) (xy 433.785565 -110.038893)
			(xy 433.730128 -110.044993) (xy 433.674394 -110.042956) (xy 433.619551 -110.032826) (xy 433.566767 -110.014819)
			(xy 433.517167 -109.989318) (xy 433.471809 -109.956867) (xy 433.43166 -109.918158) (xy 433.397574 -109.874015)
			(xy 433.370278 -109.82538) (xy 433.350355 -109.773289) (xy 433.338229 -109.718852) (xy 433.334158 -109.66323)
			(xy 413.999172 -109.66323) (xy 413.999172 -110.4265) (xy 418.726872 -110.4265) (xy 418.730943 -110.370878)
			(xy 418.743069 -110.316441) (xy 418.762992 -110.26435) (xy 418.790288 -110.215715) (xy 418.824374 -110.171572)
			(xy 418.864523 -110.132863) (xy 418.909881 -110.100412) (xy 418.959481 -110.074911) (xy 419.012265 -110.056904)
			(xy 419.067108 -110.046774) (xy 419.122842 -110.044737) (xy 419.178279 -110.050837) (xy 419.232236 -110.064943)
			(xy 419.283565 -110.086755) (xy 419.331171 -110.115809) (xy 419.374039 -110.151484) (xy 419.411256 -110.193021)
			(xy 419.442029 -110.239534) (xy 419.461448 -110.280958) (xy 419.761922 -110.280958) (xy 419.765993 -110.225336)
			(xy 419.778119 -110.170899) (xy 419.798042 -110.118808) (xy 419.825338 -110.070173) (xy 419.859424 -110.02603)
			(xy 419.899573 -109.987321) (xy 419.944931 -109.95487) (xy 419.994531 -109.929369) (xy 420.047315 -109.911362)
			(xy 420.102158 -109.901232) (xy 420.157892 -109.899195) (xy 420.213329 -109.905295) (xy 420.267286 -109.919401)
			(xy 420.318615 -109.941213) (xy 420.366221 -109.970267) (xy 420.409089 -110.005942) (xy 420.446306 -110.047479)
			(xy 420.477079 -110.093992) (xy 420.500751 -110.144489) (xy 420.516819 -110.197896) (xy 420.524939 -110.253072)
			(xy 420.525448 -110.280958) (xy 420.524939 -110.308844) (xy 420.516819 -110.36402) (xy 420.516667 -110.364524)
			(xy 420.634412 -110.364524) (xy 420.638483 -110.308902) (xy 420.650609 -110.254465) (xy 420.670532 -110.202374)
			(xy 420.697828 -110.153739) (xy 420.731914 -110.109596) (xy 420.772063 -110.070887) (xy 420.817421 -110.038436)
			(xy 420.867021 -110.012935) (xy 420.919805 -109.994928) (xy 420.974648 -109.984798) (xy 421.030382 -109.982761)
			(xy 421.085819 -109.988861) (xy 421.139776 -110.002967) (xy 421.191105 -110.024779) (xy 421.238711 -110.053833)
			(xy 421.281579 -110.089508) (xy 421.318796 -110.131045) (xy 421.349569 -110.177558) (xy 421.373241 -110.228055)
			(xy 421.387858 -110.27664) (xy 428.913542 -110.27664) (xy 428.917613 -110.221018) (xy 428.929739 -110.166581)
			(xy 428.949662 -110.11449) (xy 428.976958 -110.065855) (xy 429.011044 -110.021712) (xy 429.051193 -109.983003)
			(xy 429.096551 -109.950552) (xy 429.146151 -109.925051) (xy 429.198935 -109.907044) (xy 429.253778 -109.896914)
			(xy 429.309512 -109.894877) (xy 429.364949 -109.900977) (xy 429.418906 -109.915083) (xy 429.470235 -109.936895)
			(xy 429.517841 -109.965949) (xy 429.560709 -110.001624) (xy 429.597926 -110.043161) (xy 429.628699 -110.089674)
			(xy 429.652371 -110.140171) (xy 429.668439 -110.193578) (xy 429.676559 -110.248754) (xy 429.677068 -110.27664)
			(xy 429.676559 -110.304526) (xy 429.668439 -110.359702) (xy 429.652371 -110.413109) (xy 429.628699 -110.463606)
			(xy 429.597926 -110.510119) (xy 429.560709 -110.551656) (xy 429.517841 -110.587331) (xy 429.470235 -110.616385)
			(xy 429.418906 -110.638197) (xy 429.364949 -110.652303) (xy 429.309512 -110.658403) (xy 429.253778 -110.656366)
			(xy 429.198935 -110.646236) (xy 429.146151 -110.628229) (xy 429.096551 -110.602728) (xy 429.051193 -110.570277)
			(xy 429.011044 -110.531568) (xy 428.976958 -110.487425) (xy 428.949662 -110.43879) (xy 428.929739 -110.386699)
			(xy 428.917613 -110.332262) (xy 428.913542 -110.27664) (xy 421.387858 -110.27664) (xy 421.389309 -110.281462)
			(xy 421.397429 -110.336638) (xy 421.397938 -110.364524) (xy 421.397429 -110.39241) (xy 421.389309 -110.447586)
			(xy 421.373241 -110.500993) (xy 421.349569 -110.55149) (xy 421.318796 -110.598003) (xy 421.281579 -110.63954)
			(xy 421.238711 -110.675215) (xy 421.191105 -110.704269) (xy 421.139776 -110.726081) (xy 421.085819 -110.740187)
			(xy 421.030382 -110.746287) (xy 420.974648 -110.74425) (xy 420.919805 -110.73412) (xy 420.867021 -110.716113)
			(xy 420.817421 -110.690612) (xy 420.772063 -110.658161) (xy 420.731914 -110.619452) (xy 420.697828 -110.575309)
			(xy 420.670532 -110.526674) (xy 420.650609 -110.474583) (xy 420.638483 -110.420146) (xy 420.634412 -110.364524)
			(xy 420.516667 -110.364524) (xy 420.500751 -110.417427) (xy 420.477079 -110.467924) (xy 420.446306 -110.514437)
			(xy 420.409089 -110.555974) (xy 420.366221 -110.591649) (xy 420.318615 -110.620703) (xy 420.267286 -110.642515)
			(xy 420.213329 -110.656621) (xy 420.157892 -110.662721) (xy 420.102158 -110.660684) (xy 420.047315 -110.650554)
			(xy 419.994531 -110.632547) (xy 419.944931 -110.607046) (xy 419.899573 -110.574595) (xy 419.859424 -110.535886)
			(xy 419.825338 -110.491743) (xy 419.798042 -110.443108) (xy 419.778119 -110.391017) (xy 419.765993 -110.33658)
			(xy 419.761922 -110.280958) (xy 419.461448 -110.280958) (xy 419.465701 -110.290031) (xy 419.481769 -110.343438)
			(xy 419.489889 -110.398614) (xy 419.490398 -110.4265) (xy 419.489889 -110.454386) (xy 419.481769 -110.509562)
			(xy 419.465701 -110.562969) (xy 419.442029 -110.613466) (xy 419.411256 -110.659979) (xy 419.374039 -110.701516)
			(xy 419.331171 -110.737191) (xy 419.283565 -110.766245) (xy 419.232236 -110.788057) (xy 419.178279 -110.802163)
			(xy 419.122842 -110.808263) (xy 419.067108 -110.806226) (xy 419.012265 -110.796096) (xy 418.959481 -110.778089)
			(xy 418.909881 -110.752588) (xy 418.864523 -110.720137) (xy 418.824374 -110.681428) (xy 418.790288 -110.637285)
			(xy 418.762992 -110.58865) (xy 418.743069 -110.536559) (xy 418.730943 -110.482122) (xy 418.726872 -110.4265)
			(xy 413.999172 -110.4265) (xy 413.999172 -110.940088) (xy 429.500282 -110.940088) (xy 429.504353 -110.884466)
			(xy 429.516479 -110.830029) (xy 429.536402 -110.777938) (xy 429.563698 -110.729303) (xy 429.597784 -110.68516)
			(xy 429.637933 -110.646451) (xy 429.683291 -110.614) (xy 429.732891 -110.588499) (xy 429.785675 -110.570492)
			(xy 429.840518 -110.560362) (xy 429.896252 -110.558325) (xy 429.951689 -110.564425) (xy 430.005646 -110.578531)
			(xy 430.056975 -110.600343) (xy 430.104581 -110.629397) (xy 430.147449 -110.665072) (xy 430.184666 -110.706609)
			(xy 430.215439 -110.753122) (xy 430.239111 -110.803619) (xy 430.255179 -110.857026) (xy 430.263299 -110.912202)
			(xy 430.263808 -110.940088) (xy 430.263299 -110.967974) (xy 430.255179 -111.02315) (xy 430.239111 -111.076557)
			(xy 430.215439 -111.127054) (xy 430.184666 -111.173567) (xy 430.147449 -111.215104) (xy 430.104581 -111.250779)
			(xy 430.056975 -111.279833) (xy 430.005646 -111.301645) (xy 429.951689 -111.315751) (xy 429.896252 -111.321851)
			(xy 429.840518 -111.319814) (xy 429.785675 -111.309684) (xy 429.732891 -111.291677) (xy 429.683291 -111.266176)
			(xy 429.637933 -111.233725) (xy 429.597784 -111.195016) (xy 429.563698 -111.150873) (xy 429.536402 -111.102238)
			(xy 429.516479 -111.050147) (xy 429.504353 -110.99571) (xy 429.500282 -110.940088) (xy 413.999172 -110.940088)
			(xy 413.999172 -111.131096) (xy 413.999594 -111.141167) (xy 414.007304 -111.159775) (xy 414.014158 -111.167164)
			(xy 415.490406 -112.643412) (xy 415.497801 -112.650267) (xy 415.5164 -112.658013) (xy 415.526474 -112.658398)
		)
		(stroke
			(width 0)
			(type solid)
		)
		(fill yes)
		(layer "In15.Cu")
		(net "GND")
	)
	(gr_poly
		(pts
			(xy 122.715528 -388.287514) (xy 122.719084 -388.26948) (xy 122.724258 -388.245743) (xy 122.741106 -388.20018)
			(xy 122.764951 -388.157855) (xy 122.79519 -388.119835) (xy 122.81281 -388.10311) (xy 122.821192 -388.09549)
			(xy 122.829828 -388.075424) (xy 122.827034 -387.97611) (xy 122.817636 -387.956552) (xy 122.808746 -387.94944)
			(xy 122.790183 -387.933639) (xy 122.757452 -387.897514) (xy 122.730375 -387.856978) (xy 122.709539 -387.812907)
			(xy 122.695395 -387.766257) (xy 122.688248 -387.718036) (xy 122.687842 -387.693662) (xy 122.688281 -387.669546)
			(xy 122.695287 -387.621826) (xy 122.709146 -387.575629) (xy 122.729564 -387.531932) (xy 122.742452 -387.511544)
			(xy 122.748294 -387.502654) (xy 122.75185 -387.482588) (xy 122.730768 -387.390386) (xy 122.718576 -387.373622)
			(xy 122.709686 -387.368288) (xy 122.688882 -387.355434) (xy 122.650961 -387.324557) (xy 122.618008 -387.288428)
			(xy 122.590741 -387.247834) (xy 122.569756 -387.203664) (xy 122.555514 -387.156883) (xy 122.548324 -387.108513)
			(xy 122.547888 -387.084062) (xy 122.548449 -387.056779) (xy 122.55741 -387.002955) (xy 122.575081 -386.95133)
			(xy 122.600985 -386.903306) (xy 122.634419 -386.860183) (xy 122.65406 -386.841238) (xy 122.661513 -386.833748)
			(xy 122.670063 -386.814453) (xy 122.67057 -386.8039) (xy 122.67057 -386.729224) (xy 122.669983 -386.71869)
			(xy 122.661451 -386.699416) (xy 122.65406 -386.691886) (xy 122.634404 -386.672954) (xy 122.60096 -386.629833)
			(xy 122.57505 -386.581807) (xy 122.557377 -386.530177) (xy 122.548423 -386.476347) (xy 122.547888 -386.449062)
			(xy 122.548142 -386.43687) (xy 122.548396 -386.427218) (xy 122.5423 -386.409184) (xy 122.483626 -386.341874)
			(xy 122.466862 -386.333238) (xy 122.456956 -386.332222) (xy 122.430043 -386.328871) (xy 122.377744 -386.314526)
			(xy 122.328487 -386.291837) (xy 122.283593 -386.261414) (xy 122.244267 -386.224071) (xy 122.211563 -386.180811)
			(xy 122.186358 -386.132793) (xy 122.169327 -386.081306) (xy 122.164602 -386.0546) (xy 122.163078 -386.045202)
			(xy 121.890282 -385.57327) (xy 121.882916 -385.567428) (xy 121.864138 -385.551624) (xy 121.831007 -385.515416)
			(xy 121.803589 -385.474711) (xy 121.782485 -385.430402) (xy 121.76816 -385.383461) (xy 121.760926 -385.334919)
			(xy 121.760488 -385.31038) (xy 121.760999 -385.284394) (xy 121.769132 -385.233061) (xy 121.785195 -385.183633)
			(xy 121.808792 -385.137326) (xy 121.839342 -385.095281) (xy 121.876093 -385.058531) (xy 121.91814 -385.027983)
			(xy 121.964448 -385.004389) (xy 122.013877 -384.988328) (xy 122.06521 -384.980198) (xy 122.091196 -384.979672)
			(xy 122.117207 -384.980157) (xy 122.168587 -384.988303) (xy 122.218058 -385.004395) (xy 122.264398 -385.028035)
			(xy 122.306464 -385.058641) (xy 122.343218 -385.095457) (xy 122.373754 -385.137574) (xy 122.397317 -385.183954)
			(xy 122.413326 -385.233451) (xy 122.41784 -385.259072) (xy 122.419364 -385.26847) (xy 122.69216 -385.740402)
			(xy 122.699526 -385.746244) (xy 122.718303 -385.762049) (xy 122.751433 -385.798257) (xy 122.778852 -385.838962)
			(xy 122.799956 -385.883271) (xy 122.814284 -385.930211) (xy 122.82152 -385.978753) (xy 122.821954 -386.003292)
			(xy 122.8217 -386.015484) (xy 122.821446 -386.025136) (xy 122.827542 -386.04317) (xy 122.886216 -386.11048)
			(xy 122.90298 -386.119116) (xy 122.912886 -386.120132) (xy 122.939655 -386.123457) (xy 122.991685 -386.13768)
			(xy 123.040718 -386.160156) (xy 123.085454 -386.19029) (xy 123.124707 -386.227284) (xy 123.157438 -386.270157)
			(xy 123.182778 -386.317773) (xy 123.200056 -386.36887) (xy 123.208814 -386.422093) (xy 123.209304 -386.449062)
			(xy 123.208741 -386.476344) (xy 123.199777 -386.530166) (xy 123.182102 -386.581788) (xy 123.156196 -386.629809)
			(xy 123.12276 -386.672928) (xy 123.103132 -386.691886) (xy 123.095683 -386.699378) (xy 123.087144 -386.718673)
			(xy 123.086622 -386.729224) (xy 123.086622 -386.8039) (xy 123.087213 -386.814433) (xy 123.09575 -386.8337)
			(xy 123.103132 -386.841238) (xy 123.122787 -386.860171) (xy 123.156229 -386.903291) (xy 123.182136 -386.951318)
			(xy 123.199805 -387.002948) (xy 123.208756 -387.056777) (xy 123.209304 -387.084062) (xy 123.208871 -387.10818)
			(xy 123.201875 -387.155905) (xy 123.188027 -387.202109) (xy 123.167619 -387.245814) (xy 123.154694 -387.26618)
			(xy 123.148852 -387.27507) (xy 123.145296 -387.295136) (xy 123.166378 -387.387338) (xy 123.17857 -387.404102)
			(xy 123.18746 -387.409436) (xy 123.20826 -387.422292) (xy 123.246174 -387.453172) (xy 123.279121 -387.489304)
			(xy 123.306381 -387.529898) (xy 123.327358 -387.574067) (xy 123.341595 -387.620846) (xy 123.34878 -387.669213)
			(xy 123.349258 -387.693662) (xy 123.34882 -387.718033) (xy 123.341665 -387.766246) (xy 123.327517 -387.812889)
			(xy 123.306683 -387.856954) (xy 123.279613 -387.897487) (xy 123.246893 -387.933614) (xy 123.228354 -387.94944)
			(xy 123.219464 -387.956552) (xy 123.210066 -387.97611) (xy 123.207272 -388.075424) (xy 123.215908 -388.09549)
			(xy 123.22429 -388.10311) (xy 123.241924 -388.119825) (xy 123.272183 -388.157835) (xy 123.296034 -388.200162)
			(xy 123.312874 -388.245734) (xy 123.318016 -388.26948) (xy 123.321572 -388.287514) (xy 123.349512 -388.310628)
			(xy 123.887484 -388.310628) (xy 123.915424 -388.287514) (xy 123.91898 -388.26948) (xy 123.924154 -388.245743)
			(xy 123.941002 -388.200179) (xy 123.964846 -388.157855) (xy 123.995085 -388.119834) (xy 124.012706 -388.10311)
			(xy 124.021088 -388.09549) (xy 124.029724 -388.075424) (xy 124.02693 -387.97611) (xy 124.017532 -387.956552)
			(xy 124.008642 -387.94944) (xy 123.990079 -387.933639) (xy 123.957348 -387.897514) (xy 123.930272 -387.856977)
			(xy 123.909436 -387.812907) (xy 123.895292 -387.766257) (xy 123.888145 -387.718036) (xy 123.887738 -387.693662)
			(xy 123.888177 -387.669546) (xy 123.895183 -387.621826) (xy 123.909042 -387.575629) (xy 123.92946 -387.531932)
			(xy 123.942348 -387.511544) (xy 123.94819 -387.502654) (xy 123.951746 -387.482588) (xy 123.930664 -387.390386)
			(xy 123.918472 -387.373622) (xy 123.909582 -387.368288) (xy 123.888778 -387.355434) (xy 123.850858 -387.324557)
			(xy 123.817905 -387.288427) (xy 123.790638 -387.247833) (xy 123.769654 -387.203663) (xy 123.755412 -387.156882)
			(xy 123.748222 -387.108513) (xy 123.747784 -387.084062) (xy 123.748345 -387.056779) (xy 123.757306 -387.002955)
			(xy 123.774977 -386.95133) (xy 123.800881 -386.903305) (xy 123.834314 -386.860182) (xy 123.853956 -386.841238)
			(xy 123.86141 -386.833748) (xy 123.86996 -386.814453) (xy 123.870466 -386.8039) (xy 123.870466 -386.729224)
			(xy 123.869879 -386.71869) (xy 123.861347 -386.699417) (xy 123.853956 -386.691886) (xy 123.8343 -386.672954)
			(xy 123.800856 -386.629833) (xy 123.774946 -386.581807) (xy 123.757275 -386.530177) (xy 123.74832 -386.476347)
			(xy 123.747784 -386.449062) (xy 123.748038 -386.43687) (xy 123.748292 -386.427218) (xy 123.742196 -386.409184)
			(xy 123.683522 -386.341874) (xy 123.666758 -386.333238) (xy 123.656852 -386.332222) (xy 123.629939 -386.328871)
			(xy 123.57764 -386.314525) (xy 123.528384 -386.291836) (xy 123.483491 -386.261412) (xy 123.444166 -386.22407)
			(xy 123.411462 -386.18081) (xy 123.386257 -386.132792) (xy 123.369227 -386.081305) (xy 123.364498 -386.0546)
			(xy 123.362974 -386.045202) (xy 123.089924 -385.572762) (xy 123.082812 -385.56692) (xy 123.064077 -385.551142)
			(xy 123.031018 -385.515) (xy 123.003656 -385.474374) (xy 122.982589 -385.430156) (xy 122.968279 -385.383313)
			(xy 122.961038 -385.33487) (xy 122.960638 -385.31038) (xy 122.961123 -385.284393) (xy 122.969257 -385.23306)
			(xy 122.985321 -385.183631) (xy 123.008921 -385.137324) (xy 123.039474 -385.095279) (xy 123.076229 -385.058531)
			(xy 123.11828 -385.027986) (xy 123.164592 -385.004396) (xy 123.214024 -384.988341) (xy 123.265359 -384.980217)
			(xy 123.291346 -384.979672) (xy 123.317392 -384.980155) (xy 123.36884 -384.988313) (xy 123.418374 -385.004435)
			(xy 123.464768 -385.028123) (xy 123.506875 -385.05879) (xy 123.543654 -385.09568) (xy 123.574196 -385.137878)
			(xy 123.597744 -385.184343) (xy 123.613718 -385.233925) (xy 123.618244 -385.25958) (xy 123.619514 -385.268978)
			(xy 123.64345 -385.31038) (xy 124.160534 -385.31038) (xy 124.160957 -385.284388) (xy 124.169092 -385.233045)
			(xy 124.18516 -385.183606) (xy 124.208764 -385.13729) (xy 124.239323 -385.095237) (xy 124.276084 -385.058482)
			(xy 124.318143 -385.027931) (xy 124.364464 -385.004336) (xy 124.413905 -384.988278) (xy 124.46525 -384.980152)
			(xy 124.491242 -384.979672) (xy 124.517253 -384.980103) (xy 124.568632 -384.988268) (xy 124.618099 -385.004375)
			(xy 124.664435 -385.028026) (xy 124.706498 -385.058639) (xy 124.74325 -385.095458) (xy 124.773787 -385.137576)
			(xy 124.797354 -385.183955) (xy 124.813371 -385.233451) (xy 124.817886 -385.259072) (xy 124.81941 -385.26847)
			(xy 125.092206 -385.740402) (xy 125.099572 -385.746244) (xy 125.118368 -385.762024) (xy 125.151482 -385.798248)
			(xy 125.178887 -385.838961) (xy 125.199984 -385.883273) (xy 125.214311 -385.930213) (xy 125.221555 -385.978753)
			(xy 125.222 -386.003292) (xy 125.221746 -386.015484) (xy 125.221492 -386.025136) (xy 125.227588 -386.04317)
			(xy 125.286262 -386.11048) (xy 125.303026 -386.119116) (xy 125.312678 -386.120132) (xy 125.339437 -386.123509)
			(xy 125.39146 -386.137728) (xy 125.440486 -386.1602) (xy 125.485216 -386.19033) (xy 125.524464 -386.227318)
			(xy 125.55719 -386.270184) (xy 125.582527 -386.317793) (xy 125.599803 -386.368882) (xy 125.60856 -386.422097)
			(xy 125.609096 -386.449062) (xy 125.608586 -386.475049) (xy 125.600456 -386.526384) (xy 125.584395 -386.575814)
			(xy 125.560799 -386.622124) (xy 125.530249 -386.664172) (xy 125.493498 -386.700923) (xy 125.45145 -386.731473)
			(xy 125.40514 -386.755069) (xy 125.35571 -386.77113) (xy 125.304375 -386.77926) (xy 125.252401 -386.77926)
			(xy 125.201066 -386.77113) (xy 125.151636 -386.755069) (xy 125.105326 -386.731473) (xy 125.063278 -386.700923)
			(xy 125.026527 -386.664172) (xy 124.995977 -386.622124) (xy 124.972381 -386.575814) (xy 124.95632 -386.526384)
			(xy 124.94819 -386.475049) (xy 124.94768 -386.449062) (xy 124.947934 -386.43687) (xy 124.948188 -386.427218)
			(xy 124.942092 -386.409184) (xy 124.883418 -386.341874) (xy 124.866654 -386.333238) (xy 124.857002 -386.332222)
			(xy 124.8301 -386.328817) (xy 124.777815 -386.31446) (xy 124.728571 -386.291767) (xy 124.683688 -386.261347)
			(xy 124.644367 -386.224014) (xy 124.611661 -386.180768) (xy 124.586447 -386.132767) (xy 124.569398 -386.081296)
			(xy 124.564648 -386.0546) (xy 124.563124 -386.045202) (xy 124.290328 -385.57327) (xy 124.282962 -385.567428)
			(xy 124.264207 -385.5516) (xy 124.23109 -385.515388) (xy 124.203678 -385.474685) (xy 124.182574 -385.430382)
			(xy 124.168238 -385.38345) (xy 124.160984 -385.334916) (xy 124.160534 -385.31038) (xy 123.64345 -385.31038)
			(xy 123.892056 -385.740402) (xy 123.899422 -385.746244) (xy 123.918199 -385.762049) (xy 123.95133 -385.798257)
			(xy 123.978748 -385.838962) (xy 123.999853 -385.883271) (xy 124.014181 -385.930211) (xy 124.021417 -385.978753)
			(xy 124.02185 -386.003292) (xy 124.021596 -386.015484) (xy 124.021342 -386.025136) (xy 124.027438 -386.04317)
			(xy 124.086112 -386.11048) (xy 124.102876 -386.119116) (xy 124.112782 -386.120132) (xy 124.139551 -386.123457)
			(xy 124.191582 -386.137679) (xy 124.240615 -386.160155) (xy 124.285351 -386.190289) (xy 124.324605 -386.227283)
			(xy 124.357336 -386.270156) (xy 124.382677 -386.317772) (xy 124.399955 -386.368869) (xy 124.408714 -386.422092)
			(xy 124.4092 -386.449062) (xy 124.408637 -386.476344) (xy 124.399673 -386.530166) (xy 124.381998 -386.581788)
			(xy 124.356091 -386.629809) (xy 124.322655 -386.672928) (xy 124.303028 -386.691886) (xy 124.29558 -386.699378)
			(xy 124.287041 -386.718673) (xy 124.286518 -386.729224) (xy 124.286518 -386.8039) (xy 124.287109 -386.814433)
			(xy 124.295645 -386.833701) (xy 124.303028 -386.841238) (xy 124.322683 -386.86017) (xy 124.356126 -386.903291)
			(xy 124.382033 -386.951318) (xy 124.399702 -387.002947) (xy 124.408653 -387.056777) (xy 124.4092 -387.084062)
			(xy 124.408767 -387.10818) (xy 124.401771 -387.155905) (xy 124.387923 -387.202109) (xy 124.367514 -387.245814)
			(xy 124.35459 -387.26618) (xy 124.348748 -387.27507) (xy 124.345192 -387.295136) (xy 124.366274 -387.387338)
			(xy 124.378466 -387.404102) (xy 124.387356 -387.409436) (xy 124.408157 -387.422292) (xy 124.44607 -387.453172)
			(xy 124.479018 -387.489303) (xy 124.506278 -387.529897) (xy 124.527256 -387.574066) (xy 124.541493 -387.620846)
			(xy 124.548678 -387.669213) (xy 124.549154 -387.693662) (xy 124.548716 -387.718033) (xy 124.541561 -387.766246)
			(xy 124.527413 -387.812889) (xy 124.506578 -387.856953) (xy 124.479508 -387.897487) (xy 124.446788 -387.933613)
			(xy 124.42825 -387.94944) (xy 124.41936 -387.956552) (xy 124.409962 -387.97611) (xy 124.407168 -388.075424)
			(xy 124.415804 -388.09549) (xy 124.424186 -388.10311) (xy 124.44182 -388.119825) (xy 124.47208 -388.157835)
			(xy 124.495931 -388.200161) (xy 124.512771 -388.245734) (xy 124.517912 -388.26948) (xy 124.521468 -388.287514)
			(xy 124.549408 -388.310628) (xy 125.08738 -388.310628) (xy 125.11532 -388.287514) (xy 125.118876 -388.26948)
			(xy 125.124137 -388.245324) (xy 125.141411 -388.199005) (xy 125.165923 -388.156075) (xy 125.197032 -388.117655)
			(xy 125.233926 -388.084751) (xy 125.275639 -388.058222) (xy 125.321083 -388.038761) (xy 125.369069 -388.026877)
			(xy 125.418342 -388.022881) (xy 125.467615 -388.026877) (xy 125.515601 -388.038761) (xy 125.561045 -388.058222)
			(xy 125.602758 -388.084751) (xy 125.639652 -388.117655) (xy 125.670761 -388.156075) (xy 125.695273 -388.199005)
			(xy 125.712547 -388.245324) (xy 125.717808 -388.26948) (xy 125.721364 -388.287514) (xy 125.749304 -388.310628)
			(xy 125.993398 -388.310628) (xy 126.003469 -388.310206) (xy 126.022077 -388.302495) (xy 126.029466 -388.295642)
			(xy 126.19355 -388.131558) (xy 126.200395 -388.12416) (xy 126.208122 -388.105561) (xy 126.208536 -388.09549)
			(xy 126.208536 -387.89737) (xy 126.20371 -387.886956) (xy 126.19018 -387.856546) (xy 126.171073 -387.792791)
			(xy 126.161406 -387.72694) (xy 126.160784 -387.693662) (xy 126.161398 -387.660383) (xy 126.171068 -387.594532)
			(xy 126.19017 -387.530773) (xy 126.20371 -387.500368) (xy 126.208536 -387.489954) (xy 126.208536 -387.46684)
			(xy 126.19863 -387.44652) (xy 126.18974 -387.439154) (xy 126.167498 -387.420478) (xy 126.127443 -387.378419)
			(xy 126.093031 -387.331631) (xy 126.064815 -387.280866) (xy 126.043247 -387.226938) (xy 126.028675 -387.170716)
			(xy 126.021332 -387.113102) (xy 126.02083 -387.084062) (xy 126.021275 -387.055137) (xy 126.028569 -386.997747)
			(xy 126.043035 -386.941734) (xy 126.064443 -386.88799) (xy 126.092452 -386.837372) (xy 126.126616 -386.790686)
			(xy 126.166389 -386.748676) (xy 126.18847 -386.729986) (xy 126.195541 -386.723719) (xy 126.204821 -386.707278)
			(xy 126.206504 -386.697982) (xy 126.210822 -386.666994) (xy 126.21177 -386.657756) (xy 126.207737 -386.639644)
			(xy 126.202948 -386.631688) (xy 126.189914 -386.611291) (xy 126.169312 -386.567489) (xy 126.155324 -386.521149)
			(xy 126.14825 -386.473264) (xy 126.14783 -386.449062) (xy 126.148084 -386.43687) (xy 126.148338 -386.427218)
			(xy 126.142242 -386.409184) (xy 126.083568 -386.341874) (xy 126.066804 -386.333238) (xy 126.056898 -386.332222)
			(xy 126.029983 -386.328874) (xy 125.977678 -386.314534) (xy 125.928416 -386.291848) (xy 125.883517 -386.261427)
			(xy 125.844185 -386.224085) (xy 125.811476 -386.180823) (xy 125.786267 -386.132804) (xy 125.769233 -386.081313)
			(xy 125.764544 -386.0546) (xy 125.76302 -386.045202) (xy 125.490224 -385.57327) (xy 125.482858 -385.567428)
			(xy 125.464078 -385.551625) (xy 125.430943 -385.515419) (xy 125.403521 -385.474715) (xy 125.382415 -385.430405)
			(xy 125.368087 -385.383464) (xy 125.360853 -385.33492) (xy 125.36043 -385.31038) (xy 125.360915 -385.284393)
			(xy 125.369049 -385.233059) (xy 125.385113 -385.18363) (xy 125.408713 -385.137322) (xy 125.439266 -385.095276)
			(xy 125.47602 -385.058528) (xy 125.518071 -385.027982) (xy 125.564383 -385.004391) (xy 125.613815 -384.988335)
			(xy 125.665151 -384.98021) (xy 125.691138 -384.979672) (xy 125.717152 -384.980152) (xy 125.768539 -384.988291)
			(xy 125.818017 -385.004378) (xy 125.864365 -385.028015) (xy 125.906439 -385.058619) (xy 125.9432 -385.095435)
			(xy 125.973742 -385.137555) (xy 125.99731 -385.183938) (xy 126.013323 -385.23344) (xy 126.017782 -385.259072)
			(xy 126.019306 -385.26847) (xy 126.292102 -385.740402) (xy 126.299468 -385.746244) (xy 126.318248 -385.762047)
			(xy 126.351384 -385.798253) (xy 126.378807 -385.838957) (xy 126.399915 -385.883267) (xy 126.414246 -385.930208)
			(xy 126.421483 -385.978752) (xy 126.421896 -386.003292) (xy 126.421642 -386.015484) (xy 126.421388 -386.025136)
			(xy 126.427484 -386.04317) (xy 126.486158 -386.11048) (xy 126.502922 -386.119116) (xy 126.512828 -386.120132)
			(xy 126.539263 -386.123421) (xy 126.590673 -386.137357) (xy 126.639185 -386.159355) (xy 126.683542 -386.188845)
			(xy 126.722598 -386.225065) (xy 126.755342 -386.267078) (xy 126.780927 -386.313797) (xy 126.798692 -386.364013)
			(xy 126.803912 -386.390134) (xy 126.807214 -386.408422) (xy 126.835408 -386.43179) (xy 127.008382 -386.43179)
			(xy 127.018735 -386.431362) (xy 127.037791 -386.423279) (xy 127.052084 -386.408307) (xy 127.056134 -386.39877)
			(xy 127.094996 -386.29463) (xy 127.087122 -386.263896) (xy 127.07493 -386.253482) (xy 127.057631 -386.237983)
			(xy 127.02712 -386.202964) (xy 127.001808 -386.16402) (xy 126.982196 -386.121917) (xy 126.968668 -386.077484)
			(xy 126.964694 -386.0546) (xy 126.96317 -386.045202) (xy 126.690374 -385.57327) (xy 126.683008 -385.567428)
			(xy 126.664231 -385.551624) (xy 126.6311 -385.515416) (xy 126.603683 -385.474711) (xy 126.58258 -385.430402)
			(xy 126.568254 -385.383461) (xy 126.561021 -385.334919) (xy 126.56058 -385.31038) (xy 126.561091 -385.284394)
			(xy 126.569224 -385.233061) (xy 126.585287 -385.183632) (xy 126.608883 -385.137325) (xy 126.639433 -385.095278)
			(xy 126.676184 -385.058528) (xy 126.718231 -385.027979) (xy 126.764539 -385.004384) (xy 126.813969 -384.988322)
			(xy 126.865301 -384.98019) (xy 126.891288 -384.979672) (xy 126.917299 -384.980156) (xy 126.96868 -384.988301)
			(xy 127.018152 -385.004392) (xy 127.064493 -385.028032) (xy 127.106561 -385.058638) (xy 127.143316 -385.095454)
			(xy 127.173852 -385.137571) (xy 127.197416 -385.183951) (xy 127.213426 -385.233449) (xy 127.217932 -385.259072)
			(xy 127.219456 -385.26847) (xy 127.492252 -385.740402) (xy 127.499618 -385.746244) (xy 127.518395 -385.762049)
			(xy 127.551526 -385.798257) (xy 127.578945 -385.838962) (xy 127.60005 -385.88327) (xy 127.614378 -385.930211)
			(xy 127.621615 -385.978753) (xy 127.622046 -386.003292) (xy 127.621792 -386.015484) (xy 127.621538 -386.025136)
			(xy 127.627634 -386.04317) (xy 127.686308 -386.11048) (xy 127.703072 -386.119116) (xy 127.712724 -386.120132)
			(xy 127.739159 -386.12342) (xy 127.79057 -386.137356) (xy 127.839082 -386.159354) (xy 127.88344 -386.188844)
			(xy 127.922496 -386.225064) (xy 127.955241 -386.267077) (xy 127.980827 -386.313796) (xy 127.998592 -386.364012)
			(xy 128.003808 -386.390134) (xy 128.00711 -386.408422) (xy 128.035304 -386.43179) (xy 128.208278 -386.43179)
			(xy 128.218631 -386.431363) (xy 128.237689 -386.423281) (xy 128.251983 -386.408308) (xy 128.25603 -386.39877)
			(xy 128.294892 -386.29463) (xy 128.287018 -386.263896) (xy 128.274826 -386.253482) (xy 128.257528 -386.237982)
			(xy 128.227016 -386.202963) (xy 128.201705 -386.164019) (xy 128.182093 -386.121917) (xy 128.168565 -386.077484)
			(xy 128.16459 -386.0546) (xy 128.163066 -386.045202) (xy 127.89027 -385.57327) (xy 127.882904 -385.567428)
			(xy 127.864127 -385.551624) (xy 127.830997 -385.515416) (xy 127.80358 -385.47471) (xy 127.782477 -385.430401)
			(xy 127.768152 -385.383461) (xy 127.760919 -385.334919) (xy 127.760476 -385.31038) (xy 127.760987 -385.284393)
			(xy 127.76912 -385.23306) (xy 127.785183 -385.183631) (xy 127.808779 -385.137324) (xy 127.839329 -385.095277)
			(xy 127.87608 -385.058526) (xy 127.918127 -385.027977) (xy 127.964435 -385.004381) (xy 128.013864 -384.988319)
			(xy 128.065197 -384.980187) (xy 128.091184 -384.979672) (xy 128.117196 -384.980156) (xy 128.168577 -384.9883)
			(xy 128.218049 -385.004391) (xy 128.264391 -385.028031) (xy 128.306459 -385.058636) (xy 128.343215 -385.095452)
			(xy 128.373751 -385.13757) (xy 128.397315 -385.18395) (xy 128.413325 -385.233449) (xy 128.417828 -385.259072)
			(xy 128.419352 -385.26847) (xy 128.692148 -385.740402) (xy 128.699514 -385.746244) (xy 128.718291 -385.762048)
			(xy 128.751423 -385.798256) (xy 128.778842 -385.838961) (xy 128.799948 -385.88327) (xy 128.814276 -385.93021)
			(xy 128.821512 -385.978753) (xy 128.821942 -386.003292) (xy 128.821688 -386.015484) (xy 128.821434 -386.025136)
			(xy 128.82753 -386.04317) (xy 128.886204 -386.11048) (xy 128.902968 -386.119116) (xy 128.912874 -386.120132)
			(xy 128.939644 -386.123456) (xy 128.991675 -386.137677) (xy 129.040709 -386.160153) (xy 129.085447 -386.190287)
			(xy 129.124702 -386.227281) (xy 129.157434 -386.270154) (xy 129.182775 -386.317771) (xy 129.200054 -386.368868)
			(xy 129.208813 -386.422092) (xy 129.209292 -386.449062) (xy 129.208884 -386.472801) (xy 129.202098 -386.51979)
			(xy 129.18866 -386.565325) (xy 129.168846 -386.60847) (xy 129.143064 -386.648337) (xy 129.127758 -386.666486)
			(xy 129.121408 -386.673852) (xy 129.115058 -386.691632) (xy 129.117598 -386.77088) (xy 129.118346 -386.780477)
			(xy 129.126048 -386.798103) (xy 129.132584 -386.80517) (xy 129.815336 -387.487922) (xy 129.823197 -387.494972)
			(xy 129.842876 -387.502566) (xy 129.853436 -387.502654) (xy 129.939288 -387.498844) (xy 129.95783 -387.4897)
			(xy 129.964942 -387.481318) (xy 129.97307 -387.47192) (xy 129.960116 -387.415278) (xy 129.956968 -387.404347)
			(xy 129.942868 -387.386534) (xy 129.932938 -387.380988) (xy 129.909505 -387.368925) (xy 129.866467 -387.338509)
			(xy 129.828795 -387.301654) (xy 129.797445 -387.259291) (xy 129.773207 -387.212494) (xy 129.756697 -387.162446)
			(xy 129.748331 -387.110413) (xy 129.747772 -387.084062) (xy 129.748333 -387.056779) (xy 129.757293 -387.002954)
			(xy 129.774964 -386.951329) (xy 129.800867 -386.903304) (xy 129.8343 -386.86018) (xy 129.853944 -386.841238)
			(xy 129.861399 -386.833749) (xy 129.869952 -386.814453) (xy 129.870454 -386.8039) (xy 129.870454 -386.729224)
			(xy 129.869867 -386.71869) (xy 129.861333 -386.699418) (xy 129.853944 -386.691886) (xy 129.834289 -386.672953)
			(xy 129.800846 -386.629832) (xy 129.774937 -386.581806) (xy 129.757266 -386.530177) (xy 129.748312 -386.476347)
			(xy 129.747772 -386.449062) (xy 129.748026 -386.43687) (xy 129.74828 -386.427218) (xy 129.742184 -386.409184)
			(xy 129.68351 -386.341874) (xy 129.666746 -386.333238) (xy 129.65684 -386.332222) (xy 129.629928 -386.32887)
			(xy 129.57763 -386.314522) (xy 129.528376 -386.291833) (xy 129.483485 -386.261408) (xy 129.444161 -386.224066)
			(xy 129.411458 -386.180806) (xy 129.386254 -386.132789) (xy 129.369225 -386.081303) (xy 129.364486 -386.0546)
			(xy 129.362962 -386.045202) (xy 129.089912 -385.572762) (xy 129.0828 -385.56692) (xy 129.064065 -385.551141)
			(xy 129.031008 -385.514999) (xy 129.003647 -385.474373) (xy 128.982581 -385.430155) (xy 128.968271 -385.383312)
			(xy 128.961031 -385.33487) (xy 128.960626 -385.31038) (xy 128.961111 -385.284393) (xy 128.969245 -385.233059)
			(xy 128.985309 -385.183629) (xy 129.008908 -385.137321) (xy 129.039462 -385.095275) (xy 129.076216 -385.058526)
			(xy 129.118267 -385.02798) (xy 129.164579 -385.004388) (xy 129.214011 -384.988332) (xy 129.265347 -384.980206)
			(xy 129.291334 -384.979672) (xy 129.31738 -384.980154) (xy 129.36883 -384.98831) (xy 129.418366 -385.004431)
			(xy 129.464761 -385.028118) (xy 129.50687 -385.058786) (xy 129.543651 -385.095675) (xy 129.574193 -385.137874)
			(xy 129.597743 -385.18434) (xy 129.613717 -385.233923) (xy 129.618232 -385.25958) (xy 129.619502 -385.268978)
			(xy 129.892044 -385.740402) (xy 129.89941 -385.746244) (xy 129.918188 -385.762048) (xy 129.95132 -385.798256)
			(xy 129.978739 -385.838961) (xy 129.999845 -385.88327) (xy 130.014173 -385.93021) (xy 130.02141 -385.978753)
			(xy 130.021838 -386.003292) (xy 130.021584 -386.015484) (xy 130.02133 -386.025136) (xy 130.027426 -386.04317)
			(xy 130.0861 -386.11048) (xy 130.102864 -386.119116) (xy 130.11277 -386.120132) (xy 130.13954 -386.123456)
			(xy 130.191572 -386.137677) (xy 130.240607 -386.160152) (xy 130.285345 -386.190285) (xy 130.3246 -386.227279)
			(xy 130.357333 -386.270153) (xy 130.382675 -386.31777) (xy 130.399954 -386.368868) (xy 130.408713 -386.422092)
			(xy 130.409188 -386.449062) (xy 130.408625 -386.476344) (xy 130.39966 -386.530166) (xy 130.381985 -386.581787)
			(xy 130.356078 -386.629807) (xy 130.322641 -386.672925) (xy 130.303016 -386.691886) (xy 130.295569 -386.699379)
			(xy 130.287033 -386.718674) (xy 130.286506 -386.729224) (xy 130.286506 -386.8039) (xy 130.287097 -386.814433)
			(xy 130.295631 -386.833702) (xy 130.303016 -386.841238) (xy 130.322672 -386.86017) (xy 130.356115 -386.90329)
			(xy 130.382024 -386.951317) (xy 130.399694 -387.002947) (xy 130.408645 -387.056777) (xy 130.409188 -387.084062)
			(xy 130.408755 -387.10818) (xy 130.401759 -387.155904) (xy 130.38791 -387.202108) (xy 130.367501 -387.245813)
			(xy 130.354578 -387.26618) (xy 130.348736 -387.27507) (xy 130.34518 -387.295136) (xy 130.366262 -387.387338)
			(xy 130.378454 -387.404102) (xy 130.387344 -387.409436) (xy 130.408145 -387.422292) (xy 130.44606 -387.453171)
			(xy 130.479009 -387.489302) (xy 130.50627 -387.529896) (xy 130.527249 -387.574065) (xy 130.541487 -387.620845)
			(xy 130.548672 -387.669213) (xy 130.549142 -387.693662) (xy 130.548673 -387.718856) (xy 130.541041 -387.768661)
			(xy 130.525946 -387.816734) (xy 130.503739 -387.861964) (xy 130.489706 -387.882892) (xy 130.481578 -387.894576)
			(xy 130.479546 -387.92277) (xy 130.527806 -388.015226) (xy 130.532431 -388.023311) (xy 130.546309 -388.035712)
			(xy 130.563711 -388.042311) (xy 130.573018 -388.042658) (xy 131.064 -388.042658) (xy 131.073292 -388.042239)
			(xy 131.09066 -388.03562) (xy 131.104555 -388.023278) (xy 131.109212 -388.015226) (xy 131.157472 -387.92277)
			(xy 131.15544 -387.894576) (xy 131.147312 -387.882892) (xy 131.1333 -387.861952) (xy 131.111099 -387.816724)
			(xy 131.09601 -387.768655) (xy 131.08838 -387.718853) (xy 131.087876 -387.693662) (xy 131.088315 -387.669546)
			(xy 131.09532 -387.621825) (xy 131.109176 -387.575627) (xy 131.129591 -387.531928) (xy 131.142486 -387.511544)
			(xy 131.148328 -387.502654) (xy 131.151884 -387.482588) (xy 131.130802 -387.390386) (xy 131.11861 -387.373622)
			(xy 131.10972 -387.368288) (xy 131.088914 -387.355435) (xy 131.05099 -387.324561) (xy 131.018033 -387.288432)
			(xy 130.990763 -387.247838) (xy 130.969776 -387.203667) (xy 130.955532 -387.156885) (xy 130.948342 -387.108514)
			(xy 130.947922 -387.084062) (xy 130.948483 -387.05678) (xy 130.957444 -387.002956) (xy 130.975118 -386.951332)
			(xy 131.001023 -386.903309) (xy 131.034459 -386.860189) (xy 131.054094 -386.841238) (xy 131.061543 -386.833746)
			(xy 131.070087 -386.814451) (xy 131.070604 -386.8039) (xy 131.070604 -386.729224) (xy 131.070018 -386.718689)
			(xy 131.06149 -386.699412) (xy 131.054094 -386.691886) (xy 131.034436 -386.672955) (xy 131.000988 -386.629836)
			(xy 130.975076 -386.581809) (xy 130.957402 -386.530179) (xy 130.948446 -386.476348) (xy 130.947922 -386.449062)
			(xy 130.948176 -386.43687) (xy 130.94843 -386.427218) (xy 130.942334 -386.409184) (xy 130.88366 -386.341874)
			(xy 130.866896 -386.333238) (xy 130.85699 -386.332222) (xy 130.830075 -386.328873) (xy 130.777772 -386.314532)
			(xy 130.72851 -386.291846) (xy 130.683612 -386.261424) (xy 130.644282 -386.224082) (xy 130.611574 -386.180821)
			(xy 130.586365 -386.132802) (xy 130.569332 -386.081312) (xy 130.564636 -386.0546) (xy 130.563112 -386.045202)
			(xy 130.290316 -385.57327) (xy 130.28295 -385.567428) (xy 130.264171 -385.551625) (xy 130.231036 -385.515419)
			(xy 130.203615 -385.474714) (xy 130.182509 -385.430405) (xy 130.168182 -385.383463) (xy 130.160948 -385.33492)
			(xy 130.160522 -385.31038) (xy 130.161007 -385.284393) (xy 130.169141 -385.233058) (xy 130.185205 -385.183628)
			(xy 130.208804 -385.13732) (xy 130.239357 -385.095274) (xy 130.276112 -385.058525) (xy 130.318163 -385.027978)
			(xy 130.364475 -385.004386) (xy 130.413907 -384.988329) (xy 130.465243 -384.980203) (xy 130.49123 -384.979672)
			(xy 130.517244 -384.980152) (xy 130.568632 -384.98829) (xy 130.618111 -385.004375) (xy 130.66446 -385.028012)
			(xy 130.706535 -385.058616) (xy 130.743298 -385.095432) (xy 130.77384 -385.137552) (xy 130.797409 -385.183936)
			(xy 130.813423 -385.233438) (xy 130.817874 -385.259072) (xy 130.819398 -385.26847) (xy 131.092194 -385.740402)
			(xy 131.09956 -385.746244) (xy 131.11834 -385.762047) (xy 131.151477 -385.798253) (xy 131.178901 -385.838957)
			(xy 131.20001 -385.883266) (xy 131.21434 -385.930208) (xy 131.221578 -385.978752) (xy 131.221988 -386.003292)
			(xy 131.221734 -386.015484) (xy 131.22148 -386.025136) (xy 131.227576 -386.04317) (xy 131.28625 -386.11048)
			(xy 131.303014 -386.119116) (xy 131.31292 -386.120132) (xy 131.339687 -386.12346) (xy 131.391713 -386.137686)
			(xy 131.440741 -386.160165) (xy 131.485472 -386.1903) (xy 131.524721 -386.227295) (xy 131.557448 -386.270167)
			(xy 131.582785 -386.31778) (xy 131.600061 -386.368874) (xy 131.608818 -386.422094) (xy 131.609338 -386.449062)
			(xy 131.608775 -386.476344) (xy 131.599812 -386.530167) (xy 131.582138 -386.58179) (xy 131.556234 -386.629813)
			(xy 131.5228 -386.672935) (xy 131.503166 -386.691886) (xy 131.495725 -386.699381) (xy 131.487198 -386.718676)
			(xy 131.486656 -386.729224) (xy 131.486656 -386.8039) (xy 131.487248 -386.814432) (xy 131.495789 -386.833695)
			(xy 131.503166 -386.841238) (xy 131.522819 -386.860172) (xy 131.556258 -386.903293) (xy 131.582162 -386.95132)
			(xy 131.599829 -387.002949) (xy 131.608779 -387.056778) (xy 131.609338 -387.084062) (xy 131.608905 -387.10818)
			(xy 131.60191 -387.155905) (xy 131.588063 -387.20211) (xy 131.567656 -387.245816) (xy 131.554728 -387.26618)
			(xy 131.548886 -387.27507) (xy 131.54533 -387.295136) (xy 131.566412 -387.387338) (xy 131.578604 -387.404102)
			(xy 131.587494 -387.409436) (xy 131.608298 -387.42229) (xy 131.646218 -387.453166) (xy 131.679172 -387.489296)
			(xy 131.706437 -387.52989) (xy 131.72742 -387.57406) (xy 131.74166 -387.620842) (xy 131.748846 -387.669211)
			(xy 131.749292 -387.693662) (xy 131.748823 -387.718855) (xy 131.741189 -387.76866) (xy 131.726093 -387.816732)
			(xy 131.703883 -387.86196) (xy 131.689856 -387.882892) (xy 131.681728 -387.894576) (xy 131.679696 -387.92277)
			(xy 131.727956 -388.015226) (xy 131.732583 -388.023306) (xy 131.746464 -388.035693) (xy 131.763864 -388.042276)
			(xy 131.773168 -388.042658) (xy 132.263896 -388.042658) (xy 132.273189 -388.04224) (xy 132.290557 -388.035622)
			(xy 132.304454 -388.023279) (xy 132.309108 -388.015226) (xy 132.357368 -387.92277) (xy 132.355336 -387.894576)
			(xy 132.347208 -387.882892) (xy 132.333196 -387.861952) (xy 132.310996 -387.816724) (xy 132.295906 -387.768655)
			(xy 132.288277 -387.718853) (xy 132.287772 -387.693662) (xy 132.288211 -387.669546) (xy 132.295216 -387.621825)
			(xy 132.309072 -387.575626) (xy 132.329486 -387.531928) (xy 132.342382 -387.511544) (xy 132.348224 -387.502654)
			(xy 132.35178 -387.482588) (xy 132.330698 -387.390386) (xy 132.318506 -387.373622) (xy 132.309616 -387.368288)
			(xy 132.288811 -387.355435) (xy 132.250887 -387.32456) (xy 132.21793 -387.288431) (xy 132.19066 -387.247838)
			(xy 132.169674 -387.203667) (xy 132.15543 -387.156885) (xy 132.14824 -387.108514) (xy 132.147818 -387.084062)
			(xy 132.148379 -387.05678) (xy 132.15734 -387.002956) (xy 132.175013 -386.951332) (xy 132.200919 -386.903309)
			(xy 132.234355 -386.860188) (xy 132.25399 -386.841238) (xy 132.26144 -386.833747) (xy 132.269985 -386.814451)
			(xy 132.2705 -386.8039) (xy 132.2705 -386.729224) (xy 132.269914 -386.718689) (xy 132.261386 -386.699412)
			(xy 132.25399 -386.691886) (xy 132.234333 -386.672955) (xy 132.200885 -386.629835) (xy 132.174973 -386.581809)
			(xy 132.157299 -386.530179) (xy 132.148343 -386.476348) (xy 132.147818 -386.449062) (xy 132.148072 -386.43687)
			(xy 132.148326 -386.427218) (xy 132.14223 -386.409184) (xy 132.083556 -386.341874) (xy 132.066792 -386.333238)
			(xy 132.056886 -386.332222) (xy 132.029971 -386.328873) (xy 131.977668 -386.314531) (xy 131.928408 -386.291845)
			(xy 131.88351 -386.261423) (xy 131.84418 -386.224081) (xy 131.811472 -386.18082) (xy 131.786264 -386.132801)
			(xy 131.769232 -386.081311) (xy 131.764532 -386.0546) (xy 131.763008 -386.045202) (xy 131.489958 -385.572762)
			(xy 131.482846 -385.56692) (xy 131.464114 -385.55114) (xy 131.431062 -385.514995) (xy 131.403705 -385.474369)
			(xy 131.382643 -385.430151) (xy 131.368335 -385.383309) (xy 131.361097 -385.334869) (xy 131.360672 -385.31038)
			(xy 131.361183 -385.284393) (xy 131.369316 -385.23306) (xy 131.385378 -385.183631) (xy 131.408975 -385.137323)
			(xy 131.439525 -385.095276) (xy 131.476276 -385.058525) (xy 131.518323 -385.027975) (xy 131.564631 -385.004378)
			(xy 131.61406 -384.988316) (xy 131.665393 -384.980183) (xy 131.69138 -384.979672) (xy 131.717429 -384.98015)
			(xy 131.768885 -384.9883) (xy 131.818428 -385.004415) (xy 131.864831 -385.028099) (xy 131.906947 -385.058765)
			(xy 131.943734 -385.095655) (xy 131.974282 -385.137856) (xy 131.997837 -385.184325) (xy 132.013815 -385.233912)
			(xy 132.018278 -385.25958) (xy 132.019548 -385.268978) (xy 132.043484 -385.31038) (xy 132.560568 -385.31038)
			(xy 132.561083 -385.284393) (xy 132.569216 -385.233061) (xy 132.585278 -385.183632) (xy 132.608874 -385.137324)
			(xy 132.639424 -385.095277) (xy 132.676174 -385.058526) (xy 132.71822 -385.027976) (xy 132.764528 -385.00438)
			(xy 132.813957 -384.988317) (xy 132.865289 -384.980183) (xy 132.891276 -384.979672) (xy 132.917285 -384.980163)
			(xy 132.968661 -384.988319) (xy 133.018127 -385.004416) (xy 133.064463 -385.028059) (xy 133.106526 -385.058663)
			(xy 133.14328 -385.095476) (xy 133.173818 -385.137588) (xy 133.179793 -385.149344) (xy 134.529322 -385.149344)
			(xy 134.529744 -385.124448) (xy 134.537196 -385.075216) (xy 134.551938 -385.027655) (xy 134.573637 -384.98284)
			(xy 134.601804 -384.94178) (xy 134.618476 -384.923284) (xy 134.62508 -384.916426) (xy 134.631938 -384.899408)
			(xy 134.634224 -384.813048) (xy 134.628128 -384.795522) (xy 134.622032 -384.78841) (xy 134.607268 -384.77042)
			(xy 134.582439 -384.731058) (xy 134.563377 -384.688602) (xy 134.550459 -384.643892) (xy 134.543939 -384.597812)
			(xy 134.543546 -384.574542) (xy 134.544141 -384.548558) (xy 134.552263 -384.49723) (xy 134.568316 -384.447804)
			(xy 134.591902 -384.401498) (xy 134.622443 -384.359451) (xy 134.659184 -384.3227) (xy 134.701222 -384.292149)
			(xy 134.747522 -384.26855) (xy 134.796944 -384.252484) (xy 134.84827 -384.244348) (xy 134.874254 -384.243834)
			(xy 134.897754 -384.24424) (xy 134.944285 -384.250869) (xy 134.966964 -384.257042) (xy 134.980426 -384.261106)
			(xy 135.006842 -384.254502) (xy 135.0899 -384.173222) (xy 135.097266 -384.14706) (xy 135.09371 -384.133598)
			(xy 135.087775 -384.109652) (xy 135.0814 -384.06073) (xy 135.08101 -384.036062) (xy 135.081496 -384.008811)
			(xy 135.089252 -383.954863) (xy 135.104607 -383.902568) (xy 135.127249 -383.852991) (xy 135.156715 -383.807141)
			(xy 135.192406 -383.76595) (xy 135.233597 -383.730259) (xy 135.279447 -383.700793) (xy 135.329024 -383.678151)
			(xy 135.381319 -383.662796) (xy 135.435267 -383.65504) (xy 135.489769 -383.65504) (xy 135.543717 -383.662796)
			(xy 135.596012 -383.678151) (xy 135.645589 -383.700793) (xy 135.691439 -383.730259) (xy 135.73263 -383.76595)
			(xy 135.768321 -383.807141) (xy 135.797787 -383.852991) (xy 135.820429 -383.902568) (xy 135.835784 -383.954863)
			(xy 135.84354 -384.008811) (xy 135.844026 -384.036062) (xy 135.843556 -384.063432) (xy 135.837722 -384.10388)
			(xy 136.18032 -384.10388) (xy 136.184391 -384.048258) (xy 136.196517 -383.993821) (xy 136.21644 -383.94173)
			(xy 136.243736 -383.893095) (xy 136.277822 -383.848952) (xy 136.317971 -383.810243) (xy 136.363329 -383.777792)
			(xy 136.412929 -383.752291) (xy 136.465713 -383.734284) (xy 136.520556 -383.724154) (xy 136.57629 -383.722117)
			(xy 136.631727 -383.728217) (xy 136.685684 -383.742323) (xy 136.737013 -383.764135) (xy 136.784619 -383.793189)
			(xy 136.827487 -383.828864) (xy 136.864704 -383.870401) (xy 136.895477 -383.916914) (xy 136.919149 -383.967411)
			(xy 136.935217 -384.020818) (xy 136.943337 -384.075994) (xy 136.943846 -384.10388) (xy 136.943337 -384.131766)
			(xy 136.935217 -384.186942) (xy 136.919149 -384.240349) (xy 136.895477 -384.290846) (xy 136.864704 -384.337359)
			(xy 136.827487 -384.378896) (xy 136.784619 -384.414571) (xy 136.737013 -384.443625) (xy 136.685684 -384.465437)
			(xy 136.631727 -384.479543) (xy 136.57629 -384.485643) (xy 136.520556 -384.483606) (xy 136.465713 -384.473476)
			(xy 136.412929 -384.455469) (xy 136.363329 -384.429968) (xy 136.317971 -384.397517) (xy 136.277822 -384.358808)
			(xy 136.243736 -384.314665) (xy 136.21644 -384.26603) (xy 136.196517 -384.213939) (xy 136.184391 -384.159502)
			(xy 136.18032 -384.10388) (xy 135.837722 -384.10388) (xy 135.835742 -384.117612) (xy 135.820255 -384.170116)
			(xy 135.797413 -384.219863) (xy 135.767688 -384.265829) (xy 135.750046 -384.28676) (xy 135.74395 -384.293872)
			(xy 135.7376 -384.31089) (xy 135.7376 -384.396234) (xy 135.74395 -384.413252) (xy 135.750046 -384.420364)
			(xy 135.767651 -384.441326) (xy 135.797379 -384.487288) (xy 135.820228 -384.53703) (xy 135.835729 -384.589527)
			(xy 135.843561 -384.643702) (xy 135.843565 -384.698441) (xy 135.835741 -384.752617) (xy 135.820248 -384.805117)
			(xy 135.797407 -384.854861) (xy 135.767685 -384.900828) (xy 135.750046 -384.92176) (xy 135.74395 -384.928872)
			(xy 135.7376 -384.94589) (xy 135.7376 -385.031234) (xy 135.74395 -385.048252) (xy 135.750046 -385.055364)
			(xy 135.767673 -385.076306) (xy 135.779421 -385.09448) (xy 136.18032 -385.09448) (xy 136.184391 -385.038858)
			(xy 136.196517 -384.984421) (xy 136.21644 -384.93233) (xy 136.243736 -384.883695) (xy 136.277822 -384.839552)
			(xy 136.317971 -384.800843) (xy 136.363329 -384.768392) (xy 136.412929 -384.742891) (xy 136.465713 -384.724884)
			(xy 136.520556 -384.714754) (xy 136.57629 -384.712717) (xy 136.631727 -384.718817) (xy 136.685684 -384.732923)
			(xy 136.737013 -384.754735) (xy 136.784619 -384.783789) (xy 136.827487 -384.819464) (xy 136.864704 -384.861001)
			(xy 136.895477 -384.907514) (xy 136.919149 -384.958011) (xy 136.935217 -385.011418) (xy 136.943337 -385.066594)
			(xy 136.943846 -385.09448) (xy 136.943337 -385.122366) (xy 136.935217 -385.177542) (xy 136.919149 -385.230949)
			(xy 136.895477 -385.281446) (xy 136.864704 -385.327959) (xy 136.827487 -385.369496) (xy 136.784619 -385.405171)
			(xy 136.737013 -385.434225) (xy 136.685684 -385.456037) (xy 136.631727 -385.470143) (xy 136.57629 -385.476243)
			(xy 136.520556 -385.474206) (xy 136.465713 -385.464076) (xy 136.412929 -385.446069) (xy 136.363329 -385.420568)
			(xy 136.317971 -385.388117) (xy 136.277822 -385.349408) (xy 136.243736 -385.305265) (xy 136.21644 -385.25663)
			(xy 136.196517 -385.204539) (xy 136.184391 -385.150102) (xy 136.18032 -385.09448) (xy 135.779421 -385.09448)
			(xy 135.797389 -385.122275) (xy 135.820228 -385.17202) (xy 135.835721 -385.224519) (xy 135.843551 -385.278693)
			(xy 135.844026 -385.306062) (xy 135.843592 -385.332973) (xy 135.836046 -385.386263) (xy 135.821083 -385.437962)
			(xy 135.799002 -385.487046) (xy 135.770241 -385.532538) (xy 135.73537 -385.573535) (xy 135.695083 -385.609224)
			(xy 135.650179 -385.638895) (xy 135.60155 -385.661959) (xy 135.550161 -385.677959) (xy 135.497034 -385.686576)
			(xy 135.470138 -385.68757) (xy 135.458708 -385.687824) (xy 135.438642 -385.69773) (xy 135.37565 -385.776978)
			(xy 135.37057 -385.799076) (xy 135.372856 -385.810252) (xy 135.376778 -385.829829) (xy 135.380975 -385.869536)
			(xy 135.381238 -385.8895) (xy 135.380983 -385.909591) (xy 135.376787 -385.949552) (xy 135.372856 -385.969256)
			(xy 135.369808 -385.982718) (xy 135.378698 -386.00888) (xy 135.466582 -386.085588) (xy 135.49376 -386.090668)
			(xy 135.506714 -386.086096) (xy 135.538103 -386.075455) (xy 135.603372 -386.063965) (xy 135.636508 -386.063236)
			(xy 135.663758 -386.063686) (xy 135.717703 -386.071443) (xy 135.769995 -386.086798) (xy 135.819569 -386.109439)
			(xy 135.865417 -386.138904) (xy 135.906605 -386.174594) (xy 135.942295 -386.215782) (xy 135.971761 -386.26163)
			(xy 135.994401 -386.311204) (xy 136.009756 -386.363496) (xy 136.017514 -386.417441) (xy 136.017515 -386.471941)
			(xy 136.00976 -386.525886) (xy 135.994408 -386.578178) (xy 135.97177 -386.627754) (xy 135.942307 -386.673603)
			(xy 135.906619 -386.714793) (xy 135.865432 -386.750485) (xy 135.819586 -386.779952) (xy 135.770012 -386.802595)
			(xy 135.717721 -386.817953) (xy 135.663777 -386.825712) (xy 135.609277 -386.825716) (xy 135.555331 -386.817964)
			(xy 135.503038 -386.802614) (xy 135.453461 -386.779978) (xy 135.40761 -386.750517) (xy 135.366419 -386.714831)
			(xy 135.330725 -386.673646) (xy 135.301256 -386.627801) (xy 135.278611 -386.578229) (xy 135.263251 -386.525938)
			(xy 135.255489 -386.471994) (xy 135.255 -386.444744) (xy 135.255246 -386.424653) (xy 135.259448 -386.384692)
			(xy 135.263382 -386.364988) (xy 135.26643 -386.351526) (xy 135.25754 -386.325364) (xy 135.169656 -386.248656)
			(xy 135.142478 -386.243576) (xy 135.129524 -386.248148) (xy 135.098132 -386.258781) (xy 135.032865 -386.270276)
			(xy 134.99973 -386.271008) (xy 134.972478 -386.270517) (xy 134.918528 -386.262764) (xy 134.866231 -386.247412)
			(xy 134.816651 -386.224773) (xy 134.770797 -386.195308) (xy 134.729604 -386.159617) (xy 134.69391 -386.118427)
			(xy 134.664442 -386.072576) (xy 134.641799 -386.022998) (xy 134.626442 -385.970701) (xy 134.618685 -385.916752)
			(xy 134.618222 -385.8895) (xy 134.618633 -385.863517) (xy 134.625698 -385.812033) (xy 134.639685 -385.761984)
			(xy 134.660334 -385.714297) (xy 134.687263 -385.669852) (xy 134.719974 -385.629473) (xy 134.738618 -385.61137)
			(xy 134.748016 -385.602734) (xy 134.75589 -385.579366) (xy 134.739888 -385.47167) (xy 134.72541 -385.451604)
			(xy 134.71398 -385.446016) (xy 134.690588 -385.433954) (xy 134.647642 -385.403533) (xy 134.610058 -385.366693)
			(xy 134.578785 -385.324363) (xy 134.554615 -385.277613) (xy 134.538157 -385.227624) (xy 134.529827 -385.175658)
			(xy 134.529322 -385.149344) (xy 133.179793 -385.149344) (xy 133.197386 -385.183961) (xy 133.213405 -385.233453)
			(xy 133.21792 -385.259072) (xy 133.219444 -385.26847) (xy 133.49224 -385.740402) (xy 133.499606 -385.746244)
			(xy 133.518389 -385.76204) (xy 133.551506 -385.798258) (xy 133.578915 -385.838968) (xy 133.600015 -385.883277)
			(xy 133.614344 -385.930215) (xy 133.621589 -385.978754) (xy 133.622034 -386.003292) (xy 133.62178 -386.014976)
			(xy 133.621526 -386.024882) (xy 133.627876 -386.042916) (xy 133.687058 -386.109972) (xy 133.70433 -386.118862)
			(xy 133.713982 -386.119624) (xy 133.738322 -386.122238) (xy 133.785872 -386.133879) (xy 133.831189 -386.152397)
			(xy 133.873284 -386.177389) (xy 133.911238 -386.20831) (xy 133.944223 -386.244483) (xy 133.97152 -386.285121)
			(xy 133.992533 -386.329337) (xy 134.006803 -386.376165) (xy 134.01402 -386.424585) (xy 134.014464 -386.449062)
			(xy 134.013954 -386.475049) (xy 134.005824 -386.526384) (xy 133.989763 -386.575814) (xy 133.966167 -386.622124)
			(xy 133.935617 -386.664172) (xy 133.898866 -386.700923) (xy 133.856818 -386.731473) (xy 133.810508 -386.755069)
			(xy 133.761078 -386.77113) (xy 133.709743 -386.77926) (xy 133.657769 -386.77926) (xy 133.606434 -386.77113)
			(xy 133.557004 -386.755069) (xy 133.510694 -386.731473) (xy 133.468646 -386.700923) (xy 133.431895 -386.664172)
			(xy 133.401345 -386.622124) (xy 133.377749 -386.575814) (xy 133.361688 -386.526384) (xy 133.353558 -386.475049)
			(xy 133.353048 -386.449062) (xy 133.353302 -386.437378) (xy 133.353556 -386.427472) (xy 133.347206 -386.409438)
			(xy 133.288024 -386.342382) (xy 133.270752 -386.333492) (xy 133.2611 -386.33273) (xy 133.236917 -386.330055)
			(xy 133.189653 -386.318515) (xy 133.144586 -386.300182) (xy 133.102688 -386.275451) (xy 133.064861 -386.244853)
			(xy 133.03192 -386.209049) (xy 133.004574 -386.168808) (xy 132.983412 -386.124998) (xy 132.968891 -386.078563)
			(xy 132.964682 -386.0546) (xy 132.963158 -386.045202) (xy 132.690362 -385.57327) (xy 132.682996 -385.567428)
			(xy 132.664248 -385.551592) (xy 132.631129 -385.515382) (xy 132.603715 -385.474681) (xy 132.582609 -385.43038)
			(xy 132.568272 -385.383449) (xy 132.561018 -385.334916) (xy 132.560568 -385.31038) (xy 132.043484 -385.31038)
			(xy 132.29209 -385.740402) (xy 132.299456 -385.746244) (xy 132.318236 -385.762047) (xy 132.351373 -385.798252)
			(xy 132.378798 -385.838956) (xy 132.399907 -385.883266) (xy 132.414238 -385.930208) (xy 132.421476 -385.978752)
			(xy 132.421884 -386.003292) (xy 132.42163 -386.015484) (xy 132.421376 -386.025136) (xy 132.427472 -386.04317)
			(xy 132.486146 -386.11048) (xy 132.50291 -386.119116) (xy 132.512816 -386.120132) (xy 132.539583 -386.123459)
			(xy 132.591609 -386.137685) (xy 132.640638 -386.160164) (xy 132.68537 -386.190299) (xy 132.724619 -386.227293)
			(xy 132.757346 -386.270165) (xy 132.782684 -386.31778) (xy 132.79996 -386.368874) (xy 132.808718 -386.422094)
			(xy 132.809234 -386.449062) (xy 132.808671 -386.476344) (xy 132.799708 -386.530167) (xy 132.782034 -386.58179)
			(xy 132.756129 -386.629813) (xy 132.722695 -386.672934) (xy 132.703062 -386.691886) (xy 132.695622 -386.699382)
			(xy 132.687095 -386.718676) (xy 132.686552 -386.729224) (xy 132.686552 -386.8039) (xy 132.687144 -386.814432)
			(xy 132.695684 -386.833696) (xy 132.703062 -386.841238) (xy 132.722715 -386.860171) (xy 132.756155 -386.903293)
			(xy 132.782059 -386.95132) (xy 132.799727 -387.002949) (xy 132.808676 -387.056778) (xy 132.809234 -387.084062)
			(xy 132.808801 -387.10818) (xy 132.801806 -387.155905) (xy 132.787958 -387.20211) (xy 132.767552 -387.245816)
			(xy 132.754624 -387.26618) (xy 132.748782 -387.27507) (xy 132.745226 -387.295136) (xy 132.766308 -387.387338)
			(xy 132.7785 -387.404102) (xy 132.78739 -387.409436) (xy 132.808194 -387.42229) (xy 132.846115 -387.453165)
			(xy 132.879069 -387.489295) (xy 132.906335 -387.529889) (xy 132.927317 -387.57406) (xy 132.941558 -387.620841)
			(xy 132.948744 -387.669211) (xy 132.949188 -387.693662) (xy 132.948719 -387.718855) (xy 132.941085 -387.76866)
			(xy 132.925989 -387.816732) (xy 132.903779 -387.86196) (xy 132.889752 -387.882892) (xy 132.881624 -387.894576)
			(xy 132.879592 -387.92277) (xy 132.927852 -388.015226) (xy 132.932479 -388.023306) (xy 132.946359 -388.035695)
			(xy 132.96376 -388.042278) (xy 132.973064 -388.042658) (xy 134.687818 -388.042658) (xy 134.696485 -388.042354)
			(xy 134.712846 -388.036636) (xy 134.719822 -388.031482) (xy 134.739489 -388.016252) (xy 134.782491 -387.991254)
			(xy 134.828754 -387.972984) (xy 134.877233 -387.961854) (xy 134.926832 -387.958116) (xy 134.976431 -387.961854)
			(xy 135.02491 -387.972984) (xy 135.071173 -387.991254) (xy 135.114175 -388.016252) (xy 135.133842 -388.031482)
			(xy 135.1407 -388.036816) (xy 135.156956 -388.042658) (xy 135.226298 -388.042658) (xy 135.236367 -388.042234)
			(xy 135.254968 -388.034515) (xy 135.262366 -388.027672) (xy 136.695434 -386.594604) (xy 136.702418 -386.587008)
			(xy 136.710145 -386.567896) (xy 136.709688 -386.547286) (xy 136.705848 -386.537708) (xy 136.660128 -386.436616)
			(xy 136.633204 -386.42036) (xy 136.617202 -386.421376) (xy 136.59358 -386.422138) (xy 136.566328 -386.421651)
			(xy 136.512378 -386.413891) (xy 136.460081 -386.398533) (xy 136.410503 -386.375889) (xy 136.364651 -386.34642)
			(xy 136.32346 -386.310726) (xy 136.287768 -386.269533) (xy 136.258301 -386.22368) (xy 136.23566 -386.1741)
			(xy 136.220304 -386.121803) (xy 136.212548 -386.067852) (xy 136.212548 -386.013348) (xy 136.220304 -385.959397)
			(xy 136.23566 -385.9071) (xy 136.258301 -385.85752) (xy 136.287768 -385.811667) (xy 136.32346 -385.770474)
			(xy 136.364651 -385.73478) (xy 136.410503 -385.705311) (xy 136.460081 -385.682667) (xy 136.512378 -385.667309)
			(xy 136.566328 -385.659549) (xy 136.59358 -385.659122) (xy 136.621381 -385.659623) (xy 136.676393 -385.667689)
			(xy 136.729653 -385.683655) (xy 136.780031 -385.707181) (xy 136.826462 -385.73777) (xy 136.867962 -385.774773)
			(xy 136.903652 -385.817408) (xy 136.932776 -385.864771) (xy 136.954718 -385.915859) (xy 136.962388 -385.942586)
			(xy 136.965436 -385.954016) (xy 136.98093 -385.971796) (xy 137.07745 -386.011928) (xy 137.101072 -386.010404)
			(xy 137.111232 -386.004562) (xy 137.136939 -385.990187) (xy 137.190997 -385.966798) (xy 137.247397 -385.94982)
			(xy 137.305383 -385.939478) (xy 137.334752 -385.937252) (xy 137.34415 -385.93649) (xy 137.360914 -385.929124)
			(xy 137.603738 -385.6863) (xy 137.610591 -385.678905) (xy 137.618336 -385.660306) (xy 137.618724 -385.650232)
			(xy 137.618724 -383.097532) (xy 137.618289 -383.087467) (xy 137.61056 -383.068878) (xy 137.603738 -383.061464)
			(xy 137.39495 -382.852676) (xy 137.387553 -382.845829) (xy 137.368953 -382.838101) (xy 137.358882 -382.83769)
			(xy 134.877302 -382.83769) (xy 134.848092 -382.865376) (xy 134.847076 -382.885696) (xy 134.845275 -382.910741)
			(xy 134.835055 -382.959901) (xy 134.817523 -383.006951) (xy 134.79308 -383.050811) (xy 134.762288 -383.090472)
			(xy 134.725856 -383.125023) (xy 134.684619 -383.153671) (xy 134.639526 -383.175756) (xy 134.591613 -383.190771)
			(xy 134.541981 -383.198372) (xy 134.516876 -383.198878) (xy 134.493103 -383.198464) (xy 134.446047 -383.191651)
			(xy 134.400452 -383.178169) (xy 134.357258 -383.158295) (xy 134.317356 -383.13244) (xy 134.299198 -383.11709)
			(xy 134.292077 -383.111406) (xy 134.275027 -383.105018) (xy 134.265924 -383.104644) (xy 134.234428 -383.104644)
			(xy 134.225323 -383.105018) (xy 134.208267 -383.111394) (xy 134.201154 -383.11709) (xy 134.182994 -383.132439)
			(xy 134.143098 -383.158305) (xy 134.099905 -383.178183) (xy 134.054308 -383.191662) (xy 134.00725 -383.198463)
			(xy 133.983476 -383.198878) (xy 133.956606 -383.198351) (xy 133.903575 -383.189654) (xy 133.852649 -383.172495)
			(xy 133.805168 -383.147324) (xy 133.762385 -383.114805) (xy 133.725424 -383.075794) (xy 133.709918 -383.053844)
			(xy 133.703314 -383.044446) (xy 133.68401 -383.033016) (xy 133.594602 -383.02438) (xy 133.583386 -383.023961)
			(xy 133.562313 -383.031612) (xy 133.553962 -383.039112) (xy 132.964936 -383.628138) (xy 132.957537 -383.634981)
			(xy 132.938938 -383.642702) (xy 132.928868 -383.643124) (xy 122.889518 -383.643124) (xy 122.879455 -383.643563)
			(xy 122.860874 -383.651301) (xy 122.85345 -383.65811) (xy 122.066812 -384.444748) (xy 122.06097 -384.474974)
			(xy 122.067066 -384.489198) (xy 122.075265 -384.509622) (xy 122.086806 -384.552092) (xy 122.092619 -384.595717)
			(xy 122.092974 -384.617722) (xy 122.092489 -384.643709) (xy 122.632218 -384.643709) (xy 122.632218 -384.591735)
			(xy 122.640348 -384.5404) (xy 122.656409 -384.49097) (xy 122.680005 -384.44466) (xy 122.710555 -384.402612)
			(xy 122.747306 -384.365861) (xy 122.789354 -384.335311) (xy 122.835664 -384.311715) (xy 122.885094 -384.295654)
			(xy 122.936429 -384.287524) (xy 122.988403 -384.287524) (xy 123.039738 -384.295654) (xy 123.089168 -384.311715)
			(xy 123.135478 -384.335311) (xy 123.177526 -384.365861) (xy 123.214277 -384.402612) (xy 123.244827 -384.44466)
			(xy 123.268423 -384.49097) (xy 123.284484 -384.5404) (xy 123.292614 -384.591735) (xy 123.293124 -384.617722)
			(xy 123.292614 -384.643709) (xy 123.832114 -384.643709) (xy 123.832114 -384.591735) (xy 123.840244 -384.5404)
			(xy 123.856305 -384.49097) (xy 123.879901 -384.44466) (xy 123.910451 -384.402612) (xy 123.947202 -384.365861)
			(xy 123.98925 -384.335311) (xy 124.03556 -384.311715) (xy 124.08499 -384.295654) (xy 124.136325 -384.287524)
			(xy 124.188299 -384.287524) (xy 124.239634 -384.295654) (xy 124.289064 -384.311715) (xy 124.335374 -384.335311)
			(xy 124.377422 -384.365861) (xy 124.414173 -384.402612) (xy 124.444723 -384.44466) (xy 124.468319 -384.49097)
			(xy 124.48438 -384.5404) (xy 124.49251 -384.591735) (xy 124.49302 -384.617722) (xy 124.49251 -384.643709)
			(xy 125.032264 -384.643709) (xy 125.032264 -384.591735) (xy 125.040394 -384.5404) (xy 125.056455 -384.49097)
			(xy 125.080051 -384.44466) (xy 125.110601 -384.402612) (xy 125.147352 -384.365861) (xy 125.1894 -384.335311)
			(xy 125.23571 -384.311715) (xy 125.28514 -384.295654) (xy 125.336475 -384.287524) (xy 125.388449 -384.287524)
			(xy 125.439784 -384.295654) (xy 125.489214 -384.311715) (xy 125.535524 -384.335311) (xy 125.577572 -384.365861)
			(xy 125.614323 -384.402612) (xy 125.644873 -384.44466) (xy 125.668469 -384.49097) (xy 125.68453 -384.5404)
			(xy 125.69266 -384.591735) (xy 125.69317 -384.617722) (xy 125.69266 -384.643709) (xy 126.23216 -384.643709)
			(xy 126.23216 -384.591735) (xy 126.24029 -384.5404) (xy 126.256351 -384.49097) (xy 126.279947 -384.44466)
			(xy 126.310497 -384.402612) (xy 126.347248 -384.365861) (xy 126.389296 -384.335311) (xy 126.435606 -384.311715)
			(xy 126.485036 -384.295654) (xy 126.536371 -384.287524) (xy 126.588345 -384.287524) (xy 126.63968 -384.295654)
			(xy 126.68911 -384.311715) (xy 126.73542 -384.335311) (xy 126.777468 -384.365861) (xy 126.814219 -384.402612)
			(xy 126.844769 -384.44466) (xy 126.868365 -384.49097) (xy 126.884426 -384.5404) (xy 126.892556 -384.591735)
			(xy 126.893066 -384.617722) (xy 126.892556 -384.643709) (xy 127.432056 -384.643709) (xy 127.432056 -384.591735)
			(xy 127.440186 -384.5404) (xy 127.456247 -384.49097) (xy 127.479843 -384.44466) (xy 127.510393 -384.402612)
			(xy 127.547144 -384.365861) (xy 127.589192 -384.335311) (xy 127.635502 -384.311715) (xy 127.684932 -384.295654)
			(xy 127.736267 -384.287524) (xy 127.788241 -384.287524) (xy 127.839576 -384.295654) (xy 127.889006 -384.311715)
			(xy 127.935316 -384.335311) (xy 127.977364 -384.365861) (xy 128.014115 -384.402612) (xy 128.044665 -384.44466)
			(xy 128.068261 -384.49097) (xy 128.084322 -384.5404) (xy 128.092452 -384.591735) (xy 128.092962 -384.617722)
			(xy 128.092452 -384.643709) (xy 128.632206 -384.643709) (xy 128.632206 -384.591735) (xy 128.640336 -384.5404)
			(xy 128.656397 -384.49097) (xy 128.679993 -384.44466) (xy 128.710543 -384.402612) (xy 128.747294 -384.365861)
			(xy 128.789342 -384.335311) (xy 128.835652 -384.311715) (xy 128.885082 -384.295654) (xy 128.936417 -384.287524)
			(xy 128.988391 -384.287524) (xy 129.039726 -384.295654) (xy 129.089156 -384.311715) (xy 129.135466 -384.335311)
			(xy 129.177514 -384.365861) (xy 129.214265 -384.402612) (xy 129.244815 -384.44466) (xy 129.268411 -384.49097)
			(xy 129.284472 -384.5404) (xy 129.292602 -384.591735) (xy 129.293112 -384.617722) (xy 129.292602 -384.643709)
			(xy 129.832102 -384.643709) (xy 129.832102 -384.591735) (xy 129.840232 -384.5404) (xy 129.856293 -384.49097)
			(xy 129.879889 -384.44466) (xy 129.910439 -384.402612) (xy 129.94719 -384.365861) (xy 129.989238 -384.335311)
			(xy 130.035548 -384.311715) (xy 130.084978 -384.295654) (xy 130.136313 -384.287524) (xy 130.188287 -384.287524)
			(xy 130.239622 -384.295654) (xy 130.289052 -384.311715) (xy 130.335362 -384.335311) (xy 130.37741 -384.365861)
			(xy 130.414161 -384.402612) (xy 130.444711 -384.44466) (xy 130.468307 -384.49097) (xy 130.484368 -384.5404)
			(xy 130.492498 -384.591735) (xy 130.493008 -384.617722) (xy 130.492498 -384.643709) (xy 131.032252 -384.643709)
			(xy 131.032252 -384.591735) (xy 131.040382 -384.5404) (xy 131.056443 -384.49097) (xy 131.080039 -384.44466)
			(xy 131.110589 -384.402612) (xy 131.14734 -384.365861) (xy 131.189388 -384.335311) (xy 131.235698 -384.311715)
			(xy 131.285128 -384.295654) (xy 131.336463 -384.287524) (xy 131.388437 -384.287524) (xy 131.439772 -384.295654)
			(xy 131.489202 -384.311715) (xy 131.535512 -384.335311) (xy 131.57756 -384.365861) (xy 131.614311 -384.402612)
			(xy 131.644861 -384.44466) (xy 131.668457 -384.49097) (xy 131.684518 -384.5404) (xy 131.692648 -384.591735)
			(xy 131.693158 -384.617722) (xy 131.692648 -384.643709) (xy 132.232148 -384.643709) (xy 132.232148 -384.591735)
			(xy 132.240278 -384.5404) (xy 132.256339 -384.49097) (xy 132.279935 -384.44466) (xy 132.310485 -384.402612)
			(xy 132.347236 -384.365861) (xy 132.389284 -384.335311) (xy 132.435594 -384.311715) (xy 132.485024 -384.295654)
			(xy 132.536359 -384.287524) (xy 132.588333 -384.287524) (xy 132.639668 -384.295654) (xy 132.689098 -384.311715)
			(xy 132.735408 -384.335311) (xy 132.777456 -384.365861) (xy 132.814207 -384.402612) (xy 132.844757 -384.44466)
			(xy 132.868353 -384.49097) (xy 132.884414 -384.5404) (xy 132.892544 -384.591735) (xy 132.893054 -384.617722)
			(xy 132.892544 -384.643709) (xy 132.884414 -384.695044) (xy 132.868353 -384.744474) (xy 132.844757 -384.790784)
			(xy 132.814207 -384.832832) (xy 132.777456 -384.869583) (xy 132.735408 -384.900133) (xy 132.689098 -384.923729)
			(xy 132.639668 -384.93979) (xy 132.588333 -384.94792) (xy 132.536359 -384.94792) (xy 132.485024 -384.93979)
			(xy 132.435594 -384.923729) (xy 132.389284 -384.900133) (xy 132.347236 -384.869583) (xy 132.310485 -384.832832)
			(xy 132.279935 -384.790784) (xy 132.256339 -384.744474) (xy 132.240278 -384.695044) (xy 132.232148 -384.643709)
			(xy 131.692648 -384.643709) (xy 131.684518 -384.695044) (xy 131.668457 -384.744474) (xy 131.644861 -384.790784)
			(xy 131.614311 -384.832832) (xy 131.57756 -384.869583) (xy 131.535512 -384.900133) (xy 131.489202 -384.923729)
			(xy 131.439772 -384.93979) (xy 131.388437 -384.94792) (xy 131.336463 -384.94792) (xy 131.285128 -384.93979)
			(xy 131.235698 -384.923729) (xy 131.189388 -384.900133) (xy 131.14734 -384.869583) (xy 131.110589 -384.832832)
			(xy 131.080039 -384.790784) (xy 131.056443 -384.744474) (xy 131.040382 -384.695044) (xy 131.032252 -384.643709)
			(xy 130.492498 -384.643709) (xy 130.484368 -384.695044) (xy 130.468307 -384.744474) (xy 130.444711 -384.790784)
			(xy 130.414161 -384.832832) (xy 130.37741 -384.869583) (xy 130.335362 -384.900133) (xy 130.289052 -384.923729)
			(xy 130.239622 -384.93979) (xy 130.188287 -384.94792) (xy 130.136313 -384.94792) (xy 130.084978 -384.93979)
			(xy 130.035548 -384.923729) (xy 129.989238 -384.900133) (xy 129.94719 -384.869583) (xy 129.910439 -384.832832)
			(xy 129.879889 -384.790784) (xy 129.856293 -384.744474) (xy 129.840232 -384.695044) (xy 129.832102 -384.643709)
			(xy 129.292602 -384.643709) (xy 129.284472 -384.695044) (xy 129.268411 -384.744474) (xy 129.244815 -384.790784)
			(xy 129.214265 -384.832832) (xy 129.177514 -384.869583) (xy 129.135466 -384.900133) (xy 129.089156 -384.923729)
			(xy 129.039726 -384.93979) (xy 128.988391 -384.94792) (xy 128.936417 -384.94792) (xy 128.885082 -384.93979)
			(xy 128.835652 -384.923729) (xy 128.789342 -384.900133) (xy 128.747294 -384.869583) (xy 128.710543 -384.832832)
			(xy 128.679993 -384.790784) (xy 128.656397 -384.744474) (xy 128.640336 -384.695044) (xy 128.632206 -384.643709)
			(xy 128.092452 -384.643709) (xy 128.084322 -384.695044) (xy 128.068261 -384.744474) (xy 128.044665 -384.790784)
			(xy 128.014115 -384.832832) (xy 127.977364 -384.869583) (xy 127.935316 -384.900133) (xy 127.889006 -384.923729)
			(xy 127.839576 -384.93979) (xy 127.788241 -384.94792) (xy 127.736267 -384.94792) (xy 127.684932 -384.93979)
			(xy 127.635502 -384.923729) (xy 127.589192 -384.900133) (xy 127.547144 -384.869583) (xy 127.510393 -384.832832)
			(xy 127.479843 -384.790784) (xy 127.456247 -384.744474) (xy 127.440186 -384.695044) (xy 127.432056 -384.643709)
			(xy 126.892556 -384.643709) (xy 126.884426 -384.695044) (xy 126.868365 -384.744474) (xy 126.844769 -384.790784)
			(xy 126.814219 -384.832832) (xy 126.777468 -384.869583) (xy 126.73542 -384.900133) (xy 126.68911 -384.923729)
			(xy 126.63968 -384.93979) (xy 126.588345 -384.94792) (xy 126.536371 -384.94792) (xy 126.485036 -384.93979)
			(xy 126.435606 -384.923729) (xy 126.389296 -384.900133) (xy 126.347248 -384.869583) (xy 126.310497 -384.832832)
			(xy 126.279947 -384.790784) (xy 126.256351 -384.744474) (xy 126.24029 -384.695044) (xy 126.23216 -384.643709)
			(xy 125.69266 -384.643709) (xy 125.68453 -384.695044) (xy 125.668469 -384.744474) (xy 125.644873 -384.790784)
			(xy 125.614323 -384.832832) (xy 125.577572 -384.869583) (xy 125.535524 -384.900133) (xy 125.489214 -384.923729)
			(xy 125.439784 -384.93979) (xy 125.388449 -384.94792) (xy 125.336475 -384.94792) (xy 125.28514 -384.93979)
			(xy 125.23571 -384.923729) (xy 125.1894 -384.900133) (xy 125.147352 -384.869583) (xy 125.110601 -384.832832)
			(xy 125.080051 -384.790784) (xy 125.056455 -384.744474) (xy 125.040394 -384.695044) (xy 125.032264 -384.643709)
			(xy 124.49251 -384.643709) (xy 124.48438 -384.695044) (xy 124.468319 -384.744474) (xy 124.444723 -384.790784)
			(xy 124.414173 -384.832832) (xy 124.377422 -384.869583) (xy 124.335374 -384.900133) (xy 124.289064 -384.923729)
			(xy 124.239634 -384.93979) (xy 124.188299 -384.94792) (xy 124.136325 -384.94792) (xy 124.08499 -384.93979)
			(xy 124.03556 -384.923729) (xy 123.98925 -384.900133) (xy 123.947202 -384.869583) (xy 123.910451 -384.832832)
			(xy 123.879901 -384.790784) (xy 123.856305 -384.744474) (xy 123.840244 -384.695044) (xy 123.832114 -384.643709)
			(xy 123.292614 -384.643709) (xy 123.284484 -384.695044) (xy 123.268423 -384.744474) (xy 123.244827 -384.790784)
			(xy 123.214277 -384.832832) (xy 123.177526 -384.869583) (xy 123.135478 -384.900133) (xy 123.089168 -384.923729)
			(xy 123.039738 -384.93979) (xy 122.988403 -384.94792) (xy 122.936429 -384.94792) (xy 122.885094 -384.93979)
			(xy 122.835664 -384.923729) (xy 122.789354 -384.900133) (xy 122.747306 -384.869583) (xy 122.710555 -384.832832)
			(xy 122.680005 -384.790784) (xy 122.656409 -384.744474) (xy 122.640348 -384.695044) (xy 122.632218 -384.643709)
			(xy 122.092489 -384.643709) (xy 122.084355 -384.695043) (xy 122.06829 -384.744472) (xy 122.044691 -384.79078)
			(xy 122.014138 -384.832826) (xy 121.977383 -384.869574) (xy 121.935332 -384.90012) (xy 121.889021 -384.923712)
			(xy 121.839589 -384.939768) (xy 121.788253 -384.947894) (xy 121.762266 -384.94843) (xy 121.74026 -384.948084)
			(xy 121.696635 -384.942273) (xy 121.654167 -384.930719) (xy 121.633742 -384.922522) (xy 121.619518 -384.916426)
			(xy 121.589292 -384.922268) (xy 121.25579 -385.25577) (xy 121.248246 -385.264043) (xy 121.240538 -385.285035)
			(xy 121.242491 -385.307311) (xy 121.247662 -385.317238) (xy 121.492264 -385.740402) (xy 121.49963 -385.746244)
			(xy 121.518407 -385.762049) (xy 121.551537 -385.798257) (xy 121.578955 -385.838962) (xy 121.600059 -385.883271)
			(xy 121.614386 -385.930211) (xy 121.621623 -385.978753) (xy 121.622058 -386.003292) (xy 121.621804 -386.015484)
			(xy 121.62155 -386.025136) (xy 121.627646 -386.04317) (xy 121.68632 -386.11048) (xy 121.703084 -386.119116)
			(xy 121.712736 -386.120132) (xy 121.739502 -386.123461) (xy 121.791526 -386.137689) (xy 121.840552 -386.160169)
			(xy 121.885281 -386.190305) (xy 121.924528 -386.227299) (xy 121.957252 -386.270171) (xy 121.982588 -386.317784)
			(xy 121.999863 -386.368877) (xy 122.00862 -386.422095) (xy 122.009154 -386.449062) (xy 122.008591 -386.476344)
			(xy 121.999628 -386.530168) (xy 121.981955 -386.581791) (xy 121.956051 -386.629815) (xy 121.922619 -386.672938)
			(xy 121.902982 -386.691886) (xy 121.895539 -386.69938) (xy 121.887009 -386.718675) (xy 121.886472 -386.729224)
			(xy 121.886472 -386.8039) (xy 121.887062 -386.814434) (xy 121.895592 -386.833707) (xy 121.902982 -386.841238)
			(xy 121.922634 -386.860172) (xy 121.956072 -386.903294) (xy 121.981975 -386.951321) (xy 121.999641 -387.00295)
			(xy 122.00859 -387.056778) (xy 122.009154 -387.084062) (xy 122.008721 -387.108179) (xy 122.001724 -387.155904)
			(xy 121.987874 -387.202107) (xy 121.967463 -387.245811) (xy 121.954544 -387.26618) (xy 121.948702 -387.27507)
			(xy 121.945146 -387.295136) (xy 121.966228 -387.387338) (xy 121.97842 -387.404102) (xy 121.98731 -387.409436)
			(xy 122.008113 -387.42229) (xy 122.046032 -387.453167) (xy 122.078983 -387.489298) (xy 122.106248 -387.529892)
			(xy 122.127229 -387.574062) (xy 122.141468 -387.620843) (xy 122.148655 -387.669212) (xy 122.149108 -387.693662)
			(xy 122.14867 -387.718032) (xy 122.141514 -387.766245) (xy 122.127364 -387.812886) (xy 122.106528 -387.856949)
			(xy 122.079456 -387.89748) (xy 122.046732 -387.933602) (xy 122.028204 -387.94944) (xy 122.019314 -387.956552)
			(xy 122.009916 -387.97611) (xy 122.007122 -388.075424) (xy 122.015758 -388.09549) (xy 122.02414 -388.10311)
			(xy 122.041776 -388.119823) (xy 122.07204 -388.157832) (xy 122.095895 -388.200158) (xy 122.112738 -388.245731)
			(xy 122.117866 -388.26948) (xy 122.121422 -388.287514) (xy 122.149362 -388.310628) (xy 122.687588 -388.310628)
		)
		(stroke
			(width 0)
			(type solid)
		)
		(fill yes)
		(layer "In15.Cu")
		(net "P1V8_CPU1_RT3_1A_1D")
	)
	(gr_poly
		(pts
			(xy 232.655618 -43.50004) (xy 232.668257 -43.49936) (xy 232.690502 -43.487353) (xy 232.698036 -43.47718)
			(xy 232.705076 -43.46678) (xy 232.720328 -43.446824) (xy 232.728516 -43.437302) (xy 232.734612 -43.43019)
			(xy 232.740962 -43.413172) (xy 232.740962 -43.327828) (xy 232.734612 -43.31081) (xy 232.728516 -43.303698)
			(xy 232.710876 -43.282765) (xy 232.681152 -43.236797) (xy 232.658307 -43.187051) (xy 232.642811 -43.134549)
			(xy 232.634983 -43.08037) (xy 232.634983 -43.02563) (xy 232.642811 -42.971451) (xy 232.658307 -42.918949)
			(xy 232.681152 -42.869203) (xy 232.710876 -42.823235) (xy 232.728516 -42.802302) (xy 232.734612 -42.79519)
			(xy 232.740962 -42.778172) (xy 232.740962 -42.692828) (xy 232.734612 -42.67581) (xy 232.728516 -42.668698)
			(xy 232.710873 -42.647767) (xy 232.681146 -42.601801) (xy 232.658303 -42.552054) (xy 232.642812 -42.49955)
			(xy 232.634993 -42.445371) (xy 232.634536 -42.418) (xy 232.634999 -42.390748) (xy 232.642757 -42.3368)
			(xy 232.658113 -42.284504) (xy 232.680756 -42.234927) (xy 232.710225 -42.189077) (xy 232.745919 -42.147888)
			(xy 232.787112 -42.112198) (xy 232.832966 -42.082735) (xy 232.882546 -42.060098) (xy 232.934843 -42.044747)
			(xy 232.988792 -42.036996) (xy 233.016044 -42.036492) (xy 233.043413 -42.036967) (xy 233.097588 -42.044796)
			(xy 233.150088 -42.060288) (xy 233.199836 -42.083124) (xy 233.245809 -42.112835) (xy 233.266742 -42.130472)
			(xy 233.273854 -42.136568) (xy 233.290872 -42.142918) (xy 233.376216 -42.142918) (xy 233.393234 -42.136568)
			(xy 233.400346 -42.130472) (xy 233.421279 -42.112834) (xy 233.467247 -42.083115) (xy 233.516994 -42.06028)
			(xy 233.569497 -42.044797) (xy 233.623675 -42.036986) (xy 233.651044 -42.036492) (xy 233.678293 -42.036981)
			(xy 233.732236 -42.044742) (xy 233.784526 -42.060101) (xy 233.834097 -42.082745) (xy 233.879942 -42.112212)
			(xy 233.921127 -42.147904) (xy 233.956814 -42.189093) (xy 233.986276 -42.234941) (xy 234.008914 -42.284516)
			(xy 234.024267 -42.336807) (xy 234.032022 -42.390751) (xy 234.032552 -42.418) (xy 234.03208 -42.44537)
			(xy 234.024255 -42.499547) (xy 234.008767 -42.55205) (xy 233.985932 -42.601799) (xy 233.956221 -42.647774)
			(xy 233.938572 -42.668698) (xy 233.932476 -42.67581) (xy 233.926126 -42.692828) (xy 233.926126 -42.778172)
			(xy 233.932476 -42.79519) (xy 233.938572 -42.802302) (xy 233.956213 -42.823235) (xy 233.985938 -42.869202)
			(xy 234.008783 -42.918949) (xy 234.024279 -42.971451) (xy 234.032108 -43.025629) (xy 234.032108 -43.080371)
			(xy 234.024279 -43.134549) (xy 234.008783 -43.187051) (xy 233.985938 -43.236798) (xy 233.956213 -43.282765)
			(xy 233.938572 -43.303698) (xy 233.932476 -43.31081) (xy 233.926126 -43.327828) (xy 233.926126 -43.413172)
			(xy 233.932476 -43.43019) (xy 233.938572 -43.437302) (xy 233.946763 -43.446822) (xy 233.962018 -43.466776)
			(xy 233.969052 -43.47718) (xy 233.976571 -43.487366) (xy 233.998828 -43.499361) (xy 234.01147 -43.50004)
			(xy 241.903758 -43.50004) (xy 241.913822 -43.499605) (xy 241.932406 -43.491869) (xy 241.939826 -43.485054)
			(xy 246.987314 -38.437566) (xy 246.99471 -38.430715) (xy 247.013309 -38.422975) (xy 247.023382 -38.42258)
			(xy 247.15597 -38.42258) (xy 247.161304 -38.42131) (xy 247.197183 -38.414023) (xy 247.269984 -38.406229)
			(xy 247.3432 -38.406229) (xy 247.416001 -38.414023) (xy 247.45188 -38.42131) (xy 247.457214 -38.42258)
			(xy 247.823482 -38.42258) (xy 247.832316 -38.422203) (xy 247.848947 -38.416235) (xy 247.855994 -38.410896)
			(xy 247.886824 -38.385993) (xy 247.953198 -38.342682) (xy 248.024123 -38.307314) (xy 248.098653 -38.280358)
			(xy 248.175794 -38.262176) (xy 248.254517 -38.253009) (xy 248.294144 -38.2524) (xy 252.212856 -38.2524)
			(xy 252.252494 -38.252994) (xy 252.331236 -38.262189) (xy 252.408395 -38.280391) (xy 252.482944 -38.307358)
			(xy 252.518672 -38.324536) (xy 252.529494 -38.329241) (xy 252.553062 -38.329241) (xy 252.563884 -38.324536)
			(xy 252.599607 -38.307346) (xy 252.674155 -38.280372) (xy 252.751316 -38.262171) (xy 252.830061 -38.252986)
			(xy 252.8697 -38.2524) (xy 253.564898 -38.2524) (xy 253.604537 -38.252991) (xy 253.683281 -38.262179)
			(xy 253.760443 -38.280375) (xy 253.834996 -38.307338) (xy 253.870714 -38.324536) (xy 253.881536 -38.329241)
			(xy 253.905104 -38.329241) (xy 253.915926 -38.324536) (xy 253.951649 -38.307349) (xy 254.026198 -38.280379)
			(xy 254.103359 -38.262182) (xy 254.182104 -38.253002) (xy 254.221742 -38.2524) (xy 255.30048 -38.2524)
			(xy 255.340106 -38.252996) (xy 255.418824 -38.262189) (xy 255.49596 -38.280385) (xy 255.570487 -38.307343)
			(xy 255.641414 -38.342704) (xy 255.707797 -38.385998) (xy 255.73863 -38.410896) (xy 255.745488 -38.416484)
			(xy 255.762252 -38.42258) (xy 255.810258 -38.42258) (xy 255.820324 -38.423013) (xy 255.838915 -38.43074)
			(xy 255.846326 -38.437566) (xy 258.092194 -40.683434) (xy 258.099589 -40.690289) (xy 258.118188 -40.698036)
			(xy 258.128262 -40.69842) (xy 265.251438 -40.69842) (xy 265.261506 -40.697991) (xy 265.280102 -40.690269)
			(xy 265.287506 -40.683434) (xy 277.093934 -28.877006) (xy 277.101334 -28.870164) (xy 277.119932 -28.862441)
			(xy 277.130002 -28.86202) (xy 300.669198 -28.86202) (xy 300.679269 -28.861598) (xy 300.697876 -28.853886)
			(xy 300.705266 -28.847034) (xy 303.019714 -26.532586) (xy 303.027109 -26.525732) (xy 303.045708 -26.51799)
			(xy 303.055782 -26.5176) (xy 303.670462 -26.5176) (xy 303.67859 -26.514806) (xy 303.703527 -26.506668)
			(xy 303.755235 -26.497859) (xy 303.78146 -26.49728) (xy 317.003938 -26.49728) (xy 317.013902 -26.496799)
			(xy 317.032332 -26.489216) (xy 317.039752 -26.482548) (xy 318.300354 -25.221946) (xy 318.307753 -25.215103)
			(xy 318.326352 -25.207381) (xy 318.336422 -25.20696) (xy 319.872106 -25.20696) (xy 319.882092 -25.20642)
			(xy 319.900519 -25.198701) (xy 319.90792 -25.191974) (xy 321.145916 -23.953978) (xy 321.152595 -23.946567)
			(xy 321.160167 -23.928131) (xy 321.160648 -23.918164) (xy 321.160648 -23.40737) (xy 321.160167 -23.397406)
			(xy 321.152583 -23.378977) (xy 321.145916 -23.371556) (xy 321.043046 -23.268686) (xy 321.036197 -23.261289)
			(xy 321.02846 -23.24269) (xy 321.02806 -23.232618) (xy 321.02806 -19.665442) (xy 321.027625 -19.655377)
			(xy 321.019891 -19.636792) (xy 321.013074 -19.629374) (xy 320.377566 -18.993866) (xy 320.370169 -18.987018)
			(xy 320.35157 -18.979285) (xy 320.341498 -18.97888) (xy 317.493904 -18.97888) (xy 317.484252 -18.982944)
			(xy 317.452576 -18.99588) (xy 317.386622 -19.014087) (xy 317.318819 -19.023267) (xy 317.284608 -19.023838)
			(xy 317.250399 -19.023259) (xy 317.182603 -19.014051) (xy 317.116649 -18.995854) (xy 317.084964 -18.982944)
			(xy 317.075312 -18.97888) (xy 315.255402 -18.97888) (xy 315.244799 -18.979422) (xy 315.225377 -18.987944)
			(xy 315.21781 -18.99539) (xy 315.159898 -19.058382) (xy 315.15304 -19.078194) (xy 315.154056 -19.088862)
			(xy 315.155834 -19.13128) (xy 315.155371 -19.162012) (xy 315.147965 -19.223029) (xy 315.133258 -19.282708)
			(xy 315.111465 -19.34018) (xy 315.082903 -19.394605) (xy 315.047989 -19.445191) (xy 315.007233 -19.4912)
			(xy 314.961227 -19.531961) (xy 314.910645 -19.566879) (xy 314.856222 -19.595446) (xy 314.798752 -19.617244)
			(xy 314.739074 -19.631956) (xy 314.678058 -19.639368) (xy 314.647326 -19.639788) (xy 314.617054 -19.639353)
			(xy 314.556938 -19.632167) (xy 314.498101 -19.617892) (xy 314.441375 -19.596733) (xy 314.387563 -19.568986)
			(xy 314.337427 -19.535046) (xy 314.291675 -19.495393) (xy 314.250956 -19.450587) (xy 314.233052 -19.426174)
			(xy 314.226702 -19.41703) (xy 314.20816 -19.406362) (xy 314.111132 -19.39544) (xy 314.090812 -19.40179)
			(xy 314.082684 -19.409156) (xy 314.061595 -19.427282) (xy 314.015155 -19.457871) (xy 313.964771 -19.4814)
			(xy 313.911506 -19.497372) (xy 313.856488 -19.50545) (xy 313.828684 -19.50593) (xy 313.801433 -19.505443)
			(xy 313.747486 -19.497685) (xy 313.695192 -19.482329) (xy 313.645615 -19.459687) (xy 313.599765 -19.43022)
			(xy 313.558575 -19.394529) (xy 313.522883 -19.35334) (xy 313.493416 -19.30749) (xy 313.470773 -19.257914)
			(xy 313.455416 -19.20562) (xy 313.447657 -19.151673) (xy 313.447176 -19.124422) (xy 313.4487 -19.089624)
			(xy 313.449716 -19.078956) (xy 313.442858 -19.05889) (xy 313.3852 -18.99539) (xy 313.377703 -18.987842)
			(xy 313.358239 -18.9793) (xy 313.347608 -18.97888) (xy 297.223688 -18.97888) (xy 297.198542 -18.994882)
			(xy 297.192446 -19.008344) (xy 297.180576 -19.032685) (xy 297.150984 -19.078041) (xy 297.115279 -19.118758)
			(xy 297.074178 -19.154021) (xy 297.028505 -19.183119) (xy 296.979178 -19.205471) (xy 296.927187 -19.220626)
			(xy 296.873575 -19.22828) (xy 296.819421 -19.22828) (xy 296.765809 -19.220626) (xy 296.713818 -19.205471)
			(xy 296.664491 -19.183119) (xy 296.618818 -19.154021) (xy 296.577717 -19.118758) (xy 296.542012 -19.078041)
			(xy 296.51242 -19.032685) (xy 296.50055 -19.008344) (xy 296.494454 -18.994882) (xy 296.469308 -18.97888)
			(xy 295.667684 -18.97888) (xy 295.658395 -18.979302) (xy 295.641036 -18.985928) (xy 295.627152 -18.998275)
			(xy 295.622472 -19.006312) (xy 295.574466 -19.099276) (xy 295.576244 -19.12747) (xy 295.584626 -19.139154)
			(xy 295.602394 -19.165018) (xy 295.632116 -19.220285) (xy 295.654816 -19.278787) (xy 295.670147 -19.339637)
			(xy 295.677879 -19.40191) (xy 295.678352 -19.433286) (xy 295.67785 -19.465247) (xy 295.669839 -19.528665)
			(xy 295.653942 -19.590579) (xy 295.63041 -19.650012) (xy 295.599616 -19.706027) (xy 295.580753 -19.73199)
			(xy 300.189898 -19.73199) (xy 300.193969 -19.676368) (xy 300.206095 -19.621931) (xy 300.226018 -19.56984)
			(xy 300.253314 -19.521205) (xy 300.2874 -19.477062) (xy 300.327549 -19.438353) (xy 300.372907 -19.405902)
			(xy 300.422507 -19.380401) (xy 300.475291 -19.362394) (xy 300.530134 -19.352264) (xy 300.585868 -19.350227)
			(xy 300.641305 -19.356327) (xy 300.695262 -19.370433) (xy 300.746591 -19.392245) (xy 300.794197 -19.421299)
			(xy 300.837065 -19.456974) (xy 300.874282 -19.498511) (xy 300.905055 -19.545024) (xy 300.928727 -19.595521)
			(xy 300.944795 -19.648928) (xy 300.952915 -19.704104) (xy 300.953424 -19.73199) (xy 300.952915 -19.759876)
			(xy 300.944795 -19.815052) (xy 300.928727 -19.868459) (xy 300.905055 -19.918956) (xy 300.874282 -19.965469)
			(xy 300.837065 -20.007006) (xy 300.794197 -20.042681) (xy 300.746591 -20.071735) (xy 300.695262 -20.093547)
			(xy 300.641305 -20.107653) (xy 300.585868 -20.113753) (xy 300.530134 -20.111716) (xy 300.475291 -20.101586)
			(xy 300.422507 -20.083579) (xy 300.372907 -20.058078) (xy 300.327549 -20.025627) (xy 300.2874 -19.986918)
			(xy 300.253314 -19.942775) (xy 300.226018 -19.89414) (xy 300.206095 -19.842049) (xy 300.193969 -19.787612)
			(xy 300.189898 -19.73199) (xy 295.580753 -19.73199) (xy 295.562043 -19.757742) (xy 295.518286 -19.804339)
			(xy 295.469033 -19.845084) (xy 295.415062 -19.879335) (xy 295.357223 -19.906552) (xy 295.29643 -19.926305)
			(xy 295.23364 -19.938283) (xy 295.169844 -19.942297) (xy 295.106048 -19.938283) (xy 295.043258 -19.926305)
			(xy 294.982465 -19.906552) (xy 294.924626 -19.879335) (xy 294.870655 -19.845084) (xy 294.821402 -19.804339)
			(xy 294.777645 -19.757742) (xy 294.740072 -19.706027) (xy 294.709278 -19.650012) (xy 294.685746 -19.590579)
			(xy 294.669849 -19.528665) (xy 294.661838 -19.465247) (xy 294.661336 -19.433286) (xy 294.661803 -19.40191)
			(xy 294.66953 -19.339636) (xy 294.684864 -19.278787) (xy 294.707573 -19.220288) (xy 294.73731 -19.16503)
			(xy 294.755062 -19.139154) (xy 294.763444 -19.12747) (xy 294.765222 -19.099276) (xy 294.717216 -19.006312)
			(xy 294.712586 -18.998232) (xy 294.698706 -18.985841) (xy 294.681309 -18.979243) (xy 294.672004 -18.97888)
			(xy 293.869872 -18.97888) (xy 293.857628 -18.979611) (xy 293.835893 -18.9909) (xy 293.828216 -19.00047)
			(xy 293.811622 -19.023118) (xy 293.772874 -19.063747) (xy 293.728589 -19.098258) (xy 293.679723 -19.125905)
			(xy 293.627333 -19.146091) (xy 293.57255 -19.158379) (xy 293.516558 -19.162505) (xy 293.460566 -19.158379)
			(xy 293.405783 -19.146091) (xy 293.353393 -19.125905) (xy 293.304527 -19.098258) (xy 293.260242 -19.063747)
			(xy 293.221494 -19.023118) (xy 293.2049 -19.00047) (xy 293.197278 -18.99084) (xy 293.175507 -18.979563)
			(xy 293.163244 -18.97888) (xy 290.768786 -18.97888) (xy 290.73983 -19.005804) (xy 290.738052 -19.025362)
			(xy 290.734978 -19.056757) (xy 290.722041 -19.118499) (xy 290.701566 -19.178166) (xy 290.673867 -19.234842)
			(xy 290.639369 -19.287656) (xy 290.598603 -19.335798) (xy 290.552195 -19.378526) (xy 290.500858 -19.415185)
			(xy 290.44538 -19.445212) (xy 290.386613 -19.468145) (xy 290.325461 -19.483633) (xy 290.262863 -19.491436)
			(xy 290.199781 -19.491436) (xy 290.137183 -19.483633) (xy 290.076031 -19.468145) (xy 290.017264 -19.445212)
			(xy 289.961786 -19.415185) (xy 289.910449 -19.378526) (xy 289.864041 -19.335798) (xy 289.823275 -19.287656)
			(xy 289.788777 -19.234842) (xy 289.761078 -19.178166) (xy 289.740603 -19.118499) (xy 289.727666 -19.056757)
			(xy 289.724592 -19.025362) (xy 289.722814 -19.005804) (xy 289.693858 -18.97888) (xy 277.132542 -18.97888)
			(xy 277.122476 -18.979313) (xy 277.103885 -18.98704) (xy 277.096474 -18.993866) (xy 275.72843 -20.36191)
			(xy 301.48987 -20.36191) (xy 301.493941 -20.306288) (xy 301.506067 -20.251851) (xy 301.52599 -20.19976)
			(xy 301.553286 -20.151125) (xy 301.587372 -20.106982) (xy 301.627521 -20.068273) (xy 301.672879 -20.035822)
			(xy 301.722479 -20.010321) (xy 301.775263 -19.992314) (xy 301.830106 -19.982184) (xy 301.88584 -19.980147)
			(xy 301.941277 -19.986247) (xy 301.995234 -20.000353) (xy 302.046563 -20.022165) (xy 302.094169 -20.051219)
			(xy 302.137037 -20.086894) (xy 302.174254 -20.128431) (xy 302.205027 -20.174944) (xy 302.228699 -20.225441)
			(xy 302.244767 -20.278848) (xy 302.252887 -20.334024) (xy 302.253396 -20.36191) (xy 302.252887 -20.389796)
			(xy 302.244767 -20.444972) (xy 302.228699 -20.498379) (xy 302.205027 -20.548876) (xy 302.174254 -20.595389)
			(xy 302.137037 -20.636926) (xy 302.094169 -20.672601) (xy 302.046563 -20.701655) (xy 301.995234 -20.723467)
			(xy 301.941277 -20.737573) (xy 301.88584 -20.743673) (xy 301.830106 -20.741636) (xy 301.775263 -20.731506)
			(xy 301.722479 -20.713499) (xy 301.672879 -20.687998) (xy 301.627521 -20.655547) (xy 301.587372 -20.616838)
			(xy 301.553286 -20.572695) (xy 301.52599 -20.52406) (xy 301.506067 -20.471969) (xy 301.493941 -20.417532)
			(xy 301.48987 -20.36191) (xy 275.72843 -20.36191) (xy 274.046188 -22.044152) (xy 298.56938 -22.044152)
			(xy 298.569866 -22.016901) (xy 298.577622 -21.962953) (xy 298.592977 -21.910658) (xy 298.615619 -21.861081)
			(xy 298.645085 -21.815231) (xy 298.680776 -21.77404) (xy 298.721967 -21.738349) (xy 298.767817 -21.708883)
			(xy 298.817394 -21.686241) (xy 298.869689 -21.670886) (xy 298.923637 -21.66313) (xy 298.978139 -21.66313)
			(xy 299.032087 -21.670886) (xy 299.084382 -21.686241) (xy 299.133959 -21.708883) (xy 299.179809 -21.738349)
			(xy 299.221 -21.77404) (xy 299.256691 -21.815231) (xy 299.286157 -21.861081) (xy 299.308799 -21.910658)
			(xy 299.324154 -21.962953) (xy 299.33191 -22.016901) (xy 299.332396 -22.044152) (xy 299.331981 -22.06957)
			(xy 299.325225 -22.119956) (xy 299.322552 -22.12975) (xy 302.255934 -22.12975) (xy 302.260005 -22.074128)
			(xy 302.272131 -22.019691) (xy 302.292054 -21.9676) (xy 302.31935 -21.918965) (xy 302.353436 -21.874822)
			(xy 302.393585 -21.836113) (xy 302.438943 -21.803662) (xy 302.488543 -21.778161) (xy 302.541327 -21.760154)
			(xy 302.59617 -21.750024) (xy 302.651904 -21.747987) (xy 302.707341 -21.754087) (xy 302.761298 -21.768193)
			(xy 302.812627 -21.790005) (xy 302.860233 -21.819059) (xy 302.903101 -21.854734) (xy 302.940318 -21.896271)
			(xy 302.971091 -21.942784) (xy 302.994763 -21.993281) (xy 303.010831 -22.046688) (xy 303.018951 -22.101864)
			(xy 303.01946 -22.12975) (xy 303.018951 -22.157636) (xy 303.010831 -22.212812) (xy 302.994763 -22.266219)
			(xy 302.983308 -22.290654) (xy 305.107532 -22.290654) (xy 305.107532 -22.236146) (xy 305.115289 -22.182192)
			(xy 305.130646 -22.129891) (xy 305.153289 -22.080309) (xy 305.182759 -22.034453) (xy 305.218454 -21.993258)
			(xy 305.259648 -21.957562) (xy 305.305503 -21.928092) (xy 305.355086 -21.905448) (xy 305.407386 -21.89009)
			(xy 305.46134 -21.882332) (xy 305.488594 -21.881846) (xy 305.51424 -21.882245) (xy 305.565067 -21.889132)
			(xy 305.614512 -21.902769) (xy 305.661683 -21.922911) (xy 305.68392 -21.935694) (xy 305.693572 -21.941536)
			(xy 305.71567 -21.943822) (xy 305.81092 -21.910548) (xy 305.826668 -21.895308) (xy 305.830732 -21.884386)
			(xy 305.842064 -21.855859) (xy 305.870687 -21.801557) (xy 305.905636 -21.751093) (xy 305.946403 -21.705201)
			(xy 305.992397 -21.664548) (xy 306.042949 -21.629726) (xy 306.097323 -21.60124) (xy 306.15473 -21.579504)
			(xy 306.214336 -21.564834) (xy 306.275274 -21.557443) (xy 306.305966 -21.55698) (xy 306.337929 -21.557483)
			(xy 306.401351 -21.565491) (xy 306.46327 -21.581385) (xy 306.498397 -21.595291) (xy 317.792602 -21.595291)
			(xy 317.792602 -21.531369) (xy 317.800613 -21.467951) (xy 317.81651 -21.406037) (xy 317.840042 -21.346604)
			(xy 317.870836 -21.290589) (xy 317.908409 -21.238874) (xy 317.952166 -21.192277) (xy 318.001419 -21.151532)
			(xy 318.05539 -21.117281) (xy 318.113229 -21.090064) (xy 318.174022 -21.070311) (xy 318.236812 -21.058333)
			(xy 318.300608 -21.05432) (xy 318.364404 -21.058333) (xy 318.427194 -21.070311) (xy 318.487987 -21.090064)
			(xy 318.545826 -21.117281) (xy 318.599797 -21.151532) (xy 318.64905 -21.192277) (xy 318.692807 -21.238874)
			(xy 318.73038 -21.290589) (xy 318.761174 -21.346604) (xy 318.784706 -21.406037) (xy 318.800603 -21.467951)
			(xy 318.808614 -21.531369) (xy 318.809116 -21.56333) (xy 318.808614 -21.595291) (xy 318.800603 -21.658709)
			(xy 318.784706 -21.720623) (xy 318.761174 -21.780056) (xy 318.73038 -21.836071) (xy 318.692807 -21.887786)
			(xy 318.64905 -21.934383) (xy 318.599797 -21.975128) (xy 318.545826 -22.009379) (xy 318.487987 -22.036596)
			(xy 318.427194 -22.056349) (xy 318.364404 -22.068327) (xy 318.300608 -22.072341) (xy 318.236812 -22.068327)
			(xy 318.174022 -22.056349) (xy 318.113229 -22.036596) (xy 318.05539 -22.009379) (xy 318.001419 -21.975128)
			(xy 317.952166 -21.934383) (xy 317.908409 -21.887786) (xy 317.870836 -21.836071) (xy 317.840042 -21.780056)
			(xy 317.81651 -21.720623) (xy 317.800613 -21.658709) (xy 317.792602 -21.595291) (xy 306.498397 -21.595291)
			(xy 306.522708 -21.604915) (xy 306.578728 -21.635709) (xy 306.630447 -21.673282) (xy 306.677048 -21.71704)
			(xy 306.717797 -21.766295) (xy 306.752052 -21.820268) (xy 306.779271 -21.87811) (xy 306.799026 -21.938907)
			(xy 306.811005 -22.0017) (xy 306.81502 -22.0655) (xy 306.811005 -22.1293) (xy 306.799026 -22.192093)
			(xy 306.779271 -22.25289) (xy 306.752052 -22.310732) (xy 306.717797 -22.364705) (xy 306.677048 -22.41396)
			(xy 306.630447 -22.457718) (xy 306.578728 -22.495291) (xy 306.522708 -22.526085) (xy 306.486154 -22.540556)
			(xy 312.118145 -22.540556) (xy 312.118145 -22.486044) (xy 312.125903 -22.432088) (xy 312.141262 -22.379784)
			(xy 312.163909 -22.3302) (xy 312.193382 -22.284343) (xy 312.229082 -22.243148) (xy 312.270282 -22.207453)
			(xy 312.316142 -22.177986) (xy 312.36573 -22.155346) (xy 312.418035 -22.139993) (xy 312.471992 -22.132242)
			(xy 312.499248 -22.131782) (xy 312.526618 -22.132259) (xy 312.580798 -22.140071) (xy 312.633301 -22.155556)
			(xy 312.683048 -22.178396) (xy 312.729015 -22.20812) (xy 312.749946 -22.225762) (xy 312.757058 -22.231858)
			(xy 312.774076 -22.238208) (xy 312.85942 -22.238208) (xy 312.876438 -22.231858) (xy 312.88355 -22.225762)
			(xy 312.904485 -22.208127) (xy 312.950458 -22.178415) (xy 313.000204 -22.155579) (xy 313.052704 -22.140087)
			(xy 313.106879 -22.132257) (xy 313.134248 -22.131782) (xy 313.161496 -22.132292) (xy 313.215437 -22.140053)
			(xy 313.267725 -22.155412) (xy 313.317295 -22.178055) (xy 313.363138 -22.207522) (xy 313.404321 -22.243213)
			(xy 313.440007 -22.284401) (xy 313.469468 -22.330247) (xy 313.492105 -22.37982) (xy 313.507457 -22.43211)
			(xy 313.515212 -22.486052) (xy 313.515212 -22.540548) (xy 313.507457 -22.59449) (xy 313.492105 -22.64678)
			(xy 313.469468 -22.696353) (xy 313.440007 -22.742199) (xy 313.404321 -22.783387) (xy 313.363138 -22.819078)
			(xy 313.317295 -22.848545) (xy 313.267725 -22.871188) (xy 313.215437 -22.886547) (xy 313.161496 -22.894308)
			(xy 313.134248 -22.894798) (xy 313.106879 -22.894304) (xy 313.052701 -22.886493) (xy 313.000198 -22.871011)
			(xy 312.950451 -22.848175) (xy 312.904483 -22.818456) (xy 312.88355 -22.800818) (xy 312.876438 -22.794722)
			(xy 312.85942 -22.788372) (xy 312.774076 -22.788372) (xy 312.757058 -22.794722) (xy 312.749946 -22.800818)
			(xy 312.72901 -22.818452) (xy 312.683038 -22.848164) (xy 312.633291 -22.871) (xy 312.580792 -22.886493)
			(xy 312.526617 -22.894323) (xy 312.499248 -22.894798) (xy 312.471992 -22.894358) (xy 312.418035 -22.886607)
			(xy 312.36573 -22.871254) (xy 312.316142 -22.848614) (xy 312.270282 -22.819147) (xy 312.229082 -22.783452)
			(xy 312.193382 -22.742257) (xy 312.163909 -22.6964) (xy 312.141262 -22.646816) (xy 312.125903 -22.594512)
			(xy 312.118145 -22.540556) (xy 306.486154 -22.540556) (xy 306.46327 -22.549615) (xy 306.401351 -22.565509)
			(xy 306.337929 -22.573517) (xy 306.305966 -22.573996) (xy 306.274935 -22.573556) (xy 306.213333 -22.566005)
			(xy 306.153111 -22.551007) (xy 306.095163 -22.528786) (xy 306.040353 -22.499672) (xy 305.989497 -22.4641)
			(xy 305.966114 -22.443694) (xy 305.957732 -22.436074) (xy 305.936396 -22.429724) (xy 305.836828 -22.443694)
			(xy 305.818286 -22.455886) (xy 305.81219 -22.465538) (xy 305.797127 -22.48867) (xy 305.761423 -22.530767)
			(xy 305.720028 -22.567283) (xy 305.673806 -22.597456) (xy 305.62372 -22.620658) (xy 305.570815 -22.636405)
			(xy 305.516193 -22.644368) (xy 305.488594 -22.644862) (xy 305.46134 -22.644468) (xy 305.407386 -22.63671)
			(xy 305.355086 -22.621352) (xy 305.305503 -22.598708) (xy 305.259648 -22.569238) (xy 305.218454 -22.533542)
			(xy 305.182759 -22.492347) (xy 305.153289 -22.446491) (xy 305.130646 -22.396909) (xy 305.115289 -22.344608)
			(xy 305.107532 -22.290654) (xy 302.983308 -22.290654) (xy 302.971091 -22.316716) (xy 302.940318 -22.363229)
			(xy 302.903101 -22.404766) (xy 302.860233 -22.440441) (xy 302.812627 -22.469495) (xy 302.761298 -22.491307)
			(xy 302.707341 -22.505413) (xy 302.651904 -22.511513) (xy 302.59617 -22.509476) (xy 302.541327 -22.499346)
			(xy 302.488543 -22.481339) (xy 302.438943 -22.455838) (xy 302.393585 -22.423387) (xy 302.353436 -22.384678)
			(xy 302.31935 -22.340535) (xy 302.292054 -22.2919) (xy 302.272131 -22.239809) (xy 302.260005 -22.185372)
			(xy 302.255934 -22.12975) (xy 299.322552 -22.12975) (xy 299.311838 -22.168998) (xy 299.292058 -22.215828)
			(xy 299.266236 -22.259618) (xy 299.250862 -22.279864) (xy 299.244258 -22.2885) (xy 299.238924 -22.308566)
			(xy 299.254672 -22.40407) (xy 299.266102 -22.421596) (xy 299.275246 -22.427692) (xy 299.297652 -22.442893)
			(xy 299.338387 -22.47856) (xy 299.373668 -22.51963) (xy 299.402786 -22.565276) (xy 299.425155 -22.614582)
			(xy 299.440327 -22.666556) (xy 299.447995 -22.720153) (xy 299.448474 -22.747224) (xy 299.447988 -22.774475)
			(xy 299.440232 -22.828423) (xy 299.424877 -22.880718) (xy 299.402235 -22.930295) (xy 299.372769 -22.976145)
			(xy 299.337078 -23.017336) (xy 299.295887 -23.053027) (xy 299.250037 -23.082493) (xy 299.20046 -23.105135)
			(xy 299.148165 -23.12049) (xy 299.094217 -23.128246) (xy 299.039715 -23.128246) (xy 298.985767 -23.12049)
			(xy 298.933472 -23.105135) (xy 298.883895 -23.082493) (xy 298.838045 -23.053027) (xy 298.796854 -23.017336)
			(xy 298.761163 -22.976145) (xy 298.731697 -22.930295) (xy 298.709055 -22.880718) (xy 298.6937 -22.828423)
			(xy 298.685944 -22.774475) (xy 298.685458 -22.747224) (xy 298.685903 -22.721807) (xy 298.692651 -22.671422)
			(xy 298.70603 -22.62238) (xy 298.725803 -22.575549) (xy 298.75162 -22.531758) (xy 298.766992 -22.511512)
			(xy 298.773596 -22.502876) (xy 298.77893 -22.48281) (xy 298.763182 -22.387306) (xy 298.751752 -22.36978)
			(xy 298.742608 -22.363684) (xy 298.72018 -22.348513) (xy 298.679448 -22.31284) (xy 298.64417 -22.271764)
			(xy 298.615056 -22.226113) (xy 298.59269 -22.176802) (xy 298.577522 -22.124825) (xy 298.569857 -22.071225)
			(xy 298.56938 -22.044152) (xy 274.046188 -22.044152) (xy 272.94459 -23.14575) (xy 302.255934 -23.14575)
			(xy 302.260005 -23.090128) (xy 302.272131 -23.035691) (xy 302.292054 -22.9836) (xy 302.31935 -22.934965)
			(xy 302.353436 -22.890822) (xy 302.393585 -22.852113) (xy 302.438943 -22.819662) (xy 302.488543 -22.794161)
			(xy 302.541327 -22.776154) (xy 302.59617 -22.766024) (xy 302.651904 -22.763987) (xy 302.707341 -22.770087)
			(xy 302.761298 -22.784193) (xy 302.812627 -22.806005) (xy 302.860233 -22.835059) (xy 302.903101 -22.870734)
			(xy 302.940318 -22.912271) (xy 302.971091 -22.958784) (xy 302.994763 -23.009281) (xy 303.010831 -23.062688)
			(xy 303.018951 -23.117864) (xy 303.01946 -23.14575) (xy 303.018951 -23.173636) (xy 303.014794 -23.201884)
			(xy 308.375556 -23.201884) (xy 308.379627 -23.146262) (xy 308.391753 -23.091825) (xy 308.411676 -23.039734)
			(xy 308.438972 -22.991099) (xy 308.473058 -22.946956) (xy 308.513207 -22.908247) (xy 308.558565 -22.875796)
			(xy 308.608165 -22.850295) (xy 308.660949 -22.832288) (xy 308.715792 -22.822158) (xy 308.771526 -22.820121)
			(xy 308.826963 -22.826221) (xy 308.88092 -22.840327) (xy 308.932249 -22.862139) (xy 308.979855 -22.891193)
			(xy 309.022723 -22.926868) (xy 309.05994 -22.968405) (xy 309.090713 -23.014918) (xy 309.114385 -23.065415)
			(xy 309.130453 -23.118822) (xy 309.138573 -23.173998) (xy 309.139082 -23.201884) (xy 310.375552 -23.201884)
			(xy 310.379623 -23.146262) (xy 310.391749 -23.091825) (xy 310.411672 -23.039734) (xy 310.438968 -22.991099)
			(xy 310.473054 -22.946956) (xy 310.513203 -22.908247) (xy 310.558561 -22.875796) (xy 310.608161 -22.850295)
			(xy 310.660945 -22.832288) (xy 310.715788 -22.822158) (xy 310.771522 -22.820121) (xy 310.826959 -22.826221)
			(xy 310.880916 -22.840327) (xy 310.932245 -22.862139) (xy 310.979851 -22.891193) (xy 311.022719 -22.926868)
			(xy 311.059936 -22.968405) (xy 311.088342 -23.011341) (xy 318.429888 -23.011341) (xy 318.429888 -22.947419)
			(xy 318.437899 -22.884001) (xy 318.453796 -22.822087) (xy 318.477328 -22.762654) (xy 318.508122 -22.706639)
			(xy 318.545695 -22.654924) (xy 318.589452 -22.608327) (xy 318.638705 -22.567582) (xy 318.692676 -22.533331)
			(xy 318.750515 -22.506114) (xy 318.811308 -22.486361) (xy 318.874098 -22.474383) (xy 318.937894 -22.47037)
			(xy 319.00169 -22.474383) (xy 319.06448 -22.486361) (xy 319.125273 -22.506114) (xy 319.183112 -22.533331)
			(xy 319.237083 -22.567582) (xy 319.286336 -22.608327) (xy 319.330093 -22.654924) (xy 319.367666 -22.706639)
			(xy 319.39846 -22.762654) (xy 319.421992 -22.822087) (xy 319.437889 -22.884001) (xy 319.4459 -22.947419)
			(xy 319.446402 -22.97938) (xy 319.4459 -23.011341) (xy 319.437889 -23.074759) (xy 319.421992 -23.136673)
			(xy 319.39846 -23.196106) (xy 319.367666 -23.252121) (xy 319.330093 -23.303836) (xy 319.286336 -23.350433)
			(xy 319.237083 -23.391178) (xy 319.183112 -23.425429) (xy 319.125273 -23.452646) (xy 319.06448 -23.472399)
			(xy 319.00169 -23.484377) (xy 318.937894 -23.488391) (xy 318.874098 -23.484377) (xy 318.811308 -23.472399)
			(xy 318.750515 -23.452646) (xy 318.692676 -23.425429) (xy 318.638705 -23.391178) (xy 318.589452 -23.350433)
			(xy 318.545695 -23.303836) (xy 318.508122 -23.252121) (xy 318.477328 -23.196106) (xy 318.453796 -23.136673)
			(xy 318.437899 -23.074759) (xy 318.429888 -23.011341) (xy 311.088342 -23.011341) (xy 311.090709 -23.014918)
			(xy 311.114381 -23.065415) (xy 311.130449 -23.118822) (xy 311.138569 -23.173998) (xy 311.139078 -23.201884)
			(xy 311.138569 -23.22977) (xy 311.130449 -23.284946) (xy 311.114381 -23.338353) (xy 311.090709 -23.38885)
			(xy 311.059936 -23.435363) (xy 311.022719 -23.4769) (xy 310.979851 -23.512575) (xy 310.932245 -23.541629)
			(xy 310.880916 -23.563441) (xy 310.826959 -23.577547) (xy 310.771522 -23.583647) (xy 310.715788 -23.58161)
			(xy 310.660945 -23.57148) (xy 310.608161 -23.553473) (xy 310.558561 -23.527972) (xy 310.513203 -23.495521)
			(xy 310.473054 -23.456812) (xy 310.438968 -23.412669) (xy 310.411672 -23.364034) (xy 310.391749 -23.311943)
			(xy 310.379623 -23.257506) (xy 310.375552 -23.201884) (xy 309.139082 -23.201884) (xy 309.138573 -23.22977)
			(xy 309.130453 -23.284946) (xy 309.114385 -23.338353) (xy 309.090713 -23.38885) (xy 309.05994 -23.435363)
			(xy 309.022723 -23.4769) (xy 308.979855 -23.512575) (xy 308.932249 -23.541629) (xy 308.88092 -23.563441)
			(xy 308.826963 -23.577547) (xy 308.771526 -23.583647) (xy 308.715792 -23.58161) (xy 308.660949 -23.57148)
			(xy 308.608165 -23.553473) (xy 308.558565 -23.527972) (xy 308.513207 -23.495521) (xy 308.473058 -23.456812)
			(xy 308.438972 -23.412669) (xy 308.411676 -23.364034) (xy 308.391753 -23.311943) (xy 308.379627 -23.257506)
			(xy 308.375556 -23.201884) (xy 303.014794 -23.201884) (xy 303.010831 -23.228812) (xy 302.994763 -23.282219)
			(xy 302.971091 -23.332716) (xy 302.940318 -23.379229) (xy 302.903101 -23.420766) (xy 302.860233 -23.456441)
			(xy 302.812627 -23.485495) (xy 302.761298 -23.507307) (xy 302.707341 -23.521413) (xy 302.651904 -23.527513)
			(xy 302.59617 -23.525476) (xy 302.541327 -23.515346) (xy 302.488543 -23.497339) (xy 302.438943 -23.471838)
			(xy 302.393585 -23.439387) (xy 302.353436 -23.400678) (xy 302.31935 -23.356535) (xy 302.292054 -23.3079)
			(xy 302.272131 -23.255809) (xy 302.260005 -23.201372) (xy 302.255934 -23.14575) (xy 272.94459 -23.14575)
			(xy 272.327116 -23.763224) (xy 298.684948 -23.763224) (xy 298.689019 -23.707602) (xy 298.701145 -23.653165)
			(xy 298.721068 -23.601074) (xy 298.748364 -23.552439) (xy 298.78245 -23.508296) (xy 298.822599 -23.469587)
			(xy 298.867957 -23.437136) (xy 298.917557 -23.411635) (xy 298.970341 -23.393628) (xy 299.025184 -23.383498)
			(xy 299.080918 -23.381461) (xy 299.136355 -23.387561) (xy 299.190312 -23.401667) (xy 299.241641 -23.423479)
			(xy 299.289247 -23.452533) (xy 299.332115 -23.488208) (xy 299.369332 -23.529745) (xy 299.400105 -23.576258)
			(xy 299.423777 -23.626755) (xy 299.439845 -23.680162) (xy 299.447965 -23.735338) (xy 299.448474 -23.763224)
			(xy 299.447965 -23.79111) (xy 299.44445 -23.814997) (xy 300.713896 -23.814997) (xy 300.713896 -23.751075)
			(xy 300.721907 -23.687657) (xy 300.737804 -23.625743) (xy 300.761336 -23.56631) (xy 300.79213 -23.510295)
			(xy 300.829703 -23.45858) (xy 300.87346 -23.411983) (xy 300.922713 -23.371238) (xy 300.976684 -23.336987)
			(xy 301.034523 -23.30977) (xy 301.095316 -23.290017) (xy 301.158106 -23.278039) (xy 301.221902 -23.274026)
			(xy 301.285698 -23.278039) (xy 301.348488 -23.290017) (xy 301.409281 -23.30977) (xy 301.46712 -23.336987)
			(xy 301.521091 -23.371238) (xy 301.570344 -23.411983) (xy 301.614101 -23.45858) (xy 301.651674 -23.510295)
			(xy 301.682468 -23.56631) (xy 301.706 -23.625743) (xy 301.721897 -23.687657) (xy 301.729908 -23.751075)
			(xy 301.73041 -23.783036) (xy 301.730243 -23.793661) (xy 303.145946 -23.793661) (xy 303.145946 -23.729739)
			(xy 303.153957 -23.666321) (xy 303.169854 -23.604407) (xy 303.193386 -23.544974) (xy 303.22418 -23.488959)
			(xy 303.261753 -23.437244) (xy 303.30551 -23.390647) (xy 303.354763 -23.349902) (xy 303.408734 -23.315651)
			(xy 303.466573 -23.288434) (xy 303.527366 -23.268681) (xy 303.590156 -23.256703) (xy 303.653952 -23.25269)
			(xy 303.717748 -23.256703) (xy 303.780538 -23.268681) (xy 303.841331 -23.288434) (xy 303.89917 -23.315651)
			(xy 303.953141 -23.349902) (xy 304.002394 -23.390647) (xy 304.046151 -23.437244) (xy 304.083724 -23.488959)
			(xy 304.114518 -23.544974) (xy 304.13805 -23.604407) (xy 304.153947 -23.666321) (xy 304.161958 -23.729739)
			(xy 304.16246 -23.7617) (xy 304.161958 -23.793661) (xy 304.153947 -23.857079) (xy 304.13805 -23.918993)
			(xy 304.114518 -23.978426) (xy 304.083724 -24.034441) (xy 304.046151 -24.086156) (xy 304.011698 -24.122845)
			(xy 305.963314 -24.122845) (xy 305.963314 -24.058923) (xy 305.971325 -23.995505) (xy 305.987222 -23.933591)
			(xy 306.010754 -23.874158) (xy 306.041548 -23.818143) (xy 306.079121 -23.766428) (xy 306.122878 -23.719831)
			(xy 306.172131 -23.679086) (xy 306.226102 -23.644835) (xy 306.283941 -23.617618) (xy 306.344734 -23.597865)
			(xy 306.407524 -23.585887) (xy 306.47132 -23.581874) (xy 306.535116 -23.585887) (xy 306.597906 -23.597865)
			(xy 306.658699 -23.617618) (xy 306.716538 -23.644835) (xy 306.770509 -23.679086) (xy 306.819762 -23.719831)
			(xy 306.863519 -23.766428) (xy 306.901092 -23.818143) (xy 306.931886 -23.874158) (xy 306.955418 -23.933591)
			(xy 306.971315 -23.995505) (xy 306.979326 -24.058923) (xy 306.979828 -24.090884) (xy 308.375556 -24.090884)
			(xy 308.379627 -24.035262) (xy 308.391753 -23.980825) (xy 308.411676 -23.928734) (xy 308.438972 -23.880099)
			(xy 308.473058 -23.835956) (xy 308.513207 -23.797247) (xy 308.558565 -23.764796) (xy 308.608165 -23.739295)
			(xy 308.660949 -23.721288) (xy 308.715792 -23.711158) (xy 308.771526 -23.709121) (xy 308.826963 -23.715221)
			(xy 308.88092 -23.729327) (xy 308.932249 -23.751139) (xy 308.979855 -23.780193) (xy 309.022723 -23.815868)
			(xy 309.05994 -23.857405) (xy 309.090713 -23.903918) (xy 309.114385 -23.954415) (xy 309.116457 -23.961301)
			(xy 311.353956 -23.961301) (xy 311.353956 -23.897379) (xy 311.361967 -23.833961) (xy 311.377864 -23.772047)
			(xy 311.401396 -23.712614) (xy 311.43219 -23.656599) (xy 311.469763 -23.604884) (xy 311.51352 -23.558287)
			(xy 311.562773 -23.517542) (xy 311.616744 -23.483291) (xy 311.674583 -23.456074) (xy 311.735376 -23.436321)
			(xy 311.798166 -23.424343) (xy 311.861962 -23.42033) (xy 311.925758 -23.424343) (xy 311.988548 -23.436321)
			(xy 312.049341 -23.456074) (xy 312.10718 -23.483291) (xy 312.161151 -23.517542) (xy 312.210404 -23.558287)
			(xy 312.254161 -23.604884) (xy 312.26472 -23.619417) (xy 319.397882 -23.619417) (xy 319.397882 -23.555495)
			(xy 319.405893 -23.492077) (xy 319.42179 -23.430163) (xy 319.445322 -23.37073) (xy 319.476116 -23.314715)
			(xy 319.513689 -23.263) (xy 319.557446 -23.216403) (xy 319.606699 -23.175658) (xy 319.66067 -23.141407)
			(xy 319.718509 -23.11419) (xy 319.779302 -23.094437) (xy 319.842092 -23.082459) (xy 319.905888 -23.078446)
			(xy 319.969684 -23.082459) (xy 320.032474 -23.094437) (xy 320.093267 -23.11419) (xy 320.151106 -23.141407)
			(xy 320.205077 -23.175658) (xy 320.25433 -23.216403) (xy 320.298087 -23.263) (xy 320.33566 -23.314715)
			(xy 320.366454 -23.37073) (xy 320.389986 -23.430163) (xy 320.405883 -23.492077) (xy 320.413894 -23.555495)
			(xy 320.414396 -23.587456) (xy 320.413894 -23.619417) (xy 320.405883 -23.682835) (xy 320.389986 -23.744749)
			(xy 320.366454 -23.804182) (xy 320.33566 -23.860197) (xy 320.298087 -23.911912) (xy 320.25433 -23.958509)
			(xy 320.205077 -23.999254) (xy 320.151106 -24.033505) (xy 320.093267 -24.060722) (xy 320.032474 -24.080475)
			(xy 319.969684 -24.092453) (xy 319.905888 -24.096467) (xy 319.842092 -24.092453) (xy 319.779302 -24.080475)
			(xy 319.718509 -24.060722) (xy 319.66067 -24.033505) (xy 319.606699 -23.999254) (xy 319.557446 -23.958509)
			(xy 319.513689 -23.911912) (xy 319.476116 -23.860197) (xy 319.445322 -23.804182) (xy 319.42179 -23.744749)
			(xy 319.405893 -23.682835) (xy 319.397882 -23.619417) (xy 312.26472 -23.619417) (xy 312.291734 -23.656599)
			(xy 312.322528 -23.712614) (xy 312.34606 -23.772047) (xy 312.361957 -23.833961) (xy 312.369968 -23.897379)
			(xy 312.37047 -23.92934) (xy 312.369968 -23.961301) (xy 312.361957 -24.024719) (xy 312.34606 -24.086633)
			(xy 312.322528 -24.146066) (xy 312.291734 -24.202081) (xy 312.254161 -24.253796) (xy 312.215176 -24.295311)
			(xy 317.792602 -24.295311) (xy 317.792602 -24.231389) (xy 317.800613 -24.167971) (xy 317.81651 -24.106057)
			(xy 317.840042 -24.046624) (xy 317.870836 -23.990609) (xy 317.908409 -23.938894) (xy 317.952166 -23.892297)
			(xy 318.001419 -23.851552) (xy 318.05539 -23.817301) (xy 318.113229 -23.790084) (xy 318.174022 -23.770331)
			(xy 318.236812 -23.758353) (xy 318.300608 -23.75434) (xy 318.364404 -23.758353) (xy 318.427194 -23.770331)
			(xy 318.487987 -23.790084) (xy 318.545826 -23.817301) (xy 318.599797 -23.851552) (xy 318.64905 -23.892297)
			(xy 318.692807 -23.938894) (xy 318.73038 -23.990609) (xy 318.761174 -24.046624) (xy 318.784706 -24.106057)
			(xy 318.800603 -24.167971) (xy 318.808614 -24.231389) (xy 318.809116 -24.26335) (xy 318.808614 -24.295311)
			(xy 318.800603 -24.358729) (xy 318.784706 -24.420643) (xy 318.761174 -24.480076) (xy 318.73038 -24.536091)
			(xy 318.692807 -24.587806) (xy 318.64905 -24.634403) (xy 318.599797 -24.675148) (xy 318.545826 -24.709399)
			(xy 318.487987 -24.736616) (xy 318.427194 -24.756369) (xy 318.364404 -24.768347) (xy 318.300608 -24.772361)
			(xy 318.236812 -24.768347) (xy 318.174022 -24.756369) (xy 318.113229 -24.736616) (xy 318.05539 -24.709399)
			(xy 318.001419 -24.675148) (xy 317.952166 -24.634403) (xy 317.908409 -24.587806) (xy 317.870836 -24.536091)
			(xy 317.840042 -24.480076) (xy 317.81651 -24.420643) (xy 317.800613 -24.358729) (xy 317.792602 -24.295311)
			(xy 312.215176 -24.295311) (xy 312.210404 -24.300393) (xy 312.161151 -24.341138) (xy 312.10718 -24.375389)
			(xy 312.049341 -24.402606) (xy 311.988548 -24.422359) (xy 311.925758 -24.434337) (xy 311.861962 -24.438351)
			(xy 311.798166 -24.434337) (xy 311.735376 -24.422359) (xy 311.674583 -24.402606) (xy 311.616744 -24.375389)
			(xy 311.562773 -24.341138) (xy 311.51352 -24.300393) (xy 311.469763 -24.253796) (xy 311.43219 -24.202081)
			(xy 311.401396 -24.146066) (xy 311.377864 -24.086633) (xy 311.361967 -24.024719) (xy 311.353956 -23.961301)
			(xy 309.116457 -23.961301) (xy 309.130453 -24.007822) (xy 309.138573 -24.062998) (xy 309.139082 -24.090884)
			(xy 309.138573 -24.11877) (xy 309.130453 -24.173946) (xy 309.114385 -24.227353) (xy 309.090713 -24.27785)
			(xy 309.05994 -24.324363) (xy 309.022723 -24.3659) (xy 308.979855 -24.401575) (xy 308.932249 -24.430629)
			(xy 308.88092 -24.452441) (xy 308.826963 -24.466547) (xy 308.771526 -24.472647) (xy 308.715792 -24.47061)
			(xy 308.660949 -24.46048) (xy 308.608165 -24.442473) (xy 308.558565 -24.416972) (xy 308.513207 -24.384521)
			(xy 308.473058 -24.345812) (xy 308.438972 -24.301669) (xy 308.411676 -24.253034) (xy 308.391753 -24.200943)
			(xy 308.379627 -24.146506) (xy 308.375556 -24.090884) (xy 306.979828 -24.090884) (xy 306.979326 -24.122845)
			(xy 306.971315 -24.186263) (xy 306.955418 -24.248177) (xy 306.931886 -24.30761) (xy 306.901092 -24.363625)
			(xy 306.863519 -24.41534) (xy 306.819762 -24.461937) (xy 306.770509 -24.502682) (xy 306.716538 -24.536933)
			(xy 306.658699 -24.56415) (xy 306.597906 -24.583903) (xy 306.535116 -24.595881) (xy 306.47132 -24.599895)
			(xy 306.407524 -24.595881) (xy 306.344734 -24.583903) (xy 306.283941 -24.56415) (xy 306.226102 -24.536933)
			(xy 306.172131 -24.502682) (xy 306.122878 -24.461937) (xy 306.079121 -24.41534) (xy 306.041548 -24.363625)
			(xy 306.010754 -24.30761) (xy 305.987222 -24.248177) (xy 305.971325 -24.186263) (xy 305.963314 -24.122845)
			(xy 304.011698 -24.122845) (xy 304.002394 -24.132753) (xy 303.953141 -24.173498) (xy 303.89917 -24.207749)
			(xy 303.841331 -24.234966) (xy 303.780538 -24.254719) (xy 303.717748 -24.266697) (xy 303.653952 -24.270711)
			(xy 303.590156 -24.266697) (xy 303.527366 -24.254719) (xy 303.466573 -24.234966) (xy 303.408734 -24.207749)
			(xy 303.354763 -24.173498) (xy 303.30551 -24.132753) (xy 303.261753 -24.086156) (xy 303.22418 -24.034441)
			(xy 303.193386 -23.978426) (xy 303.169854 -23.918993) (xy 303.153957 -23.857079) (xy 303.145946 -23.793661)
			(xy 301.730243 -23.793661) (xy 301.729908 -23.814997) (xy 301.721897 -23.878415) (xy 301.706 -23.940329)
			(xy 301.682468 -23.999762) (xy 301.651674 -24.055777) (xy 301.614101 -24.107492) (xy 301.570344 -24.154089)
			(xy 301.521091 -24.194834) (xy 301.46712 -24.229085) (xy 301.409281 -24.256302) (xy 301.348488 -24.276055)
			(xy 301.285698 -24.288033) (xy 301.221902 -24.292047) (xy 301.158106 -24.288033) (xy 301.095316 -24.276055)
			(xy 301.034523 -24.256302) (xy 300.976684 -24.229085) (xy 300.922713 -24.194834) (xy 300.87346 -24.154089)
			(xy 300.829703 -24.107492) (xy 300.79213 -24.055777) (xy 300.761336 -23.999762) (xy 300.737804 -23.940329)
			(xy 300.721907 -23.878415) (xy 300.713896 -23.814997) (xy 299.44445 -23.814997) (xy 299.439845 -23.846286)
			(xy 299.423777 -23.899693) (xy 299.400105 -23.95019) (xy 299.369332 -23.996703) (xy 299.332115 -24.03824)
			(xy 299.289247 -24.073915) (xy 299.241641 -24.102969) (xy 299.190312 -24.124781) (xy 299.136355 -24.138887)
			(xy 299.080918 -24.144987) (xy 299.025184 -24.14295) (xy 298.970341 -24.13282) (xy 298.917557 -24.114813)
			(xy 298.867957 -24.089312) (xy 298.822599 -24.056861) (xy 298.78245 -24.018152) (xy 298.748364 -23.974009)
			(xy 298.721068 -23.925374) (xy 298.701145 -23.873283) (xy 298.689019 -23.818846) (xy 298.684948 -23.763224)
			(xy 272.327116 -23.763224) (xy 270.736103 -25.354237) (xy 301.901092 -25.354237) (xy 301.901092 -25.290315)
			(xy 301.909103 -25.226897) (xy 301.925 -25.164983) (xy 301.948532 -25.10555) (xy 301.979326 -25.049535)
			(xy 302.016899 -24.99782) (xy 302.060656 -24.951223) (xy 302.109909 -24.910478) (xy 302.16388 -24.876227)
			(xy 302.221719 -24.84901) (xy 302.282512 -24.829257) (xy 302.345302 -24.817279) (xy 302.409098 -24.813266)
			(xy 302.472894 -24.817279) (xy 302.535684 -24.829257) (xy 302.596477 -24.84901) (xy 302.654316 -24.876227)
			(xy 302.708287 -24.910478) (xy 302.75754 -24.951223) (xy 302.801297 -24.99782) (xy 302.83887 -25.049535)
			(xy 302.869664 -25.10555) (xy 302.893196 -25.164983) (xy 302.909093 -25.226897) (xy 302.917104 -25.290315)
			(xy 302.917606 -25.322276) (xy 302.917104 -25.354237) (xy 302.909093 -25.417655) (xy 302.893196 -25.479569)
			(xy 302.869664 -25.539002) (xy 302.83887 -25.595017) (xy 302.819084 -25.62225) (xy 304.549554 -25.62225)
			(xy 304.553625 -25.566628) (xy 304.565751 -25.512191) (xy 304.585674 -25.4601) (xy 304.61297 -25.411465)
			(xy 304.647056 -25.367322) (xy 304.687205 -25.328613) (xy 304.732563 -25.296162) (xy 304.782163 -25.270661)
			(xy 304.834947 -25.252654) (xy 304.88979 -25.242524) (xy 304.945524 -25.240487) (xy 305.000961 -25.246587)
			(xy 305.054918 -25.260693) (xy 305.106247 -25.282505) (xy 305.153853 -25.311559) (xy 305.196721 -25.347234)
			(xy 305.233938 -25.388771) (xy 305.264711 -25.435284) (xy 305.288383 -25.485781) (xy 305.304451 -25.539188)
			(xy 305.312571 -25.594364) (xy 305.31308 -25.62225) (xy 305.312571 -25.650136) (xy 305.304451 -25.705312)
			(xy 305.288383 -25.758719) (xy 305.264711 -25.809216) (xy 305.233938 -25.855729) (xy 305.196721 -25.897266)
			(xy 305.153853 -25.932941) (xy 305.106247 -25.961995) (xy 305.054918 -25.983807) (xy 305.000961 -25.997913)
			(xy 304.945524 -26.004013) (xy 304.88979 -26.001976) (xy 304.834947 -25.991846) (xy 304.782163 -25.973839)
			(xy 304.732563 -25.948338) (xy 304.687205 -25.915887) (xy 304.647056 -25.877178) (xy 304.61297 -25.833035)
			(xy 304.585674 -25.7844) (xy 304.565751 -25.732309) (xy 304.553625 -25.677872) (xy 304.549554 -25.62225)
			(xy 302.819084 -25.62225) (xy 302.801297 -25.646732) (xy 302.75754 -25.693329) (xy 302.708287 -25.734074)
			(xy 302.654316 -25.768325) (xy 302.596477 -25.795542) (xy 302.535684 -25.815295) (xy 302.472894 -25.827273)
			(xy 302.409098 -25.831287) (xy 302.345302 -25.827273) (xy 302.282512 -25.815295) (xy 302.221719 -25.795542)
			(xy 302.16388 -25.768325) (xy 302.109909 -25.734074) (xy 302.060656 -25.693329) (xy 302.016899 -25.646732)
			(xy 301.979326 -25.595017) (xy 301.948532 -25.539002) (xy 301.925 -25.479569) (xy 301.909103 -25.417655)
			(xy 301.901092 -25.354237) (xy 270.736103 -25.354237) (xy 259.372354 -36.717986) (xy 259.364028 -36.727196)
			(xy 259.356717 -36.750894) (xy 259.358384 -36.763198) (xy 259.37591 -36.858194) (xy 259.39115 -36.877498)
			(xy 259.402834 -36.882832) (xy 259.429444 -36.895236) (xy 259.478814 -36.927003) (xy 259.501132 -36.946078)
			(xy 259.508244 -36.952428) (xy 259.525516 -36.958778) (xy 259.611876 -36.958778) (xy 259.629148 -36.952428)
			(xy 259.63626 -36.946078) (xy 259.657304 -36.928045) (xy 259.703624 -36.897622) (xy 259.753861 -36.874226)
			(xy 259.806955 -36.858349) (xy 259.861789 -36.850325) (xy 259.889498 -36.849812) (xy 259.91675 -36.850275)
			(xy 259.970698 -36.858031) (xy 260.022993 -36.873387) (xy 260.072571 -36.896028) (xy 260.118422 -36.925494)
			(xy 260.159613 -36.961186) (xy 260.195305 -37.002376) (xy 260.224771 -37.048227) (xy 260.247413 -37.097805)
			(xy 260.262768 -37.1501) (xy 260.270525 -37.204048) (xy 260.270525 -37.258552) (xy 260.262768 -37.3125)
			(xy 260.247413 -37.364795) (xy 260.224771 -37.414373) (xy 260.195305 -37.460224) (xy 260.159613 -37.501414)
			(xy 260.118422 -37.537106) (xy 260.072571 -37.566572) (xy 260.022993 -37.589213) (xy 259.970698 -37.604569)
			(xy 259.91675 -37.612325) (xy 259.889498 -37.612828) (xy 259.861789 -37.61233) (xy 259.806955 -37.604304)
			(xy 259.753862 -37.588421) (xy 259.703629 -37.565016) (xy 259.657316 -37.534582) (xy 259.63626 -37.516562)
			(xy 259.629148 -37.510212) (xy 259.611876 -37.503862) (xy 259.525516 -37.503862) (xy 259.508244 -37.510212)
			(xy 259.501132 -37.516562) (xy 259.480087 -37.534593) (xy 259.433766 -37.565011) (xy 259.383529 -37.588404)
			(xy 259.330435 -37.604279) (xy 259.275602 -37.6123) (xy 259.247894 -37.612828) (xy 259.220405 -37.612347)
			(xy 259.165997 -37.604451) (xy 259.113287 -37.588823) (xy 259.063367 -37.565787) (xy 259.017273 -37.535822)
			(xy 258.975961 -37.499547) (xy 258.940285 -37.457716) (xy 258.910987 -37.411195) (xy 258.899406 -37.38626)
			(xy 258.894072 -37.374576) (xy 258.874768 -37.359336) (xy 258.779772 -37.34181) (xy 258.767471 -37.340125)
			(xy 258.74378 -37.347462) (xy 258.73456 -37.35578) (xy 258.647946 -37.442394) (xy 258.640545 -37.449233)
			(xy 258.621947 -37.456948) (xy 258.611878 -37.45738) (xy 241.188748 -37.45738) (xy 241.177898 -37.457884)
			(xy 241.158141 -37.466858) (xy 241.143879 -37.483213) (xy 241.140234 -37.493448) (xy 241.107214 -37.602668)
			(xy 241.11839 -37.634164) (xy 241.132614 -37.643562) (xy 241.186936 -37.680328) (xy 241.291465 -37.759596)
			(xy 241.390927 -37.845135) (xy 241.484946 -37.936622) (xy 241.573168 -38.033712) (xy 241.65526 -38.136038)
			(xy 241.73091 -38.243213) (xy 241.799835 -38.354833) (xy 241.861772 -38.470476) (xy 241.916489 -38.589705)
			(xy 241.963779 -38.712071) (xy 242.003463 -38.83711) (xy 242.03539 -38.96435) (xy 242.059442 -39.093312)
			(xy 242.075526 -39.223508) (xy 242.083582 -39.354445) (xy 242.084098 -39.420038) (xy 242.083592 -39.485774)
			(xy 242.075499 -39.616995) (xy 242.059342 -39.74747) (xy 242.035185 -39.876703) (xy 242.003117 -40.004203)
			(xy 241.978129 -40.082751) (xy 242.803901 -40.082751) (xy 242.803901 -40.028249) (xy 242.811658 -39.974301)
			(xy 242.827014 -39.922007) (xy 242.849656 -39.872431) (xy 242.879124 -39.826582) (xy 242.914817 -39.785393)
			(xy 242.956009 -39.749704) (xy 243.001861 -39.72024) (xy 243.051439 -39.697602) (xy 243.103735 -39.682251)
			(xy 243.157683 -39.674499) (xy 243.184934 -39.674038) (xy 243.21385 -39.674589) (xy 243.27102 -39.683309)
			(xy 243.326219 -39.70056) (xy 243.378181 -39.725945) (xy 243.425716 -39.758884) (xy 243.467734 -39.79862)
			(xy 243.485924 -39.821104) (xy 243.493479 -39.829873) (xy 243.514243 -39.840052) (xy 243.525802 -39.840662)
			(xy 243.606066 -39.840662) (xy 243.617633 -39.840085) (xy 243.638405 -39.829896) (xy 243.645944 -39.821104)
			(xy 243.664111 -39.7986) (xy 243.706136 -39.758866) (xy 243.753676 -39.725929) (xy 243.805642 -39.700544)
			(xy 243.860843 -39.683293) (xy 243.918017 -39.67457) (xy 243.946934 -39.674038) (xy 243.974187 -39.674434)
			(xy 244.028137 -39.682196) (xy 244.080434 -39.697556) (xy 244.130013 -39.720201) (xy 244.175865 -39.749672)
			(xy 244.217056 -39.785368) (xy 244.252748 -39.826562) (xy 244.282215 -39.872417) (xy 244.304856 -39.921997)
			(xy 244.320212 -39.974296) (xy 244.327968 -40.028247) (xy 244.327968 -40.082753) (xy 244.320212 -40.136704)
			(xy 244.304856 -40.189003) (xy 244.282215 -40.238583) (xy 244.252748 -40.284438) (xy 244.217056 -40.325632)
			(xy 244.175865 -40.361328) (xy 244.130013 -40.390799) (xy 244.080434 -40.413444) (xy 244.028137 -40.428804)
			(xy 243.974187 -40.436566) (xy 243.946934 -40.437054) (xy 243.918017 -40.436529) (xy 243.860845 -40.427804)
			(xy 243.805646 -40.410548) (xy 243.753684 -40.385158) (xy 243.70615 -40.352215) (xy 243.664134 -40.312474)
			(xy 243.645944 -40.289988) (xy 243.638361 -40.281248) (xy 243.617618 -40.271053) (xy 243.606066 -40.27043)
			(xy 243.525802 -40.27043) (xy 243.514233 -40.270991) (xy 243.493461 -40.281191) (xy 243.485924 -40.289988)
			(xy 243.467716 -40.312457) (xy 243.4257 -40.352194) (xy 243.378169 -40.385135) (xy 243.326211 -40.410526)
			(xy 243.271016 -40.427785) (xy 243.213849 -40.436517) (xy 243.184934 -40.437054) (xy 243.157683 -40.436501)
			(xy 243.103735 -40.428749) (xy 243.051439 -40.413398) (xy 243.001861 -40.39076) (xy 242.956009 -40.361296)
			(xy 242.914817 -40.325607) (xy 242.879124 -40.284418) (xy 242.849656 -40.238569) (xy 242.827014 -40.188993)
			(xy 242.811658 -40.136699) (xy 242.803901 -40.082751) (xy 241.978129 -40.082751) (xy 241.963261 -40.129487)
			(xy 241.915768 -40.252081) (xy 241.860819 -40.371518) (xy 241.79862 -40.487345) (xy 241.72941 -40.599124)
			(xy 241.653449 -40.706431) (xy 241.571027 -40.808857) (xy 241.482455 -40.906016) (xy 241.38807 -40.997537)
			(xy 241.288231 -41.083075) (xy 241.183314 -41.162304) (xy 241.07372 -41.234924) (xy 240.959862 -41.300659)
			(xy 240.842174 -41.359261) (xy 240.721102 -41.410507) (xy 240.597104 -41.454202) (xy 240.470652 -41.490181)
			(xy 240.342224 -41.518307) (xy 240.212309 -41.538473) (xy 240.081399 -41.550604) (xy 239.94999 -41.554653)
			(xy 239.818581 -41.550604) (xy 239.687671 -41.538473) (xy 239.557756 -41.518307) (xy 239.429328 -41.490181)
			(xy 239.302876 -41.454202) (xy 239.178878 -41.410507) (xy 239.057806 -41.359261) (xy 238.940118 -41.300659)
			(xy 238.82626 -41.234924) (xy 238.716666 -41.162304) (xy 238.611749 -41.083075) (xy 238.51191 -40.997537)
			(xy 238.417525 -40.906016) (xy 238.328953 -40.808857) (xy 238.246531 -40.706431) (xy 238.17057 -40.599124)
			(xy 238.10136 -40.487345) (xy 238.039161 -40.371518) (xy 237.984212 -40.252081) (xy 237.936719 -40.129487)
			(xy 237.896863 -40.004203) (xy 237.864795 -39.876703) (xy 237.840638 -39.74747) (xy 237.824481 -39.616995)
			(xy 237.816388 -39.485774) (xy 237.815882 -39.420038) (xy 237.816385 -39.354446) (xy 237.824447 -39.22351)
			(xy 237.840537 -39.093317) (xy 237.864593 -38.964358) (xy 237.896526 -38.83712) (xy 237.936214 -38.712084)
			(xy 237.983507 -38.589722) (xy 238.038227 -38.470496) (xy 238.100168 -38.354857) (xy 238.169095 -38.24324)
			(xy 238.244748 -38.136068) (xy 238.326841 -38.033746) (xy 238.415065 -37.93666) (xy 238.509085 -37.845176)
			(xy 238.608548 -37.75964) (xy 238.713076 -37.680375) (xy 238.767366 -37.643562) (xy 238.78159 -37.634164)
			(xy 238.792766 -37.602668) (xy 238.759746 -37.493448) (xy 238.756108 -37.483216) (xy 238.741815 -37.466895)
			(xy 238.722077 -37.457889) (xy 238.711232 -37.45738) (xy 214.021162 -37.45738) (xy 214.011094 -37.457809)
			(xy 213.992498 -37.465531) (xy 213.985094 -37.472366) (xy 213.052406 -38.405054) (xy 213.04501 -38.411906)
			(xy 213.026412 -38.41965) (xy 213.016338 -38.42004) (xy 212.918802 -38.42004) (xy 212.908733 -38.419616)
			(xy 212.890134 -38.411895) (xy 212.882734 -38.405054) (xy 212.8774 -38.39972) (xy 212.812122 -38.39972)
			(xy 212.802133 -38.400254) (xy 212.783697 -38.407964) (xy 212.776308 -38.414706) (xy 211.952452 -39.23844)
			(xy 232.433327 -39.23844) (xy 232.433327 -39.15156) (xy 232.441343 -39.065052) (xy 232.457307 -38.979652)
			(xy 232.481083 -38.89609) (xy 232.512467 -38.815078) (xy 232.551193 -38.737307) (xy 232.596929 -38.663441)
			(xy 232.649286 -38.594111) (xy 232.707817 -38.529907) (xy 232.772021 -38.471377) (xy 232.841353 -38.419021)
			(xy 232.915219 -38.373286) (xy 232.992991 -38.334562) (xy 233.074003 -38.303178) (xy 233.157566 -38.279404)
			(xy 233.242966 -38.263441) (xy 233.329474 -38.255426) (xy 233.372914 -38.25494) (xy 235.227114 -38.25494)
			(xy 235.270552 -38.255434) (xy 235.357058 -38.263451) (xy 235.442455 -38.279416) (xy 235.526014 -38.303192)
			(xy 235.607024 -38.334576) (xy 235.684792 -38.373301) (xy 235.758656 -38.419036) (xy 235.827984 -38.471391)
			(xy 235.892186 -38.529919) (xy 235.950714 -38.594122) (xy 236.003069 -38.663451) (xy 236.048803 -38.737315)
			(xy 236.087527 -38.815083) (xy 236.118911 -38.896093) (xy 236.142686 -38.979653) (xy 236.15865 -39.06505)
			(xy 236.166666 -39.151556) (xy 236.167168 -39.194994) (xy 236.166635 -39.240727) (xy 236.157774 -39.331761)
			(xy 236.140106 -39.421504) (xy 236.113797 -39.509104) (xy 236.079099 -39.593731) (xy 236.058202 -39.634414)
			(xy 236.052106 -39.645844) (xy 236.05236 -39.67099) (xy 236.104938 -39.768272) (xy 236.125766 -39.781988)
			(xy 236.13872 -39.783258) (xy 236.182616 -39.78783) (xy 236.269396 -39.803922) (xy 236.354346 -39.827866)
			(xy 236.436758 -39.85946) (xy 236.515942 -39.898442) (xy 236.59124 -39.944487) (xy 236.662022 -39.99721)
			(xy 236.727699 -40.056171) (xy 236.787722 -40.120878) (xy 236.841591 -40.190792) (xy 236.888855 -40.26533)
			(xy 236.929122 -40.343869) (xy 236.962055 -40.425755) (xy 236.987379 -40.510304) (xy 237.004883 -40.59681)
			(xy 237.014421 -40.684554) (xy 237.015914 -40.772801) (xy 237.009348 -40.860816) (xy 236.994779 -40.947866)
			(xy 236.972328 -41.033222) (xy 236.942183 -41.116175) (xy 236.904595 -41.196031) (xy 236.859878 -41.272124)
			(xy 236.808404 -41.34382) (xy 236.750603 -41.41052) (xy 236.686958 -41.471668) (xy 236.617999 -41.526754)
			(xy 236.544301 -41.575318) (xy 236.46648 -41.616955) (xy 236.385184 -41.651319) (xy 236.301092 -41.678121)
			(xy 236.214906 -41.697139) (xy 236.127343 -41.708213) (xy 236.039135 -41.711252) (xy 235.951018 -41.706231)
			(xy 235.863727 -41.69319) (xy 235.77799 -41.672239) (xy 235.694522 -41.643553) (xy 235.614019 -41.60737)
			(xy 235.537154 -41.563994) (xy 235.464567 -41.513785) (xy 235.396864 -41.457162) (xy 235.334609 -41.394598)
			(xy 235.278323 -41.326615) (xy 235.228474 -41.25378) (xy 235.185479 -41.176701) (xy 235.149696 -41.09602)
			(xy 235.121424 -41.012411) (xy 235.100898 -40.926571) (xy 235.08829 -40.839216) (xy 235.083706 -40.751075)
			(xy 235.087182 -40.662884) (xy 235.09869 -40.575377) (xy 235.118135 -40.489286) (xy 235.145354 -40.405328)
			(xy 235.18012 -40.324203) (xy 235.200698 -40.285162) (xy 235.207048 -40.273224) (xy 235.20654 -40.246554)
			(xy 235.154978 -40.15994) (xy 235.150175 -40.152568) (xy 235.136624 -40.141366) (xy 235.120081 -40.135416)
			(xy 235.11129 -40.135048) (xy 233.372914 -40.135048) (xy 233.329474 -40.134574) (xy 233.242966 -40.126559)
			(xy 233.157566 -40.110596) (xy 233.074003 -40.086822) (xy 232.992991 -40.055438) (xy 232.915219 -40.016714)
			(xy 232.841353 -39.970979) (xy 232.772021 -39.918623) (xy 232.707817 -39.860093) (xy 232.649286 -39.795889)
			(xy 232.596929 -39.726559) (xy 232.551193 -39.652693) (xy 232.512467 -39.574922) (xy 232.481083 -39.49391)
			(xy 232.457307 -39.410348) (xy 232.441343 -39.324948) (xy 232.433327 -39.23844) (xy 211.952452 -39.23844)
			(xy 211.06511 -40.12565) (xy 211.041195 -40.148807) (xy 210.988395 -40.189349) (xy 210.930758 -40.222657)
			(xy 210.869269 -40.248163) (xy 210.804978 -40.265431) (xy 210.738984 -40.274166) (xy 210.7057 -40.274748)
			(xy 204.655674 -40.274748) (xy 204.64571 -40.275228) (xy 204.627279 -40.282811) (xy 204.61986 -40.28948)
			(xy 204.594206 -40.315134) (xy 204.587364 -40.322534) (xy 204.579641 -40.341132) (xy 204.57922 -40.351202)
			(xy 204.57922 -40.6748) (xy 215.072166 -40.6748) (xy 215.076181 -40.610999) (xy 215.08816 -40.548204)
			(xy 215.107915 -40.487406) (xy 215.135135 -40.429563) (xy 215.16939 -40.375588) (xy 215.21014 -40.326332)
			(xy 215.256743 -40.282572) (xy 215.308462 -40.244999) (xy 215.364484 -40.214204) (xy 215.423923 -40.190673)
			(xy 215.485843 -40.174778) (xy 215.549266 -40.166769) (xy 215.58123 -40.16629) (xy 215.61484 -40.166843)
			(xy 215.681474 -40.17571) (xy 215.746361 -40.193272) (xy 215.80837 -40.219225) (xy 215.866423 -40.253115)
			(xy 215.919509 -40.294353) (xy 215.966704 -40.342221) (xy 215.987376 -40.368728) (xy 215.993726 -40.377364)
			(xy 216.01176 -40.387524) (xy 216.106502 -40.397938) (xy 216.12606 -40.392096) (xy 216.134188 -40.384984)
			(xy 216.154998 -40.367949) (xy 216.200471 -40.339238) (xy 216.249527 -40.317201) (xy 216.301191 -40.302273)
			(xy 216.354441 -40.294751) (xy 216.38133 -40.294306) (xy 216.408581 -40.294766) (xy 216.462527 -40.302526)
			(xy 216.51482 -40.317884) (xy 216.564396 -40.340528) (xy 216.610244 -40.369996) (xy 216.651432 -40.405689)
			(xy 216.687122 -40.44688) (xy 216.716586 -40.492731) (xy 216.739226 -40.542308) (xy 216.75458 -40.594602)
			(xy 216.762336 -40.648549) (xy 216.762336 -40.703051) (xy 216.75458 -40.756998) (xy 216.739226 -40.809292)
			(xy 216.716586 -40.858869) (xy 216.687122 -40.90472) (xy 216.651432 -40.945911) (xy 216.610244 -40.981604)
			(xy 216.564396 -41.011072) (xy 216.51482 -41.033716) (xy 216.462527 -41.049074) (xy 216.408581 -41.056834)
			(xy 216.38133 -41.057322) (xy 216.354361 -41.056827) (xy 216.300963 -41.049226) (xy 216.249169 -41.034172)
			(xy 216.200015 -41.011965) (xy 216.154484 -40.98305) (xy 216.13368 -40.965882) (xy 216.125298 -40.959024)
			(xy 216.10574 -40.952928) (xy 216.010998 -40.963088) (xy 215.992964 -40.973248) (xy 215.986614 -40.981884)
			(xy 215.965942 -41.008279) (xy 215.918783 -41.055934) (xy 215.86577 -41.096978) (xy 215.807823 -41.1307)
			(xy 215.745948 -41.156514) (xy 215.681217 -41.173973) (xy 215.614752 -41.182775) (xy 215.58123 -41.183306)
			(xy 215.549266 -41.182831) (xy 215.485843 -41.174822) (xy 215.423923 -41.158927) (xy 215.364484 -41.135396)
			(xy 215.308462 -41.104601) (xy 215.256743 -41.067028) (xy 215.21014 -41.023268) (xy 215.16939 -40.974012)
			(xy 215.135135 -40.920037) (xy 215.107915 -40.862194) (xy 215.08816 -40.801396) (xy 215.076181 -40.738601)
			(xy 215.072166 -40.6748) (xy 204.57922 -40.6748) (xy 204.57922 -41.320466) (xy 204.579752 -41.330456)
			(xy 204.587459 -41.348895) (xy 204.594206 -41.35628) (xy 205.266826 -42.0289) (xy 208.440261 -42.0289)
			(xy 208.444275 -41.965101) (xy 208.456253 -41.902309) (xy 208.476007 -41.841513) (xy 208.503225 -41.783672)
			(xy 208.537477 -41.729698) (xy 208.578224 -41.680443) (xy 208.624822 -41.636683) (xy 208.676538 -41.599108)
			(xy 208.732555 -41.568311) (xy 208.791991 -41.544778) (xy 208.853907 -41.52888) (xy 208.917328 -41.520867)
			(xy 208.94929 -41.520364) (xy 208.979827 -41.520794) (xy 209.040462 -41.528101) (xy 209.099784 -41.542624)
			(xy 209.156937 -41.564152) (xy 209.211099 -41.592375) (xy 209.252745 -41.6209) (xy 211.637116 -41.6209)
			(xy 211.64113 -41.557105) (xy 211.653109 -41.494316) (xy 211.672862 -41.433523) (xy 211.70008 -41.375686)
			(xy 211.734332 -41.321716) (xy 211.775078 -41.272465) (xy 211.821676 -41.228709) (xy 211.873391 -41.191139)
			(xy 211.929408 -41.160348) (xy 211.988841 -41.13682) (xy 212.050755 -41.120926) (xy 212.114173 -41.112919)
			(xy 212.146134 -41.11244) (xy 212.176349 -41.112905) (xy 212.23635 -41.120086) (xy 212.295078 -41.134329)
			(xy 212.351702 -41.155435) (xy 212.405424 -41.183105) (xy 212.455488 -41.216949) (xy 212.47862 -41.236392)
			(xy 212.485752 -41.242025) (xy 212.50281 -41.248265) (xy 212.511894 -41.248584) (xy 212.542374 -41.248584)
			(xy 212.551457 -41.248277) (xy 212.568508 -41.242017) (xy 212.575648 -41.236392) (xy 212.598777 -41.216945)
			(xy 212.648844 -41.183106) (xy 212.702568 -41.155437) (xy 212.759192 -41.13433) (xy 212.817918 -41.12008)
			(xy 212.877919 -41.112888) (xy 212.908134 -41.11244) (xy 212.940097 -41.112848) (xy 213.003518 -41.120863)
			(xy 213.065434 -41.136765) (xy 213.124869 -41.1603) (xy 213.180886 -41.191099) (xy 213.232601 -41.228675)
			(xy 213.279199 -41.272437) (xy 213.319945 -41.321694) (xy 213.354197 -41.375669) (xy 213.381414 -41.43351)
			(xy 213.401167 -41.494307) (xy 213.413145 -41.557101) (xy 213.417159 -41.6209) (xy 213.413145 -41.684699)
			(xy 213.401167 -41.747493) (xy 213.381414 -41.80829) (xy 213.354197 -41.866132) (xy 213.319945 -41.920106)
			(xy 213.279199 -41.969363) (xy 213.232601 -42.013125) (xy 213.180886 -42.050701) (xy 213.124869 -42.0815)
			(xy 213.065434 -42.105035) (xy 213.003518 -42.120937) (xy 212.940097 -42.128952) (xy 212.908134 -42.129456)
			(xy 212.877919 -42.129011) (xy 212.817916 -42.121826) (xy 212.759189 -42.107579) (xy 212.702564 -42.08647)
			(xy 212.648842 -42.058796) (xy 212.59878 -42.024948) (xy 212.575648 -42.005504) (xy 212.568497 -41.999899)
			(xy 212.551453 -41.993642) (xy 212.542374 -41.993312) (xy 212.511894 -41.993312) (xy 212.502814 -41.993652)
			(xy 212.485763 -41.999889) (xy 212.47862 -42.005504) (xy 212.455503 -42.024966) (xy 212.405433 -42.058803)
			(xy 212.351706 -42.086469) (xy 212.29508 -42.107575) (xy 212.236352 -42.121822) (xy 212.17635 -42.12901)
			(xy 212.146134 -42.129456) (xy 212.114173 -42.128881) (xy 212.050755 -42.120874) (xy 211.988841 -42.10498)
			(xy 211.929408 -42.081452) (xy 211.873391 -42.050661) (xy 211.821676 -42.013091) (xy 211.775078 -41.969335)
			(xy 211.734332 -41.920084) (xy 211.70008 -41.866114) (xy 211.672862 -41.808277) (xy 211.653109 -41.747484)
			(xy 211.64113 -41.684695) (xy 211.637116 -41.6209) (xy 209.252745 -41.6209) (xy 209.261486 -41.626887)
			(xy 209.307374 -41.667189) (xy 209.348101 -41.712701) (xy 209.383078 -41.762767) (xy 209.411803 -41.816664)
			(xy 209.423254 -41.844976) (xy 209.426991 -41.853415) (xy 209.439357 -41.867093) (xy 209.447384 -41.871646)
			(xy 209.474562 -41.885616) (xy 209.482879 -41.889519) (xy 209.501108 -41.891718) (xy 209.510122 -41.889934)
			(xy 209.540663 -41.882696) (xy 209.602945 -41.874922) (xy 209.634328 -41.87444) (xy 209.666291 -41.874847)
			(xy 209.729712 -41.882862) (xy 209.791629 -41.898763) (xy 209.851065 -41.922298) (xy 209.907083 -41.953097)
			(xy 209.958799 -41.990673) (xy 210.005397 -42.034435) (xy 210.046144 -42.083692) (xy 210.080396 -42.137667)
			(xy 210.107614 -42.195509) (xy 210.127367 -42.256307) (xy 210.139345 -42.3191) (xy 210.143359 -42.3829)
			(xy 210.139345 -42.4467) (xy 210.127367 -42.509493) (xy 210.107614 -42.570291) (xy 210.080396 -42.628133)
			(xy 210.046144 -42.682108) (xy 210.005397 -42.731365) (xy 209.958799 -42.775127) (xy 209.907083 -42.812703)
			(xy 209.851065 -42.843502) (xy 209.791629 -42.867037) (xy 209.729712 -42.882938) (xy 209.666291 -42.890953)
			(xy 209.634328 -42.891456) (xy 209.603792 -42.890997) (xy 209.543159 -42.883693) (xy 209.483838 -42.869173)
			(xy 209.426685 -42.847648) (xy 209.372525 -42.819428) (xy 209.322137 -42.784919) (xy 209.276249 -42.74462)
			(xy 209.235521 -42.699111) (xy 209.200542 -42.649049) (xy 209.171816 -42.595155) (xy 209.160364 -42.566844)
			(xy 209.156614 -42.558412) (xy 209.144258 -42.54473) (xy 209.136234 -42.540174) (xy 209.109056 -42.526204)
			(xy 209.100735 -42.52231) (xy 209.082509 -42.520105) (xy 209.073496 -42.521886) (xy 209.042959 -42.529139)
			(xy 208.980674 -42.536904) (xy 208.94929 -42.53738) (xy 208.917328 -42.536933) (xy 208.853907 -42.52892)
			(xy 208.791991 -42.513022) (xy 208.732555 -42.489489) (xy 208.676538 -42.458692) (xy 208.624822 -42.421117)
			(xy 208.578224 -42.377357) (xy 208.537477 -42.328102) (xy 208.503225 -42.274128) (xy 208.476007 -42.216287)
			(xy 208.456253 -42.155491) (xy 208.444275 -42.092699) (xy 208.440261 -42.0289) (xy 205.266826 -42.0289)
			(xy 206.40294 -43.165014) (xy 206.410283 -43.171828) (xy 206.428747 -43.179559) (xy 206.438754 -43.18)
			(xy 217.082878 -43.18) (xy 217.092942 -43.179562) (xy 217.111526 -43.171828) (xy 217.118946 -43.165014)
			(xy 219.595954 -40.688006) (xy 219.603355 -40.681167) (xy 219.621953 -40.673452) (xy 219.632022 -40.67302)
			(xy 228.482398 -40.67302) (xy 228.492468 -40.673443) (xy 228.511071 -40.681159) (xy 228.518466 -40.688006)
			(xy 231.315514 -43.485054) (xy 231.322911 -43.491903) (xy 231.34151 -43.49964) (xy 231.351582 -43.50004)
		)
		(stroke
			(width 0)
			(type solid)
		)
		(fill yes)
		(layer "In15.Cu")
		(net "P5V_AUX")
	)
	(gr_poly
		(pts
			(xy 88.143334 -388.287514) (xy 88.14689 -388.26948) (xy 88.152064 -388.245743) (xy 88.168913 -388.20018)
			(xy 88.192757 -388.157856) (xy 88.222997 -388.119836) (xy 88.240616 -388.10311) (xy 88.248998 -388.09549)
			(xy 88.257634 -388.075424) (xy 88.25484 -387.97611) (xy 88.245442 -387.956552) (xy 88.236552 -387.94944)
			(xy 88.217988 -387.933639) (xy 88.185257 -387.897514) (xy 88.15818 -387.856978) (xy 88.137343 -387.812908)
			(xy 88.123199 -387.766257) (xy 88.116052 -387.718036) (xy 88.115648 -387.693662) (xy 88.116087 -387.669546)
			(xy 88.123093 -387.621826) (xy 88.136953 -387.575629) (xy 88.157371 -387.531933) (xy 88.170258 -387.511544)
			(xy 88.1761 -387.502654) (xy 88.179656 -387.482588) (xy 88.158574 -387.390386) (xy 88.146382 -387.373622)
			(xy 88.137492 -387.368288) (xy 88.116688 -387.355434) (xy 88.078767 -387.324558) (xy 88.045812 -387.288428)
			(xy 88.018544 -387.247835) (xy 87.99756 -387.203664) (xy 87.983317 -387.156883) (xy 87.976127 -387.108513)
			(xy 87.975694 -387.084062) (xy 87.976255 -387.056779) (xy 87.985216 -387.002955) (xy 88.002888 -386.951331)
			(xy 88.028792 -386.903306) (xy 88.062226 -386.860184) (xy 88.081866 -386.841238) (xy 88.089319 -386.833748)
			(xy 88.097867 -386.814452) (xy 88.098376 -386.8039) (xy 88.098376 -386.729224) (xy 88.097789 -386.718689)
			(xy 88.089259 -386.699415) (xy 88.081866 -386.691886) (xy 88.06221 -386.672954) (xy 88.028765 -386.629834)
			(xy 88.002854 -386.581807) (xy 87.985182 -386.530178) (xy 87.976227 -386.476347) (xy 87.975694 -386.449062)
			(xy 87.975948 -386.43687) (xy 87.976202 -386.427218) (xy 87.970106 -386.409184) (xy 87.911432 -386.341874)
			(xy 87.894668 -386.333238) (xy 87.884762 -386.332222) (xy 87.857849 -386.328871) (xy 87.805549 -386.314527)
			(xy 87.756291 -386.291839) (xy 87.711397 -386.261415) (xy 87.67207 -386.224073) (xy 87.639365 -386.180813)
			(xy 87.614159 -386.132795) (xy 87.597128 -386.081307) (xy 87.592408 -386.0546) (xy 87.590884 -386.045202)
			(xy 87.318088 -385.57327) (xy 87.310722 -385.567428) (xy 87.291944 -385.551624) (xy 87.258812 -385.515417)
			(xy 87.231393 -385.474712) (xy 87.210289 -385.430403) (xy 87.195964 -385.383462) (xy 87.18873 -385.334919)
			(xy 87.188294 -385.31038) (xy 87.188805 -385.284394) (xy 87.196938 -385.233062) (xy 87.213001 -385.183634)
			(xy 87.236598 -385.137328) (xy 87.267148 -385.095282) (xy 87.303899 -385.058534) (xy 87.345946 -385.027986)
			(xy 87.392255 -385.004392) (xy 87.441683 -384.988333) (xy 87.493016 -384.980203) (xy 87.519002 -384.979672)
			(xy 87.545013 -384.980157) (xy 87.596392 -384.988304) (xy 87.645862 -385.004396) (xy 87.692201 -385.028037)
			(xy 87.734267 -385.058643) (xy 87.77102 -385.095459) (xy 87.801555 -385.137576) (xy 87.825118 -385.183955)
			(xy 87.841126 -385.233452) (xy 87.845646 -385.259072) (xy 87.84717 -385.26847) (xy 88.119966 -385.740402)
			(xy 88.127332 -385.746244) (xy 88.146109 -385.762049) (xy 88.179238 -385.798258) (xy 88.206656 -385.838963)
			(xy 88.22776 -385.883271) (xy 88.242088 -385.930211) (xy 88.249324 -385.978753) (xy 88.24976 -386.003292)
			(xy 88.249506 -386.015484) (xy 88.249252 -386.025136) (xy 88.255348 -386.04317) (xy 88.314022 -386.11048)
			(xy 88.330786 -386.119116) (xy 88.340692 -386.120132) (xy 88.367461 -386.123458) (xy 88.41949 -386.137681)
			(xy 88.468522 -386.160157) (xy 88.513257 -386.190292) (xy 88.552509 -386.227286) (xy 88.585239 -386.270159)
			(xy 88.610579 -386.317774) (xy 88.627857 -386.368871) (xy 88.636615 -386.422093) (xy 88.63711 -386.449062)
			(xy 88.636547 -386.476344) (xy 88.627583 -386.530166) (xy 88.609908 -386.581788) (xy 88.584002 -386.62981)
			(xy 88.550567 -386.672929) (xy 88.530938 -386.691886) (xy 88.523489 -386.699377) (xy 88.514948 -386.718673)
			(xy 88.514428 -386.729224) (xy 88.514428 -386.8039) (xy 88.51502 -386.814432) (xy 88.523557 -386.833699)
			(xy 88.530938 -386.841238) (xy 88.550593 -386.860171) (xy 88.584034 -386.903292) (xy 88.609941 -386.951319)
			(xy 88.627609 -387.002948) (xy 88.63656 -387.056778) (xy 88.63711 -387.084062) (xy 88.636677 -387.10818)
			(xy 88.629681 -387.155905) (xy 88.615833 -387.202109) (xy 88.595425 -387.245814) (xy 88.5825 -387.26618)
			(xy 88.576658 -387.27507) (xy 88.573102 -387.295136) (xy 88.594184 -387.387338) (xy 88.606376 -387.404102)
			(xy 88.615266 -387.409436) (xy 88.636066 -387.422293) (xy 88.673979 -387.453173) (xy 88.706925 -387.489304)
			(xy 88.734185 -387.529898) (xy 88.755162 -387.574067) (xy 88.769399 -387.620846) (xy 88.776583 -387.669213)
			(xy 88.777064 -387.693662) (xy 88.776626 -387.718033) (xy 88.769471 -387.766246) (xy 88.755323 -387.81289)
			(xy 88.734489 -387.856954) (xy 88.70742 -387.897488) (xy 88.6747 -387.933615) (xy 88.65616 -387.94944)
			(xy 88.64727 -387.956552) (xy 88.637872 -387.97611) (xy 88.635078 -388.075424) (xy 88.643714 -388.09549)
			(xy 88.652096 -388.10311) (xy 88.669729 -388.119825) (xy 88.699988 -388.157835) (xy 88.723839 -388.200162)
			(xy 88.740678 -388.245735) (xy 88.745822 -388.26948) (xy 88.749378 -388.287514) (xy 88.777318 -388.310628)
			(xy 89.31529 -388.310628) (xy 89.34323 -388.287514) (xy 89.346786 -388.26948) (xy 89.35196 -388.245743)
			(xy 89.368808 -388.20018) (xy 89.392653 -388.157855) (xy 89.422892 -388.119836) (xy 89.440512 -388.10311)
			(xy 89.448894 -388.09549) (xy 89.45753 -388.075424) (xy 89.454736 -387.97611) (xy 89.445338 -387.956552)
			(xy 89.436448 -387.94944) (xy 89.417885 -387.933639) (xy 89.385153 -387.897514) (xy 89.358077 -387.856978)
			(xy 89.33724 -387.812907) (xy 89.323096 -387.766257) (xy 89.315949 -387.718036) (xy 89.315544 -387.693662)
			(xy 89.315983 -387.669546) (xy 89.322989 -387.621826) (xy 89.336848 -387.575629) (xy 89.357266 -387.531932)
			(xy 89.370154 -387.511544) (xy 89.375996 -387.502654) (xy 89.379552 -387.482588) (xy 89.35847 -387.390386)
			(xy 89.346278 -387.373622) (xy 89.337388 -387.368288) (xy 89.316584 -387.355434) (xy 89.278663 -387.324558)
			(xy 89.245709 -387.288428) (xy 89.218442 -387.247834) (xy 89.197458 -387.203664) (xy 89.183215 -387.156883)
			(xy 89.176025 -387.108513) (xy 89.17559 -387.084062) (xy 89.176151 -387.056779) (xy 89.185112 -387.002955)
			(xy 89.202784 -386.95133) (xy 89.228688 -386.903306) (xy 89.262121 -386.860183) (xy 89.281762 -386.841238)
			(xy 89.289215 -386.833748) (xy 89.297765 -386.814452) (xy 89.298272 -386.8039) (xy 89.298272 -386.729224)
			(xy 89.297685 -386.718689) (xy 89.289154 -386.699416) (xy 89.281762 -386.691886) (xy 89.262106 -386.672954)
			(xy 89.228661 -386.629834) (xy 89.202751 -386.581807) (xy 89.185079 -386.530178) (xy 89.176124 -386.476347)
			(xy 89.17559 -386.449062) (xy 89.175844 -386.43687) (xy 89.176098 -386.427218) (xy 89.170002 -386.409184)
			(xy 89.111328 -386.341874) (xy 89.094564 -386.333238) (xy 89.084658 -386.332222) (xy 89.057745 -386.328871)
			(xy 89.005445 -386.314526) (xy 88.956188 -386.291837) (xy 88.911295 -386.261414) (xy 88.871968 -386.224072)
			(xy 88.839264 -386.180812) (xy 88.814058 -386.132794) (xy 88.797027 -386.081306) (xy 88.792304 -386.0546)
			(xy 88.79078 -386.045202) (xy 88.51773 -385.572762) (xy 88.510618 -385.56692) (xy 88.491882 -385.551142)
			(xy 88.458824 -385.515) (xy 88.431461 -385.474375) (xy 88.410394 -385.430156) (xy 88.396083 -385.383313)
			(xy 88.388842 -385.33487) (xy 88.388444 -385.31038) (xy 88.388955 -385.284392) (xy 88.397088 -385.233058)
			(xy 88.41315 -385.183627) (xy 88.436746 -385.137316) (xy 88.467295 -385.095267) (xy 88.504046 -385.058514)
			(xy 88.546093 -385.027961) (xy 88.592401 -385.004361) (xy 88.64183 -384.988294) (xy 88.693165 -384.980157)
			(xy 88.719152 -384.979672) (xy 88.745197 -384.980156) (xy 88.796646 -384.988314) (xy 88.846179 -385.004437)
			(xy 88.892572 -385.028125) (xy 88.934678 -385.058792) (xy 88.971456 -385.095682) (xy 89.001997 -385.13788)
			(xy 89.025545 -385.184345) (xy 89.041518 -385.233926) (xy 89.04605 -385.25958) (xy 89.04732 -385.268978)
			(xy 89.071256 -385.31038) (xy 89.58834 -385.31038) (xy 89.588757 -385.284388) (xy 89.596893 -385.233044)
			(xy 89.61296 -385.183605) (xy 89.636565 -385.137289) (xy 89.667125 -385.095235) (xy 89.703887 -385.05848)
			(xy 89.745947 -385.027929) (xy 89.792268 -385.004334) (xy 89.84171 -384.988277) (xy 89.893056 -384.980152)
			(xy 89.919048 -384.979672) (xy 89.94506 -384.980098) (xy 89.996438 -384.988264) (xy 90.045905 -385.004371)
			(xy 90.092241 -385.028023) (xy 90.134304 -385.058636) (xy 90.171057 -385.095456) (xy 90.201593 -385.137575)
			(xy 90.22516 -385.183954) (xy 90.241177 -385.23345) (xy 90.245692 -385.259072) (xy 90.247216 -385.26847)
			(xy 90.520012 -385.740402) (xy 90.527378 -385.746244) (xy 90.546155 -385.762047) (xy 90.579273 -385.798263)
			(xy 90.606684 -385.838971) (xy 90.627785 -385.883279) (xy 90.642115 -385.930216) (xy 90.64936 -385.978754)
			(xy 90.649806 -386.003292) (xy 90.649552 -386.015484) (xy 90.649298 -386.025136) (xy 90.655394 -386.04317)
			(xy 90.714068 -386.11048) (xy 90.730832 -386.119116) (xy 90.740484 -386.120132) (xy 90.767244 -386.123504)
			(xy 90.819267 -386.137724) (xy 90.868293 -386.160197) (xy 90.913022 -386.190327) (xy 90.95227 -386.227316)
			(xy 90.984996 -386.270183) (xy 91.010333 -386.317792) (xy 91.027609 -386.368881) (xy 91.036366 -386.422097)
			(xy 91.036902 -386.449062) (xy 91.036392 -386.475049) (xy 91.028262 -386.526384) (xy 91.012201 -386.575814)
			(xy 90.988605 -386.622124) (xy 90.958055 -386.664172) (xy 90.921304 -386.700923) (xy 90.879256 -386.731473)
			(xy 90.832946 -386.755069) (xy 90.783516 -386.77113) (xy 90.732181 -386.77926) (xy 90.680207 -386.77926)
			(xy 90.628872 -386.77113) (xy 90.579442 -386.755069) (xy 90.533132 -386.731473) (xy 90.491084 -386.700923)
			(xy 90.454333 -386.664172) (xy 90.423783 -386.622124) (xy 90.400187 -386.575814) (xy 90.384126 -386.526384)
			(xy 90.375996 -386.475049) (xy 90.375486 -386.449062) (xy 90.37574 -386.43687) (xy 90.375994 -386.427218)
			(xy 90.369898 -386.409184) (xy 90.311224 -386.341874) (xy 90.29446 -386.333238) (xy 90.284808 -386.332222)
			(xy 90.257907 -386.328812) (xy 90.205621 -386.314456) (xy 90.156378 -386.291764) (xy 90.111495 -386.261345)
			(xy 90.072173 -386.224013) (xy 90.039468 -386.180767) (xy 90.014253 -386.132767) (xy 89.997204 -386.081296)
			(xy 89.992454 -386.0546) (xy 89.99093 -386.045202) (xy 89.718134 -385.57327) (xy 89.710768 -385.567428)
			(xy 89.692015 -385.551599) (xy 89.658896 -385.515387) (xy 89.631485 -385.474684) (xy 89.61038 -385.430382)
			(xy 89.596044 -385.38345) (xy 89.58879 -385.334916) (xy 89.58834 -385.31038) (xy 89.071256 -385.31038)
			(xy 89.319862 -385.740402) (xy 89.327228 -385.746244) (xy 89.346005 -385.762049) (xy 89.379135 -385.798257)
			(xy 89.406553 -385.838962) (xy 89.427657 -385.883271) (xy 89.441985 -385.930211) (xy 89.449221 -385.978753)
			(xy 89.449656 -386.003292) (xy 89.449402 -386.015484) (xy 89.449148 -386.025136) (xy 89.455244 -386.04317)
			(xy 89.513918 -386.11048) (xy 89.530682 -386.119116) (xy 89.540588 -386.120132) (xy 89.567357 -386.123457)
			(xy 89.619386 -386.13768) (xy 89.668419 -386.160156) (xy 89.713155 -386.190291) (xy 89.752408 -386.227285)
			(xy 89.785138 -386.270158) (xy 89.810478 -386.317774) (xy 89.827756 -386.36887) (xy 89.836514 -386.422093)
			(xy 89.837006 -386.449062) (xy 89.836443 -386.476344) (xy 89.827479 -386.530166) (xy 89.809804 -386.581788)
			(xy 89.783898 -386.629809) (xy 89.750462 -386.672929) (xy 89.730834 -386.691886) (xy 89.723385 -386.699377)
			(xy 89.714845 -386.718673) (xy 89.714324 -386.729224) (xy 89.714324 -386.8039) (xy 89.714915 -386.814433)
			(xy 89.723452 -386.8337) (xy 89.730834 -386.841238) (xy 89.750489 -386.860171) (xy 89.783931 -386.903291)
			(xy 89.809838 -386.951318) (xy 89.827507 -387.002948) (xy 89.836457 -387.056777) (xy 89.837006 -387.084062)
			(xy 89.836573 -387.10818) (xy 89.829577 -387.155905) (xy 89.815729 -387.202109) (xy 89.795321 -387.245814)
			(xy 89.782396 -387.26618) (xy 89.776554 -387.27507) (xy 89.772998 -387.295136) (xy 89.79408 -387.387338)
			(xy 89.806272 -387.404102) (xy 89.815162 -387.409436) (xy 89.835962 -387.422292) (xy 89.873875 -387.453172)
			(xy 89.906822 -387.489304) (xy 89.934082 -387.529898) (xy 89.95506 -387.574067) (xy 89.969296 -387.620846)
			(xy 89.976481 -387.669213) (xy 89.97696 -387.693662) (xy 89.976522 -387.718033) (xy 89.969367 -387.766246)
			(xy 89.955219 -387.812889) (xy 89.934385 -387.856954) (xy 89.907315 -387.897488) (xy 89.874595 -387.933614)
			(xy 89.856056 -387.94944) (xy 89.847166 -387.956552) (xy 89.837768 -387.97611) (xy 89.834974 -388.075424)
			(xy 89.84361 -388.09549) (xy 89.851992 -388.10311) (xy 89.869626 -388.119825) (xy 89.899885 -388.157835)
			(xy 89.923736 -388.200162) (xy 89.940575 -388.245734) (xy 89.945718 -388.26948) (xy 89.949274 -388.287514)
			(xy 89.977214 -388.310628) (xy 90.515186 -388.310628) (xy 90.543126 -388.287514) (xy 90.546682 -388.26948)
			(xy 90.551943 -388.245324) (xy 90.569217 -388.199005) (xy 90.593729 -388.156075) (xy 90.624838 -388.117655)
			(xy 90.661732 -388.084751) (xy 90.703445 -388.058222) (xy 90.748889 -388.038761) (xy 90.796875 -388.026877)
			(xy 90.846148 -388.022881) (xy 90.895421 -388.026877) (xy 90.943407 -388.038761) (xy 90.988851 -388.058222)
			(xy 91.030564 -388.084751) (xy 91.067458 -388.117655) (xy 91.098567 -388.156075) (xy 91.123079 -388.199005)
			(xy 91.140353 -388.245324) (xy 91.145614 -388.26948) (xy 91.14917 -388.287514) (xy 91.17711 -388.310628)
			(xy 91.421204 -388.310628) (xy 91.431275 -388.310205) (xy 91.449881 -388.302493) (xy 91.457272 -388.295642)
			(xy 91.621356 -388.131558) (xy 91.628137 -388.124134) (xy 91.635743 -388.105538) (xy 91.636088 -388.09549)
			(xy 91.636088 -387.89737) (xy 91.631516 -387.886956) (xy 91.617986 -387.856546) (xy 91.598879 -387.792791)
			(xy 91.589211 -387.72694) (xy 91.58859 -387.693662) (xy 91.589204 -387.660383) (xy 91.598874 -387.594532)
			(xy 91.617976 -387.530774) (xy 91.631516 -387.500368) (xy 91.636088 -387.489954) (xy 91.636088 -387.46684)
			(xy 91.626436 -387.44652) (xy 91.617546 -387.439154) (xy 91.595303 -387.420478) (xy 91.555248 -387.378419)
			(xy 91.520836 -387.331631) (xy 91.492619 -387.280866) (xy 91.471051 -387.226939) (xy 91.456479 -387.170716)
			(xy 91.449136 -387.113102) (xy 91.448636 -387.084062) (xy 91.449081 -387.055137) (xy 91.456375 -386.997747)
			(xy 91.470841 -386.941735) (xy 91.49225 -386.887991) (xy 91.520259 -386.837373) (xy 91.554423 -386.790687)
			(xy 91.594196 -386.748678) (xy 91.616276 -386.729986) (xy 91.623346 -386.723719) (xy 91.632625 -386.707277)
			(xy 91.63431 -386.697982) (xy 91.638628 -386.666994) (xy 91.639576 -386.657756) (xy 91.635544 -386.639644)
			(xy 91.630754 -386.631688) (xy 91.61772 -386.611291) (xy 91.597118 -386.567489) (xy 91.58313 -386.521149)
			(xy 91.576055 -386.473264) (xy 91.575636 -386.449062) (xy 91.57589 -386.43687) (xy 91.576144 -386.427218)
			(xy 91.570048 -386.409184) (xy 91.511374 -386.341874) (xy 91.49461 -386.333238) (xy 91.484704 -386.332222)
			(xy 91.457788 -386.328874) (xy 91.405483 -386.314535) (xy 91.35622 -386.29185) (xy 91.31132 -386.261429)
			(xy 91.271988 -386.224086) (xy 91.239278 -386.180825) (xy 91.214068 -386.132805) (xy 91.197034 -386.081314)
			(xy 91.19235 -386.0546) (xy 91.190826 -386.045202) (xy 90.91803 -385.57327) (xy 90.910664 -385.567428)
			(xy 90.891884 -385.551625) (xy 90.858748 -385.51542) (xy 90.831326 -385.474715) (xy 90.810219 -385.430406)
			(xy 90.795891 -385.383464) (xy 90.788657 -385.33492) (xy 90.788236 -385.31038) (xy 90.788721 -385.284393)
			(xy 90.796855 -385.233059) (xy 90.812919 -385.18363) (xy 90.836519 -385.137323) (xy 90.867072 -385.095278)
			(xy 90.903827 -385.05853) (xy 90.945878 -385.027985) (xy 90.99219 -385.004395) (xy 91.041622 -384.98834)
			(xy 91.092957 -384.980216) (xy 91.118944 -384.979672) (xy 91.144957 -384.980153) (xy 91.196344 -384.988292)
			(xy 91.245821 -385.004379) (xy 91.292168 -385.028017) (xy 91.334241 -385.058621) (xy 91.371002 -385.095438)
			(xy 91.401543 -385.137557) (xy 91.425111 -385.183939) (xy 91.441124 -385.233441) (xy 91.445588 -385.259072)
			(xy 91.447112 -385.26847) (xy 91.719908 -385.740402) (xy 91.727274 -385.746244) (xy 91.746053 -385.762047)
			(xy 91.779189 -385.798254) (xy 91.806611 -385.838958) (xy 91.827719 -385.883267) (xy 91.842049 -385.930208)
			(xy 91.849287 -385.978752) (xy 91.849702 -386.003292) (xy 91.849448 -386.015484) (xy 91.849194 -386.025136)
			(xy 91.85529 -386.04317) (xy 91.913964 -386.11048) (xy 91.930728 -386.119116) (xy 91.940634 -386.120132)
			(xy 91.967068 -386.123421) (xy 92.018478 -386.137358) (xy 92.066989 -386.159356) (xy 92.111345 -386.188847)
			(xy 92.1504 -386.225067) (xy 92.183144 -386.26708) (xy 92.208729 -386.313798) (xy 92.226493 -386.364014)
			(xy 92.231718 -386.390134) (xy 92.23502 -386.408422) (xy 92.263214 -386.43179) (xy 92.436188 -386.43179)
			(xy 92.44654 -386.431361) (xy 92.465594 -386.423277) (xy 92.479885 -386.408304) (xy 92.48394 -386.39877)
			(xy 92.522802 -386.29463) (xy 92.514928 -386.263896) (xy 92.502736 -386.253482) (xy 92.485437 -386.237983)
			(xy 92.454925 -386.202964) (xy 92.429613 -386.16402) (xy 92.41 -386.121917) (xy 92.396472 -386.077485)
			(xy 92.3925 -386.0546) (xy 92.390976 -386.045202) (xy 92.11818 -385.57327) (xy 92.110814 -385.567428)
			(xy 92.092037 -385.551624) (xy 92.058905 -385.515416) (xy 92.031487 -385.474711) (xy 92.010384 -385.430402)
			(xy 91.996058 -385.383461) (xy 91.988825 -385.334919) (xy 91.988386 -385.31038) (xy 91.988897 -385.284394)
			(xy 91.99703 -385.233061) (xy 92.013093 -385.183633) (xy 92.03669 -385.137326) (xy 92.06724 -385.09528)
			(xy 92.103991 -385.05853) (xy 92.146038 -385.027982) (xy 92.192346 -385.004387) (xy 92.241775 -384.988327)
			(xy 92.293108 -384.980196) (xy 92.319094 -384.979672) (xy 92.345105 -384.980157) (xy 92.396485 -384.988302)
			(xy 92.445956 -385.004394) (xy 92.492297 -385.028034) (xy 92.534363 -385.05864) (xy 92.571118 -385.095456)
			(xy 92.601653 -385.137573) (xy 92.625217 -385.183953) (xy 92.641226 -385.233451) (xy 92.645738 -385.259072)
			(xy 92.647262 -385.26847) (xy 92.920058 -385.740402) (xy 92.927424 -385.746244) (xy 92.946201 -385.762049)
			(xy 92.979332 -385.798257) (xy 93.00675 -385.838962) (xy 93.027855 -385.883271) (xy 93.042182 -385.930211)
			(xy 93.049419 -385.978753) (xy 93.049852 -386.003292) (xy 93.049598 -386.015484) (xy 93.049344 -386.025136)
			(xy 93.05544 -386.04317) (xy 93.114114 -386.11048) (xy 93.130878 -386.119116) (xy 93.14053 -386.120132)
			(xy 93.166964 -386.123421) (xy 93.218375 -386.137357) (xy 93.266886 -386.159355) (xy 93.311243 -386.188846)
			(xy 93.350299 -386.225066) (xy 93.383043 -386.267079) (xy 93.408628 -386.313797) (xy 93.426392 -386.364013)
			(xy 93.431614 -386.390134) (xy 93.434916 -386.408422) (xy 93.46311 -386.43179) (xy 93.636084 -386.43179)
			(xy 93.646436 -386.431362) (xy 93.665492 -386.423278) (xy 93.679784 -386.408306) (xy 93.683836 -386.39877)
			(xy 93.722698 -386.29463) (xy 93.714824 -386.263896) (xy 93.702632 -386.253482) (xy 93.685333 -386.237983)
			(xy 93.654821 -386.202964) (xy 93.62951 -386.16402) (xy 93.609897 -386.121917) (xy 93.596369 -386.077484)
			(xy 93.592396 -386.0546) (xy 93.590872 -386.045202) (xy 93.318076 -385.57327) (xy 93.31071 -385.567428)
			(xy 93.291933 -385.551624) (xy 93.258802 -385.515416) (xy 93.231384 -385.474711) (xy 93.210281 -385.430402)
			(xy 93.195956 -385.383461) (xy 93.188722 -385.334919) (xy 93.188282 -385.31038) (xy 93.188793 -385.284394)
			(xy 93.196926 -385.233061) (xy 93.212989 -385.183632) (xy 93.236585 -385.137325) (xy 93.267135 -385.095279)
			(xy 93.303886 -385.058529) (xy 93.345933 -385.02798) (xy 93.392242 -385.004385) (xy 93.441671 -384.988324)
			(xy 93.493004 -384.980192) (xy 93.51899 -384.979672) (xy 93.545001 -384.980156) (xy 93.596382 -384.988302)
			(xy 93.645853 -385.004393) (xy 93.692194 -385.028033) (xy 93.734261 -385.058639) (xy 93.771017 -385.095455)
			(xy 93.801553 -385.137572) (xy 93.825116 -385.183952) (xy 93.841126 -385.23345) (xy 93.845634 -385.259072)
			(xy 93.847158 -385.26847) (xy 94.119954 -385.740402) (xy 94.12732 -385.746244) (xy 94.146097 -385.762049)
			(xy 94.179228 -385.798257) (xy 94.206647 -385.838962) (xy 94.227752 -385.88327) (xy 94.24208 -385.930211)
			(xy 94.249316 -385.978753) (xy 94.249748 -386.003292) (xy 94.249494 -386.015484) (xy 94.24924 -386.025136)
			(xy 94.255336 -386.04317) (xy 94.31401 -386.11048) (xy 94.330774 -386.119116) (xy 94.34068 -386.120132)
			(xy 94.367449 -386.123457) (xy 94.41948 -386.137678) (xy 94.468514 -386.160154) (xy 94.51325 -386.190288)
			(xy 94.552505 -386.227282) (xy 94.585236 -386.270156) (xy 94.610577 -386.317772) (xy 94.627855 -386.368869)
			(xy 94.636614 -386.422092) (xy 94.637098 -386.449062) (xy 94.636691 -386.472801) (xy 94.629904 -386.51979)
			(xy 94.616466 -386.565326) (xy 94.596653 -386.60847) (xy 94.570871 -386.648337) (xy 94.555564 -386.666486)
			(xy 94.549214 -386.673852) (xy 94.542864 -386.691632) (xy 94.545404 -386.77088) (xy 94.546152 -386.780477)
			(xy 94.553855 -386.798102) (xy 94.56039 -386.80517) (xy 95.243142 -387.487922) (xy 95.251003 -387.494971)
			(xy 95.270682 -387.502563) (xy 95.281242 -387.502654) (xy 95.367094 -387.498844) (xy 95.385636 -387.4897)
			(xy 95.392748 -387.481318) (xy 95.400876 -387.47192) (xy 95.387922 -387.415278) (xy 95.384775 -387.404347)
			(xy 95.370675 -387.386532) (xy 95.360744 -387.380988) (xy 95.337311 -387.368925) (xy 95.294271 -387.33851)
			(xy 95.2566 -387.301655) (xy 95.225248 -387.259292) (xy 95.20101 -387.212495) (xy 95.184499 -387.162446)
			(xy 95.176133 -387.110413) (xy 95.175578 -387.084062) (xy 95.176139 -387.056779) (xy 95.185099 -387.002954)
			(xy 95.202771 -386.95133) (xy 95.228674 -386.903304) (xy 95.262107 -386.860181) (xy 95.28175 -386.841238)
			(xy 95.289205 -386.833749) (xy 95.297756 -386.814453) (xy 95.29826 -386.8039) (xy 95.29826 -386.729224)
			(xy 95.297673 -386.71869) (xy 95.28914 -386.699418) (xy 95.28175 -386.691886) (xy 95.262095 -386.672953)
			(xy 95.228651 -386.629833) (xy 95.202742 -386.581806) (xy 95.18507 -386.530177) (xy 95.176116 -386.476347)
			(xy 95.175578 -386.449062) (xy 95.175832 -386.43687) (xy 95.176086 -386.427218) (xy 95.16999 -386.409184)
			(xy 95.111316 -386.341874) (xy 95.094552 -386.333238) (xy 95.084646 -386.332222) (xy 95.057733 -386.32887)
			(xy 95.005435 -386.314524) (xy 94.95618 -386.291834) (xy 94.911288 -386.26141) (xy 94.871963 -386.224068)
			(xy 94.83926 -386.180808) (xy 94.814056 -386.132791) (xy 94.797026 -386.081304) (xy 94.792292 -386.0546)
			(xy 94.790768 -386.045202) (xy 94.517718 -385.572762) (xy 94.510606 -385.56692) (xy 94.491871 -385.551141)
			(xy 94.458813 -385.514999) (xy 94.431452 -385.474374) (xy 94.410385 -385.430156) (xy 94.396075 -385.383312)
			(xy 94.388835 -385.33487) (xy 94.388432 -385.31038) (xy 94.388917 -385.284393) (xy 94.397051 -385.233059)
			(xy 94.413115 -385.18363) (xy 94.436715 -385.137322) (xy 94.467268 -385.095277) (xy 94.504023 -385.058529)
			(xy 94.546074 -385.027983) (xy 94.592385 -385.004392) (xy 94.641818 -384.988337) (xy 94.693153 -384.980212)
			(xy 94.71914 -384.979672) (xy 94.745186 -384.980155) (xy 94.796635 -384.988312) (xy 94.84617 -385.004433)
			(xy 94.892565 -385.02812) (xy 94.934673 -385.058788) (xy 94.971453 -385.095677) (xy 95.001995 -385.137876)
			(xy 95.025544 -385.184342) (xy 95.041518 -385.233924) (xy 95.046038 -385.25958) (xy 95.047308 -385.268978)
			(xy 95.31985 -385.740402) (xy 95.327216 -385.746244) (xy 95.345993 -385.762049) (xy 95.379125 -385.798256)
			(xy 95.406544 -385.838961) (xy 95.427649 -385.88327) (xy 95.441977 -385.930211) (xy 95.449214 -385.978753)
			(xy 95.449644 -386.003292) (xy 95.44939 -386.015484) (xy 95.449136 -386.025136) (xy 95.455232 -386.04317)
			(xy 95.513906 -386.11048) (xy 95.53067 -386.119116) (xy 95.540576 -386.120132) (xy 95.567345 -386.123457)
			(xy 95.619377 -386.137678) (xy 95.668411 -386.160153) (xy 95.713148 -386.190287) (xy 95.752403 -386.227281)
			(xy 95.785135 -386.270155) (xy 95.810476 -386.317771) (xy 95.827755 -386.368868) (xy 95.836513 -386.422092)
			(xy 95.836994 -386.449062) (xy 95.836431 -386.476344) (xy 95.827467 -386.530166) (xy 95.809791 -386.581787)
			(xy 95.783884 -386.629808) (xy 95.750448 -386.672926) (xy 95.730822 -386.691886) (xy 95.723375 -386.699378)
			(xy 95.714837 -386.718674) (xy 95.714312 -386.729224) (xy 95.714312 -386.8039) (xy 95.714903 -386.814433)
			(xy 95.723438 -386.833701) (xy 95.730822 -386.841238) (xy 95.750477 -386.86017) (xy 95.783921 -386.903291)
			(xy 95.809829 -386.951318) (xy 95.827498 -387.002947) (xy 95.836449 -387.056777) (xy 95.836994 -387.084062)
			(xy 95.836561 -387.10818) (xy 95.829565 -387.155904) (xy 95.815716 -387.202109) (xy 95.795308 -387.245813)
			(xy 95.782384 -387.26618) (xy 95.776542 -387.27507) (xy 95.772986 -387.295136) (xy 95.794068 -387.387338)
			(xy 95.80626 -387.404102) (xy 95.81515 -387.409436) (xy 95.835951 -387.422292) (xy 95.873865 -387.453171)
			(xy 95.906813 -387.489302) (xy 95.934074 -387.529896) (xy 95.955053 -387.574066) (xy 95.96929 -387.620845)
			(xy 95.976475 -387.669213) (xy 95.976948 -387.693662) (xy 95.976479 -387.718856) (xy 95.968847 -387.768661)
			(xy 95.953753 -387.816735) (xy 95.931546 -387.861964) (xy 95.917512 -387.882892) (xy 95.909384 -387.894576)
			(xy 95.907352 -387.92277) (xy 95.955612 -388.015226) (xy 95.960238 -388.023311) (xy 95.974116 -388.03571)
			(xy 95.991517 -388.042307) (xy 96.000824 -388.042658) (xy 96.491806 -388.042658) (xy 96.501098 -388.042238)
			(xy 96.518463 -388.035618) (xy 96.532357 -388.023275) (xy 96.537018 -388.015226) (xy 96.585278 -387.92277)
			(xy 96.583246 -387.894576) (xy 96.575118 -387.882892) (xy 96.561106 -387.861952) (xy 96.538905 -387.816725)
			(xy 96.523815 -387.768655) (xy 96.516185 -387.718853) (xy 96.515682 -387.693662) (xy 96.516121 -387.669546)
			(xy 96.523126 -387.621825) (xy 96.536983 -387.575627) (xy 96.557397 -387.531928) (xy 96.570292 -387.511544)
			(xy 96.576134 -387.502654) (xy 96.57969 -387.482588) (xy 96.558608 -387.390386) (xy 96.546416 -387.373622)
			(xy 96.537526 -387.368288) (xy 96.516725 -387.355431) (xy 96.478811 -387.324552) (xy 96.445863 -387.28842)
			(xy 96.418601 -387.247827) (xy 96.397621 -387.203658) (xy 96.383382 -387.156879) (xy 96.376194 -387.108511)
			(xy 96.375728 -387.084062) (xy 96.376289 -387.05678) (xy 96.385251 -387.002956) (xy 96.402924 -386.951333)
			(xy 96.42883 -386.90331) (xy 96.462266 -386.86019) (xy 96.4819 -386.841238) (xy 96.489349 -386.833746)
			(xy 96.497892 -386.814451) (xy 96.49841 -386.8039) (xy 96.49841 -386.729224) (xy 96.497824 -386.718688)
			(xy 96.489297 -386.699411) (xy 96.4819 -386.691886) (xy 96.462242 -386.672955) (xy 96.428794 -386.629836)
			(xy 96.40288 -386.581809) (xy 96.385206 -386.530179) (xy 96.37625 -386.476348) (xy 96.375728 -386.449062)
			(xy 96.375982 -386.43687) (xy 96.376236 -386.427218) (xy 96.37014 -386.409184) (xy 96.311466 -386.341874)
			(xy 96.294702 -386.333238) (xy 96.284796 -386.332222) (xy 96.257881 -386.328874) (xy 96.205577 -386.314533)
			(xy 96.156314 -386.291848) (xy 96.111416 -386.261426) (xy 96.072084 -386.224084) (xy 96.039376 -386.180823)
			(xy 96.014166 -386.132803) (xy 95.997133 -386.081313) (xy 95.992442 -386.0546) (xy 95.990918 -386.045202)
			(xy 95.718122 -385.57327) (xy 95.710756 -385.567428) (xy 95.691977 -385.551625) (xy 95.658841 -385.515419)
			(xy 95.63142 -385.474715) (xy 95.610313 -385.430405) (xy 95.595986 -385.383463) (xy 95.588752 -385.33492)
			(xy 95.588328 -385.31038) (xy 95.588813 -385.284393) (xy 95.596947 -385.233059) (xy 95.613011 -385.183629)
			(xy 95.63661 -385.137321) (xy 95.667164 -385.095276) (xy 95.703918 -385.058527) (xy 95.745969 -385.027981)
			(xy 95.792281 -385.00439) (xy 95.841713 -384.988334) (xy 95.893049 -384.980208) (xy 95.919036 -384.979672)
			(xy 95.94505 -384.980152) (xy 95.996437 -384.988291) (xy 96.045915 -385.004377) (xy 96.092263 -385.028014)
			(xy 96.134338 -385.058618) (xy 96.1711 -385.095435) (xy 96.201642 -385.137554) (xy 96.22521 -385.183937)
			(xy 96.241223 -385.233439) (xy 96.24568 -385.259072) (xy 96.247204 -385.26847) (xy 96.52 -385.740402)
			(xy 96.527366 -385.746244) (xy 96.546146 -385.762047) (xy 96.579282 -385.798253) (xy 96.606705 -385.838957)
			(xy 96.627814 -385.883266) (xy 96.642144 -385.930208) (xy 96.649382 -385.978752) (xy 96.649794 -386.003292)
			(xy 96.64954 -386.015484) (xy 96.649286 -386.025136) (xy 96.655382 -386.04317) (xy 96.714056 -386.11048)
			(xy 96.73082 -386.119116) (xy 96.740726 -386.120132) (xy 96.767493 -386.12346) (xy 96.819518 -386.137687)
			(xy 96.868545 -386.160166) (xy 96.913275 -386.190302) (xy 96.952523 -386.227296) (xy 96.985249 -386.270168)
			(xy 97.010586 -386.317782) (xy 97.027862 -386.368875) (xy 97.036619 -386.422095) (xy 97.037144 -386.449062)
			(xy 97.036581 -386.476344) (xy 97.027618 -386.530167) (xy 97.009945 -386.58179) (xy 96.98404 -386.629814)
			(xy 96.950607 -386.672936) (xy 96.930972 -386.691886) (xy 96.923531 -386.699381) (xy 96.915002 -386.718676)
			(xy 96.914462 -386.729224) (xy 96.914462 -386.8039) (xy 96.915054 -386.814432) (xy 96.923596 -386.833695)
			(xy 96.930972 -386.841238) (xy 96.950625 -386.860172) (xy 96.984063 -386.903294) (xy 97.009967 -386.951321)
			(xy 97.027634 -387.002949) (xy 97.036583 -387.056778) (xy 97.037144 -387.084062) (xy 97.036711 -387.10818)
			(xy 97.029716 -387.155905) (xy 97.015869 -387.20211) (xy 96.995463 -387.245817) (xy 96.982534 -387.26618)
			(xy 96.976692 -387.27507) (xy 96.973136 -387.295136) (xy 96.994218 -387.387338) (xy 97.00641 -387.404102)
			(xy 97.0153 -387.409436) (xy 97.036103 -387.42229) (xy 97.074023 -387.453166) (xy 97.106976 -387.489296)
			(xy 97.134241 -387.52989) (xy 97.155223 -387.574061) (xy 97.169463 -387.620842) (xy 97.17665 -387.669212)
			(xy 97.177098 -387.693662) (xy 97.176629 -387.718855) (xy 97.168996 -387.76866) (xy 97.1539 -387.816733)
			(xy 97.13169 -387.86196) (xy 97.117662 -387.882892) (xy 97.109534 -387.894576) (xy 97.107502 -387.92277)
			(xy 97.155762 -388.015226) (xy 97.16039 -388.023305) (xy 97.17427 -388.03569) (xy 97.19167 -388.042271)
			(xy 97.200974 -388.042658) (xy 97.691702 -388.042658) (xy 97.700994 -388.042239) (xy 97.718361 -388.03562)
			(xy 97.732256 -388.023277) (xy 97.736914 -388.015226) (xy 97.785174 -387.92277) (xy 97.783142 -387.894576)
			(xy 97.775014 -387.882892) (xy 97.761002 -387.861952) (xy 97.738801 -387.816725) (xy 97.723712 -387.768655)
			(xy 97.716081 -387.718853) (xy 97.715578 -387.693662) (xy 97.716017 -387.669546) (xy 97.723022 -387.621825)
			(xy 97.736879 -387.575627) (xy 97.757293 -387.531928) (xy 97.770188 -387.511544) (xy 97.77603 -387.502654)
			(xy 97.779586 -387.482588) (xy 97.758504 -387.390386) (xy 97.746312 -387.373622) (xy 97.737422 -387.368288)
			(xy 97.716622 -387.355431) (xy 97.678708 -387.324551) (xy 97.64576 -387.28842) (xy 97.618499 -387.247826)
			(xy 97.597519 -387.203657) (xy 97.58328 -387.156878) (xy 97.576092 -387.108511) (xy 97.575624 -387.084062)
			(xy 97.576185 -387.05678) (xy 97.585147 -387.002956) (xy 97.60282 -386.951333) (xy 97.628726 -386.90331)
			(xy 97.662162 -386.86019) (xy 97.681796 -386.841238) (xy 97.689245 -386.833746) (xy 97.697789 -386.814451)
			(xy 97.698306 -386.8039) (xy 97.698306 -386.729224) (xy 97.69772 -386.718689) (xy 97.689193 -386.699412)
			(xy 97.681796 -386.691886) (xy 97.662138 -386.672955) (xy 97.62869 -386.629836) (xy 97.602777 -386.581809)
			(xy 97.585103 -386.530179) (xy 97.576147 -386.476348) (xy 97.575624 -386.449062) (xy 97.575878 -386.43687)
			(xy 97.576132 -386.427218) (xy 97.570036 -386.409184) (xy 97.511362 -386.341874) (xy 97.494598 -386.333238)
			(xy 97.484692 -386.332222) (xy 97.457777 -386.328873) (xy 97.405473 -386.314532) (xy 97.356212 -386.291847)
			(xy 97.311313 -386.261425) (xy 97.271983 -386.224083) (xy 97.239274 -386.180822) (xy 97.214066 -386.132802)
			(xy 97.197033 -386.081312) (xy 97.192338 -386.0546) (xy 97.190814 -386.045202) (xy 96.917764 -385.572762)
			(xy 96.910652 -385.56692) (xy 96.89192 -385.55114) (xy 96.858867 -385.514995) (xy 96.83151 -385.47437)
			(xy 96.810447 -385.430152) (xy 96.796139 -385.38331) (xy 96.7889 -385.334869) (xy 96.788478 -385.31038)
			(xy 96.788989 -385.284393) (xy 96.797122 -385.233061) (xy 96.813185 -385.183632) (xy 96.836781 -385.137324)
			(xy 96.867331 -385.095277) (xy 96.904082 -385.058527) (xy 96.946129 -385.027978) (xy 96.992437 -385.004382)
			(xy 97.041866 -384.988321) (xy 97.093199 -384.980189) (xy 97.119186 -384.979672) (xy 97.145235 -384.980151)
			(xy 97.19669 -384.988301) (xy 97.246232 -385.004417) (xy 97.292634 -385.028101) (xy 97.334749 -385.058768)
			(xy 97.371536 -385.095657) (xy 97.402084 -385.137858) (xy 97.425638 -385.184327) (xy 97.441615 -385.233913)
			(xy 97.446084 -385.25958) (xy 97.447354 -385.268978) (xy 97.47129 -385.31038) (xy 97.988374 -385.31038)
			(xy 97.988883 -385.284393) (xy 97.997016 -385.23306) (xy 98.013079 -385.18363) (xy 98.036675 -385.137322)
			(xy 98.067225 -385.095275) (xy 98.103976 -385.058524) (xy 98.146024 -385.027974) (xy 98.192332 -385.004378)
			(xy 98.241762 -384.988316) (xy 98.293095 -384.980183) (xy 98.319082 -384.979672) (xy 98.345092 -384.980158)
			(xy 98.396468 -384.988314) (xy 98.445933 -385.004412) (xy 98.492269 -385.028056) (xy 98.534333 -385.058661)
			(xy 98.571086 -385.095474) (xy 98.601624 -385.137587) (xy 98.607599 -385.149344) (xy 99.957128 -385.149344)
			(xy 99.957549 -385.124448) (xy 99.965001 -385.075215) (xy 99.979743 -385.027655) (xy 100.001442 -384.982839)
			(xy 100.02961 -384.941779) (xy 100.046282 -384.923284) (xy 100.052886 -384.916426) (xy 100.059744 -384.899408)
			(xy 100.06203 -384.813048) (xy 100.055934 -384.795522) (xy 100.049838 -384.78841) (xy 100.035075 -384.77042)
			(xy 100.010246 -384.731057) (xy 99.991183 -384.688601) (xy 99.978265 -384.643892) (xy 99.971745 -384.597812)
			(xy 99.971352 -384.574542) (xy 99.971914 -384.548556) (xy 99.980037 -384.497223) (xy 99.996091 -384.447792)
			(xy 100.019681 -384.401482) (xy 100.050224 -384.359432) (xy 100.086969 -384.322677) (xy 100.129012 -384.292123)
			(xy 100.175316 -384.268523) (xy 100.224743 -384.252457) (xy 100.276074 -384.24432) (xy 100.30206 -384.243834)
			(xy 100.32556 -384.244239) (xy 100.372091 -384.250869) (xy 100.39477 -384.257042) (xy 100.408232 -384.261106)
			(xy 100.434648 -384.254502) (xy 100.517706 -384.173222) (xy 100.525072 -384.14706) (xy 100.521516 -384.133598)
			(xy 100.515581 -384.109652) (xy 100.509206 -384.06073) (xy 100.508816 -384.036062) (xy 100.509302 -384.008811)
			(xy 100.517058 -383.954863) (xy 100.532413 -383.902568) (xy 100.555055 -383.852991) (xy 100.584521 -383.807141)
			(xy 100.620212 -383.76595) (xy 100.661403 -383.730259) (xy 100.707253 -383.700793) (xy 100.75683 -383.678151)
			(xy 100.809125 -383.662796) (xy 100.863073 -383.65504) (xy 100.917575 -383.65504) (xy 100.971523 -383.662796)
			(xy 101.023818 -383.678151) (xy 101.073395 -383.700793) (xy 101.119245 -383.730259) (xy 101.160436 -383.76595)
			(xy 101.196127 -383.807141) (xy 101.225593 -383.852991) (xy 101.248235 -383.902568) (xy 101.26359 -383.954863)
			(xy 101.271346 -384.008811) (xy 101.271832 -384.036062) (xy 101.27136 -384.063432) (xy 101.265526 -384.10388)
			(xy 101.608126 -384.10388) (xy 101.612197 -384.048258) (xy 101.624323 -383.993821) (xy 101.644246 -383.94173)
			(xy 101.671542 -383.893095) (xy 101.705628 -383.848952) (xy 101.745777 -383.810243) (xy 101.791135 -383.777792)
			(xy 101.840735 -383.752291) (xy 101.893519 -383.734284) (xy 101.948362 -383.724154) (xy 102.004096 -383.722117)
			(xy 102.059533 -383.728217) (xy 102.11349 -383.742323) (xy 102.164819 -383.764135) (xy 102.212425 -383.793189)
			(xy 102.255293 -383.828864) (xy 102.29251 -383.870401) (xy 102.323283 -383.916914) (xy 102.346955 -383.967411)
			(xy 102.363023 -384.020818) (xy 102.371143 -384.075994) (xy 102.371652 -384.10388) (xy 102.371143 -384.131766)
			(xy 102.363023 -384.186942) (xy 102.346955 -384.240349) (xy 102.323283 -384.290846) (xy 102.29251 -384.337359)
			(xy 102.255293 -384.378896) (xy 102.212425 -384.414571) (xy 102.164819 -384.443625) (xy 102.11349 -384.465437)
			(xy 102.059533 -384.479543) (xy 102.004096 -384.485643) (xy 101.948362 -384.483606) (xy 101.893519 -384.473476)
			(xy 101.840735 -384.455469) (xy 101.791135 -384.429968) (xy 101.745777 -384.397517) (xy 101.705628 -384.358808)
			(xy 101.671542 -384.314665) (xy 101.644246 -384.26603) (xy 101.624323 -384.213939) (xy 101.612197 -384.159502)
			(xy 101.608126 -384.10388) (xy 101.265526 -384.10388) (xy 101.263546 -384.117612) (xy 101.24806 -384.170115)
			(xy 101.225219 -384.219862) (xy 101.195494 -384.265829) (xy 101.177852 -384.28676) (xy 101.171756 -384.293872)
			(xy 101.165406 -384.31089) (xy 101.165406 -384.396234) (xy 101.171756 -384.413252) (xy 101.177852 -384.420364)
			(xy 101.195456 -384.441326) (xy 101.225184 -384.487289) (xy 101.248033 -384.53703) (xy 101.263533 -384.589528)
			(xy 101.271366 -384.643702) (xy 101.27137 -384.69844) (xy 101.263545 -384.752616) (xy 101.248053 -384.805117)
			(xy 101.225212 -384.854861) (xy 101.195491 -384.900828) (xy 101.177852 -384.92176) (xy 101.171756 -384.928872)
			(xy 101.165406 -384.94589) (xy 101.165406 -385.031234) (xy 101.171756 -385.048252) (xy 101.177852 -385.055364)
			(xy 101.19548 -385.076305) (xy 101.207228 -385.09448) (xy 101.608126 -385.09448) (xy 101.612197 -385.038858)
			(xy 101.624323 -384.984421) (xy 101.644246 -384.93233) (xy 101.671542 -384.883695) (xy 101.705628 -384.839552)
			(xy 101.745777 -384.800843) (xy 101.791135 -384.768392) (xy 101.840735 -384.742891) (xy 101.893519 -384.724884)
			(xy 101.948362 -384.714754) (xy 102.004096 -384.712717) (xy 102.059533 -384.718817) (xy 102.11349 -384.732923)
			(xy 102.164819 -384.754735) (xy 102.212425 -384.783789) (xy 102.255293 -384.819464) (xy 102.29251 -384.861001)
			(xy 102.323283 -384.907514) (xy 102.346955 -384.958011) (xy 102.363023 -385.011418) (xy 102.371143 -385.066594)
			(xy 102.371652 -385.09448) (xy 102.371143 -385.122366) (xy 102.363023 -385.177542) (xy 102.346955 -385.230949)
			(xy 102.323283 -385.281446) (xy 102.29251 -385.327959) (xy 102.255293 -385.369496) (xy 102.212425 -385.405171)
			(xy 102.164819 -385.434225) (xy 102.11349 -385.456037) (xy 102.059533 -385.470143) (xy 102.004096 -385.476243)
			(xy 101.948362 -385.474206) (xy 101.893519 -385.464076) (xy 101.840735 -385.446069) (xy 101.791135 -385.420568)
			(xy 101.745777 -385.388117) (xy 101.705628 -385.349408) (xy 101.671542 -385.305265) (xy 101.644246 -385.25663)
			(xy 101.624323 -385.204539) (xy 101.612197 -385.150102) (xy 101.608126 -385.09448) (xy 101.207228 -385.09448)
			(xy 101.225195 -385.122275) (xy 101.248034 -385.17202) (xy 101.263528 -385.224519) (xy 101.271357 -385.278693)
			(xy 101.271832 -385.306062) (xy 101.271392 -385.332973) (xy 101.263846 -385.386262) (xy 101.248884 -385.437961)
			(xy 101.226803 -385.487044) (xy 101.198042 -385.532536) (xy 101.163172 -385.573533) (xy 101.122886 -385.609222)
			(xy 101.077982 -385.638893) (xy 101.029354 -385.661958) (xy 100.977967 -385.677958) (xy 100.92484 -385.686576)
			(xy 100.897944 -385.68757) (xy 100.886514 -385.687824) (xy 100.866448 -385.69773) (xy 100.803456 -385.776978)
			(xy 100.798376 -385.799076) (xy 100.800662 -385.810252) (xy 100.804584 -385.829829) (xy 100.808781 -385.869536)
			(xy 100.809044 -385.8895) (xy 100.808788 -385.909591) (xy 100.804593 -385.949552) (xy 100.800662 -385.969256)
			(xy 100.797614 -385.982718) (xy 100.806504 -386.00888) (xy 100.894388 -386.085588) (xy 100.921566 -386.090668)
			(xy 100.93452 -386.086096) (xy 100.965909 -386.075454) (xy 101.031178 -386.063964) (xy 101.064314 -386.063236)
			(xy 101.091563 -386.063693) (xy 101.145507 -386.071451) (xy 101.197798 -386.086806) (xy 101.247371 -386.109447)
			(xy 101.293218 -386.138912) (xy 101.334404 -386.174602) (xy 101.370093 -386.215789) (xy 101.399557 -386.261637)
			(xy 101.422197 -386.31121) (xy 101.437551 -386.363501) (xy 101.445307 -386.417445) (xy 101.445308 -386.471944)
			(xy 101.437553 -386.525888) (xy 101.4222 -386.57818) (xy 101.399562 -386.627754) (xy 101.370099 -386.673602)
			(xy 101.334412 -386.714791) (xy 101.293226 -386.750481) (xy 101.24738 -386.779948) (xy 101.197808 -386.80259)
			(xy 101.145517 -386.817947) (xy 101.091574 -386.825706) (xy 101.037075 -386.82571) (xy 100.983131 -386.817957)
			(xy 100.930839 -386.802607) (xy 100.881263 -386.779971) (xy 100.835413 -386.750511) (xy 100.794223 -386.714826)
			(xy 100.75853 -386.673642) (xy 100.729061 -386.627797) (xy 100.706417 -386.578226) (xy 100.691057 -386.525936)
			(xy 100.683295 -386.471993) (xy 100.682806 -386.444744) (xy 100.683052 -386.424653) (xy 100.687254 -386.384692)
			(xy 100.691188 -386.364988) (xy 100.694236 -386.351526) (xy 100.685346 -386.325364) (xy 100.597462 -386.248656)
			(xy 100.570284 -386.243576) (xy 100.55733 -386.248148) (xy 100.525938 -386.258779) (xy 100.460671 -386.270275)
			(xy 100.427536 -386.271008) (xy 100.400284 -386.270511) (xy 100.346334 -386.262759) (xy 100.294037 -386.247408)
			(xy 100.244457 -386.224769) (xy 100.198604 -386.195305) (xy 100.157411 -386.159615) (xy 100.121716 -386.118425)
			(xy 100.092248 -386.072575) (xy 100.069605 -386.022997) (xy 100.054249 -385.970701) (xy 100.046491 -385.916752)
			(xy 100.046028 -385.8895) (xy 100.046437 -385.863517) (xy 100.053503 -385.812033) (xy 100.067489 -385.761984)
			(xy 100.088139 -385.714296) (xy 100.115068 -385.669852) (xy 100.14778 -385.629473) (xy 100.166424 -385.61137)
			(xy 100.175822 -385.602734) (xy 100.183696 -385.579366) (xy 100.167694 -385.47167) (xy 100.153216 -385.451604)
			(xy 100.141786 -385.446016) (xy 100.118395 -385.433951) (xy 100.075449 -385.403532) (xy 100.037864 -385.366692)
			(xy 100.006592 -385.324362) (xy 99.982421 -385.277612) (xy 99.965963 -385.227623) (xy 99.957633 -385.175658)
			(xy 99.957128 -385.149344) (xy 98.607599 -385.149344) (xy 98.625192 -385.183961) (xy 98.641211 -385.233453)
			(xy 98.645726 -385.259072) (xy 98.64725 -385.26847) (xy 98.920046 -385.740402) (xy 98.927412 -385.746244)
			(xy 98.946196 -385.762039) (xy 98.979313 -385.798257) (xy 99.006721 -385.838967) (xy 99.027821 -385.883276)
			(xy 99.04215 -385.930215) (xy 99.049395 -385.978754) (xy 99.04984 -386.003292) (xy 99.049586 -386.014976)
			(xy 99.049332 -386.024882) (xy 99.055682 -386.042916) (xy 99.114864 -386.109972) (xy 99.132136 -386.118862)
			(xy 99.141788 -386.119624) (xy 99.166129 -386.122233) (xy 99.213679 -386.133875) (xy 99.258996 -386.152394)
			(xy 99.30109 -386.177387) (xy 99.339044 -386.208307) (xy 99.372029 -386.244482) (xy 99.399326 -386.28512)
			(xy 99.420339 -386.329336) (xy 99.434609 -386.376165) (xy 99.441826 -386.424585) (xy 99.44227 -386.449062)
			(xy 99.44176 -386.475049) (xy 99.43363 -386.526384) (xy 99.417569 -386.575814) (xy 99.393973 -386.622124)
			(xy 99.363423 -386.664172) (xy 99.326672 -386.700923) (xy 99.284624 -386.731473) (xy 99.238314 -386.755069)
			(xy 99.188884 -386.77113) (xy 99.137549 -386.77926) (xy 99.085575 -386.77926) (xy 99.03424 -386.77113)
			(xy 98.98481 -386.755069) (xy 98.9385 -386.731473) (xy 98.896452 -386.700923) (xy 98.859701 -386.664172)
			(xy 98.829151 -386.622124) (xy 98.805555 -386.575814) (xy 98.789494 -386.526384) (xy 98.781364 -386.475049)
			(xy 98.780854 -386.449062) (xy 98.781108 -386.437378) (xy 98.781362 -386.427472) (xy 98.775012 -386.409438)
			(xy 98.71583 -386.342382) (xy 98.698558 -386.333492) (xy 98.688906 -386.33273) (xy 98.664724 -386.33005)
			(xy 98.61746 -386.318511) (xy 98.572393 -386.300179) (xy 98.530495 -386.275448) (xy 98.492668 -386.244851)
			(xy 98.459726 -386.209047) (xy 98.43238 -386.168807) (xy 98.411219 -386.124998) (xy 98.396697 -386.078563)
			(xy 98.392488 -386.0546) (xy 98.390964 -386.045202) (xy 98.118168 -385.57327) (xy 98.110802 -385.567428)
			(xy 98.092056 -385.55159) (xy 98.058936 -385.515381) (xy 98.031522 -385.47468) (xy 98.010416 -385.430379)
			(xy 97.996079 -385.383449) (xy 97.988825 -385.334916) (xy 97.988374 -385.31038) (xy 97.47129 -385.31038)
			(xy 97.719896 -385.740402) (xy 97.727262 -385.746244) (xy 97.746042 -385.762047) (xy 97.779179 -385.798253)
			(xy 97.806602 -385.838957) (xy 97.827711 -385.883266) (xy 97.842042 -385.930208) (xy 97.849279 -385.978752)
			(xy 97.84969 -386.003292) (xy 97.849436 -386.015484) (xy 97.849182 -386.025136) (xy 97.855278 -386.04317)
			(xy 97.913952 -386.11048) (xy 97.930716 -386.119116) (xy 97.940622 -386.120132) (xy 97.967389 -386.12346)
			(xy 98.019414 -386.137686) (xy 98.068442 -386.160165) (xy 98.113173 -386.190301) (xy 98.152422 -386.227295)
			(xy 98.185148 -386.270167) (xy 98.210485 -386.317781) (xy 98.227761 -386.368875) (xy 98.236518 -386.422094)
			(xy 98.23704 -386.449062) (xy 98.236477 -386.476344) (xy 98.227514 -386.530167) (xy 98.20984 -386.58179)
			(xy 98.183936 -386.629813) (xy 98.150502 -386.672935) (xy 98.130868 -386.691886) (xy 98.123427 -386.699381)
			(xy 98.114899 -386.718676) (xy 98.114358 -386.729224) (xy 98.114358 -386.8039) (xy 98.11495 -386.814432)
			(xy 98.123491 -386.833695) (xy 98.130868 -386.841238) (xy 98.150521 -386.860172) (xy 98.18396 -386.903293)
			(xy 98.209864 -386.951321) (xy 98.227531 -387.002949) (xy 98.236481 -387.056778) (xy 98.23704 -387.084062)
			(xy 98.236607 -387.10818) (xy 98.229612 -387.155905) (xy 98.215765 -387.20211) (xy 98.195359 -387.245816)
			(xy 98.18243 -387.26618) (xy 98.176588 -387.27507) (xy 98.173032 -387.295136) (xy 98.194114 -387.387338)
			(xy 98.206306 -387.404102) (xy 98.215196 -387.409436) (xy 98.236 -387.42229) (xy 98.27392 -387.453166)
			(xy 98.306873 -387.489296) (xy 98.334139 -387.52989) (xy 98.355121 -387.57406) (xy 98.369361 -387.620842)
			(xy 98.376548 -387.669211) (xy 98.376994 -387.693662) (xy 98.376525 -387.718855) (xy 98.368891 -387.76866)
			(xy 98.353795 -387.816732) (xy 98.331585 -387.86196) (xy 98.317558 -387.882892) (xy 98.30943 -387.894576)
			(xy 98.307398 -387.92277) (xy 98.355658 -388.015226) (xy 98.360286 -388.023306) (xy 98.374166 -388.035692)
			(xy 98.391566 -388.042274) (xy 98.40087 -388.042658) (xy 100.115624 -388.042658) (xy 100.124291 -388.042353)
			(xy 100.14065 -388.036633) (xy 100.147628 -388.031482) (xy 100.167295 -388.016252) (xy 100.210297 -387.991254)
			(xy 100.25656 -387.972984) (xy 100.305039 -387.961854) (xy 100.354638 -387.958116) (xy 100.404237 -387.961854)
			(xy 100.452716 -387.972984) (xy 100.498979 -387.991254) (xy 100.541981 -388.016252) (xy 100.561648 -388.031482)
			(xy 100.568506 -388.036816) (xy 100.584762 -388.042658) (xy 100.654104 -388.042658) (xy 100.664173 -388.042233)
			(xy 100.682772 -388.034513) (xy 100.690172 -388.027672) (xy 102.12324 -386.594604) (xy 102.130235 -386.587012)
			(xy 102.137976 -386.567897) (xy 102.137518 -386.54728) (xy 102.133654 -386.537708) (xy 102.087934 -386.436616)
			(xy 102.06101 -386.42036) (xy 102.045008 -386.421376) (xy 102.021386 -386.422138) (xy 101.994133 -386.421651)
			(xy 101.940183 -386.413892) (xy 101.887886 -386.398535) (xy 101.838306 -386.375891) (xy 101.792454 -386.346422)
			(xy 101.751262 -386.310728) (xy 101.715569 -386.269535) (xy 101.686102 -386.223681) (xy 101.66346 -386.174101)
			(xy 101.648105 -386.121803) (xy 101.640348 -386.067853) (xy 101.640348 -386.013347) (xy 101.648105 -385.959397)
			(xy 101.66346 -385.907099) (xy 101.686102 -385.857519) (xy 101.715569 -385.811665) (xy 101.751262 -385.770472)
			(xy 101.792454 -385.734778) (xy 101.838306 -385.705309) (xy 101.887886 -385.682665) (xy 101.940183 -385.667308)
			(xy 101.994133 -385.659549) (xy 102.021386 -385.659122) (xy 102.049191 -385.659616) (xy 102.104213 -385.667672)
			(xy 102.157483 -385.683628) (xy 102.207873 -385.707148) (xy 102.254315 -385.737734) (xy 102.295826 -385.774736)
			(xy 102.331526 -385.817372) (xy 102.36066 -385.864739) (xy 102.382609 -385.915832) (xy 102.390194 -385.942586)
			(xy 102.393242 -385.954016) (xy 102.408736 -385.971796) (xy 102.505256 -386.011928) (xy 102.528878 -386.010404)
			(xy 102.539038 -386.004562) (xy 102.564744 -385.990182) (xy 102.6188 -385.966784) (xy 102.675199 -385.949794)
			(xy 102.733185 -385.939442) (xy 102.762558 -385.937252) (xy 102.771956 -385.93649) (xy 102.78872 -385.929124)
			(xy 103.031544 -385.6863) (xy 103.038397 -385.678904) (xy 103.04614 -385.660306) (xy 103.04653 -385.650232)
			(xy 103.04653 -383.83718) (xy 103.046149 -383.827754) (xy 103.039322 -383.81018) (xy 103.0266 -383.796267)
			(xy 103.018336 -383.791714) (xy 102.923594 -383.744724) (xy 102.8954 -383.747518) (xy 102.883716 -383.756408)
			(xy 102.858685 -383.774585) (xy 102.803973 -383.803446) (xy 102.745322 -383.823103) (xy 102.684267 -383.833041)
			(xy 102.653338 -383.833624) (xy 102.626082 -383.833164) (xy 102.572125 -383.825411) (xy 102.51982 -383.810057)
			(xy 102.470233 -383.787416) (xy 102.424373 -383.757948) (xy 102.383174 -383.722253) (xy 102.347475 -383.681057)
			(xy 102.318002 -383.6352) (xy 102.295356 -383.585615) (xy 102.279997 -383.533312) (xy 102.272239 -383.479356)
			(xy 102.272239 -383.424844) (xy 102.279997 -383.370888) (xy 102.295356 -383.318585) (xy 102.318002 -383.269)
			(xy 102.347475 -383.223143) (xy 102.383174 -383.181947) (xy 102.424373 -383.146252) (xy 102.470233 -383.116784)
			(xy 102.51982 -383.094143) (xy 102.572125 -383.078789) (xy 102.626082 -383.071036) (xy 102.653338 -383.070608)
			(xy 102.682423 -383.07115) (xy 102.73992 -383.079967) (xy 102.795413 -383.097406) (xy 102.847618 -383.123063)
			(xy 102.895326 -383.156345) (xy 102.937431 -383.196479) (xy 102.955598 -383.219198) (xy 102.962964 -383.22885)
			(xy 102.983792 -383.23901) (xy 102.99573 -383.23901) (xy 103.005734 -383.238517) (xy 103.024218 -383.230852)
			(xy 103.038363 -383.216701) (xy 103.046021 -383.198215) (xy 103.04653 -383.18821) (xy 103.04653 -383.097532)
			(xy 103.046027 -383.08748) (xy 103.038309 -383.068916) (xy 103.031544 -383.061464) (xy 102.822756 -382.852676)
			(xy 102.815359 -382.845828) (xy 102.79676 -382.838098) (xy 102.786688 -382.83769) (xy 100.305108 -382.83769)
			(xy 100.275898 -382.865376) (xy 100.274882 -382.885696) (xy 100.273081 -382.910741) (xy 100.262861 -382.959901)
			(xy 100.245329 -383.006952) (xy 100.220886 -383.050812) (xy 100.190095 -383.090474) (xy 100.153662 -383.125026)
			(xy 100.112426 -383.153674) (xy 100.067333 -383.17576) (xy 100.01942 -383.190776) (xy 99.969787 -383.198378)
			(xy 99.944682 -383.198878) (xy 99.920909 -383.198465) (xy 99.873852 -383.191652) (xy 99.828257 -383.178171)
			(xy 99.785062 -383.158298) (xy 99.745159 -383.132443) (xy 99.727004 -383.11709) (xy 99.719884 -383.111405)
			(xy 99.702833 -383.105015) (xy 99.69373 -383.104644) (xy 99.662234 -383.104644) (xy 99.653129 -383.105017)
			(xy 99.636071 -383.111392) (xy 99.62896 -383.11709) (xy 99.6108 -383.132439) (xy 99.570905 -383.158306)
			(xy 99.527712 -383.178185) (xy 99.482115 -383.191665) (xy 99.435056 -383.198466) (xy 99.411282 -383.198878)
			(xy 99.384412 -383.198351) (xy 99.33138 -383.189656) (xy 99.280453 -383.172497) (xy 99.232972 -383.147327)
			(xy 99.190188 -383.114808) (xy 99.153227 -383.075797) (xy 99.137724 -383.053844) (xy 99.13112 -383.044446)
			(xy 99.111816 -383.033016) (xy 99.022408 -383.02438) (xy 99.011192 -383.02396) (xy 98.990117 -383.031609)
			(xy 98.981768 -383.039112) (xy 98.392742 -383.628138) (xy 98.385343 -383.634982) (xy 98.366744 -383.642705)
			(xy 98.356674 -383.643124) (xy 88.317324 -383.643124) (xy 88.30726 -383.643562) (xy 88.288678 -383.651298)
			(xy 88.281256 -383.65811) (xy 87.494618 -384.444748) (xy 87.488776 -384.474974) (xy 87.494872 -384.489198)
			(xy 87.503071 -384.509622) (xy 87.514611 -384.552092) (xy 87.520424 -384.595717) (xy 87.52078 -384.617722)
			(xy 87.520295 -384.643709) (xy 88.060024 -384.643709) (xy 88.060024 -384.591735) (xy 88.068154 -384.5404)
			(xy 88.084215 -384.49097) (xy 88.107811 -384.44466) (xy 88.138361 -384.402612) (xy 88.175112 -384.365861)
			(xy 88.21716 -384.335311) (xy 88.26347 -384.311715) (xy 88.3129 -384.295654) (xy 88.364235 -384.287524)
			(xy 88.416209 -384.287524) (xy 88.467544 -384.295654) (xy 88.516974 -384.311715) (xy 88.563284 -384.335311)
			(xy 88.605332 -384.365861) (xy 88.642083 -384.402612) (xy 88.672633 -384.44466) (xy 88.696229 -384.49097)
			(xy 88.71229 -384.5404) (xy 88.72042 -384.591735) (xy 88.72093 -384.617722) (xy 88.72042 -384.643709)
			(xy 89.25992 -384.643709) (xy 89.25992 -384.591735) (xy 89.26805 -384.5404) (xy 89.284111 -384.49097)
			(xy 89.307707 -384.44466) (xy 89.338257 -384.402612) (xy 89.375008 -384.365861) (xy 89.417056 -384.335311)
			(xy 89.463366 -384.311715) (xy 89.512796 -384.295654) (xy 89.564131 -384.287524) (xy 89.616105 -384.287524)
			(xy 89.66744 -384.295654) (xy 89.71687 -384.311715) (xy 89.76318 -384.335311) (xy 89.805228 -384.365861)
			(xy 89.841979 -384.402612) (xy 89.872529 -384.44466) (xy 89.896125 -384.49097) (xy 89.912186 -384.5404)
			(xy 89.920316 -384.591735) (xy 89.920826 -384.617722) (xy 89.920316 -384.643709) (xy 90.46007 -384.643709)
			(xy 90.46007 -384.591735) (xy 90.4682 -384.5404) (xy 90.484261 -384.49097) (xy 90.507857 -384.44466)
			(xy 90.538407 -384.402612) (xy 90.575158 -384.365861) (xy 90.617206 -384.335311) (xy 90.663516 -384.311715)
			(xy 90.712946 -384.295654) (xy 90.764281 -384.287524) (xy 90.816255 -384.287524) (xy 90.86759 -384.295654)
			(xy 90.91702 -384.311715) (xy 90.96333 -384.335311) (xy 91.005378 -384.365861) (xy 91.042129 -384.402612)
			(xy 91.072679 -384.44466) (xy 91.096275 -384.49097) (xy 91.112336 -384.5404) (xy 91.120466 -384.591735)
			(xy 91.120976 -384.617722) (xy 91.120466 -384.643709) (xy 91.659966 -384.643709) (xy 91.659966 -384.591735)
			(xy 91.668096 -384.5404) (xy 91.684157 -384.49097) (xy 91.707753 -384.44466) (xy 91.738303 -384.402612)
			(xy 91.775054 -384.365861) (xy 91.817102 -384.335311) (xy 91.863412 -384.311715) (xy 91.912842 -384.295654)
			(xy 91.964177 -384.287524) (xy 92.016151 -384.287524) (xy 92.067486 -384.295654) (xy 92.116916 -384.311715)
			(xy 92.163226 -384.335311) (xy 92.205274 -384.365861) (xy 92.242025 -384.402612) (xy 92.272575 -384.44466)
			(xy 92.296171 -384.49097) (xy 92.312232 -384.5404) (xy 92.320362 -384.591735) (xy 92.320872 -384.617722)
			(xy 92.320362 -384.643709) (xy 92.859862 -384.643709) (xy 92.859862 -384.591735) (xy 92.867992 -384.5404)
			(xy 92.884053 -384.49097) (xy 92.907649 -384.44466) (xy 92.938199 -384.402612) (xy 92.97495 -384.365861)
			(xy 93.016998 -384.335311) (xy 93.063308 -384.311715) (xy 93.112738 -384.295654) (xy 93.164073 -384.287524)
			(xy 93.216047 -384.287524) (xy 93.267382 -384.295654) (xy 93.316812 -384.311715) (xy 93.363122 -384.335311)
			(xy 93.40517 -384.365861) (xy 93.441921 -384.402612) (xy 93.472471 -384.44466) (xy 93.496067 -384.49097)
			(xy 93.512128 -384.5404) (xy 93.520258 -384.591735) (xy 93.520768 -384.617722) (xy 93.520258 -384.643709)
			(xy 94.060012 -384.643709) (xy 94.060012 -384.591735) (xy 94.068142 -384.5404) (xy 94.084203 -384.49097)
			(xy 94.107799 -384.44466) (xy 94.138349 -384.402612) (xy 94.1751 -384.365861) (xy 94.217148 -384.335311)
			(xy 94.263458 -384.311715) (xy 94.312888 -384.295654) (xy 94.364223 -384.287524) (xy 94.416197 -384.287524)
			(xy 94.467532 -384.295654) (xy 94.516962 -384.311715) (xy 94.563272 -384.335311) (xy 94.60532 -384.365861)
			(xy 94.642071 -384.402612) (xy 94.672621 -384.44466) (xy 94.696217 -384.49097) (xy 94.712278 -384.5404)
			(xy 94.720408 -384.591735) (xy 94.720918 -384.617722) (xy 94.720408 -384.643709) (xy 95.259908 -384.643709)
			(xy 95.259908 -384.591735) (xy 95.268038 -384.5404) (xy 95.284099 -384.49097) (xy 95.307695 -384.44466)
			(xy 95.338245 -384.402612) (xy 95.374996 -384.365861) (xy 95.417044 -384.335311) (xy 95.463354 -384.311715)
			(xy 95.512784 -384.295654) (xy 95.564119 -384.287524) (xy 95.616093 -384.287524) (xy 95.667428 -384.295654)
			(xy 95.716858 -384.311715) (xy 95.763168 -384.335311) (xy 95.805216 -384.365861) (xy 95.841967 -384.402612)
			(xy 95.872517 -384.44466) (xy 95.896113 -384.49097) (xy 95.912174 -384.5404) (xy 95.920304 -384.591735)
			(xy 95.920814 -384.617722) (xy 95.920304 -384.643709) (xy 96.460058 -384.643709) (xy 96.460058 -384.591735)
			(xy 96.468188 -384.5404) (xy 96.484249 -384.49097) (xy 96.507845 -384.44466) (xy 96.538395 -384.402612)
			(xy 96.575146 -384.365861) (xy 96.617194 -384.335311) (xy 96.663504 -384.311715) (xy 96.712934 -384.295654)
			(xy 96.764269 -384.287524) (xy 96.816243 -384.287524) (xy 96.867578 -384.295654) (xy 96.917008 -384.311715)
			(xy 96.963318 -384.335311) (xy 97.005366 -384.365861) (xy 97.042117 -384.402612) (xy 97.072667 -384.44466)
			(xy 97.096263 -384.49097) (xy 97.112324 -384.5404) (xy 97.120454 -384.591735) (xy 97.120964 -384.617722)
			(xy 97.120454 -384.643709) (xy 97.659954 -384.643709) (xy 97.659954 -384.591735) (xy 97.668084 -384.5404)
			(xy 97.684145 -384.49097) (xy 97.707741 -384.44466) (xy 97.738291 -384.402612) (xy 97.775042 -384.365861)
			(xy 97.81709 -384.335311) (xy 97.8634 -384.311715) (xy 97.91283 -384.295654) (xy 97.964165 -384.287524)
			(xy 98.016139 -384.287524) (xy 98.067474 -384.295654) (xy 98.116904 -384.311715) (xy 98.163214 -384.335311)
			(xy 98.205262 -384.365861) (xy 98.242013 -384.402612) (xy 98.272563 -384.44466) (xy 98.296159 -384.49097)
			(xy 98.31222 -384.5404) (xy 98.32035 -384.591735) (xy 98.32086 -384.617722) (xy 98.32035 -384.643709)
			(xy 98.31222 -384.695044) (xy 98.296159 -384.744474) (xy 98.272563 -384.790784) (xy 98.242013 -384.832832)
			(xy 98.205262 -384.869583) (xy 98.163214 -384.900133) (xy 98.116904 -384.923729) (xy 98.067474 -384.93979)
			(xy 98.016139 -384.94792) (xy 97.964165 -384.94792) (xy 97.91283 -384.93979) (xy 97.8634 -384.923729)
			(xy 97.81709 -384.900133) (xy 97.775042 -384.869583) (xy 97.738291 -384.832832) (xy 97.707741 -384.790784)
			(xy 97.684145 -384.744474) (xy 97.668084 -384.695044) (xy 97.659954 -384.643709) (xy 97.120454 -384.643709)
			(xy 97.112324 -384.695044) (xy 97.096263 -384.744474) (xy 97.072667 -384.790784) (xy 97.042117 -384.832832)
			(xy 97.005366 -384.869583) (xy 96.963318 -384.900133) (xy 96.917008 -384.923729) (xy 96.867578 -384.93979)
			(xy 96.816243 -384.94792) (xy 96.764269 -384.94792) (xy 96.712934 -384.93979) (xy 96.663504 -384.923729)
			(xy 96.617194 -384.900133) (xy 96.575146 -384.869583) (xy 96.538395 -384.832832) (xy 96.507845 -384.790784)
			(xy 96.484249 -384.744474) (xy 96.468188 -384.695044) (xy 96.460058 -384.643709) (xy 95.920304 -384.643709)
			(xy 95.912174 -384.695044) (xy 95.896113 -384.744474) (xy 95.872517 -384.790784) (xy 95.841967 -384.832832)
			(xy 95.805216 -384.869583) (xy 95.763168 -384.900133) (xy 95.716858 -384.923729) (xy 95.667428 -384.93979)
			(xy 95.616093 -384.94792) (xy 95.564119 -384.94792) (xy 95.512784 -384.93979) (xy 95.463354 -384.923729)
			(xy 95.417044 -384.900133) (xy 95.374996 -384.869583) (xy 95.338245 -384.832832) (xy 95.307695 -384.790784)
			(xy 95.284099 -384.744474) (xy 95.268038 -384.695044) (xy 95.259908 -384.643709) (xy 94.720408 -384.643709)
			(xy 94.712278 -384.695044) (xy 94.696217 -384.744474) (xy 94.672621 -384.790784) (xy 94.642071 -384.832832)
			(xy 94.60532 -384.869583) (xy 94.563272 -384.900133) (xy 94.516962 -384.923729) (xy 94.467532 -384.93979)
			(xy 94.416197 -384.94792) (xy 94.364223 -384.94792) (xy 94.312888 -384.93979) (xy 94.263458 -384.923729)
			(xy 94.217148 -384.900133) (xy 94.1751 -384.869583) (xy 94.138349 -384.832832) (xy 94.107799 -384.790784)
			(xy 94.084203 -384.744474) (xy 94.068142 -384.695044) (xy 94.060012 -384.643709) (xy 93.520258 -384.643709)
			(xy 93.512128 -384.695044) (xy 93.496067 -384.744474) (xy 93.472471 -384.790784) (xy 93.441921 -384.832832)
			(xy 93.40517 -384.869583) (xy 93.363122 -384.900133) (xy 93.316812 -384.923729) (xy 93.267382 -384.93979)
			(xy 93.216047 -384.94792) (xy 93.164073 -384.94792) (xy 93.112738 -384.93979) (xy 93.063308 -384.923729)
			(xy 93.016998 -384.900133) (xy 92.97495 -384.869583) (xy 92.938199 -384.832832) (xy 92.907649 -384.790784)
			(xy 92.884053 -384.744474) (xy 92.867992 -384.695044) (xy 92.859862 -384.643709) (xy 92.320362 -384.643709)
			(xy 92.312232 -384.695044) (xy 92.296171 -384.744474) (xy 92.272575 -384.790784) (xy 92.242025 -384.832832)
			(xy 92.205274 -384.869583) (xy 92.163226 -384.900133) (xy 92.116916 -384.923729) (xy 92.067486 -384.93979)
			(xy 92.016151 -384.94792) (xy 91.964177 -384.94792) (xy 91.912842 -384.93979) (xy 91.863412 -384.923729)
			(xy 91.817102 -384.900133) (xy 91.775054 -384.869583) (xy 91.738303 -384.832832) (xy 91.707753 -384.790784)
			(xy 91.684157 -384.744474) (xy 91.668096 -384.695044) (xy 91.659966 -384.643709) (xy 91.120466 -384.643709)
			(xy 91.112336 -384.695044) (xy 91.096275 -384.744474) (xy 91.072679 -384.790784) (xy 91.042129 -384.832832)
			(xy 91.005378 -384.869583) (xy 90.96333 -384.900133) (xy 90.91702 -384.923729) (xy 90.86759 -384.93979)
			(xy 90.816255 -384.94792) (xy 90.764281 -384.94792) (xy 90.712946 -384.93979) (xy 90.663516 -384.923729)
			(xy 90.617206 -384.900133) (xy 90.575158 -384.869583) (xy 90.538407 -384.832832) (xy 90.507857 -384.790784)
			(xy 90.484261 -384.744474) (xy 90.4682 -384.695044) (xy 90.46007 -384.643709) (xy 89.920316 -384.643709)
			(xy 89.912186 -384.695044) (xy 89.896125 -384.744474) (xy 89.872529 -384.790784) (xy 89.841979 -384.832832)
			(xy 89.805228 -384.869583) (xy 89.76318 -384.900133) (xy 89.71687 -384.923729) (xy 89.66744 -384.93979)
			(xy 89.616105 -384.94792) (xy 89.564131 -384.94792) (xy 89.512796 -384.93979) (xy 89.463366 -384.923729)
			(xy 89.417056 -384.900133) (xy 89.375008 -384.869583) (xy 89.338257 -384.832832) (xy 89.307707 -384.790784)
			(xy 89.284111 -384.744474) (xy 89.26805 -384.695044) (xy 89.25992 -384.643709) (xy 88.72042 -384.643709)
			(xy 88.71229 -384.695044) (xy 88.696229 -384.744474) (xy 88.672633 -384.790784) (xy 88.642083 -384.832832)
			(xy 88.605332 -384.869583) (xy 88.563284 -384.900133) (xy 88.516974 -384.923729) (xy 88.467544 -384.93979)
			(xy 88.416209 -384.94792) (xy 88.364235 -384.94792) (xy 88.3129 -384.93979) (xy 88.26347 -384.923729)
			(xy 88.21716 -384.900133) (xy 88.175112 -384.869583) (xy 88.138361 -384.832832) (xy 88.107811 -384.790784)
			(xy 88.084215 -384.744474) (xy 88.068154 -384.695044) (xy 88.060024 -384.643709) (xy 87.520295 -384.643709)
			(xy 87.512161 -384.695044) (xy 87.496097 -384.744473) (xy 87.472497 -384.790782) (xy 87.441944 -384.832828)
			(xy 87.40519 -384.869577) (xy 87.363139 -384.900123) (xy 87.316827 -384.923716) (xy 87.267395 -384.939773)
			(xy 87.216059 -384.947899) (xy 87.190072 -384.94843) (xy 87.168066 -384.948084) (xy 87.12444 -384.942274)
			(xy 87.081973 -384.930721) (xy 87.061548 -384.922522) (xy 87.047324 -384.916426) (xy 87.017098 -384.922268)
			(xy 86.683596 -385.25577) (xy 86.676052 -385.264043) (xy 86.668343 -385.285034) (xy 86.670296 -385.307311)
			(xy 86.675468 -385.317238) (xy 86.92007 -385.740402) (xy 86.927436 -385.746244) (xy 86.946217 -385.762046)
			(xy 86.979356 -385.798251) (xy 87.006782 -385.838955) (xy 87.027893 -385.883264) (xy 87.042224 -385.930207)
			(xy 87.049463 -385.978751) (xy 87.049864 -386.003292) (xy 87.04961 -386.015484) (xy 87.049356 -386.025136)
			(xy 87.055452 -386.04317) (xy 87.114126 -386.11048) (xy 87.13089 -386.119116) (xy 87.140542 -386.120132)
			(xy 87.167313 -386.123454) (xy 87.219349 -386.137671) (xy 87.268388 -386.160144) (xy 87.31313 -386.190277)
			(xy 87.352389 -386.227271) (xy 87.385125 -386.270145) (xy 87.410469 -386.317764) (xy 87.42775 -386.368864)
			(xy 87.43651 -386.422091) (xy 87.43696 -386.449062) (xy 87.436397 -386.476344) (xy 87.427434 -386.530168)
			(xy 87.409762 -386.581791) (xy 87.383858 -386.629816) (xy 87.350426 -386.672939) (xy 87.330788 -386.691886)
			(xy 87.323345 -386.69938) (xy 87.314813 -386.718675) (xy 87.314278 -386.729224) (xy 87.314278 -386.8039)
			(xy 87.314868 -386.814434) (xy 87.323399 -386.833706) (xy 87.330788 -386.841238) (xy 87.35044 -386.860172)
			(xy 87.383877 -386.903295) (xy 87.409779 -386.951322) (xy 87.427445 -387.00295) (xy 87.436394 -387.056778)
			(xy 87.43696 -387.084062) (xy 87.436527 -387.108179) (xy 87.42953 -387.155904) (xy 87.41568 -387.202107)
			(xy 87.39527 -387.245811) (xy 87.38235 -387.26618) (xy 87.376508 -387.27507) (xy 87.372952 -387.295136)
			(xy 87.394034 -387.387338) (xy 87.406226 -387.404102) (xy 87.415116 -387.409436) (xy 87.435919 -387.422291)
			(xy 87.473837 -387.453168) (xy 87.506788 -387.489298) (xy 87.534052 -387.529892) (xy 87.555033 -387.574062)
			(xy 87.569272 -387.620843) (xy 87.576458 -387.669212) (xy 87.576914 -387.693662) (xy 87.576476 -387.718032)
			(xy 87.56932 -387.766245) (xy 87.555171 -387.812887) (xy 87.534335 -387.856949) (xy 87.507263 -387.89748)
			(xy 87.47454 -387.933603) (xy 87.45601 -387.94944) (xy 87.44712 -387.956552) (xy 87.437722 -387.97611)
			(xy 87.434928 -388.075424) (xy 87.443564 -388.09549) (xy 87.451946 -388.10311) (xy 87.469582 -388.119823)
			(xy 87.499845 -388.157832) (xy 87.5237 -388.200158) (xy 87.540542 -388.245731) (xy 87.545672 -388.26948)
			(xy 87.549228 -388.287514) (xy 87.577168 -388.310628) (xy 88.115394 -388.310628)
		)
		(stroke
			(width 0)
			(type solid)
		)
		(fill yes)
		(layer "In15.Cu")
		(net "P1V8_CPU1_RT1_1A_1D")
	)
	(gr_poly
		(pts
			(xy 378.715524 -396.669514) (xy 378.71908 -396.65148) (xy 378.724254 -396.627743) (xy 378.741102 -396.582179)
			(xy 378.764946 -396.539855) (xy 378.795185 -396.501834) (xy 378.812806 -396.48511) (xy 378.821188 -396.47749)
			(xy 378.829824 -396.457424) (xy 378.82703 -396.35811) (xy 378.817632 -396.338552) (xy 378.808742 -396.33144)
			(xy 378.790179 -396.315639) (xy 378.757448 -396.279514) (xy 378.730372 -396.238977) (xy 378.709536 -396.194907)
			(xy 378.695392 -396.148257) (xy 378.688245 -396.100036) (xy 378.687838 -396.075662) (xy 378.688277 -396.051546)
			(xy 378.695283 -396.003826) (xy 378.709142 -395.957629) (xy 378.72956 -395.913932) (xy 378.742448 -395.893544)
			(xy 378.74829 -395.884654) (xy 378.751846 -395.864588) (xy 378.730764 -395.772386) (xy 378.718572 -395.755622)
			(xy 378.709682 -395.750288) (xy 378.688878 -395.737434) (xy 378.650958 -395.706557) (xy 378.618005 -395.670427)
			(xy 378.590738 -395.629833) (xy 378.569754 -395.585663) (xy 378.555512 -395.538882) (xy 378.548322 -395.490513)
			(xy 378.547884 -395.466062) (xy 378.548445 -395.438779) (xy 378.557406 -395.384955) (xy 378.575077 -395.33333)
			(xy 378.600981 -395.285305) (xy 378.634414 -395.242182) (xy 378.654056 -395.223238) (xy 378.66151 -395.215748)
			(xy 378.67006 -395.196453) (xy 378.670566 -395.1859) (xy 378.670566 -395.111224) (xy 378.669979 -395.10069)
			(xy 378.661447 -395.081417) (xy 378.654056 -395.073886) (xy 378.6344 -395.054954) (xy 378.600956 -395.011833)
			(xy 378.575046 -394.963807) (xy 378.557375 -394.912177) (xy 378.54842 -394.858347) (xy 378.547884 -394.831062)
			(xy 378.548138 -394.81887) (xy 378.548392 -394.809218) (xy 378.542296 -394.791184) (xy 378.483622 -394.723874)
			(xy 378.466858 -394.715238) (xy 378.456952 -394.714222) (xy 378.430039 -394.710871) (xy 378.37774 -394.696525)
			(xy 378.328484 -394.673836) (xy 378.283591 -394.643412) (xy 378.244266 -394.60607) (xy 378.211562 -394.56281)
			(xy 378.186357 -394.514792) (xy 378.169327 -394.463305) (xy 378.164598 -394.4366) (xy 378.163074 -394.427202)
			(xy 377.890278 -393.95527) (xy 377.882912 -393.949428) (xy 377.864135 -393.933624) (xy 377.831004 -393.897416)
			(xy 377.803586 -393.856711) (xy 377.782482 -393.812402) (xy 377.768157 -393.765461) (xy 377.760924 -393.716919)
			(xy 377.760484 -393.69238) (xy 377.760995 -393.666394) (xy 377.769128 -393.615061) (xy 377.785191 -393.565633)
			(xy 377.808787 -393.519325) (xy 377.839337 -393.477279) (xy 377.876088 -393.44053) (xy 377.918136 -393.409981)
			(xy 377.964444 -393.386386) (xy 378.013873 -393.370325) (xy 378.065206 -393.362194) (xy 378.091192 -393.361672)
			(xy 378.117203 -393.362156) (xy 378.168584 -393.370302) (xy 378.218055 -393.386394) (xy 378.264396 -393.410034)
			(xy 378.306462 -393.440639) (xy 378.343217 -393.477455) (xy 378.373753 -393.519573) (xy 378.397316 -393.565953)
			(xy 378.413326 -393.61545) (xy 378.417836 -393.641072) (xy 378.41936 -393.65047) (xy 378.692156 -394.122402)
			(xy 378.699522 -394.128244) (xy 378.718299 -394.144049) (xy 378.75143 -394.180257) (xy 378.778848 -394.220962)
			(xy 378.799953 -394.265271) (xy 378.814281 -394.312211) (xy 378.821517 -394.360753) (xy 378.82195 -394.385292)
			(xy 378.821696 -394.397484) (xy 378.821442 -394.407136) (xy 378.827538 -394.42517) (xy 378.886212 -394.49248)
			(xy 378.902976 -394.501116) (xy 378.912882 -394.502132) (xy 378.939651 -394.505457) (xy 378.991682 -394.519679)
			(xy 379.040715 -394.542155) (xy 379.085451 -394.572289) (xy 379.124705 -394.609283) (xy 379.157436 -394.652156)
			(xy 379.182777 -394.699772) (xy 379.200055 -394.750869) (xy 379.208814 -394.804092) (xy 379.2093 -394.831062)
			(xy 379.208737 -394.858344) (xy 379.199773 -394.912166) (xy 379.182098 -394.963788) (xy 379.156191 -395.011809)
			(xy 379.122755 -395.054928) (xy 379.103128 -395.073886) (xy 379.09568 -395.081378) (xy 379.087141 -395.100673)
			(xy 379.086618 -395.111224) (xy 379.086618 -395.1859) (xy 379.087209 -395.196433) (xy 379.095745 -395.215701)
			(xy 379.103128 -395.223238) (xy 379.122783 -395.24217) (xy 379.156226 -395.285291) (xy 379.182133 -395.333318)
			(xy 379.199802 -395.384947) (xy 379.208753 -395.438777) (xy 379.2093 -395.466062) (xy 379.208867 -395.49018)
			(xy 379.201871 -395.537905) (xy 379.188023 -395.584109) (xy 379.167614 -395.627814) (xy 379.15469 -395.64818)
			(xy 379.148848 -395.65707) (xy 379.145292 -395.677136) (xy 379.166374 -395.769338) (xy 379.178566 -395.786102)
			(xy 379.187456 -395.791436) (xy 379.208257 -395.804292) (xy 379.24617 -395.835172) (xy 379.279118 -395.871303)
			(xy 379.306378 -395.911897) (xy 379.327356 -395.956066) (xy 379.341593 -396.002846) (xy 379.348778 -396.051213)
			(xy 379.349254 -396.075662) (xy 379.348816 -396.100033) (xy 379.341661 -396.148246) (xy 379.327513 -396.194889)
			(xy 379.306678 -396.238953) (xy 379.279608 -396.279487) (xy 379.246888 -396.315613) (xy 379.22835 -396.33144)
			(xy 379.21946 -396.338552) (xy 379.210062 -396.35811) (xy 379.207268 -396.457424) (xy 379.215904 -396.47749)
			(xy 379.224286 -396.48511) (xy 379.24192 -396.501825) (xy 379.27218 -396.539835) (xy 379.296031 -396.582161)
			(xy 379.312871 -396.627734) (xy 379.318012 -396.65148) (xy 379.321568 -396.669514) (xy 379.349508 -396.692628)
			(xy 379.88748 -396.692628) (xy 379.91542 -396.669514) (xy 379.918976 -396.65148) (xy 379.92415 -396.627743)
			(xy 379.940998 -396.582179) (xy 379.964842 -396.539854) (xy 379.99508 -396.501834) (xy 380.012702 -396.48511)
			(xy 380.021084 -396.47749) (xy 380.02972 -396.457424) (xy 380.026926 -396.35811) (xy 380.017528 -396.338552)
			(xy 380.008638 -396.33144) (xy 379.990075 -396.315639) (xy 379.957345 -396.279513) (xy 379.930269 -396.238977)
			(xy 379.909433 -396.194907) (xy 379.895289 -396.148256) (xy 379.888143 -396.100036) (xy 379.887734 -396.075662)
			(xy 379.888173 -396.051546) (xy 379.895179 -396.003826) (xy 379.909038 -395.957629) (xy 379.929455 -395.913932)
			(xy 379.942344 -395.893544) (xy 379.948186 -395.884654) (xy 379.951742 -395.864588) (xy 379.93066 -395.772386)
			(xy 379.918468 -395.755622) (xy 379.909578 -395.750288) (xy 379.888775 -395.737434) (xy 379.850855 -395.706557)
			(xy 379.817902 -395.670427) (xy 379.790635 -395.629833) (xy 379.769652 -395.585663) (xy 379.75541 -395.538882)
			(xy 379.74822 -395.490513) (xy 379.74778 -395.466062) (xy 379.748341 -395.438779) (xy 379.757301 -395.384954)
			(xy 379.774973 -395.33333) (xy 379.800876 -395.285305) (xy 379.83431 -395.242181) (xy 379.853952 -395.223238)
			(xy 379.861406 -395.215749) (xy 379.869958 -395.196453) (xy 379.870462 -395.1859) (xy 379.870462 -395.111224)
			(xy 379.869875 -395.10069) (xy 379.861342 -395.081417) (xy 379.853952 -395.073886) (xy 379.834297 -395.054953)
			(xy 379.800853 -395.011833) (xy 379.774943 -394.963806) (xy 379.757272 -394.912177) (xy 379.748317 -394.858347)
			(xy 379.74778 -394.831062) (xy 379.748034 -394.81887) (xy 379.748288 -394.809218) (xy 379.742192 -394.791184)
			(xy 379.683518 -394.723874) (xy 379.666754 -394.715238) (xy 379.656848 -394.714222) (xy 379.629935 -394.71087)
			(xy 379.577637 -394.696524) (xy 379.528381 -394.673835) (xy 379.483489 -394.643411) (xy 379.444164 -394.606068)
			(xy 379.411461 -394.562809) (xy 379.386256 -394.514791) (xy 379.369226 -394.463304) (xy 379.364494 -394.4366)
			(xy 379.36297 -394.427202) (xy 379.08992 -393.954762) (xy 379.082808 -393.94892) (xy 379.064073 -393.933142)
			(xy 379.031015 -393.896999) (xy 379.003653 -393.856374) (xy 378.982586 -393.812156) (xy 378.968276 -393.765312)
			(xy 378.961036 -393.71687) (xy 378.960634 -393.69238) (xy 378.961119 -393.666393) (xy 378.969253 -393.615059)
			(xy 378.985317 -393.56563) (xy 379.008917 -393.519323) (xy 379.03947 -393.477277) (xy 379.076225 -393.44053)
			(xy 379.118276 -393.409984) (xy 379.164587 -393.386393) (xy 379.21402 -393.370338) (xy 379.265355 -393.362214)
			(xy 379.291342 -393.361672) (xy 379.317388 -393.362155) (xy 379.368837 -393.370312) (xy 379.418371 -393.386434)
			(xy 379.464766 -393.410121) (xy 379.506874 -393.440789) (xy 379.543653 -393.477678) (xy 379.574195 -393.519877)
			(xy 379.597744 -393.566342) (xy 379.613718 -393.615924) (xy 379.61824 -393.64158) (xy 379.61951 -393.650978)
			(xy 379.643446 -393.69238) (xy 380.16053 -393.69238) (xy 380.160957 -393.666388) (xy 380.169092 -393.615045)
			(xy 380.18516 -393.565607) (xy 380.208763 -393.519292) (xy 380.239322 -393.477239) (xy 380.276083 -393.440484)
			(xy 380.318141 -393.409933) (xy 380.364461 -393.386337) (xy 380.413902 -393.370279) (xy 380.465246 -393.362152)
			(xy 380.491238 -393.361672) (xy 380.517249 -393.362107) (xy 380.568627 -393.370272) (xy 380.618094 -393.386378)
			(xy 380.66443 -393.410028) (xy 380.706493 -393.44064) (xy 380.743246 -393.477459) (xy 380.773782 -393.519577)
			(xy 380.79735 -393.565955) (xy 380.813367 -393.615451) (xy 380.817882 -393.641072) (xy 380.819406 -393.65047)
			(xy 381.092202 -394.122402) (xy 381.099568 -394.128244) (xy 381.118363 -394.144025) (xy 381.151477 -394.180248)
			(xy 381.178883 -394.220961) (xy 381.19998 -394.265273) (xy 381.214307 -394.312213) (xy 381.221551 -394.360753)
			(xy 381.221996 -394.385292) (xy 381.221742 -394.397484) (xy 381.221488 -394.407136) (xy 381.227584 -394.42517)
			(xy 381.286258 -394.49248) (xy 381.303022 -394.501116) (xy 381.312674 -394.502132) (xy 381.339433 -394.505513)
			(xy 381.391456 -394.519731) (xy 381.440482 -394.542202) (xy 381.485211 -394.572331) (xy 381.52446 -394.609319)
			(xy 381.557186 -394.652185) (xy 381.582523 -394.699793) (xy 381.599799 -394.750882) (xy 381.608556 -394.804097)
			(xy 381.609092 -394.831062) (xy 381.608582 -394.857049) (xy 381.600452 -394.908384) (xy 381.584391 -394.957814)
			(xy 381.560795 -395.004124) (xy 381.530245 -395.046172) (xy 381.493494 -395.082923) (xy 381.451446 -395.113473)
			(xy 381.405136 -395.137069) (xy 381.355706 -395.15313) (xy 381.304371 -395.16126) (xy 381.252397 -395.16126)
			(xy 381.201062 -395.15313) (xy 381.151632 -395.137069) (xy 381.105322 -395.113473) (xy 381.063274 -395.082923)
			(xy 381.026523 -395.046172) (xy 380.995973 -395.004124) (xy 380.972377 -394.957814) (xy 380.956316 -394.908384)
			(xy 380.948186 -394.857049) (xy 380.947676 -394.831062) (xy 380.94793 -394.81887) (xy 380.948184 -394.809218)
			(xy 380.942088 -394.791184) (xy 380.883414 -394.723874) (xy 380.86665 -394.715238) (xy 380.856998 -394.714222)
			(xy 380.830095 -394.71082) (xy 380.77781 -394.696462) (xy 380.728567 -394.673769) (xy 380.683683 -394.643349)
			(xy 380.644363 -394.606015) (xy 380.611657 -394.562769) (xy 380.586442 -394.514768) (xy 380.569394 -394.463297)
			(xy 380.564644 -394.4366) (xy 380.56312 -394.427202) (xy 380.290324 -393.95527) (xy 380.282958 -393.949428)
			(xy 380.264202 -393.933601) (xy 380.231085 -393.897388) (xy 380.203674 -393.856685) (xy 380.182569 -393.812382)
			(xy 380.168234 -393.76545) (xy 380.16098 -393.716916) (xy 380.16053 -393.69238) (xy 379.643446 -393.69238)
			(xy 379.892052 -394.122402) (xy 379.899418 -394.128244) (xy 379.918195 -394.144049) (xy 379.951326 -394.180257)
			(xy 379.978745 -394.220962) (xy 379.99985 -394.26527) (xy 380.014178 -394.312211) (xy 380.021415 -394.360753)
			(xy 380.021846 -394.385292) (xy 380.021592 -394.397484) (xy 380.021338 -394.407136) (xy 380.027434 -394.42517)
			(xy 380.086108 -394.49248) (xy 380.102872 -394.501116) (xy 380.112778 -394.502132) (xy 380.139547 -394.505457)
			(xy 380.191578 -394.519678) (xy 380.240612 -394.542154) (xy 380.285349 -394.572288) (xy 380.324604 -394.609282)
			(xy 380.357335 -394.652155) (xy 380.382676 -394.699771) (xy 380.399955 -394.750869) (xy 380.408713 -394.804092)
			(xy 380.409196 -394.831062) (xy 380.408633 -394.858344) (xy 380.399669 -394.912166) (xy 380.381993 -394.963787)
			(xy 380.356087 -395.011808) (xy 380.32265 -395.054927) (xy 380.303024 -395.073886) (xy 380.295576 -395.081378)
			(xy 380.287038 -395.100674) (xy 380.286514 -395.111224) (xy 380.286514 -395.1859) (xy 380.287105 -395.196433)
			(xy 380.295641 -395.215701) (xy 380.303024 -395.223238) (xy 380.322679 -395.24217) (xy 380.356122 -395.285291)
			(xy 380.38203 -395.333318) (xy 380.399699 -395.384947) (xy 380.408651 -395.438777) (xy 380.409196 -395.466062)
			(xy 380.408763 -395.49018) (xy 380.401767 -395.537905) (xy 380.387918 -395.584109) (xy 380.36751 -395.627813)
			(xy 380.354586 -395.64818) (xy 380.348744 -395.65707) (xy 380.345188 -395.677136) (xy 380.36627 -395.769338)
			(xy 380.378462 -395.786102) (xy 380.387352 -395.791436) (xy 380.408153 -395.804292) (xy 380.446067 -395.835171)
			(xy 380.479015 -395.871303) (xy 380.506275 -395.911897) (xy 380.527254 -395.956066) (xy 380.541491 -396.002845)
			(xy 380.548676 -396.051213) (xy 380.54915 -396.075662) (xy 380.548712 -396.100033) (xy 380.541557 -396.148246)
			(xy 380.527408 -396.194889) (xy 380.506574 -396.238953) (xy 380.479504 -396.279486) (xy 380.446783 -396.315612)
			(xy 380.428246 -396.33144) (xy 380.419356 -396.338552) (xy 380.409958 -396.35811) (xy 380.407164 -396.457424)
			(xy 380.4158 -396.47749) (xy 380.424182 -396.48511) (xy 380.441816 -396.501824) (xy 380.472076 -396.539834)
			(xy 380.495928 -396.582161) (xy 380.512768 -396.627734) (xy 380.517908 -396.65148) (xy 380.521464 -396.669514)
			(xy 380.549404 -396.692628) (xy 381.087376 -396.692628) (xy 381.115316 -396.669514) (xy 381.118872 -396.65148)
			(xy 381.124133 -396.627324) (xy 381.141407 -396.581005) (xy 381.165919 -396.538075) (xy 381.197028 -396.499655)
			(xy 381.233922 -396.466751) (xy 381.275635 -396.440222) (xy 381.321079 -396.420761) (xy 381.369065 -396.408877)
			(xy 381.418338 -396.404881) (xy 381.467611 -396.408877) (xy 381.515597 -396.420761) (xy 381.561041 -396.440222)
			(xy 381.602754 -396.466751) (xy 381.639648 -396.499655) (xy 381.670757 -396.538075) (xy 381.695269 -396.581005)
			(xy 381.712543 -396.627324) (xy 381.717804 -396.65148) (xy 381.72136 -396.669514) (xy 381.7493 -396.692628)
			(xy 381.993394 -396.692628) (xy 382.003465 -396.692207) (xy 382.022074 -396.684497) (xy 382.029462 -396.677642)
			(xy 382.193546 -396.513558) (xy 382.200392 -396.50616) (xy 382.208119 -396.487561) (xy 382.208532 -396.47749)
			(xy 382.208532 -396.27937) (xy 382.203706 -396.268956) (xy 382.190177 -396.238546) (xy 382.17107 -396.174791)
			(xy 382.161402 -396.10894) (xy 382.16078 -396.075662) (xy 382.161394 -396.042383) (xy 382.171064 -395.976531)
			(xy 382.190166 -395.912773) (xy 382.203706 -395.882368) (xy 382.208532 -395.871954) (xy 382.208532 -395.84884)
			(xy 382.198626 -395.82852) (xy 382.189736 -395.821154) (xy 382.167489 -395.80248) (xy 382.127427 -395.760425)
			(xy 382.093008 -395.713639) (xy 382.064786 -395.662873) (xy 382.043213 -395.608945) (xy 382.028638 -395.55272)
			(xy 382.021293 -395.495104) (xy 382.020826 -395.466062) (xy 382.021271 -395.437137) (xy 382.028565 -395.379747)
			(xy 382.043031 -395.323734) (xy 382.064439 -395.26999) (xy 382.092448 -395.219371) (xy 382.126611 -395.172685)
			(xy 382.166384 -395.130675) (xy 382.188466 -395.111986) (xy 382.195537 -395.10572) (xy 382.204818 -395.089278)
			(xy 382.2065 -395.079982) (xy 382.210818 -395.048994) (xy 382.211766 -395.039756) (xy 382.207733 -395.021644)
			(xy 382.202944 -395.013688) (xy 382.18991 -394.993291) (xy 382.169309 -394.949489) (xy 382.155321 -394.903149)
			(xy 382.148247 -394.855264) (xy 382.147826 -394.831062) (xy 382.14808 -394.81887) (xy 382.148334 -394.809218)
			(xy 382.142238 -394.791184) (xy 382.083564 -394.723874) (xy 382.0668 -394.715238) (xy 382.056894 -394.714222)
			(xy 382.029979 -394.710874) (xy 381.977675 -394.696533) (xy 381.928413 -394.673847) (xy 381.883515 -394.643425)
			(xy 381.844184 -394.606083) (xy 381.811475 -394.562822) (xy 381.786266 -394.514803) (xy 381.769233 -394.463313)
			(xy 381.76454 -394.4366) (xy 381.763016 -394.427202) (xy 381.49022 -393.95527) (xy 381.482854 -393.949428)
			(xy 381.464075 -393.933625) (xy 381.43094 -393.897419) (xy 381.403518 -393.856715) (xy 381.382412 -393.812405)
			(xy 381.368085 -393.765463) (xy 381.36085 -393.71692) (xy 381.360426 -393.69238) (xy 381.360911 -393.666393)
			(xy 381.369045 -393.615059) (xy 381.385109 -393.565629) (xy 381.408708 -393.519321) (xy 381.439262 -393.477275)
			(xy 381.476016 -393.440526) (xy 381.518067 -393.40998) (xy 381.564379 -393.386388) (xy 381.613811 -393.370332)
			(xy 381.665147 -393.362206) (xy 381.691134 -393.361672) (xy 381.717148 -393.362152) (xy 381.768535 -393.37029)
			(xy 381.818014 -393.386377) (xy 381.864362 -393.410013) (xy 381.906437 -393.440618) (xy 381.943199 -393.477434)
			(xy 381.973741 -393.519553) (xy 381.99731 -393.565937) (xy 382.013323 -393.615439) (xy 382.017778 -393.641072)
			(xy 382.019302 -393.65047) (xy 382.292098 -394.122402) (xy 382.299464 -394.128244) (xy 382.318244 -394.144047)
			(xy 382.35138 -394.180253) (xy 382.378804 -394.220957) (xy 382.399912 -394.265266) (xy 382.414243 -394.312208)
			(xy 382.421481 -394.360752) (xy 382.421892 -394.385292) (xy 382.421638 -394.397484) (xy 382.421384 -394.407136)
			(xy 382.42748 -394.42517) (xy 382.486154 -394.49248) (xy 382.502918 -394.501116) (xy 382.512824 -394.502132)
			(xy 382.539259 -394.50542) (xy 382.59067 -394.519356) (xy 382.639182 -394.541354) (xy 382.68354 -394.570844)
			(xy 382.722596 -394.607064) (xy 382.755341 -394.649077) (xy 382.780927 -394.695796) (xy 382.798692 -394.746012)
			(xy 382.803908 -394.772134) (xy 382.80721 -394.790422) (xy 382.835404 -394.81379) (xy 383.008378 -394.81379)
			(xy 383.018731 -394.813363) (xy 383.037789 -394.805281) (xy 383.052083 -394.790308) (xy 383.05613 -394.78077)
			(xy 383.094992 -394.67663) (xy 383.087118 -394.645896) (xy 383.074926 -394.635482) (xy 383.057628 -394.619982)
			(xy 383.027116 -394.584963) (xy 383.001805 -394.546019) (xy 382.982193 -394.503917) (xy 382.968665 -394.459484)
			(xy 382.96469 -394.4366) (xy 382.963166 -394.427202) (xy 382.69037 -393.95527) (xy 382.683004 -393.949428)
			(xy 382.664227 -393.933624) (xy 382.631097 -393.897416) (xy 382.60368 -393.85671) (xy 382.582577 -393.812401)
			(xy 382.568252 -393.765461) (xy 382.561019 -393.716919) (xy 382.560576 -393.69238) (xy 382.561087 -393.666393)
			(xy 382.56922 -393.61506) (xy 382.585283 -393.565631) (xy 382.608879 -393.519324) (xy 382.639429 -393.477277)
			(xy 382.67618 -393.440526) (xy 382.718227 -393.409977) (xy 382.764535 -393.386381) (xy 382.813964 -393.370319)
			(xy 382.865297 -393.362187) (xy 382.891284 -393.361672) (xy 382.917296 -393.362156) (xy 382.968677 -393.3703)
			(xy 383.018149 -393.386391) (xy 383.064491 -393.410031) (xy 383.106559 -393.440636) (xy 383.143315 -393.477452)
			(xy 383.173851 -393.51957) (xy 383.197415 -393.56595) (xy 383.213425 -393.615449) (xy 383.217928 -393.641072)
			(xy 383.219452 -393.65047) (xy 383.492248 -394.122402) (xy 383.499614 -394.128244) (xy 383.518391 -394.144048)
			(xy 383.551523 -394.180256) (xy 383.578942 -394.220961) (xy 383.600048 -394.26527) (xy 383.614376 -394.31221)
			(xy 383.621612 -394.360753) (xy 383.622042 -394.385292) (xy 383.621788 -394.397484) (xy 383.621534 -394.407136)
			(xy 383.62763 -394.42517) (xy 383.686304 -394.49248) (xy 383.703068 -394.501116) (xy 383.71272 -394.502132)
			(xy 383.739155 -394.50542) (xy 383.790566 -394.519355) (xy 383.839079 -394.541353) (xy 383.883437 -394.570843)
			(xy 383.922494 -394.607063) (xy 383.955239 -394.649076) (xy 383.980826 -394.695795) (xy 383.998591 -394.746011)
			(xy 384.003804 -394.772134) (xy 384.007106 -394.790422) (xy 384.0353 -394.81379) (xy 384.208274 -394.81379)
			(xy 384.218628 -394.813364) (xy 384.237686 -394.805282) (xy 384.251982 -394.79031) (xy 384.256026 -394.78077)
			(xy 384.294888 -394.67663) (xy 384.287014 -394.645896) (xy 384.274822 -394.635482) (xy 384.257524 -394.619982)
			(xy 384.227013 -394.584963) (xy 384.201702 -394.546019) (xy 384.18209 -394.503916) (xy 384.168562 -394.459484)
			(xy 384.164586 -394.4366) (xy 384.163062 -394.427202) (xy 383.890266 -393.95527) (xy 383.8829 -393.949428)
			(xy 383.864123 -393.933623) (xy 383.830993 -393.897415) (xy 383.803576 -393.85671) (xy 383.782474 -393.812401)
			(xy 383.768149 -393.765461) (xy 383.760916 -393.716919) (xy 383.760472 -393.69238) (xy 383.760983 -393.666393)
			(xy 383.769116 -393.61506) (xy 383.785178 -393.565631) (xy 383.808775 -393.519323) (xy 383.839325 -393.477276)
			(xy 383.876076 -393.440525) (xy 383.918123 -393.409975) (xy 383.964431 -393.386378) (xy 384.01386 -393.370316)
			(xy 384.065193 -393.362183) (xy 384.09118 -393.361672) (xy 384.117192 -393.362156) (xy 384.168574 -393.3703)
			(xy 384.218046 -393.38639) (xy 384.264389 -393.41003) (xy 384.306457 -393.440635) (xy 384.343213 -393.477451)
			(xy 384.373751 -393.519569) (xy 384.397315 -393.565949) (xy 384.413325 -393.615448) (xy 384.417824 -393.641072)
			(xy 384.419348 -393.65047) (xy 384.692144 -394.122402) (xy 384.69951 -394.128244) (xy 384.718288 -394.144048)
			(xy 384.75142 -394.180256) (xy 384.778839 -394.220961) (xy 384.799945 -394.26527) (xy 384.814273 -394.31221)
			(xy 384.82151 -394.360753) (xy 384.821938 -394.385292) (xy 384.821684 -394.397484) (xy 384.82143 -394.407136)
			(xy 384.827526 -394.42517) (xy 384.8862 -394.49248) (xy 384.902964 -394.501116) (xy 384.91287 -394.502132)
			(xy 384.93964 -394.505456) (xy 384.991672 -394.519677) (xy 385.040707 -394.542152) (xy 385.085445 -394.572285)
			(xy 385.1247 -394.609279) (xy 385.157433 -394.652153) (xy 385.182775 -394.69977) (xy 385.200054 -394.750868)
			(xy 385.208813 -394.804092) (xy 385.209288 -394.831062) (xy 385.20888 -394.8548) (xy 385.202094 -394.90179)
			(xy 385.188656 -394.947325) (xy 385.168842 -394.99047) (xy 385.143059 -395.030336) (xy 385.127754 -395.048486)
			(xy 385.121404 -395.055852) (xy 385.115054 -395.073632) (xy 385.117594 -395.15288) (xy 385.118341 -395.162477)
			(xy 385.126043 -395.180103) (xy 385.13258 -395.18717) (xy 385.815332 -395.869922) (xy 385.823193 -395.876973)
			(xy 385.842871 -395.884568) (xy 385.853432 -395.884654) (xy 385.939284 -395.880844) (xy 385.957826 -395.8717)
			(xy 385.964938 -395.863318) (xy 385.973066 -395.85392) (xy 385.960112 -395.797278) (xy 385.956964 -395.786347)
			(xy 385.942863 -395.768535) (xy 385.932934 -395.762988) (xy 385.909495 -395.75093) (xy 385.866446 -395.72052)
			(xy 385.828764 -395.683668) (xy 385.797403 -395.641306) (xy 385.773158 -395.594506) (xy 385.756642 -395.544454)
			(xy 385.748273 -395.492415) (xy 385.747768 -395.466062) (xy 385.748329 -395.438779) (xy 385.757289 -395.384954)
			(xy 385.77496 -395.333329) (xy 385.800863 -395.285303) (xy 385.834295 -395.242179) (xy 385.85394 -395.223238)
			(xy 385.861384 -395.215744) (xy 385.869919 -395.196449) (xy 385.87045 -395.1859) (xy 385.87045 -395.111224)
			(xy 385.869862 -395.10069) (xy 385.861329 -395.081419) (xy 385.85394 -395.073886) (xy 385.834285 -395.054953)
			(xy 385.800843 -395.011832) (xy 385.774934 -394.963805) (xy 385.757263 -394.912177) (xy 385.748309 -394.858347)
			(xy 385.747768 -394.831062) (xy 385.748022 -394.81887) (xy 385.748276 -394.809218) (xy 385.74218 -394.791184)
			(xy 385.683506 -394.723874) (xy 385.666742 -394.715238) (xy 385.656836 -394.714222) (xy 385.629924 -394.710869)
			(xy 385.577627 -394.696522) (xy 385.528373 -394.673832) (xy 385.483482 -394.643407) (xy 385.444159 -394.606065)
			(xy 385.411457 -394.562805) (xy 385.386253 -394.514788) (xy 385.369224 -394.463302) (xy 385.364482 -394.4366)
			(xy 385.362958 -394.427202) (xy 385.089908 -393.954762) (xy 385.082796 -393.94892) (xy 385.064061 -393.933141)
			(xy 385.031005 -393.896998) (xy 385.003644 -393.856373) (xy 384.982578 -393.812155) (xy 384.968268 -393.765312)
			(xy 384.961028 -393.71687) (xy 384.960622 -393.69238) (xy 384.961107 -393.666393) (xy 384.969241 -393.615058)
			(xy 384.985305 -393.565628) (xy 385.008904 -393.51932) (xy 385.039457 -393.477274) (xy 385.076212 -393.440525)
			(xy 385.118263 -393.409978) (xy 385.164575 -393.386386) (xy 385.214007 -393.370329) (xy 385.265343 -393.362203)
			(xy 385.29133 -393.361672) (xy 385.317377 -393.362154) (xy 385.368827 -393.37031) (xy 385.418363 -393.38643)
			(xy 385.464759 -393.410117) (xy 385.506868 -393.440784) (xy 385.543649 -393.477674) (xy 385.574193 -393.519873)
			(xy 385.597743 -393.566339) (xy 385.613717 -393.615922) (xy 385.618228 -393.64158) (xy 385.619498 -393.650978)
			(xy 385.89204 -394.122402) (xy 385.899406 -394.128244) (xy 385.918184 -394.144048) (xy 385.951316 -394.180256)
			(xy 385.978736 -394.220961) (xy 385.999842 -394.265269) (xy 386.01417 -394.31221) (xy 386.021407 -394.360752)
			(xy 386.021834 -394.385292) (xy 386.02158 -394.397484) (xy 386.021326 -394.407136) (xy 386.027422 -394.42517)
			(xy 386.086096 -394.49248) (xy 386.10286 -394.501116) (xy 386.112766 -394.502132) (xy 386.139536 -394.505456)
			(xy 386.191569 -394.519676) (xy 386.240604 -394.542151) (xy 386.285343 -394.572284) (xy 386.324599 -394.609278)
			(xy 386.357332 -394.652152) (xy 386.382674 -394.699769) (xy 386.399953 -394.750867) (xy 386.408712 -394.804092)
			(xy 386.409184 -394.831062) (xy 386.408621 -394.858344) (xy 386.399656 -394.912165) (xy 386.381981 -394.963786)
			(xy 386.356073 -395.011807) (xy 386.322636 -395.054924) (xy 386.303012 -395.073886) (xy 386.295566 -395.081379)
			(xy 386.28703 -395.100674) (xy 386.286502 -395.111224) (xy 386.286502 -395.1859) (xy 386.287093 -395.196433)
			(xy 386.295627 -395.215703) (xy 386.303012 -395.223238) (xy 386.322668 -395.24217) (xy 386.356112 -395.28529)
			(xy 386.382021 -395.333317) (xy 386.399691 -395.384947) (xy 386.408642 -395.438777) (xy 386.409184 -395.466062)
			(xy 386.408751 -395.490179) (xy 386.401755 -395.537904) (xy 386.387906 -395.584108) (xy 386.367497 -395.627813)
			(xy 386.354574 -395.64818) (xy 386.348732 -395.65707) (xy 386.345176 -395.677136) (xy 386.366258 -395.769338)
			(xy 386.37845 -395.786102) (xy 386.38734 -395.791436) (xy 386.408141 -395.804292) (xy 386.446057 -395.83517)
			(xy 386.479006 -395.871301) (xy 386.506268 -395.911895) (xy 386.527247 -395.956065) (xy 386.541485 -396.002845)
			(xy 386.54867 -396.051212) (xy 386.549138 -396.075662) (xy 386.548669 -396.100856) (xy 386.541036 -396.150661)
			(xy 386.525942 -396.198734) (xy 386.503735 -396.243963) (xy 386.489702 -396.264892) (xy 386.481574 -396.276576)
			(xy 386.479542 -396.30477) (xy 386.527802 -396.397226) (xy 386.532427 -396.405312) (xy 386.546305 -396.417714)
			(xy 386.563707 -396.424314) (xy 386.573014 -396.424658) (xy 387.063996 -396.424658) (xy 387.073289 -396.42424)
			(xy 387.090657 -396.417622) (xy 387.104554 -396.405279) (xy 387.109208 -396.397226) (xy 387.157468 -396.30477)
			(xy 387.155436 -396.276576) (xy 387.147308 -396.264892) (xy 387.133296 -396.243952) (xy 387.111096 -396.198724)
			(xy 387.096006 -396.150655) (xy 387.088377 -396.100853) (xy 387.087872 -396.075662) (xy 387.088311 -396.051546)
			(xy 387.095316 -396.003825) (xy 387.109172 -395.957626) (xy 387.129586 -395.913928) (xy 387.142482 -395.893544)
			(xy 387.148324 -395.884654) (xy 387.15188 -395.864588) (xy 387.130798 -395.772386) (xy 387.118606 -395.755622)
			(xy 387.109716 -395.750288) (xy 387.088911 -395.737435) (xy 387.050987 -395.70656) (xy 387.01803 -395.670431)
			(xy 386.99076 -395.629838) (xy 386.969774 -395.585667) (xy 386.95553 -395.538885) (xy 386.94834 -395.490514)
			(xy 386.947918 -395.466062) (xy 386.948479 -395.43878) (xy 386.95744 -395.384956) (xy 386.975113 -395.333332)
			(xy 387.001019 -395.285309) (xy 387.034455 -395.242188) (xy 387.05409 -395.223238) (xy 387.06154 -395.215747)
			(xy 387.070085 -395.196451) (xy 387.0706 -395.1859) (xy 387.0706 -395.111224) (xy 387.070014 -395.100689)
			(xy 387.061486 -395.081412) (xy 387.05409 -395.073886) (xy 387.034433 -395.054955) (xy 387.000985 -395.011835)
			(xy 386.975073 -394.963809) (xy 386.957399 -394.912179) (xy 386.948443 -394.858348) (xy 386.947918 -394.831062)
			(xy 386.948172 -394.81887) (xy 386.948426 -394.809218) (xy 386.94233 -394.791184) (xy 386.883656 -394.723874)
			(xy 386.866892 -394.715238) (xy 386.856986 -394.714222) (xy 386.830071 -394.710873) (xy 386.777768 -394.696531)
			(xy 386.728508 -394.673845) (xy 386.68361 -394.643423) (xy 386.64428 -394.606081) (xy 386.611572 -394.56282)
			(xy 386.586364 -394.514801) (xy 386.569332 -394.463311) (xy 386.564632 -394.4366) (xy 386.563108 -394.427202)
			(xy 386.290312 -393.95527) (xy 386.282946 -393.949428) (xy 386.264167 -393.933625) (xy 386.231033 -393.897418)
			(xy 386.203612 -393.856714) (xy 386.182506 -393.812404) (xy 386.168179 -393.765463) (xy 386.160945 -393.71692)
			(xy 386.160518 -393.69238) (xy 386.161003 -393.666393) (xy 386.169137 -393.615058) (xy 386.185201 -393.565628)
			(xy 386.2088 -393.519319) (xy 386.239353 -393.477273) (xy 386.276108 -393.440523) (xy 386.318158 -393.409976)
			(xy 386.36447 -393.386383) (xy 386.413903 -393.370326) (xy 386.465238 -393.362199) (xy 386.491226 -393.361672)
			(xy 386.51724 -393.362152) (xy 386.568629 -393.370289) (xy 386.618108 -393.386374) (xy 386.664458 -393.410011)
			(xy 386.706533 -393.440615) (xy 386.743296 -393.477431) (xy 386.77384 -393.519551) (xy 386.797409 -393.565934)
			(xy 386.813423 -393.615437) (xy 386.81787 -393.641072) (xy 386.819394 -393.65047) (xy 387.09219 -394.122402)
			(xy 387.099556 -394.128244) (xy 387.118336 -394.144047) (xy 387.151473 -394.180252) (xy 387.178898 -394.220956)
			(xy 387.200007 -394.265266) (xy 387.214338 -394.312208) (xy 387.221576 -394.360752) (xy 387.221984 -394.385292)
			(xy 387.22173 -394.397484) (xy 387.221476 -394.407136) (xy 387.227572 -394.42517) (xy 387.286246 -394.49248)
			(xy 387.30301 -394.501116) (xy 387.312916 -394.502132) (xy 387.339683 -394.505459) (xy 387.391709 -394.519685)
			(xy 387.440738 -394.542164) (xy 387.48547 -394.572299) (xy 387.524719 -394.609293) (xy 387.557446 -394.652165)
			(xy 387.582784 -394.69978) (xy 387.60006 -394.750874) (xy 387.608818 -394.804094) (xy 387.609334 -394.831062)
			(xy 387.608771 -394.858344) (xy 387.599808 -394.912167) (xy 387.582134 -394.96379) (xy 387.556229 -395.011813)
			(xy 387.522795 -395.054934) (xy 387.503162 -395.073886) (xy 387.495722 -395.081382) (xy 387.487195 -395.100676)
			(xy 387.486652 -395.111224) (xy 387.486652 -395.1859) (xy 387.487244 -395.196432) (xy 387.495784 -395.215696)
			(xy 387.503162 -395.223238) (xy 387.522815 -395.242171) (xy 387.556255 -395.285293) (xy 387.582159 -395.33332)
			(xy 387.599827 -395.384949) (xy 387.608776 -395.438778) (xy 387.609334 -395.466062) (xy 387.608901 -395.49018)
			(xy 387.601906 -395.537905) (xy 387.588058 -395.58411) (xy 387.567652 -395.627816) (xy 387.554724 -395.64818)
			(xy 387.548882 -395.65707) (xy 387.545326 -395.677136) (xy 387.566408 -395.769338) (xy 387.5786 -395.786102)
			(xy 387.58749 -395.791436) (xy 387.608294 -395.80429) (xy 387.646215 -395.835165) (xy 387.679169 -395.871295)
			(xy 387.706435 -395.911889) (xy 387.727417 -395.95606) (xy 387.741658 -396.002841) (xy 387.748844 -396.051211)
			(xy 387.749288 -396.075662) (xy 387.748819 -396.100855) (xy 387.741185 -396.15066) (xy 387.726089 -396.198732)
			(xy 387.703879 -396.24396) (xy 387.689852 -396.264892) (xy 387.681724 -396.276576) (xy 387.679692 -396.30477)
			(xy 387.727952 -396.397226) (xy 387.732579 -396.405306) (xy 387.746459 -396.417695) (xy 387.76386 -396.424278)
			(xy 387.773164 -396.424658) (xy 388.263892 -396.424658) (xy 388.273185 -396.42424) (xy 388.290555 -396.417623)
			(xy 388.304453 -396.405281) (xy 388.309104 -396.397226) (xy 388.357364 -396.30477) (xy 388.355332 -396.276576)
			(xy 388.347204 -396.264892) (xy 388.333192 -396.243952) (xy 388.310992 -396.198724) (xy 388.295903 -396.150655)
			(xy 388.288273 -396.100853) (xy 388.287768 -396.075662) (xy 388.288207 -396.051546) (xy 388.295212 -396.003825)
			(xy 388.309068 -395.957626) (xy 388.329482 -395.913927) (xy 388.342378 -395.893544) (xy 388.34822 -395.884654)
			(xy 388.351776 -395.864588) (xy 388.330694 -395.772386) (xy 388.318502 -395.755622) (xy 388.309612 -395.750288)
			(xy 388.288807 -395.737435) (xy 388.250883 -395.70656) (xy 388.217927 -395.670431) (xy 388.190658 -395.629837)
			(xy 388.169672 -395.585667) (xy 388.155428 -395.538884) (xy 388.148238 -395.490513) (xy 388.147814 -395.466062)
			(xy 388.148375 -395.43878) (xy 388.157336 -395.384956) (xy 388.175009 -395.333332) (xy 388.200914 -395.285309)
			(xy 388.23435 -395.242188) (xy 388.253986 -395.223238) (xy 388.261436 -395.215747) (xy 388.269981 -395.196451)
			(xy 388.270496 -395.1859) (xy 388.270496 -395.111224) (xy 388.26991 -395.100689) (xy 388.261381 -395.081413)
			(xy 388.253986 -395.073886) (xy 388.234329 -395.054954) (xy 388.200882 -395.011835) (xy 388.17497 -394.963808)
			(xy 388.157296 -394.912179) (xy 388.148341 -394.858348) (xy 388.147814 -394.831062) (xy 388.148068 -394.81887)
			(xy 388.148322 -394.809218) (xy 388.142226 -394.791184) (xy 388.083552 -394.723874) (xy 388.066788 -394.715238)
			(xy 388.056882 -394.714222) (xy 388.029967 -394.710873) (xy 387.977665 -394.69653) (xy 387.928405 -394.673844)
			(xy 387.883508 -394.643422) (xy 387.844178 -394.606079) (xy 387.811471 -394.562819) (xy 387.786263 -394.5148)
			(xy 387.769231 -394.463311) (xy 387.764528 -394.4366) (xy 387.763004 -394.427202) (xy 387.489954 -393.954762)
			(xy 387.482842 -393.94892) (xy 387.46411 -393.93314) (xy 387.431059 -393.896995) (xy 387.403702 -393.856369)
			(xy 387.38264 -393.812151) (xy 387.368333 -393.765309) (xy 387.361094 -393.716869) (xy 387.360668 -393.69238)
			(xy 387.361179 -393.666393) (xy 387.369312 -393.61506) (xy 387.385374 -393.56563) (xy 387.408971 -393.519322)
			(xy 387.439521 -393.477274) (xy 387.476271 -393.440523) (xy 387.518318 -393.409973) (xy 387.564627 -393.386376)
			(xy 387.614056 -393.370313) (xy 387.665389 -393.362179) (xy 387.691376 -393.361672) (xy 387.717425 -393.36215)
			(xy 387.768882 -393.370299) (xy 387.818425 -393.386414) (xy 387.864828 -393.410098) (xy 387.906945 -393.440764)
			(xy 387.943732 -393.477654) (xy 387.974282 -393.519855) (xy 387.997836 -393.566324) (xy 388.013815 -393.615911)
			(xy 388.018274 -393.64158) (xy 388.019544 -393.650978) (xy 388.04348 -393.69238) (xy 388.560564 -393.69238)
			(xy 388.561083 -393.666394) (xy 388.569216 -393.615061) (xy 388.585278 -393.565633) (xy 388.608874 -393.519325)
			(xy 388.639422 -393.477278) (xy 388.676172 -393.440528) (xy 388.718218 -393.409978) (xy 388.764525 -393.386381)
			(xy 388.813953 -393.370318) (xy 388.865286 -393.362184) (xy 388.891272 -393.361672) (xy 388.917281 -393.362167)
			(xy 388.968657 -393.370322) (xy 389.018123 -393.386418) (xy 389.064458 -393.410061) (xy 389.106522 -393.440665)
			(xy 389.143276 -393.477477) (xy 389.173813 -393.519589) (xy 389.179787 -393.531344) (xy 390.529318 -393.531344)
			(xy 390.529741 -393.506448) (xy 390.537193 -393.457216) (xy 390.551935 -393.409655) (xy 390.573634 -393.36484)
			(xy 390.601801 -393.32378) (xy 390.618472 -393.305284) (xy 390.625076 -393.298426) (xy 390.631934 -393.281408)
			(xy 390.63422 -393.195048) (xy 390.628124 -393.177522) (xy 390.622028 -393.17041) (xy 390.607263 -393.152421)
			(xy 390.582435 -393.113058) (xy 390.563373 -393.070602) (xy 390.550454 -393.025892) (xy 390.543935 -392.979812)
			(xy 390.543542 -392.956542) (xy 390.544014 -392.930551) (xy 390.552141 -392.879209) (xy 390.5682 -392.829771)
			(xy 390.591797 -392.783455) (xy 390.62235 -392.741401) (xy 390.659107 -392.704645) (xy 390.701162 -392.674093)
			(xy 390.747479 -392.650497) (xy 390.796917 -392.634439) (xy 390.848259 -392.626313) (xy 390.87425 -392.625834)
			(xy 390.89775 -392.626241) (xy 390.944281 -392.632869) (xy 390.96696 -392.639042) (xy 390.980422 -392.643106)
			(xy 391.006838 -392.636502) (xy 391.089896 -392.555222) (xy 391.097262 -392.52906) (xy 391.093706 -392.515598)
			(xy 391.087772 -392.491651) (xy 391.081396 -392.44273) (xy 391.081006 -392.418062) (xy 391.081492 -392.390811)
			(xy 391.089248 -392.336863) (xy 391.104603 -392.284568) (xy 391.127245 -392.234991) (xy 391.156711 -392.189141)
			(xy 391.192402 -392.14795) (xy 391.233593 -392.112259) (xy 391.279443 -392.082793) (xy 391.32902 -392.060151)
			(xy 391.381315 -392.044796) (xy 391.435263 -392.03704) (xy 391.489765 -392.03704) (xy 391.543713 -392.044796)
			(xy 391.596008 -392.060151) (xy 391.645585 -392.082793) (xy 391.691435 -392.112259) (xy 391.732626 -392.14795)
			(xy 391.768317 -392.189141) (xy 391.797783 -392.234991) (xy 391.820425 -392.284568) (xy 391.83578 -392.336863)
			(xy 391.843536 -392.390811) (xy 391.844022 -392.418062) (xy 391.843553 -392.445432) (xy 391.837719 -392.48588)
			(xy 392.180316 -392.48588) (xy 392.184387 -392.430258) (xy 392.196513 -392.375821) (xy 392.216436 -392.32373)
			(xy 392.243732 -392.275095) (xy 392.277818 -392.230952) (xy 392.317967 -392.192243) (xy 392.363325 -392.159792)
			(xy 392.412925 -392.134291) (xy 392.465709 -392.116284) (xy 392.520552 -392.106154) (xy 392.576286 -392.104117)
			(xy 392.631723 -392.110217) (xy 392.68568 -392.124323) (xy 392.737009 -392.146135) (xy 392.784615 -392.175189)
			(xy 392.827483 -392.210864) (xy 392.8647 -392.252401) (xy 392.895473 -392.298914) (xy 392.919145 -392.349411)
			(xy 392.935213 -392.402818) (xy 392.943333 -392.457994) (xy 392.943842 -392.48588) (xy 392.943333 -392.513766)
			(xy 392.935213 -392.568942) (xy 392.919145 -392.622349) (xy 392.895473 -392.672846) (xy 392.8647 -392.719359)
			(xy 392.827483 -392.760896) (xy 392.784615 -392.796571) (xy 392.737009 -392.825625) (xy 392.68568 -392.847437)
			(xy 392.631723 -392.861543) (xy 392.576286 -392.867643) (xy 392.520552 -392.865606) (xy 392.465709 -392.855476)
			(xy 392.412925 -392.837469) (xy 392.363325 -392.811968) (xy 392.317967 -392.779517) (xy 392.277818 -392.740808)
			(xy 392.243732 -392.696665) (xy 392.216436 -392.64803) (xy 392.196513 -392.595939) (xy 392.184387 -392.541502)
			(xy 392.180316 -392.48588) (xy 391.837719 -392.48588) (xy 391.835739 -392.499612) (xy 391.820251 -392.552116)
			(xy 391.79741 -392.601863) (xy 391.767684 -392.647829) (xy 391.750042 -392.66876) (xy 391.743946 -392.675872)
			(xy 391.737596 -392.69289) (xy 391.737596 -392.778234) (xy 391.743946 -392.795252) (xy 391.750042 -392.802364)
			(xy 391.767647 -392.823326) (xy 391.797375 -392.869288) (xy 391.820225 -392.919029) (xy 391.835725 -392.971527)
			(xy 391.843558 -393.025702) (xy 391.843562 -393.080441) (xy 391.835738 -393.134617) (xy 391.820245 -393.187117)
			(xy 391.797403 -393.236862) (xy 391.767681 -393.282828) (xy 391.750042 -393.30376) (xy 391.743946 -393.310872)
			(xy 391.737596 -393.32789) (xy 391.737596 -393.413234) (xy 391.743946 -393.430252) (xy 391.750042 -393.437364)
			(xy 391.767685 -393.458293) (xy 391.779438 -393.47648) (xy 392.180316 -393.47648) (xy 392.184387 -393.420858)
			(xy 392.196513 -393.366421) (xy 392.216436 -393.31433) (xy 392.243732 -393.265695) (xy 392.277818 -393.221552)
			(xy 392.317967 -393.182843) (xy 392.363325 -393.150392) (xy 392.412925 -393.124891) (xy 392.465709 -393.106884)
			(xy 392.520552 -393.096754) (xy 392.576286 -393.094717) (xy 392.631723 -393.100817) (xy 392.68568 -393.114923)
			(xy 392.737009 -393.136735) (xy 392.784615 -393.165789) (xy 392.827483 -393.201464) (xy 392.8647 -393.243001)
			(xy 392.895473 -393.289514) (xy 392.919145 -393.340011) (xy 392.935213 -393.393418) (xy 392.943333 -393.448594)
			(xy 392.943842 -393.47648) (xy 392.943333 -393.504366) (xy 392.935213 -393.559542) (xy 392.919145 -393.612949)
			(xy 392.895473 -393.663446) (xy 392.8647 -393.709959) (xy 392.827483 -393.751496) (xy 392.784615 -393.787171)
			(xy 392.737009 -393.816225) (xy 392.68568 -393.838037) (xy 392.631723 -393.852143) (xy 392.576286 -393.858243)
			(xy 392.520552 -393.856206) (xy 392.465709 -393.846076) (xy 392.412925 -393.828069) (xy 392.363325 -393.802568)
			(xy 392.317967 -393.770117) (xy 392.277818 -393.731408) (xy 392.243732 -393.687265) (xy 392.216436 -393.63863)
			(xy 392.196513 -393.586539) (xy 392.184387 -393.532102) (xy 392.180316 -393.47648) (xy 391.779438 -393.47648)
			(xy 391.797395 -393.504267) (xy 391.820229 -393.554016) (xy 391.83572 -393.606517) (xy 391.843548 -393.660693)
			(xy 391.844022 -393.688062) (xy 391.843592 -393.714973) (xy 391.836045 -393.768263) (xy 391.821083 -393.819963)
			(xy 391.799002 -393.869047) (xy 391.77024 -393.914539) (xy 391.735369 -393.955537) (xy 391.695081 -393.991225)
			(xy 391.650176 -394.020896) (xy 391.601547 -394.04396) (xy 391.550158 -394.05996) (xy 391.497031 -394.068576)
			(xy 391.470134 -394.06957) (xy 391.458704 -394.069824) (xy 391.438638 -394.07973) (xy 391.375646 -394.158978)
			(xy 391.370566 -394.181076) (xy 391.372852 -394.192252) (xy 391.376774 -394.211829) (xy 391.380971 -394.251536)
			(xy 391.381234 -394.2715) (xy 391.380979 -394.291591) (xy 391.376783 -394.331552) (xy 391.372852 -394.351256)
			(xy 391.369804 -394.364718) (xy 391.378694 -394.39088) (xy 391.466578 -394.467588) (xy 391.493756 -394.472668)
			(xy 391.50671 -394.468096) (xy 391.538099 -394.457456) (xy 391.603368 -394.445965) (xy 391.636504 -394.445236)
			(xy 391.663754 -394.445682) (xy 391.7177 -394.453439) (xy 391.769993 -394.468793) (xy 391.819568 -394.491434)
			(xy 391.865417 -394.520899) (xy 391.906606 -394.556588) (xy 391.942297 -394.597777) (xy 391.971763 -394.643625)
			(xy 391.994404 -394.6932) (xy 392.00976 -394.745492) (xy 392.017517 -394.799438) (xy 392.017519 -394.853938)
			(xy 392.009765 -394.907884) (xy 391.994412 -394.960178) (xy 391.971774 -395.009754) (xy 391.942311 -395.055604)
			(xy 391.906623 -395.096795) (xy 391.865436 -395.132487) (xy 391.819589 -395.161955) (xy 391.770015 -395.184598)
			(xy 391.717723 -395.199956) (xy 391.663778 -395.207716) (xy 391.609278 -395.20772) (xy 391.555331 -395.199968)
			(xy 391.503037 -395.184618) (xy 391.45346 -395.161982) (xy 391.407609 -395.132521) (xy 391.366417 -395.096834)
			(xy 391.330723 -395.055649) (xy 391.301253 -395.009803) (xy 391.278607 -394.96023) (xy 391.263247 -394.907939)
			(xy 391.255485 -394.853994) (xy 391.254996 -394.826744) (xy 391.255242 -394.806653) (xy 391.259444 -394.766692)
			(xy 391.263378 -394.746988) (xy 391.266426 -394.733526) (xy 391.257536 -394.707364) (xy 391.169652 -394.630656)
			(xy 391.142474 -394.625576) (xy 391.12952 -394.630148) (xy 391.098129 -394.640782) (xy 391.032861 -394.652276)
			(xy 390.999726 -394.653008) (xy 390.972474 -394.652521) (xy 390.918524 -394.644767) (xy 390.866226 -394.629414)
			(xy 390.816646 -394.606775) (xy 390.770793 -394.57731) (xy 390.7296 -394.541618) (xy 390.693906 -394.500428)
			(xy 390.664438 -394.454577) (xy 390.641795 -394.404998) (xy 390.626438 -394.352702) (xy 390.618681 -394.298752)
			(xy 390.618218 -394.2715) (xy 390.61863 -394.245517) (xy 390.625696 -394.194033) (xy 390.639682 -394.143985)
			(xy 390.660331 -394.096297) (xy 390.687259 -394.051852) (xy 390.71997 -394.011473) (xy 390.738614 -393.99337)
			(xy 390.748012 -393.984734) (xy 390.755886 -393.961366) (xy 390.739884 -393.85367) (xy 390.725406 -393.833604)
			(xy 390.713976 -393.828016) (xy 390.690583 -393.815956) (xy 390.647637 -393.785535) (xy 390.610053 -393.748694)
			(xy 390.578781 -393.706364) (xy 390.554611 -393.659613) (xy 390.538153 -393.609624) (xy 390.529823 -393.557658)
			(xy 390.529318 -393.531344) (xy 389.179787 -393.531344) (xy 389.197382 -393.565962) (xy 389.213401 -393.615453)
			(xy 389.217916 -393.641072) (xy 389.21944 -393.65047) (xy 389.492236 -394.122402) (xy 389.499602 -394.128244)
			(xy 389.518384 -394.144041) (xy 389.551501 -394.180259) (xy 389.57891 -394.220968) (xy 389.600011 -394.265277)
			(xy 389.61434 -394.312215) (xy 389.621585 -394.360754) (xy 389.62203 -394.385292) (xy 389.621776 -394.396976)
			(xy 389.621522 -394.406882) (xy 389.627872 -394.424916) (xy 389.687054 -394.491972) (xy 389.704326 -394.500862)
			(xy 389.713978 -394.501624) (xy 389.738318 -394.504241) (xy 389.785868 -394.515882) (xy 389.831185 -394.5344)
			(xy 389.873279 -394.559391) (xy 389.911233 -394.590311) (xy 389.944219 -394.626484) (xy 389.971516 -394.667122)
			(xy 389.992529 -394.711337) (xy 390.006799 -394.758165) (xy 390.014016 -394.806585) (xy 390.01446 -394.831062)
			(xy 390.01395 -394.857049) (xy 390.00582 -394.908384) (xy 389.989759 -394.957814) (xy 389.966163 -395.004124)
			(xy 389.935613 -395.046172) (xy 389.898862 -395.082923) (xy 389.856814 -395.113473) (xy 389.810504 -395.137069)
			(xy 389.761074 -395.15313) (xy 389.709739 -395.16126) (xy 389.657765 -395.16126) (xy 389.60643 -395.15313)
			(xy 389.557 -395.137069) (xy 389.51069 -395.113473) (xy 389.468642 -395.082923) (xy 389.431891 -395.046172)
			(xy 389.401341 -395.004124) (xy 389.377745 -394.957814) (xy 389.361684 -394.908384) (xy 389.353554 -394.857049)
			(xy 389.353044 -394.831062) (xy 389.353298 -394.819378) (xy 389.353552 -394.809472) (xy 389.347202 -394.791438)
			(xy 389.28802 -394.724382) (xy 389.270748 -394.715492) (xy 389.261096 -394.71473) (xy 389.236913 -394.712058)
			(xy 389.189648 -394.700518) (xy 389.144582 -394.682185) (xy 389.102684 -394.657453) (xy 389.064857 -394.626855)
			(xy 389.031916 -394.591049) (xy 389.00457 -394.550809) (xy 388.983408 -394.506999) (xy 388.968887 -394.460563)
			(xy 388.964678 -394.4366) (xy 388.963154 -394.427202) (xy 388.690358 -393.95527) (xy 388.682992 -393.949428)
			(xy 388.664243 -393.933593) (xy 388.631124 -393.897383) (xy 388.603711 -393.856682) (xy 388.582605 -393.81238)
			(xy 388.568268 -393.765449) (xy 388.561014 -393.716916) (xy 388.560564 -393.69238) (xy 388.04348 -393.69238)
			(xy 388.292086 -394.122402) (xy 388.299452 -394.128244) (xy 388.318233 -394.144047) (xy 388.35137 -394.180252)
			(xy 388.378794 -394.220956) (xy 388.399904 -394.265265) (xy 388.414235 -394.312207) (xy 388.421473 -394.360751)
			(xy 388.42188 -394.385292) (xy 388.421626 -394.397484) (xy 388.421372 -394.407136) (xy 388.427468 -394.42517)
			(xy 388.486142 -394.49248) (xy 388.502906 -394.501116) (xy 388.512812 -394.502132) (xy 388.539579 -394.505459)
			(xy 388.591606 -394.519684) (xy 388.640635 -394.542163) (xy 388.685368 -394.572298) (xy 388.724618 -394.609292)
			(xy 388.757345 -394.652164) (xy 388.782683 -394.699779) (xy 388.79996 -394.750873) (xy 388.808717 -394.804094)
			(xy 388.80923 -394.831062) (xy 388.808667 -394.858344) (xy 388.799703 -394.912167) (xy 388.78203 -394.963789)
			(xy 388.756125 -395.011812) (xy 388.722691 -395.054933) (xy 388.703058 -395.073886) (xy 388.695607 -395.081376)
			(xy 388.687063 -395.100672) (xy 388.686548 -395.111224) (xy 388.686548 -395.1859) (xy 388.68714 -395.196432)
			(xy 388.69568 -395.215696) (xy 388.703058 -395.223238) (xy 388.722712 -395.242171) (xy 388.756151 -395.285293)
			(xy 388.782056 -395.33332) (xy 388.799724 -395.384949) (xy 388.808674 -395.438778) (xy 388.80923 -395.466062)
			(xy 388.808797 -395.49018) (xy 388.801802 -395.537905) (xy 388.787954 -395.58411) (xy 388.767548 -395.627816)
			(xy 388.75462 -395.64818) (xy 388.748778 -395.65707) (xy 388.745222 -395.677136) (xy 388.766304 -395.769338)
			(xy 388.778496 -395.786102) (xy 388.787386 -395.791436) (xy 388.80819 -395.804289) (xy 388.846111 -395.835165)
			(xy 388.879066 -395.871295) (xy 388.906332 -395.911889) (xy 388.927315 -395.956059) (xy 388.941556 -396.002841)
			(xy 388.948742 -396.051211) (xy 388.949184 -396.075662) (xy 388.948715 -396.100856) (xy 388.941083 -396.150662)
			(xy 388.925991 -396.198736) (xy 388.903786 -396.243967) (xy 388.889748 -396.264892) (xy 388.88162 -396.276576)
			(xy 388.879588 -396.30477) (xy 388.927848 -396.397226) (xy 388.932475 -396.405307) (xy 388.946355 -396.417696)
			(xy 388.963755 -396.424281) (xy 388.97306 -396.424658) (xy 390.687814 -396.424658) (xy 390.696482 -396.424355)
			(xy 390.712843 -396.418637) (xy 390.719818 -396.413482) (xy 390.739485 -396.398252) (xy 390.782487 -396.373254)
			(xy 390.82875 -396.354984) (xy 390.877229 -396.343854) (xy 390.926828 -396.340116) (xy 390.976427 -396.343854)
			(xy 391.024906 -396.354984) (xy 391.071169 -396.373254) (xy 391.114171 -396.398252) (xy 391.133838 -396.413482)
			(xy 391.140696 -396.418816) (xy 391.156952 -396.424658) (xy 391.226294 -396.424658) (xy 391.236364 -396.424235)
			(xy 391.254966 -396.416517) (xy 391.262362 -396.409672) (xy 392.69543 -394.976604) (xy 392.702414 -394.969008)
			(xy 392.710142 -394.949896) (xy 392.709684 -394.929286) (xy 392.705844 -394.919708) (xy 392.660124 -394.818616)
			(xy 392.6332 -394.80236) (xy 392.617198 -394.803376) (xy 392.593576 -394.804138) (xy 392.566324 -394.803651)
			(xy 392.512374 -394.795891) (xy 392.460078 -394.780532) (xy 392.4105 -394.757888) (xy 392.364649 -394.728419)
			(xy 392.323459 -394.692724) (xy 392.287767 -394.651531) (xy 392.258301 -394.605679) (xy 392.235659 -394.556099)
			(xy 392.220304 -394.503802) (xy 392.212548 -394.449852) (xy 392.212548 -394.395348) (xy 392.220304 -394.341398)
			(xy 392.235659 -394.289101) (xy 392.258301 -394.239521) (xy 392.287767 -394.193669) (xy 392.323459 -394.152476)
			(xy 392.364649 -394.116781) (xy 392.4105 -394.087312) (xy 392.460078 -394.064668) (xy 392.512374 -394.049309)
			(xy 392.566324 -394.041549) (xy 392.593576 -394.041122) (xy 392.621377 -394.041622) (xy 392.67639 -394.049689)
			(xy 392.72965 -394.065654) (xy 392.780029 -394.08918) (xy 392.82646 -394.119768) (xy 392.86796 -394.156771)
			(xy 392.903651 -394.199406) (xy 392.932775 -394.246769) (xy 392.954718 -394.297858) (xy 392.962384 -394.324586)
			(xy 392.965432 -394.336016) (xy 392.980926 -394.353796) (xy 393.077446 -394.393928) (xy 393.101068 -394.392404)
			(xy 393.111228 -394.386562) (xy 393.136935 -394.372186) (xy 393.190993 -394.348798) (xy 393.247393 -394.331818)
			(xy 393.305378 -394.321477) (xy 393.334748 -394.319252) (xy 393.344146 -394.31849) (xy 393.36091 -394.311124)
			(xy 393.603734 -394.0683) (xy 393.610588 -394.060905) (xy 393.618333 -394.042306) (xy 393.61872 -394.032232)
			(xy 393.61872 -392.21918) (xy 393.618338 -392.209754) (xy 393.611511 -392.192182) (xy 393.598788 -392.17827)
			(xy 393.590526 -392.173714) (xy 393.495784 -392.126724) (xy 393.46759 -392.129518) (xy 393.455906 -392.138408)
			(xy 393.430875 -392.156584) (xy 393.376163 -392.185444) (xy 393.317511 -392.2051) (xy 393.256457 -392.215035)
			(xy 393.225528 -392.215624) (xy 393.198273 -392.215163) (xy 393.144316 -392.207409) (xy 393.092013 -392.192055)
			(xy 393.042427 -392.169413) (xy 392.996569 -392.139944) (xy 392.955371 -392.104249) (xy 392.919672 -392.063054)
			(xy 392.890201 -392.017197) (xy 392.867555 -391.967613) (xy 392.852197 -391.915311) (xy 392.844439 -391.861355)
			(xy 392.844439 -391.806845) (xy 392.852197 -391.752889) (xy 392.867555 -391.700587) (xy 392.890201 -391.651003)
			(xy 392.919673 -391.605146) (xy 392.955371 -391.563951) (xy 392.996569 -391.528256) (xy 393.042427 -391.498787)
			(xy 393.092013 -391.476145) (xy 393.144316 -391.460791) (xy 393.198273 -391.453037) (xy 393.225528 -391.452608)
			(xy 393.25461 -391.453157) (xy 393.312099 -391.461985) (xy 393.367584 -391.479434) (xy 393.419778 -391.505098)
			(xy 393.467475 -391.538385) (xy 393.50957 -391.578523) (xy 393.527788 -391.601198) (xy 393.535154 -391.61085)
			(xy 393.555982 -391.62101) (xy 393.56792 -391.62101) (xy 393.577926 -391.620518) (xy 393.596412 -391.612856)
			(xy 393.610561 -391.598704) (xy 393.61822 -391.580216) (xy 393.61872 -391.57021) (xy 393.61872 -391.479532)
			(xy 393.618285 -391.469467) (xy 393.610556 -391.450878) (xy 393.603734 -391.443464) (xy 393.394946 -391.234676)
			(xy 393.387548 -391.22783) (xy 393.368949 -391.220103) (xy 393.358878 -391.21969) (xy 390.877298 -391.21969)
			(xy 390.848088 -391.247376) (xy 390.847072 -391.267696) (xy 390.845271 -391.292741) (xy 390.835051 -391.341901)
			(xy 390.817519 -391.388951) (xy 390.793076 -391.43281) (xy 390.762284 -391.472471) (xy 390.725852 -391.507022)
			(xy 390.684615 -391.535669) (xy 390.639522 -391.557753) (xy 390.591609 -391.572768) (xy 390.541977 -391.580369)
			(xy 390.516872 -391.580878) (xy 390.493099 -391.580464) (xy 390.446043 -391.57365) (xy 390.400449 -391.560168)
			(xy 390.357255 -391.540294) (xy 390.317353 -391.514438) (xy 390.299194 -391.49909) (xy 390.292073 -391.493406)
			(xy 390.275023 -391.48702) (xy 390.26592 -391.486644) (xy 390.234424 -391.486644) (xy 390.225319 -391.487019)
			(xy 390.208264 -391.493396) (xy 390.20115 -391.49909) (xy 390.18299 -391.514438) (xy 390.143094 -391.540305)
			(xy 390.099901 -391.560182) (xy 390.054304 -391.57366) (xy 390.007246 -391.580461) (xy 389.983472 -391.580878)
			(xy 389.956602 -391.58035) (xy 389.903572 -391.571654) (xy 389.852646 -391.554494) (xy 389.805166 -391.529323)
			(xy 389.762383 -391.496803) (xy 389.725423 -391.457792) (xy 389.709914 -391.435844) (xy 389.70331 -391.426446)
			(xy 389.684006 -391.415016) (xy 389.594598 -391.40638) (xy 389.583382 -391.405962) (xy 389.562311 -391.413614)
			(xy 389.553958 -391.421112) (xy 388.964932 -392.010138) (xy 388.957533 -392.016981) (xy 388.938934 -392.0247)
			(xy 388.928864 -392.025124) (xy 378.889514 -392.025124) (xy 378.879451 -392.025563) (xy 378.860872 -392.033302)
			(xy 378.853446 -392.04011) (xy 378.066808 -392.826748) (xy 378.060966 -392.856974) (xy 378.067062 -392.871198)
			(xy 378.075262 -392.891622) (xy 378.086802 -392.934092) (xy 378.092615 -392.977717) (xy 378.09297 -392.999722)
			(xy 378.092485 -393.025709) (xy 378.632214 -393.025709) (xy 378.632214 -392.973735) (xy 378.640344 -392.9224)
			(xy 378.656405 -392.87297) (xy 378.680001 -392.82666) (xy 378.710551 -392.784612) (xy 378.747302 -392.747861)
			(xy 378.78935 -392.717311) (xy 378.83566 -392.693715) (xy 378.88509 -392.677654) (xy 378.936425 -392.669524)
			(xy 378.988399 -392.669524) (xy 379.039734 -392.677654) (xy 379.089164 -392.693715) (xy 379.135474 -392.717311)
			(xy 379.177522 -392.747861) (xy 379.214273 -392.784612) (xy 379.244823 -392.82666) (xy 379.268419 -392.87297)
			(xy 379.28448 -392.9224) (xy 379.29261 -392.973735) (xy 379.29312 -392.999722) (xy 379.29261 -393.025709)
			(xy 379.83211 -393.025709) (xy 379.83211 -392.973735) (xy 379.84024 -392.9224) (xy 379.856301 -392.87297)
			(xy 379.879897 -392.82666) (xy 379.910447 -392.784612) (xy 379.947198 -392.747861) (xy 379.989246 -392.717311)
			(xy 380.035556 -392.693715) (xy 380.084986 -392.677654) (xy 380.136321 -392.669524) (xy 380.188295 -392.669524)
			(xy 380.23963 -392.677654) (xy 380.28906 -392.693715) (xy 380.33537 -392.717311) (xy 380.377418 -392.747861)
			(xy 380.414169 -392.784612) (xy 380.444719 -392.82666) (xy 380.468315 -392.87297) (xy 380.484376 -392.9224)
			(xy 380.492506 -392.973735) (xy 380.493016 -392.999722) (xy 380.492506 -393.025709) (xy 381.03226 -393.025709)
			(xy 381.03226 -392.973735) (xy 381.04039 -392.9224) (xy 381.056451 -392.87297) (xy 381.080047 -392.82666)
			(xy 381.110597 -392.784612) (xy 381.147348 -392.747861) (xy 381.189396 -392.717311) (xy 381.235706 -392.693715)
			(xy 381.285136 -392.677654) (xy 381.336471 -392.669524) (xy 381.388445 -392.669524) (xy 381.43978 -392.677654)
			(xy 381.48921 -392.693715) (xy 381.53552 -392.717311) (xy 381.577568 -392.747861) (xy 381.614319 -392.784612)
			(xy 381.644869 -392.82666) (xy 381.668465 -392.87297) (xy 381.684526 -392.9224) (xy 381.692656 -392.973735)
			(xy 381.693166 -392.999722) (xy 381.692656 -393.025709) (xy 382.232156 -393.025709) (xy 382.232156 -392.973735)
			(xy 382.240286 -392.9224) (xy 382.256347 -392.87297) (xy 382.279943 -392.82666) (xy 382.310493 -392.784612)
			(xy 382.347244 -392.747861) (xy 382.389292 -392.717311) (xy 382.435602 -392.693715) (xy 382.485032 -392.677654)
			(xy 382.536367 -392.669524) (xy 382.588341 -392.669524) (xy 382.639676 -392.677654) (xy 382.689106 -392.693715)
			(xy 382.735416 -392.717311) (xy 382.777464 -392.747861) (xy 382.814215 -392.784612) (xy 382.844765 -392.82666)
			(xy 382.868361 -392.87297) (xy 382.884422 -392.9224) (xy 382.892552 -392.973735) (xy 382.893062 -392.999722)
			(xy 382.892552 -393.025709) (xy 383.432052 -393.025709) (xy 383.432052 -392.973735) (xy 383.440182 -392.9224)
			(xy 383.456243 -392.87297) (xy 383.479839 -392.82666) (xy 383.510389 -392.784612) (xy 383.54714 -392.747861)
			(xy 383.589188 -392.717311) (xy 383.635498 -392.693715) (xy 383.684928 -392.677654) (xy 383.736263 -392.669524)
			(xy 383.788237 -392.669524) (xy 383.839572 -392.677654) (xy 383.889002 -392.693715) (xy 383.935312 -392.717311)
			(xy 383.97736 -392.747861) (xy 384.014111 -392.784612) (xy 384.044661 -392.82666) (xy 384.068257 -392.87297)
			(xy 384.084318 -392.9224) (xy 384.092448 -392.973735) (xy 384.092958 -392.999722) (xy 384.092448 -393.025709)
			(xy 384.632202 -393.025709) (xy 384.632202 -392.973735) (xy 384.640332 -392.9224) (xy 384.656393 -392.87297)
			(xy 384.679989 -392.82666) (xy 384.710539 -392.784612) (xy 384.74729 -392.747861) (xy 384.789338 -392.717311)
			(xy 384.835648 -392.693715) (xy 384.885078 -392.677654) (xy 384.936413 -392.669524) (xy 384.988387 -392.669524)
			(xy 385.039722 -392.677654) (xy 385.089152 -392.693715) (xy 385.135462 -392.717311) (xy 385.17751 -392.747861)
			(xy 385.214261 -392.784612) (xy 385.244811 -392.82666) (xy 385.268407 -392.87297) (xy 385.284468 -392.9224)
			(xy 385.292598 -392.973735) (xy 385.293108 -392.999722) (xy 385.292598 -393.025709) (xy 385.832098 -393.025709)
			(xy 385.832098 -392.973735) (xy 385.840228 -392.9224) (xy 385.856289 -392.87297) (xy 385.879885 -392.82666)
			(xy 385.910435 -392.784612) (xy 385.947186 -392.747861) (xy 385.989234 -392.717311) (xy 386.035544 -392.693715)
			(xy 386.084974 -392.677654) (xy 386.136309 -392.669524) (xy 386.188283 -392.669524) (xy 386.239618 -392.677654)
			(xy 386.289048 -392.693715) (xy 386.335358 -392.717311) (xy 386.377406 -392.747861) (xy 386.414157 -392.784612)
			(xy 386.444707 -392.82666) (xy 386.468303 -392.87297) (xy 386.484364 -392.9224) (xy 386.492494 -392.973735)
			(xy 386.493004 -392.999722) (xy 386.492494 -393.025709) (xy 387.032248 -393.025709) (xy 387.032248 -392.973735)
			(xy 387.040378 -392.9224) (xy 387.056439 -392.87297) (xy 387.080035 -392.82666) (xy 387.110585 -392.784612)
			(xy 387.147336 -392.747861) (xy 387.189384 -392.717311) (xy 387.235694 -392.693715) (xy 387.285124 -392.677654)
			(xy 387.336459 -392.669524) (xy 387.388433 -392.669524) (xy 387.439768 -392.677654) (xy 387.489198 -392.693715)
			(xy 387.535508 -392.717311) (xy 387.577556 -392.747861) (xy 387.614307 -392.784612) (xy 387.644857 -392.82666)
			(xy 387.668453 -392.87297) (xy 387.684514 -392.9224) (xy 387.692644 -392.973735) (xy 387.693154 -392.999722)
			(xy 387.692644 -393.025709) (xy 388.232144 -393.025709) (xy 388.232144 -392.973735) (xy 388.240274 -392.9224)
			(xy 388.256335 -392.87297) (xy 388.279931 -392.82666) (xy 388.310481 -392.784612) (xy 388.347232 -392.747861)
			(xy 388.38928 -392.717311) (xy 388.43559 -392.693715) (xy 388.48502 -392.677654) (xy 388.536355 -392.669524)
			(xy 388.588329 -392.669524) (xy 388.639664 -392.677654) (xy 388.689094 -392.693715) (xy 388.735404 -392.717311)
			(xy 388.777452 -392.747861) (xy 388.814203 -392.784612) (xy 388.844753 -392.82666) (xy 388.868349 -392.87297)
			(xy 388.88441 -392.9224) (xy 388.89254 -392.973735) (xy 388.89305 -392.999722) (xy 388.89254 -393.025709)
			(xy 388.88441 -393.077044) (xy 388.868349 -393.126474) (xy 388.844753 -393.172784) (xy 388.814203 -393.214832)
			(xy 388.777452 -393.251583) (xy 388.735404 -393.282133) (xy 388.689094 -393.305729) (xy 388.639664 -393.32179)
			(xy 388.588329 -393.32992) (xy 388.536355 -393.32992) (xy 388.48502 -393.32179) (xy 388.43559 -393.305729)
			(xy 388.38928 -393.282133) (xy 388.347232 -393.251583) (xy 388.310481 -393.214832) (xy 388.279931 -393.172784)
			(xy 388.256335 -393.126474) (xy 388.240274 -393.077044) (xy 388.232144 -393.025709) (xy 387.692644 -393.025709)
			(xy 387.684514 -393.077044) (xy 387.668453 -393.126474) (xy 387.644857 -393.172784) (xy 387.614307 -393.214832)
			(xy 387.577556 -393.251583) (xy 387.535508 -393.282133) (xy 387.489198 -393.305729) (xy 387.439768 -393.32179)
			(xy 387.388433 -393.32992) (xy 387.336459 -393.32992) (xy 387.285124 -393.32179) (xy 387.235694 -393.305729)
			(xy 387.189384 -393.282133) (xy 387.147336 -393.251583) (xy 387.110585 -393.214832) (xy 387.080035 -393.172784)
			(xy 387.056439 -393.126474) (xy 387.040378 -393.077044) (xy 387.032248 -393.025709) (xy 386.492494 -393.025709)
			(xy 386.484364 -393.077044) (xy 386.468303 -393.126474) (xy 386.444707 -393.172784) (xy 386.414157 -393.214832)
			(xy 386.377406 -393.251583) (xy 386.335358 -393.282133) (xy 386.289048 -393.305729) (xy 386.239618 -393.32179)
			(xy 386.188283 -393.32992) (xy 386.136309 -393.32992) (xy 386.084974 -393.32179) (xy 386.035544 -393.305729)
			(xy 385.989234 -393.282133) (xy 385.947186 -393.251583) (xy 385.910435 -393.214832) (xy 385.879885 -393.172784)
			(xy 385.856289 -393.126474) (xy 385.840228 -393.077044) (xy 385.832098 -393.025709) (xy 385.292598 -393.025709)
			(xy 385.284468 -393.077044) (xy 385.268407 -393.126474) (xy 385.244811 -393.172784) (xy 385.214261 -393.214832)
			(xy 385.17751 -393.251583) (xy 385.135462 -393.282133) (xy 385.089152 -393.305729) (xy 385.039722 -393.32179)
			(xy 384.988387 -393.32992) (xy 384.936413 -393.32992) (xy 384.885078 -393.32179) (xy 384.835648 -393.305729)
			(xy 384.789338 -393.282133) (xy 384.74729 -393.251583) (xy 384.710539 -393.214832) (xy 384.679989 -393.172784)
			(xy 384.656393 -393.126474) (xy 384.640332 -393.077044) (xy 384.632202 -393.025709) (xy 384.092448 -393.025709)
			(xy 384.084318 -393.077044) (xy 384.068257 -393.126474) (xy 384.044661 -393.172784) (xy 384.014111 -393.214832)
			(xy 383.97736 -393.251583) (xy 383.935312 -393.282133) (xy 383.889002 -393.305729) (xy 383.839572 -393.32179)
			(xy 383.788237 -393.32992) (xy 383.736263 -393.32992) (xy 383.684928 -393.32179) (xy 383.635498 -393.305729)
			(xy 383.589188 -393.282133) (xy 383.54714 -393.251583) (xy 383.510389 -393.214832) (xy 383.479839 -393.172784)
			(xy 383.456243 -393.126474) (xy 383.440182 -393.077044) (xy 383.432052 -393.025709) (xy 382.892552 -393.025709)
			(xy 382.884422 -393.077044) (xy 382.868361 -393.126474) (xy 382.844765 -393.172784) (xy 382.814215 -393.214832)
			(xy 382.777464 -393.251583) (xy 382.735416 -393.282133) (xy 382.689106 -393.305729) (xy 382.639676 -393.32179)
			(xy 382.588341 -393.32992) (xy 382.536367 -393.32992) (xy 382.485032 -393.32179) (xy 382.435602 -393.305729)
			(xy 382.389292 -393.282133) (xy 382.347244 -393.251583) (xy 382.310493 -393.214832) (xy 382.279943 -393.172784)
			(xy 382.256347 -393.126474) (xy 382.240286 -393.077044) (xy 382.232156 -393.025709) (xy 381.692656 -393.025709)
			(xy 381.684526 -393.077044) (xy 381.668465 -393.126474) (xy 381.644869 -393.172784) (xy 381.614319 -393.214832)
			(xy 381.577568 -393.251583) (xy 381.53552 -393.282133) (xy 381.48921 -393.305729) (xy 381.43978 -393.32179)
			(xy 381.388445 -393.32992) (xy 381.336471 -393.32992) (xy 381.285136 -393.32179) (xy 381.235706 -393.305729)
			(xy 381.189396 -393.282133) (xy 381.147348 -393.251583) (xy 381.110597 -393.214832) (xy 381.080047 -393.172784)
			(xy 381.056451 -393.126474) (xy 381.04039 -393.077044) (xy 381.03226 -393.025709) (xy 380.492506 -393.025709)
			(xy 380.484376 -393.077044) (xy 380.468315 -393.126474) (xy 380.444719 -393.172784) (xy 380.414169 -393.214832)
			(xy 380.377418 -393.251583) (xy 380.33537 -393.282133) (xy 380.28906 -393.305729) (xy 380.23963 -393.32179)
			(xy 380.188295 -393.32992) (xy 380.136321 -393.32992) (xy 380.084986 -393.32179) (xy 380.035556 -393.305729)
			(xy 379.989246 -393.282133) (xy 379.947198 -393.251583) (xy 379.910447 -393.214832) (xy 379.879897 -393.172784)
			(xy 379.856301 -393.126474) (xy 379.84024 -393.077044) (xy 379.83211 -393.025709) (xy 379.29261 -393.025709)
			(xy 379.28448 -393.077044) (xy 379.268419 -393.126474) (xy 379.244823 -393.172784) (xy 379.214273 -393.214832)
			(xy 379.177522 -393.251583) (xy 379.135474 -393.282133) (xy 379.089164 -393.305729) (xy 379.039734 -393.32179)
			(xy 378.988399 -393.32992) (xy 378.936425 -393.32992) (xy 378.88509 -393.32179) (xy 378.83566 -393.305729)
			(xy 378.78935 -393.282133) (xy 378.747302 -393.251583) (xy 378.710551 -393.214832) (xy 378.680001 -393.172784)
			(xy 378.656405 -393.126474) (xy 378.640344 -393.077044) (xy 378.632214 -393.025709) (xy 378.092485 -393.025709)
			(xy 378.084351 -393.077043) (xy 378.068286 -393.126472) (xy 378.044687 -393.172779) (xy 378.014134 -393.214825)
			(xy 377.977379 -393.251573) (xy 377.935328 -393.282118) (xy 377.889016 -393.305709) (xy 377.839584 -393.321765)
			(xy 377.788249 -393.32989) (xy 377.762262 -393.33043) (xy 377.740256 -393.330084) (xy 377.696631 -393.324272)
			(xy 377.654164 -393.312718) (xy 377.633738 -393.304522) (xy 377.619514 -393.298426) (xy 377.589288 -393.304268)
			(xy 377.255786 -393.63777) (xy 377.248243 -393.646043) (xy 377.240536 -393.667035) (xy 377.242488 -393.689311)
			(xy 377.247658 -393.699238) (xy 377.49226 -394.122402) (xy 377.499626 -394.128244) (xy 377.518403 -394.144049)
			(xy 377.551533 -394.180257) (xy 377.578952 -394.220962) (xy 377.600056 -394.265271) (xy 377.614384 -394.312211)
			(xy 377.62162 -394.360753) (xy 377.622054 -394.385292) (xy 377.6218 -394.397484) (xy 377.621546 -394.407136)
			(xy 377.627642 -394.42517) (xy 377.686316 -394.49248) (xy 377.70308 -394.501116) (xy 377.712732 -394.502132)
			(xy 377.739498 -394.505461) (xy 377.791522 -394.519688) (xy 377.840549 -394.542168) (xy 377.885278 -394.572304)
			(xy 377.924526 -394.609298) (xy 377.957251 -394.65217) (xy 377.982587 -394.699783) (xy 377.999862 -394.750876)
			(xy 378.008619 -394.804095) (xy 378.00915 -394.831062) (xy 378.008587 -394.858344) (xy 377.999624 -394.912168)
			(xy 377.981951 -394.963791) (xy 377.956047 -395.011814) (xy 377.922614 -395.054937) (xy 377.902978 -395.073886)
			(xy 377.895536 -395.081381) (xy 377.887006 -395.100676) (xy 377.886468 -395.111224) (xy 377.886468 -395.1859)
			(xy 377.887058 -395.196434) (xy 377.895588 -395.215707) (xy 377.902978 -395.223238) (xy 377.92263 -395.242172)
			(xy 377.956068 -395.285294) (xy 377.981972 -395.333321) (xy 377.999638 -395.38495) (xy 378.008587 -395.438778)
			(xy 378.00915 -395.466062) (xy 378.008717 -395.490179) (xy 378.00172 -395.537904) (xy 377.98787 -395.584107)
			(xy 377.967459 -395.62781) (xy 377.95454 -395.64818) (xy 377.948698 -395.65707) (xy 377.945142 -395.677136)
			(xy 377.966224 -395.769338) (xy 377.978416 -395.786102) (xy 377.987306 -395.791436) (xy 378.008109 -395.80429)
			(xy 378.046028 -395.835167) (xy 378.07898 -395.871297) (xy 378.106245 -395.911891) (xy 378.127227 -395.956061)
			(xy 378.141466 -396.002842) (xy 378.148653 -396.051212) (xy 378.149104 -396.075662) (xy 378.148666 -396.100032)
			(xy 378.14151 -396.148245) (xy 378.12736 -396.194886) (xy 378.106524 -396.238948) (xy 378.079451 -396.279479)
			(xy 378.046728 -396.315601) (xy 378.0282 -396.33144) (xy 378.01931 -396.338552) (xy 378.009912 -396.35811)
			(xy 378.007118 -396.457424) (xy 378.015754 -396.47749) (xy 378.024136 -396.48511) (xy 378.041772 -396.501823)
			(xy 378.072037 -396.539831) (xy 378.095892 -396.582157) (xy 378.112735 -396.62773) (xy 378.117862 -396.65148)
			(xy 378.121418 -396.669514) (xy 378.149358 -396.692628) (xy 378.687584 -396.692628)
		)
		(stroke
			(width 0)
			(type solid)
		)
		(fill yes)
		(layer "In15.Cu")
		(net "P1V8_CPU0_RT3_1A_1D")
	)
	(gr_poly
		(pts
			(xy 344.143076 -396.669514) (xy 344.146632 -396.65148) (xy 344.151806 -396.627744) (xy 344.168657 -396.582182)
			(xy 344.192504 -396.53986) (xy 344.222746 -396.501844) (xy 344.240358 -396.48511) (xy 344.24874 -396.47749)
			(xy 344.257376 -396.457424) (xy 344.254582 -396.35811) (xy 344.245184 -396.338552) (xy 344.236294 -396.33144)
			(xy 344.217733 -396.315637) (xy 344.185007 -396.279511) (xy 344.157935 -396.238974) (xy 344.137102 -396.194904)
			(xy 344.12296 -396.148254) (xy 344.115815 -396.100035) (xy 344.11539 -396.075662) (xy 344.115829 -396.051546)
			(xy 344.122834 -396.003826) (xy 344.136691 -395.957627) (xy 344.157106 -395.913929) (xy 344.17 -395.893544)
			(xy 344.175842 -395.884654) (xy 344.179398 -395.864588) (xy 344.158316 -395.772386) (xy 344.146124 -395.755622)
			(xy 344.137234 -395.750288) (xy 344.116433 -395.737432) (xy 344.078518 -395.706553) (xy 344.045569 -395.670421)
			(xy 344.018306 -395.629828) (xy 343.997326 -395.585659) (xy 343.983086 -395.538879) (xy 343.975898 -395.490512)
			(xy 343.975436 -395.466062) (xy 343.975997 -395.438779) (xy 343.984956 -395.384953) (xy 344.002626 -395.333327)
			(xy 344.028527 -395.2853) (xy 344.061958 -395.242173) (xy 344.081608 -395.223238) (xy 344.089056 -395.215745)
			(xy 344.097597 -395.196451) (xy 344.098118 -395.1859) (xy 344.098118 -395.111224) (xy 344.097532 -395.100688)
			(xy 344.089006 -395.08141) (xy 344.081608 -395.073886) (xy 344.061955 -395.054952) (xy 344.028515 -395.01183)
			(xy 344.00261 -394.963803) (xy 343.98494 -394.912175) (xy 343.975987 -394.858346) (xy 343.975436 -394.831062)
			(xy 343.97569 -394.81887) (xy 343.975944 -394.809218) (xy 343.969848 -394.791184) (xy 343.911174 -394.723874)
			(xy 343.89441 -394.715238) (xy 343.884504 -394.714222) (xy 343.857588 -394.710874) (xy 343.805283 -394.696535)
			(xy 343.75602 -394.67385) (xy 343.71112 -394.643429) (xy 343.671788 -394.606086) (xy 343.639078 -394.562825)
			(xy 343.613868 -394.514805) (xy 343.596834 -394.463314) (xy 343.59215 -394.4366) (xy 343.590626 -394.427202)
			(xy 343.31783 -393.95527) (xy 343.310464 -393.949428) (xy 343.291684 -393.933625) (xy 343.258548 -393.89742)
			(xy 343.231126 -393.856715) (xy 343.210019 -393.812406) (xy 343.195691 -393.765464) (xy 343.188457 -393.71692)
			(xy 343.188036 -393.69238) (xy 343.188521 -393.666393) (xy 343.196655 -393.615059) (xy 343.212719 -393.56563)
			(xy 343.236319 -393.519323) (xy 343.266872 -393.477278) (xy 343.303627 -393.44053) (xy 343.345678 -393.409985)
			(xy 343.39199 -393.386395) (xy 343.441422 -393.37034) (xy 343.492757 -393.362216) (xy 343.518744 -393.361672)
			(xy 343.544757 -393.362153) (xy 343.596144 -393.370292) (xy 343.645621 -393.386379) (xy 343.691968 -393.410017)
			(xy 343.734041 -393.440621) (xy 343.770802 -393.477438) (xy 343.801343 -393.519557) (xy 343.824911 -393.565939)
			(xy 343.840924 -393.615441) (xy 343.845388 -393.641072) (xy 343.846912 -393.65047) (xy 344.119708 -394.122402)
			(xy 344.127074 -394.128244) (xy 344.145853 -394.144047) (xy 344.178989 -394.180254) (xy 344.206411 -394.220958)
			(xy 344.227519 -394.265267) (xy 344.241849 -394.312208) (xy 344.249087 -394.360752) (xy 344.249502 -394.385292)
			(xy 344.249248 -394.397484) (xy 344.248994 -394.407136) (xy 344.25509 -394.42517) (xy 344.313764 -394.49248)
			(xy 344.330528 -394.501116) (xy 344.340434 -394.502132) (xy 344.3672 -394.505461) (xy 344.419224 -394.519689)
			(xy 344.46825 -394.542168) (xy 344.512979 -394.572305) (xy 344.552227 -394.609299) (xy 344.584952 -394.65217)
			(xy 344.610288 -394.699783) (xy 344.627563 -394.750876) (xy 344.636319 -394.804095) (xy 344.636852 -394.831062)
			(xy 344.636289 -394.858344) (xy 344.627326 -394.912168) (xy 344.609653 -394.963791) (xy 344.583749 -395.011815)
			(xy 344.550317 -395.054937) (xy 344.53068 -395.073886) (xy 344.523238 -395.081381) (xy 344.514707 -395.100675)
			(xy 344.51417 -395.111224) (xy 344.51417 -395.1859) (xy 344.51476 -395.196434) (xy 344.52329 -395.215707)
			(xy 344.53068 -395.223238) (xy 344.550332 -395.242172) (xy 344.58377 -395.285294) (xy 344.609673 -395.333321)
			(xy 344.627339 -395.38495) (xy 344.636289 -395.438778) (xy 344.636852 -395.466062) (xy 344.636419 -395.490179)
			(xy 344.629422 -395.537904) (xy 344.615572 -395.584107) (xy 344.595161 -395.627811) (xy 344.582242 -395.64818)
			(xy 344.5764 -395.65707) (xy 344.572844 -395.677136) (xy 344.593926 -395.769338) (xy 344.606118 -395.786102)
			(xy 344.615008 -395.791436) (xy 344.635811 -395.80429) (xy 344.67373 -395.835167) (xy 344.706682 -395.871297)
			(xy 344.733947 -395.911891) (xy 344.754928 -395.956061) (xy 344.769167 -396.002842) (xy 344.776354 -396.051212)
			(xy 344.776806 -396.075662) (xy 344.776368 -396.100032) (xy 344.769212 -396.148245) (xy 344.755062 -396.194886)
			(xy 344.734226 -396.238949) (xy 344.707153 -396.279479) (xy 344.67443 -396.315601) (xy 344.655902 -396.33144)
			(xy 344.647012 -396.338552) (xy 344.637614 -396.35811) (xy 344.63482 -396.457424) (xy 344.643456 -396.47749)
			(xy 344.651838 -396.48511) (xy 344.669474 -396.501823) (xy 344.699739 -396.539831) (xy 344.723594 -396.582158)
			(xy 344.740436 -396.627731) (xy 344.745564 -396.65148) (xy 344.74912 -396.669514) (xy 344.77706 -396.692628)
			(xy 345.315032 -396.692628) (xy 345.342972 -396.669514) (xy 345.346528 -396.65148) (xy 345.351702 -396.627744)
			(xy 345.368553 -396.582182) (xy 345.392399 -396.53986) (xy 345.422642 -396.501843) (xy 345.440254 -396.48511)
			(xy 345.448636 -396.47749) (xy 345.457272 -396.457424) (xy 345.454478 -396.35811) (xy 345.44508 -396.338552)
			(xy 345.43619 -396.33144) (xy 345.417629 -396.315637) (xy 345.384904 -396.27951) (xy 345.357832 -396.238973)
			(xy 345.336999 -396.194903) (xy 345.322858 -396.148254) (xy 345.315712 -396.100035) (xy 345.315286 -396.075662)
			(xy 345.315725 -396.051546) (xy 345.32273 -396.003826) (xy 345.336587 -395.957627) (xy 345.357002 -395.913928)
			(xy 345.369896 -395.893544) (xy 345.375738 -395.884654) (xy 345.379294 -395.864588) (xy 345.358212 -395.772386)
			(xy 345.34602 -395.755622) (xy 345.33713 -395.750288) (xy 345.316329 -395.737432) (xy 345.278414 -395.706552)
			(xy 345.245466 -395.670421) (xy 345.218204 -395.629827) (xy 345.197224 -395.585658) (xy 345.182984 -395.538879)
			(xy 345.175796 -395.490511) (xy 345.175332 -395.466062) (xy 345.175893 -395.438779) (xy 345.184852 -395.384953)
			(xy 345.202522 -395.333327) (xy 345.228423 -395.285299) (xy 345.261853 -395.242172) (xy 345.281504 -395.223238)
			(xy 345.288952 -395.215746) (xy 345.297494 -395.196451) (xy 345.298014 -395.1859) (xy 345.298014 -395.111224)
			(xy 345.297428 -395.100688) (xy 345.288902 -395.08141) (xy 345.281504 -395.073886) (xy 345.261846 -395.054955)
			(xy 345.228397 -395.011836) (xy 345.202483 -394.96381) (xy 345.184809 -394.91218) (xy 345.175853 -394.858348)
			(xy 345.175332 -394.831062) (xy 345.175586 -394.81887) (xy 345.17584 -394.809218) (xy 345.169744 -394.791184)
			(xy 345.11107 -394.723874) (xy 345.094306 -394.715238) (xy 345.0844 -394.714222) (xy 345.057451 -394.710857)
			(xy 345.005085 -394.696472) (xy 344.955769 -394.673733) (xy 344.910826 -394.64325) (xy 344.871461 -394.605839)
			(xy 344.838731 -394.562504) (xy 344.813514 -394.514408) (xy 344.796485 -394.462841) (xy 344.791792 -394.436092)
			(xy 344.790522 -394.426694) (xy 344.51798 -393.95527) (xy 344.510614 -393.949428) (xy 344.491837 -393.933624)
			(xy 344.458705 -393.897416) (xy 344.431287 -393.856711) (xy 344.410184 -393.812402) (xy 344.395858 -393.765461)
			(xy 344.388625 -393.716919) (xy 344.388186 -393.69238) (xy 344.388697 -393.666394) (xy 344.39683 -393.615061)
			(xy 344.412893 -393.565633) (xy 344.43649 -393.519326) (xy 344.46704 -393.47728) (xy 344.503791 -393.44053)
			(xy 344.545838 -393.409982) (xy 344.592146 -393.386387) (xy 344.641575 -393.370327) (xy 344.692908 -393.362196)
			(xy 344.718894 -393.361672) (xy 344.744905 -393.362157) (xy 344.796285 -393.370302) (xy 344.845756 -393.386394)
			(xy 344.892097 -393.410034) (xy 344.934163 -393.44064) (xy 344.970918 -393.477456) (xy 345.001453 -393.519573)
			(xy 345.025017 -393.565953) (xy 345.041026 -393.615451) (xy 345.045538 -393.641072) (xy 345.047062 -393.65047)
			(xy 345.071284 -393.69238) (xy 345.588082 -393.69238) (xy 345.588583 -393.666393) (xy 345.596716 -393.615059)
			(xy 345.612779 -393.565629) (xy 345.636377 -393.51932) (xy 345.666928 -393.477272) (xy 345.70368 -393.440521)
			(xy 345.745728 -393.409972) (xy 345.792038 -393.386376) (xy 345.841468 -393.370314) (xy 345.892803 -393.362182)
			(xy 345.91879 -393.361672) (xy 345.9448 -393.362151) (xy 345.996176 -393.370308) (xy 346.045642 -393.386407)
			(xy 346.091978 -393.410052) (xy 346.134041 -393.440658) (xy 346.170795 -393.477472) (xy 346.201332 -393.519585)
			(xy 346.224901 -393.56596) (xy 346.240919 -393.615452) (xy 346.245434 -393.641072) (xy 346.246958 -393.65047)
			(xy 346.519754 -394.122402) (xy 346.52712 -394.128244) (xy 346.545906 -394.144037) (xy 346.579022 -394.180256)
			(xy 346.60643 -394.220966) (xy 346.62753 -394.265276) (xy 346.641858 -394.312214) (xy 346.649103 -394.360754)
			(xy 346.649548 -394.385292) (xy 346.649294 -394.397484) (xy 346.64904 -394.407136) (xy 346.655136 -394.42517)
			(xy 346.71381 -394.49248) (xy 346.730574 -394.501116) (xy 346.740226 -394.502132) (xy 346.766991 -394.50547)
			(xy 346.819014 -394.519696) (xy 346.86804 -394.542175) (xy 346.912769 -394.57231) (xy 346.952016 -394.609303)
			(xy 346.984741 -394.652174) (xy 347.010077 -394.699786) (xy 347.027352 -394.750878) (xy 347.036109 -394.804095)
			(xy 347.036644 -394.831062) (xy 347.036134 -394.857049) (xy 347.028004 -394.908384) (xy 347.011943 -394.957814)
			(xy 346.988347 -395.004124) (xy 346.957797 -395.046172) (xy 346.921046 -395.082923) (xy 346.878998 -395.113473)
			(xy 346.832688 -395.137069) (xy 346.783258 -395.15313) (xy 346.731923 -395.16126) (xy 346.679949 -395.16126)
			(xy 346.628614 -395.15313) (xy 346.579184 -395.137069) (xy 346.532874 -395.113473) (xy 346.490826 -395.082923)
			(xy 346.454075 -395.046172) (xy 346.423525 -395.004124) (xy 346.399929 -394.957814) (xy 346.383868 -394.908384)
			(xy 346.375738 -394.857049) (xy 346.375228 -394.831062) (xy 346.375482 -394.81887) (xy 346.375736 -394.809218)
			(xy 346.36964 -394.791184) (xy 346.310966 -394.723874) (xy 346.294202 -394.715238) (xy 346.28455 -394.714222)
			(xy 346.257642 -394.710859) (xy 346.205356 -394.696493) (xy 346.156113 -394.673793) (xy 346.11123 -394.643367)
			(xy 346.071911 -394.606028) (xy 346.039206 -394.562777) (xy 346.013993 -394.514772) (xy 345.996946 -394.463298)
			(xy 345.992196 -394.4366) (xy 345.990672 -394.427202) (xy 345.717876 -393.95527) (xy 345.71051 -393.949428)
			(xy 345.691765 -393.933589) (xy 345.658645 -393.89738) (xy 345.631231 -393.856679) (xy 345.610124 -393.812379)
			(xy 345.595787 -393.765448) (xy 345.588533 -393.716916) (xy 345.588082 -393.69238) (xy 345.071284 -393.69238)
			(xy 345.320112 -394.12291) (xy 345.327224 -394.128752) (xy 345.345954 -394.144533) (xy 345.379001 -394.180678)
			(xy 345.406351 -394.221305) (xy 345.427406 -394.265524) (xy 345.441705 -394.312365) (xy 345.448934 -394.360804)
			(xy 345.449398 -394.385292) (xy 345.449144 -394.397484) (xy 345.44889 -394.407136) (xy 345.454986 -394.42517)
			(xy 345.51366 -394.49248) (xy 345.530424 -394.501116) (xy 345.54033 -394.502132) (xy 345.567096 -394.50546)
			(xy 345.619121 -394.519688) (xy 345.668147 -394.542167) (xy 345.712877 -394.572303) (xy 345.752125 -394.609298)
			(xy 345.784851 -394.652169) (xy 345.810187 -394.699783) (xy 345.827462 -394.750876) (xy 345.836219 -394.804095)
			(xy 345.836748 -394.831062) (xy 345.836185 -394.858344) (xy 345.827222 -394.912167) (xy 345.809549 -394.963791)
			(xy 345.783645 -395.011814) (xy 345.750212 -395.054937) (xy 345.730576 -395.073886) (xy 345.723134 -395.081381)
			(xy 345.714604 -395.100676) (xy 345.714066 -395.111224) (xy 345.714066 -395.1859) (xy 345.714658 -395.196431)
			(xy 345.7232 -395.215694) (xy 345.730576 -395.223238) (xy 345.750229 -395.242172) (xy 345.783666 -395.285294)
			(xy 345.80957 -395.333321) (xy 345.827236 -395.38495) (xy 345.836186 -395.438778) (xy 345.836748 -395.466062)
			(xy 345.836315 -395.490179) (xy 345.829318 -395.537904) (xy 345.815468 -395.584107) (xy 345.795057 -395.62781)
			(xy 345.782138 -395.64818) (xy 345.776296 -395.65707) (xy 345.77274 -395.677136) (xy 345.793822 -395.769338)
			(xy 345.806014 -395.786102) (xy 345.814904 -395.791436) (xy 345.835707 -395.80429) (xy 345.873627 -395.835167)
			(xy 345.906579 -395.871297) (xy 345.933844 -395.911891) (xy 345.954826 -395.956061) (xy 345.969065 -396.002842)
			(xy 345.976252 -396.051212) (xy 345.976702 -396.075662) (xy 345.976264 -396.100032) (xy 345.969108 -396.148244)
			(xy 345.954958 -396.194886) (xy 345.934122 -396.238948) (xy 345.907049 -396.279479) (xy 345.874325 -396.315601)
			(xy 345.855798 -396.33144) (xy 345.846908 -396.338552) (xy 345.83751 -396.35811) (xy 345.834716 -396.457424)
			(xy 345.843352 -396.47749) (xy 345.851734 -396.48511) (xy 345.86937 -396.501823) (xy 345.899635 -396.539831)
			(xy 345.923491 -396.582157) (xy 345.940334 -396.62773) (xy 345.94546 -396.65148) (xy 345.949016 -396.669514)
			(xy 345.976956 -396.692628) (xy 346.514928 -396.692628) (xy 346.542868 -396.669514) (xy 346.546424 -396.65148)
			(xy 346.551685 -396.627324) (xy 346.568959 -396.581005) (xy 346.593471 -396.538075) (xy 346.62458 -396.499655)
			(xy 346.661474 -396.466751) (xy 346.703187 -396.440222) (xy 346.748631 -396.420761) (xy 346.796617 -396.408877)
			(xy 346.84589 -396.404881) (xy 346.895163 -396.408877) (xy 346.943149 -396.420761) (xy 346.988593 -396.440222)
			(xy 347.030306 -396.466751) (xy 347.0672 -396.499655) (xy 347.098309 -396.538075) (xy 347.122821 -396.581005)
			(xy 347.140095 -396.627324) (xy 347.145356 -396.65148) (xy 347.148912 -396.669514) (xy 347.176852 -396.692628)
			(xy 347.420946 -396.692628) (xy 347.431013 -396.692197) (xy 347.449608 -396.684474) (xy 347.457014 -396.677642)
			(xy 347.621098 -396.513558) (xy 347.627938 -396.506157) (xy 347.635658 -396.487559) (xy 347.636084 -396.47749)
			(xy 347.636084 -396.27937) (xy 347.631258 -396.268956) (xy 347.61773 -396.238546) (xy 347.598625 -396.174791)
			(xy 347.588959 -396.10894) (xy 347.588332 -396.075662) (xy 347.588946 -396.042383) (xy 347.598617 -395.976532)
			(xy 347.617721 -395.912775) (xy 347.631258 -395.882368) (xy 347.636084 -395.871954) (xy 347.636084 -395.84884)
			(xy 347.626178 -395.82852) (xy 347.617288 -395.821154) (xy 347.595043 -395.802479) (xy 347.554985 -395.760422)
			(xy 347.52057 -395.713635) (xy 347.49235 -395.662869) (xy 347.47078 -395.608942) (xy 347.456206 -395.552718)
			(xy 347.448863 -395.495103) (xy 347.448378 -395.466062) (xy 347.448823 -395.437136) (xy 347.456116 -395.379746)
			(xy 347.470581 -395.323732) (xy 347.491987 -395.269986) (xy 347.519994 -395.219365) (xy 347.554155 -395.172677)
			(xy 347.593926 -395.130663) (xy 347.616018 -395.111986) (xy 347.623083 -395.105716) (xy 347.632355 -395.089274)
			(xy 347.634052 -395.079982) (xy 347.63837 -395.048994) (xy 347.639318 -395.039756) (xy 347.635282 -395.021646)
			(xy 347.630496 -395.013688) (xy 347.617464 -394.99329) (xy 347.596865 -394.949488) (xy 347.58288 -394.903148)
			(xy 347.575807 -394.855264) (xy 347.575378 -394.831062) (xy 347.575632 -394.81887) (xy 347.575886 -394.809218)
			(xy 347.56979 -394.791184) (xy 347.511116 -394.723874) (xy 347.494352 -394.715238) (xy 347.484446 -394.714222)
			(xy 347.457533 -394.71087) (xy 347.405235 -394.696524) (xy 347.35598 -394.673834) (xy 347.311088 -394.64341)
			(xy 347.271763 -394.606068) (xy 347.23906 -394.562808) (xy 347.213856 -394.514791) (xy 347.196826 -394.463304)
			(xy 347.192092 -394.4366) (xy 347.190568 -394.427202) (xy 346.917772 -393.95527) (xy 346.910406 -393.949428)
			(xy 346.891629 -393.933624) (xy 346.858499 -393.897416) (xy 346.831081 -393.856711) (xy 346.809978 -393.812401)
			(xy 346.795653 -393.765461) (xy 346.78842 -393.716919) (xy 346.787978 -393.69238) (xy 346.788489 -393.666393)
			(xy 346.796622 -393.615061) (xy 346.812685 -393.565632) (xy 346.836281 -393.519324) (xy 346.866831 -393.477277)
			(xy 346.903582 -393.440527) (xy 346.945629 -393.409978) (xy 346.991937 -393.386382) (xy 347.041366 -393.370321)
			(xy 347.092699 -393.362189) (xy 347.118686 -393.361672) (xy 347.144697 -393.362156) (xy 347.196079 -393.370301)
			(xy 347.245551 -393.386392) (xy 347.291892 -393.410032) (xy 347.33396 -393.440637) (xy 347.370715 -393.477453)
			(xy 347.401252 -393.519571) (xy 347.424816 -393.565951) (xy 347.440826 -393.615449) (xy 347.44533 -393.641072)
			(xy 347.446854 -393.65047) (xy 347.71965 -394.122402) (xy 347.727016 -394.128244) (xy 347.745793 -394.144049)
			(xy 347.778925 -394.180256) (xy 347.806344 -394.220961) (xy 347.827449 -394.26527) (xy 347.841777 -394.312211)
			(xy 347.849014 -394.360753) (xy 347.849444 -394.385292) (xy 347.84919 -394.397484) (xy 347.848936 -394.407136)
			(xy 347.855032 -394.42517) (xy 347.913706 -394.49248) (xy 347.93047 -394.501116) (xy 347.940376 -394.502132)
			(xy 347.966808 -394.505424) (xy 348.018213 -394.519366) (xy 348.066718 -394.541368) (xy 348.111069 -394.57086)
			(xy 348.150119 -394.607081) (xy 348.182858 -394.649093) (xy 348.208438 -394.695809) (xy 348.2262 -394.746022)
			(xy 348.23146 -394.772134) (xy 348.234762 -394.790422) (xy 348.262956 -394.81379) (xy 348.43593 -394.81379)
			(xy 348.446289 -394.813372) (xy 348.465362 -394.8053) (xy 348.479671 -394.790327) (xy 348.483682 -394.78077)
			(xy 348.522544 -394.67663) (xy 348.51467 -394.645896) (xy 348.502478 -394.635482) (xy 348.485177 -394.619984)
			(xy 348.454661 -394.584967) (xy 348.429346 -394.546024) (xy 348.409731 -394.503921) (xy 348.396201 -394.459487)
			(xy 348.392242 -394.4366) (xy 348.390718 -394.427202) (xy 348.117922 -393.95527) (xy 348.110556 -393.949428)
			(xy 348.091777 -393.933625) (xy 348.058641 -393.897419) (xy 348.03122 -393.856715) (xy 348.010113 -393.812405)
			(xy 347.995786 -393.765463) (xy 347.988552 -393.71692) (xy 347.988128 -393.69238) (xy 347.988613 -393.666393)
			(xy 347.996747 -393.615059) (xy 348.012811 -393.565629) (xy 348.03641 -393.519321) (xy 348.066964 -393.477276)
			(xy 348.103718 -393.440527) (xy 348.145769 -393.409981) (xy 348.192081 -393.38639) (xy 348.241513 -393.370334)
			(xy 348.292849 -393.362208) (xy 348.318836 -393.361672) (xy 348.34485 -393.362152) (xy 348.396237 -393.370291)
			(xy 348.445715 -393.386377) (xy 348.492063 -393.410014) (xy 348.534138 -393.440618) (xy 348.5709 -393.477435)
			(xy 348.601442 -393.519554) (xy 348.62501 -393.565937) (xy 348.641023 -393.615439) (xy 348.64548 -393.641072)
			(xy 348.647004 -393.65047) (xy 348.9198 -394.122402) (xy 348.927166 -394.128244) (xy 348.945946 -394.144047)
			(xy 348.979082 -394.180253) (xy 349.006505 -394.220957) (xy 349.027614 -394.265266) (xy 349.041944 -394.312208)
			(xy 349.049182 -394.360752) (xy 349.049594 -394.385292) (xy 349.04934 -394.397484) (xy 349.049086 -394.407136)
			(xy 349.055182 -394.42517) (xy 349.113856 -394.49248) (xy 349.13062 -394.501116) (xy 349.140272 -394.502132)
			(xy 349.166704 -394.505424) (xy 349.21811 -394.519365) (xy 349.266615 -394.541367) (xy 349.310967 -394.570859)
			(xy 349.350017 -394.607079) (xy 349.382756 -394.649091) (xy 349.408338 -394.695808) (xy 349.426099 -394.746022)
			(xy 349.431356 -394.772134) (xy 349.434658 -394.790422) (xy 349.462852 -394.81379) (xy 349.635826 -394.81379)
			(xy 349.646185 -394.813372) (xy 349.66526 -394.805301) (xy 349.679571 -394.790329) (xy 349.683578 -394.78077)
			(xy 349.72244 -394.67663) (xy 349.714566 -394.645896) (xy 349.702374 -394.635482) (xy 349.685073 -394.619984)
			(xy 349.654558 -394.584967) (xy 349.629243 -394.546023) (xy 349.609628 -394.50392) (xy 349.596098 -394.459487)
			(xy 349.592138 -394.4366) (xy 349.590614 -394.427202) (xy 349.317818 -393.95527) (xy 349.310452 -393.949428)
			(xy 349.291673 -393.933625) (xy 349.258538 -393.897419) (xy 349.231117 -393.856714) (xy 349.210011 -393.812405)
			(xy 349.195683 -393.765463) (xy 349.188449 -393.71692) (xy 349.188024 -393.69238) (xy 349.188509 -393.666393)
			(xy 349.196643 -393.615058) (xy 349.212707 -393.565629) (xy 349.236306 -393.51932) (xy 349.266859 -393.477274)
			(xy 349.303614 -393.440526) (xy 349.345665 -393.409979) (xy 349.391977 -393.386387) (xy 349.441409 -393.37033)
			(xy 349.492745 -393.362205) (xy 349.518732 -393.361672) (xy 349.544746 -393.362152) (xy 349.596134 -393.37029)
			(xy 349.645612 -393.386376) (xy 349.691961 -393.410013) (xy 349.734036 -393.440617) (xy 349.770798 -393.477433)
			(xy 349.801341 -393.519553) (xy 349.82491 -393.565936) (xy 349.840923 -393.615438) (xy 349.845376 -393.641072)
			(xy 349.8469 -393.65047) (xy 350.119696 -394.122402) (xy 350.127062 -394.128244) (xy 350.145842 -394.144047)
			(xy 350.178979 -394.180253) (xy 350.206402 -394.220957) (xy 350.227511 -394.265266) (xy 350.241842 -394.312208)
			(xy 350.249079 -394.360752) (xy 350.24949 -394.385292) (xy 350.249236 -394.397484) (xy 350.248982 -394.407136)
			(xy 350.255078 -394.42517) (xy 350.313752 -394.49248) (xy 350.330516 -394.501116) (xy 350.340422 -394.502132)
			(xy 350.367189 -394.50546) (xy 350.419214 -394.519686) (xy 350.468242 -394.542165) (xy 350.512973 -394.572301)
			(xy 350.552222 -394.609295) (xy 350.584948 -394.652167) (xy 350.610285 -394.699781) (xy 350.627561 -394.750875)
			(xy 350.636318 -394.804094) (xy 350.63684 -394.831062) (xy 350.636433 -394.854801) (xy 350.629647 -394.901791)
			(xy 350.61621 -394.947327) (xy 350.596399 -394.990474) (xy 350.570619 -395.030343) (xy 350.555306 -395.048486)
			(xy 350.548956 -395.055852) (xy 350.542606 -395.073632) (xy 350.545146 -395.15288) (xy 350.545895 -395.162476)
			(xy 350.553603 -395.180097) (xy 350.560132 -395.18717) (xy 351.242884 -395.869922) (xy 351.250742 -395.876981)
			(xy 351.270421 -395.884595) (xy 351.280984 -395.884654) (xy 351.366836 -395.880844) (xy 351.385378 -395.8717)
			(xy 351.39249 -395.863318) (xy 351.400618 -395.85392) (xy 351.387664 -395.797278) (xy 351.384513 -395.78635)
			(xy 351.370406 -395.768549) (xy 351.360486 -395.762988) (xy 351.33705 -395.750927) (xy 351.294006 -395.720515)
			(xy 351.25633 -395.683661) (xy 351.224974 -395.641299) (xy 351.200733 -395.5945) (xy 351.184219 -395.54445)
			(xy 351.175852 -395.492414) (xy 351.17532 -395.466062) (xy 351.175881 -395.43878) (xy 351.184842 -395.384956)
			(xy 351.202515 -395.333332) (xy 351.228421 -395.285309) (xy 351.261857 -395.242189) (xy 351.281492 -395.223238)
			(xy 351.288942 -395.215746) (xy 351.297486 -395.196451) (xy 351.298002 -395.1859) (xy 351.298002 -395.111224)
			(xy 351.297416 -395.100689) (xy 351.288888 -395.081412) (xy 351.281492 -395.073886) (xy 351.261834 -395.054955)
			(xy 351.228387 -395.011835) (xy 351.202474 -394.963809) (xy 351.1848 -394.912179) (xy 351.175845 -394.858348)
			(xy 351.17532 -394.831062) (xy 351.175574 -394.81887) (xy 351.175828 -394.809218) (xy 351.169732 -394.791184)
			(xy 351.111058 -394.723874) (xy 351.094294 -394.715238) (xy 351.084388 -394.714222) (xy 351.05744 -394.710856)
			(xy 351.005075 -394.69647) (xy 350.95576 -394.67373) (xy 350.910819 -394.643246) (xy 350.871456 -394.605835)
			(xy 350.838728 -394.5625) (xy 350.813511 -394.514405) (xy 350.796483 -394.462839) (xy 350.79178 -394.436092)
			(xy 350.79051 -394.426694) (xy 350.517968 -393.95527) (xy 350.510602 -393.949428) (xy 350.491825 -393.933623)
			(xy 350.458695 -393.897415) (xy 350.431278 -393.85671) (xy 350.410175 -393.812401) (xy 350.39585 -393.765461)
			(xy 350.388617 -393.716919) (xy 350.388174 -393.69238) (xy 350.388685 -393.666393) (xy 350.396818 -393.61506)
			(xy 350.41288 -393.565631) (xy 350.436477 -393.519323) (xy 350.467027 -393.477276) (xy 350.503778 -393.440526)
			(xy 350.545825 -393.409976) (xy 350.592133 -393.38638) (xy 350.641562 -393.370317) (xy 350.692895 -393.362185)
			(xy 350.718882 -393.361672) (xy 350.744894 -393.362156) (xy 350.796275 -393.3703) (xy 350.845748 -393.386391)
			(xy 350.89209 -393.41003) (xy 350.934158 -393.440636) (xy 350.970914 -393.477452) (xy 351.001451 -393.519569)
			(xy 351.025015 -393.56595) (xy 351.041025 -393.615448) (xy 351.045526 -393.641072) (xy 351.04705 -393.65047)
			(xy 351.3201 -394.12291) (xy 351.327212 -394.128752) (xy 351.345943 -394.144532) (xy 351.37899 -394.180678)
			(xy 351.406342 -394.221304) (xy 351.427398 -394.265523) (xy 351.441697 -394.312365) (xy 351.448926 -394.360804)
			(xy 351.449386 -394.385292) (xy 351.449132 -394.397484) (xy 351.448878 -394.407136) (xy 351.454974 -394.42517)
			(xy 351.513648 -394.49248) (xy 351.530412 -394.501116) (xy 351.540318 -394.502132) (xy 351.567085 -394.50546)
			(xy 351.619111 -394.519686) (xy 351.668139 -394.542164) (xy 351.712871 -394.5723) (xy 351.75212 -394.609294)
			(xy 351.784847 -394.652166) (xy 351.810184 -394.69978) (xy 351.827461 -394.750874) (xy 351.836218 -394.804094)
			(xy 351.836736 -394.831062) (xy 351.836173 -394.858344) (xy 351.82721 -394.912167) (xy 351.809536 -394.96379)
			(xy 351.783631 -395.011813) (xy 351.750198 -395.054934) (xy 351.730564 -395.073886) (xy 351.723124 -395.081381)
			(xy 351.714596 -395.100676) (xy 351.714054 -395.111224) (xy 351.714054 -395.1859) (xy 351.714646 -395.196432)
			(xy 351.723187 -395.215696) (xy 351.730564 -395.223238) (xy 351.750217 -395.242172) (xy 351.783656 -395.285293)
			(xy 351.809561 -395.33332) (xy 351.827228 -395.384949) (xy 351.836178 -395.438778) (xy 351.836736 -395.466062)
			(xy 351.836303 -395.49018) (xy 351.829308 -395.537905) (xy 351.815461 -395.58411) (xy 351.795054 -395.627816)
			(xy 351.782126 -395.64818) (xy 351.776284 -395.65707) (xy 351.772728 -395.677136) (xy 351.79381 -395.769338)
			(xy 351.806002 -395.786102) (xy 351.814892 -395.791436) (xy 351.835696 -395.80429) (xy 351.873617 -395.835166)
			(xy 351.90657 -395.871295) (xy 351.933836 -395.911889) (xy 351.954819 -395.95606) (xy 351.969059 -396.002841)
			(xy 351.976245 -396.051211) (xy 351.97669 -396.075662) (xy 351.976221 -396.100855) (xy 351.968587 -396.15066)
			(xy 351.953491 -396.198732) (xy 351.931281 -396.24396) (xy 351.917254 -396.264892) (xy 351.909126 -396.276576)
			(xy 351.907094 -396.30477) (xy 351.955354 -396.397226) (xy 351.959981 -396.405306) (xy 351.973861 -396.417694)
			(xy 351.991262 -396.424277) (xy 352.000566 -396.424658) (xy 352.491548 -396.424658) (xy 352.500845 -396.424248)
			(xy 352.518227 -396.41764) (xy 352.532137 -396.4053) (xy 352.53676 -396.397226) (xy 352.58502 -396.30477)
			(xy 352.582988 -396.276576) (xy 352.57486 -396.264892) (xy 352.560846 -396.243953) (xy 352.538642 -396.198726)
			(xy 352.523551 -396.150656) (xy 352.515919 -396.100854) (xy 352.515424 -396.075662) (xy 352.515863 -396.051546)
			(xy 352.522869 -396.003826) (xy 352.536727 -395.957628) (xy 352.557144 -395.913931) (xy 352.570034 -395.893544)
			(xy 352.575876 -395.884654) (xy 352.579432 -395.864588) (xy 352.55835 -395.772386) (xy 352.546158 -395.755622)
			(xy 352.537268 -395.750288) (xy 352.516465 -395.737433) (xy 352.478546 -395.706556) (xy 352.445594 -395.670425)
			(xy 352.418329 -395.629832) (xy 352.397346 -395.585662) (xy 352.383104 -395.538881) (xy 352.375915 -395.490512)
			(xy 352.37547 -395.466062) (xy 352.376031 -395.438779) (xy 352.384991 -395.384954) (xy 352.402662 -395.333329)
			(xy 352.428565 -395.285303) (xy 352.461998 -395.242179) (xy 352.481642 -395.223238) (xy 352.489098 -395.215749)
			(xy 352.497651 -395.196453) (xy 352.498152 -395.1859) (xy 352.498152 -395.111224) (xy 352.497565 -395.10069)
			(xy 352.489031 -395.081419) (xy 352.481642 -395.073886) (xy 352.461987 -395.054953) (xy 352.428544 -395.011832)
			(xy 352.402636 -394.963806) (xy 352.384965 -394.912177) (xy 352.376011 -394.858347) (xy 352.37547 -394.831062)
			(xy 352.375724 -394.81887) (xy 352.375978 -394.809218) (xy 352.369882 -394.791184) (xy 352.311208 -394.723874)
			(xy 352.294444 -394.715238) (xy 352.284538 -394.714222) (xy 352.257626 -394.71087) (xy 352.205329 -394.696522)
			(xy 352.156074 -394.673832) (xy 352.111183 -394.643408) (xy 352.07186 -394.606065) (xy 352.039158 -394.562806)
			(xy 352.013954 -394.514789) (xy 351.996924 -394.463303) (xy 351.992184 -394.4366) (xy 351.99066 -394.427202)
			(xy 351.717864 -393.95527) (xy 351.710498 -393.949428) (xy 351.691721 -393.933623) (xy 351.658592 -393.897415)
			(xy 351.631175 -393.85671) (xy 351.610073 -393.812401) (xy 351.595748 -393.765461) (xy 351.588515 -393.716919)
			(xy 351.58807 -393.69238) (xy 351.588581 -393.666393) (xy 351.596714 -393.61506) (xy 351.612776 -393.565631)
			(xy 351.636373 -393.519322) (xy 351.666923 -393.477275) (xy 351.703673 -393.440524) (xy 351.745721 -393.409974)
			(xy 351.792029 -393.386377) (xy 351.841458 -393.370314) (xy 351.892791 -393.362181) (xy 351.918778 -393.361672)
			(xy 351.94479 -393.362155) (xy 351.996172 -393.370299) (xy 352.045645 -393.386389) (xy 352.091988 -393.410029)
			(xy 352.134056 -393.440634) (xy 352.170813 -393.47745) (xy 352.20135 -393.519568) (xy 352.224915 -393.565949)
			(xy 352.240925 -393.615447) (xy 352.245422 -393.641072) (xy 352.246946 -393.65047) (xy 352.519742 -394.122402)
			(xy 352.527108 -394.128244) (xy 352.545886 -394.144048) (xy 352.579018 -394.180256) (xy 352.606438 -394.220961)
			(xy 352.627543 -394.26527) (xy 352.641872 -394.31221) (xy 352.649109 -394.360752) (xy 352.649536 -394.385292)
			(xy 352.649282 -394.397484) (xy 352.649028 -394.407136) (xy 352.655124 -394.42517) (xy 352.713798 -394.49248)
			(xy 352.730562 -394.501116) (xy 352.740468 -394.502132) (xy 352.767238 -394.505456) (xy 352.81927 -394.519676)
			(xy 352.868305 -394.542151) (xy 352.913044 -394.572285) (xy 352.9523 -394.609279) (xy 352.985032 -394.652153)
			(xy 353.010374 -394.699769) (xy 353.027653 -394.750867) (xy 353.036412 -394.804092) (xy 353.036886 -394.831062)
			(xy 353.036323 -394.858344) (xy 353.027358 -394.912166) (xy 353.009683 -394.963787) (xy 352.983775 -395.011807)
			(xy 352.950339 -395.054925) (xy 352.930714 -395.073886) (xy 352.923268 -395.081379) (xy 352.914731 -395.100674)
			(xy 352.914204 -395.111224) (xy 352.914204 -395.1859) (xy 352.914795 -395.196433) (xy 352.923329 -395.215702)
			(xy 352.930714 -395.223238) (xy 352.95037 -395.24217) (xy 352.983814 -395.28529) (xy 353.009722 -395.333317)
			(xy 353.027392 -395.384947) (xy 353.036344 -395.438777) (xy 353.036886 -395.466062) (xy 353.036453 -395.490179)
			(xy 353.029457 -395.537904) (xy 353.015608 -395.584108) (xy 352.995199 -395.627813) (xy 352.982276 -395.64818)
			(xy 352.976434 -395.65707) (xy 352.972878 -395.677136) (xy 352.99396 -395.769338) (xy 353.006152 -395.786102)
			(xy 353.015042 -395.791436) (xy 353.035843 -395.804292) (xy 353.073759 -395.83517) (xy 353.106707 -395.871301)
			(xy 353.133969 -395.911895) (xy 353.154948 -395.956065) (xy 353.169186 -396.002845) (xy 353.176371 -396.051212)
			(xy 353.17684 -396.075662) (xy 353.176371 -396.100856) (xy 353.168738 -396.150661) (xy 353.153644 -396.198734)
			(xy 353.131437 -396.243964) (xy 353.117404 -396.264892) (xy 353.109276 -396.276576) (xy 353.107244 -396.30477)
			(xy 353.155504 -396.397226) (xy 353.160129 -396.405312) (xy 353.174007 -396.417713) (xy 353.191409 -396.424313)
			(xy 353.200716 -396.424658) (xy 353.691444 -396.424658) (xy 353.700742 -396.424248) (xy 353.718124 -396.417642)
			(xy 353.732036 -396.405302) (xy 353.736656 -396.397226) (xy 353.784916 -396.30477) (xy 353.782884 -396.276576)
			(xy 353.774756 -396.264892) (xy 353.760742 -396.243953) (xy 353.738539 -396.198726) (xy 353.723447 -396.150656)
			(xy 353.715816 -396.100854) (xy 353.71532 -396.075662) (xy 353.715759 -396.051546) (xy 353.722765 -396.003826)
			(xy 353.736623 -395.957628) (xy 353.75704 -395.913931) (xy 353.76993 -395.893544) (xy 353.775772 -395.884654)
			(xy 353.779328 -395.864588) (xy 353.758246 -395.772386) (xy 353.746054 -395.755622) (xy 353.737164 -395.750288)
			(xy 353.716361 -395.737433) (xy 353.678443 -395.706555) (xy 353.645491 -395.670425) (xy 353.618226 -395.629831)
			(xy 353.597244 -395.585662) (xy 353.583002 -395.538881) (xy 353.575813 -395.490512) (xy 353.575366 -395.466062)
			(xy 353.575927 -395.438779) (xy 353.584887 -395.384954) (xy 353.602558 -395.333329) (xy 353.628461 -395.285303)
			(xy 353.661893 -395.242179) (xy 353.681538 -395.223238) (xy 353.688982 -395.215744) (xy 353.697518 -395.196449)
			(xy 353.698048 -395.1859) (xy 353.698048 -395.111224) (xy 353.69746 -395.10069) (xy 353.688926 -395.081419)
			(xy 353.681538 -395.073886) (xy 353.661883 -395.054953) (xy 353.628441 -395.011832) (xy 353.602533 -394.963805)
			(xy 353.584862 -394.912176) (xy 353.575908 -394.858347) (xy 353.575366 -394.831062) (xy 353.57562 -394.81887)
			(xy 353.575874 -394.809218) (xy 353.569778 -394.791184) (xy 353.511104 -394.723874) (xy 353.49434 -394.715238)
			(xy 353.484434 -394.714222) (xy 353.457483 -394.710859) (xy 353.405113 -394.696479) (xy 353.355792 -394.673742)
			(xy 353.310844 -394.64326) (xy 353.271476 -394.605849) (xy 353.238742 -394.562514) (xy 353.213521 -394.514417)
			(xy 353.19649 -394.462847) (xy 353.191826 -394.436092) (xy 353.190556 -394.426694) (xy 352.918014 -393.95527)
			(xy 352.910648 -393.949428) (xy 352.891869 -393.933625) (xy 352.858735 -393.897419) (xy 352.831314 -393.856714)
			(xy 352.810208 -393.812405) (xy 352.795881 -393.765463) (xy 352.788647 -393.71692) (xy 352.78822 -393.69238)
			(xy 352.788705 -393.666393) (xy 352.796839 -393.615058) (xy 352.812903 -393.565628) (xy 352.836502 -393.51932)
			(xy 352.867055 -393.477273) (xy 352.90381 -393.440524) (xy 352.945861 -393.409977) (xy 352.992172 -393.386385)
			(xy 353.041605 -393.370327) (xy 353.09294 -393.362201) (xy 353.118928 -393.361672) (xy 353.144942 -393.362152)
			(xy 353.19633 -393.370289) (xy 353.24581 -393.386375) (xy 353.292159 -393.410011) (xy 353.334234 -393.440615)
			(xy 353.370997 -393.477432) (xy 353.40154 -393.519551) (xy 353.425109 -393.565935) (xy 353.441123 -393.615438)
			(xy 353.445572 -393.641072) (xy 353.447096 -393.65047) (xy 353.471318 -393.69238) (xy 353.988116 -393.69238)
			(xy 353.988557 -393.666389) (xy 353.996692 -393.615047) (xy 354.012758 -393.565611) (xy 354.036361 -393.519296)
			(xy 354.066918 -393.477243) (xy 354.103677 -393.440489) (xy 354.145733 -393.409937) (xy 354.192051 -393.386341)
			(xy 354.24149 -393.370281) (xy 354.292833 -393.362153) (xy 354.318824 -393.361672) (xy 354.344835 -393.36212)
			(xy 354.396213 -393.370282) (xy 354.445679 -393.386386) (xy 354.492015 -393.410035) (xy 354.534078 -393.440645)
			(xy 354.570831 -393.477463) (xy 354.601368 -393.519579) (xy 354.607346 -393.531344) (xy 355.95687 -393.531344)
			(xy 355.957306 -393.506448) (xy 355.964757 -393.457218) (xy 355.979496 -393.409658) (xy 356.001192 -393.364842)
			(xy 356.029355 -393.323781) (xy 356.046024 -393.305284) (xy 356.052628 -393.298426) (xy 356.059486 -393.281408)
			(xy 356.061772 -393.195048) (xy 356.055676 -393.177522) (xy 356.04958 -393.17041) (xy 356.034823 -393.152415)
			(xy 356.009992 -393.113054) (xy 355.990927 -393.0706) (xy 355.978007 -393.025891) (xy 355.971487 -392.979811)
			(xy 355.971094 -392.956542) (xy 355.971614 -392.930554) (xy 355.979739 -392.879216) (xy 355.995796 -392.829782)
			(xy 356.019388 -392.783469) (xy 356.049936 -392.741417) (xy 356.086687 -392.704662) (xy 356.128735 -392.674109)
			(xy 356.175045 -392.650511) (xy 356.224477 -392.634448) (xy 356.275814 -392.626317) (xy 356.301802 -392.625834)
			(xy 356.325303 -392.62623) (xy 356.371834 -392.632866) (xy 356.394512 -392.639042) (xy 356.407974 -392.643106)
			(xy 356.43439 -392.636502) (xy 356.517448 -392.555222) (xy 356.524814 -392.52906) (xy 356.521258 -392.515598)
			(xy 356.515324 -392.491651) (xy 356.508948 -392.44273) (xy 356.508558 -392.418062) (xy 356.509044 -392.390811)
			(xy 356.5168 -392.336863) (xy 356.532155 -392.284568) (xy 356.554797 -392.234991) (xy 356.584263 -392.189141)
			(xy 356.619954 -392.14795) (xy 356.661145 -392.112259) (xy 356.706995 -392.082793) (xy 356.756572 -392.060151)
			(xy 356.808867 -392.044796) (xy 356.862815 -392.03704) (xy 356.917317 -392.03704) (xy 356.971265 -392.044796)
			(xy 357.02356 -392.060151) (xy 357.073137 -392.082793) (xy 357.118987 -392.112259) (xy 357.160178 -392.14795)
			(xy 357.195869 -392.189141) (xy 357.225335 -392.234991) (xy 357.247977 -392.284568) (xy 357.263332 -392.336863)
			(xy 357.271088 -392.390811) (xy 357.271574 -392.418062) (xy 357.271092 -392.445432) (xy 357.265259 -392.48588)
			(xy 357.607868 -392.48588) (xy 357.611939 -392.430258) (xy 357.624065 -392.375821) (xy 357.643988 -392.32373)
			(xy 357.671284 -392.275095) (xy 357.70537 -392.230952) (xy 357.745519 -392.192243) (xy 357.790877 -392.159792)
			(xy 357.840477 -392.134291) (xy 357.893261 -392.116284) (xy 357.948104 -392.106154) (xy 358.003838 -392.104117)
			(xy 358.059275 -392.110217) (xy 358.113232 -392.124323) (xy 358.164561 -392.146135) (xy 358.212167 -392.175189)
			(xy 358.255035 -392.210864) (xy 358.292252 -392.252401) (xy 358.323025 -392.298914) (xy 358.346697 -392.349411)
			(xy 358.362765 -392.402818) (xy 358.370885 -392.457994) (xy 358.371394 -392.48588) (xy 358.370885 -392.513766)
			(xy 358.362765 -392.568942) (xy 358.346697 -392.622349) (xy 358.323025 -392.672846) (xy 358.292252 -392.719359)
			(xy 358.255035 -392.760896) (xy 358.212167 -392.796571) (xy 358.164561 -392.825625) (xy 358.113232 -392.847437)
			(xy 358.059275 -392.861543) (xy 358.003838 -392.867643) (xy 357.948104 -392.865606) (xy 357.893261 -392.855476)
			(xy 357.840477 -392.837469) (xy 357.790877 -392.811968) (xy 357.745519 -392.779517) (xy 357.70537 -392.740808)
			(xy 357.671284 -392.696665) (xy 357.643988 -392.64803) (xy 357.624065 -392.595939) (xy 357.611939 -392.541502)
			(xy 357.607868 -392.48588) (xy 357.265259 -392.48588) (xy 357.263279 -392.49961) (xy 357.247794 -392.552114)
			(xy 357.224956 -392.601861) (xy 357.195234 -392.647828) (xy 357.177594 -392.66876) (xy 357.171498 -392.675872)
			(xy 357.165148 -392.69289) (xy 357.165148 -392.778234) (xy 357.171498 -392.795252) (xy 357.177594 -392.802364)
			(xy 357.195197 -392.823327) (xy 357.224921 -392.86929) (xy 357.247768 -392.919032) (xy 357.263266 -392.971529)
			(xy 357.271098 -393.025703) (xy 357.271102 -393.08044) (xy 357.263278 -393.134615) (xy 357.247788 -393.187115)
			(xy 357.224949 -393.236859) (xy 357.195231 -393.282827) (xy 357.177594 -393.30376) (xy 357.171498 -393.310872)
			(xy 357.165148 -393.32789) (xy 357.165148 -393.413234) (xy 357.171498 -393.430252) (xy 357.177594 -393.437364)
			(xy 357.195229 -393.4583) (xy 357.206979 -393.47648) (xy 357.607868 -393.47648) (xy 357.611939 -393.420858)
			(xy 357.624065 -393.366421) (xy 357.643988 -393.31433) (xy 357.671284 -393.265695) (xy 357.70537 -393.221552)
			(xy 357.745519 -393.182843) (xy 357.790877 -393.150392) (xy 357.840477 -393.124891) (xy 357.893261 -393.106884)
			(xy 357.948104 -393.096754) (xy 358.003838 -393.094717) (xy 358.059275 -393.100817) (xy 358.113232 -393.114923)
			(xy 358.164561 -393.136735) (xy 358.212167 -393.165789) (xy 358.255035 -393.201464) (xy 358.292252 -393.243001)
			(xy 358.323025 -393.289514) (xy 358.346697 -393.340011) (xy 358.362765 -393.393418) (xy 358.370885 -393.448594)
			(xy 358.371394 -393.47648) (xy 358.370885 -393.504366) (xy 358.362765 -393.559542) (xy 358.346697 -393.612949)
			(xy 358.323025 -393.663446) (xy 358.292252 -393.709959) (xy 358.255035 -393.751496) (xy 358.212167 -393.787171)
			(xy 358.164561 -393.816225) (xy 358.113232 -393.838037) (xy 358.059275 -393.852143) (xy 358.003838 -393.858243)
			(xy 357.948104 -393.856206) (xy 357.893261 -393.846076) (xy 357.840477 -393.828069) (xy 357.790877 -393.802568)
			(xy 357.745519 -393.770117) (xy 357.70537 -393.731408) (xy 357.671284 -393.687265) (xy 357.643988 -393.63863)
			(xy 357.624065 -393.586539) (xy 357.611939 -393.532102) (xy 357.607868 -393.47648) (xy 357.206979 -393.47648)
			(xy 357.224941 -393.504271) (xy 357.247778 -393.554018) (xy 357.26327 -393.606518) (xy 357.2711 -393.660693)
			(xy 357.271574 -393.688062) (xy 357.271093 -393.714971) (xy 357.263548 -393.768256) (xy 357.248588 -393.819953)
			(xy 357.22651 -393.869033) (xy 357.197753 -393.914523) (xy 357.162888 -393.955519) (xy 357.122606 -393.991207)
			(xy 357.077708 -394.02088) (xy 357.029085 -394.043947) (xy 356.977702 -394.05995) (xy 356.92458 -394.068573)
			(xy 356.897686 -394.06957) (xy 356.886256 -394.069824) (xy 356.86619 -394.07973) (xy 356.803198 -394.158978)
			(xy 356.798118 -394.181076) (xy 356.800404 -394.192252) (xy 356.804325 -394.211829) (xy 356.808523 -394.251536)
			(xy 356.808786 -394.2715) (xy 356.808532 -394.291591) (xy 356.804336 -394.331552) (xy 356.800404 -394.351256)
			(xy 356.797356 -394.364718) (xy 356.806246 -394.39088) (xy 356.89413 -394.467588) (xy 356.921308 -394.472668)
			(xy 356.934262 -394.468096) (xy 356.965655 -394.457468) (xy 357.030921 -394.445969) (xy 357.064056 -394.445236)
			(xy 357.091312 -394.445608) (xy 357.14527 -394.453359) (xy 357.197576 -394.468711) (xy 357.247164 -394.491351)
			(xy 357.293026 -394.520817) (xy 357.334228 -394.55651) (xy 357.36993 -394.597703) (xy 357.399407 -394.643558)
			(xy 357.422058 -394.693142) (xy 357.437422 -394.745444) (xy 357.445186 -394.7994) (xy 357.445192 -394.853912)
			(xy 357.437441 -394.90787) (xy 357.422089 -394.960176) (xy 357.399449 -395.009764) (xy 357.369983 -395.055626)
			(xy 357.33429 -395.096828) (xy 357.293097 -395.13253) (xy 357.247242 -395.162007) (xy 357.197658 -395.184658)
			(xy 357.145356 -395.200022) (xy 357.0914 -395.207786) (xy 357.036888 -395.207792) (xy 356.98293 -395.200041)
			(xy 356.930624 -395.184689) (xy 356.881036 -395.162049) (xy 356.835174 -395.132583) (xy 356.793972 -395.09689)
			(xy 356.75827 -395.055697) (xy 356.728793 -395.009842) (xy 356.706142 -394.960258) (xy 356.690778 -394.907956)
			(xy 356.683014 -394.854) (xy 356.682548 -394.826744) (xy 356.682795 -394.806653) (xy 356.686996 -394.766692)
			(xy 356.69093 -394.746988) (xy 356.693978 -394.733526) (xy 356.685088 -394.707364) (xy 356.597204 -394.630656)
			(xy 356.570026 -394.625576) (xy 356.557072 -394.630148) (xy 356.525684 -394.640794) (xy 356.460414 -394.65228)
			(xy 356.427278 -394.653008) (xy 356.400026 -394.652543) (xy 356.346078 -394.644783) (xy 356.293783 -394.629425)
			(xy 356.244205 -394.606782) (xy 356.198355 -394.577313) (xy 356.157165 -394.541619) (xy 356.121474 -394.500427)
			(xy 356.092008 -394.454575) (xy 356.069367 -394.404997) (xy 356.054012 -394.352701) (xy 356.046256 -394.298752)
			(xy 356.04577 -394.2715) (xy 356.046197 -394.245518) (xy 356.053262 -394.194035) (xy 356.067246 -394.143988)
			(xy 356.087892 -394.0963) (xy 356.114817 -394.051855) (xy 356.147524 -394.011474) (xy 356.166166 -393.99337)
			(xy 356.175564 -393.984734) (xy 356.183438 -393.961366) (xy 356.167436 -393.85367) (xy 356.152958 -393.833604)
			(xy 356.141528 -393.828016) (xy 356.118124 -393.815977) (xy 356.07518 -393.78555) (xy 356.037598 -393.748705)
			(xy 356.006328 -393.706371) (xy 355.98216 -393.659618) (xy 355.965704 -393.609626) (xy 355.957375 -393.557659)
			(xy 355.95687 -393.531344) (xy 354.607346 -393.531344) (xy 354.624935 -393.565957) (xy 354.640953 -393.615451)
			(xy 354.645468 -393.641072) (xy 354.646992 -393.65047) (xy 354.919788 -394.122402) (xy 354.927154 -394.128244)
			(xy 354.945947 -394.144029) (xy 354.979061 -394.180251) (xy 355.006467 -394.220963) (xy 355.027565 -394.265274)
			(xy 355.041893 -394.312213) (xy 355.049137 -394.360753) (xy 355.049582 -394.385292) (xy 355.049328 -394.396976)
			(xy 355.049074 -394.406882) (xy 355.055424 -394.424916) (xy 355.114606 -394.491972) (xy 355.131878 -394.500862)
			(xy 355.14153 -394.501624) (xy 355.165865 -394.504281) (xy 355.213414 -394.515915) (xy 355.258731 -394.534427)
			(xy 355.300826 -394.559413) (xy 355.338781 -394.590328) (xy 355.371768 -394.626497) (xy 355.399066 -394.667131)
			(xy 355.42008 -394.711343) (xy 355.434351 -394.758169) (xy 355.441568 -394.806586) (xy 355.442012 -394.831062)
			(xy 355.441502 -394.857049) (xy 355.433372 -394.908384) (xy 355.417311 -394.957814) (xy 355.393715 -395.004124)
			(xy 355.363165 -395.046172) (xy 355.326414 -395.082923) (xy 355.284366 -395.113473) (xy 355.238056 -395.137069)
			(xy 355.188626 -395.15313) (xy 355.137291 -395.16126) (xy 355.085317 -395.16126) (xy 355.033982 -395.15313)
			(xy 354.984552 -395.137069) (xy 354.938242 -395.113473) (xy 354.896194 -395.082923) (xy 354.859443 -395.046172)
			(xy 354.828893 -395.004124) (xy 354.805297 -394.957814) (xy 354.789236 -394.908384) (xy 354.781106 -394.857049)
			(xy 354.780596 -394.831062) (xy 354.78085 -394.819378) (xy 354.781104 -394.809472) (xy 354.774754 -394.791438)
			(xy 354.715572 -394.724382) (xy 354.6983 -394.715492) (xy 354.688648 -394.71473) (xy 354.66446 -394.712097)
			(xy 354.617195 -394.70055) (xy 354.572128 -394.682211) (xy 354.53023 -394.657473) (xy 354.492404 -394.62687)
			(xy 354.459464 -394.591061) (xy 354.432119 -394.550816) (xy 354.410959 -394.507003) (xy 354.396438 -394.460565)
			(xy 354.39223 -394.4366) (xy 354.390706 -394.427202) (xy 354.11791 -393.95527) (xy 354.110544 -393.949428)
			(xy 354.091786 -393.933605) (xy 354.058669 -393.897391) (xy 354.031259 -393.856686) (xy 354.010155 -393.812383)
			(xy 353.995819 -393.765451) (xy 353.988566 -393.716916) (xy 353.988116 -393.69238) (xy 353.471318 -393.69238)
			(xy 353.720146 -394.12291) (xy 353.727258 -394.128752) (xy 353.745986 -394.144534) (xy 353.77903 -394.180681)
			(xy 353.806377 -394.221308) (xy 353.82743 -394.265526) (xy 353.841727 -394.312367) (xy 353.848955 -394.360805)
			(xy 353.849432 -394.385292) (xy 353.849178 -394.397484) (xy 353.848924 -394.407136) (xy 353.85502 -394.42517)
			(xy 353.913694 -394.49248) (xy 353.930458 -394.501116) (xy 353.940364 -394.502132) (xy 353.967134 -394.505456)
			(xy 354.019167 -394.519675) (xy 354.068203 -394.54215) (xy 354.112942 -394.572284) (xy 354.152198 -394.609278)
			(xy 354.184931 -394.652151) (xy 354.210273 -394.699768) (xy 354.227553 -394.750867) (xy 354.236312 -394.804092)
			(xy 354.236782 -394.831062) (xy 354.236219 -394.858344) (xy 354.227254 -394.912165) (xy 354.209579 -394.963786)
			(xy 354.183671 -395.011807) (xy 354.150234 -395.054924) (xy 354.13061 -395.073886) (xy 354.123164 -395.081379)
			(xy 354.114629 -395.100674) (xy 354.1141 -395.111224) (xy 354.1141 -395.1859) (xy 354.114691 -395.196433)
			(xy 354.123225 -395.215703) (xy 354.13061 -395.223238) (xy 354.150266 -395.24217) (xy 354.18371 -395.28529)
			(xy 354.209619 -395.333317) (xy 354.227289 -395.384946) (xy 354.236241 -395.438777) (xy 354.236782 -395.466062)
			(xy 354.236349 -395.490179) (xy 354.229353 -395.537904) (xy 354.215504 -395.584108) (xy 354.195094 -395.627813)
			(xy 354.182172 -395.64818) (xy 354.17633 -395.65707) (xy 354.172774 -395.677136) (xy 354.193856 -395.769338)
			(xy 354.206048 -395.786102) (xy 354.214938 -395.791436) (xy 354.235739 -395.804292) (xy 354.273655 -395.83517)
			(xy 354.306604 -395.871301) (xy 354.333866 -395.911895) (xy 354.354846 -395.956065) (xy 354.369084 -396.002845)
			(xy 354.376269 -396.051212) (xy 354.376736 -396.075662) (xy 354.376267 -396.100856) (xy 354.368634 -396.150661)
			(xy 354.35354 -396.198734) (xy 354.331332 -396.243963) (xy 354.3173 -396.264892) (xy 354.309172 -396.276576)
			(xy 354.30714 -396.30477) (xy 354.3554 -396.397226) (xy 354.360025 -396.405312) (xy 354.373903 -396.417714)
			(xy 354.391305 -396.424316) (xy 354.400612 -396.424658) (xy 356.115366 -396.424658) (xy 356.124037 -396.424362)
			(xy 356.140408 -396.418657) (xy 356.14737 -396.413482) (xy 356.167037 -396.398252) (xy 356.210039 -396.373254)
			(xy 356.256302 -396.354984) (xy 356.304781 -396.343854) (xy 356.35438 -396.340116) (xy 356.403979 -396.343854)
			(xy 356.452458 -396.354984) (xy 356.498721 -396.373254) (xy 356.541723 -396.398252) (xy 356.56139 -396.413482)
			(xy 356.568248 -396.418816) (xy 356.584504 -396.424658) (xy 356.653846 -396.424658) (xy 356.663912 -396.424225)
			(xy 356.6825 -396.416494) (xy 356.689914 -396.409672) (xy 358.122982 -394.976604) (xy 358.129972 -394.96901)
			(xy 358.137707 -394.949897) (xy 358.137249 -394.929283) (xy 358.133396 -394.919708) (xy 358.087676 -394.818616)
			(xy 358.060752 -394.80236) (xy 358.04475 -394.803376) (xy 358.021128 -394.804138) (xy 357.993872 -394.803677)
			(xy 357.939913 -394.795923) (xy 357.887608 -394.780568) (xy 357.83802 -394.757925) (xy 357.79216 -394.728456)
			(xy 357.750961 -394.692759) (xy 357.715261 -394.651562) (xy 357.685788 -394.605704) (xy 357.663142 -394.556118)
			(xy 357.647783 -394.503814) (xy 357.640025 -394.449856) (xy 357.640025 -394.395344) (xy 357.647783 -394.341386)
			(xy 357.663142 -394.289082) (xy 357.685788 -394.239496) (xy 357.715261 -394.193638) (xy 357.750961 -394.152441)
			(xy 357.79216 -394.116744) (xy 357.83802 -394.087275) (xy 357.887608 -394.064632) (xy 357.939913 -394.049277)
			(xy 357.993872 -394.041523) (xy 358.021128 -394.041122) (xy 358.048931 -394.041619) (xy 358.103949 -394.04968)
			(xy 358.157214 -394.06564) (xy 358.207599 -394.089163) (xy 358.254036 -394.11975) (xy 358.295542 -394.156753)
			(xy 358.331238 -394.199388) (xy 358.360367 -394.246753) (xy 358.382313 -394.297844) (xy 358.389936 -394.324586)
			(xy 358.392984 -394.336016) (xy 358.408478 -394.353796) (xy 358.504998 -394.393928) (xy 358.52862 -394.392404)
			(xy 358.53878 -394.386562) (xy 358.564486 -394.372184) (xy 358.618543 -394.34879) (xy 358.674943 -394.331806)
			(xy 358.732929 -394.321458) (xy 358.7623 -394.319252) (xy 358.771698 -394.31849) (xy 358.788462 -394.311124)
			(xy 359.031286 -394.0683) (xy 359.038134 -394.060902) (xy 359.04587 -394.042304) (xy 359.046272 -394.032232)
			(xy 359.046272 -392.21918) (xy 359.045889 -392.209756) (xy 359.039058 -392.192189) (xy 359.02633 -392.178287)
			(xy 359.018078 -392.173714) (xy 358.923336 -392.126724) (xy 358.895142 -392.129518) (xy 358.883458 -392.138408)
			(xy 358.858428 -392.156588) (xy 358.803717 -392.185455) (xy 358.745065 -392.205118) (xy 358.68401 -392.215063)
			(xy 358.65308 -392.215624) (xy 358.625829 -392.215137) (xy 358.571881 -392.207378) (xy 358.519586 -392.19202)
			(xy 358.470009 -392.169377) (xy 358.42416 -392.139909) (xy 358.38297 -392.104216) (xy 358.347279 -392.063024)
			(xy 358.317813 -392.017173) (xy 358.295173 -391.967595) (xy 358.279818 -391.9153) (xy 358.272062 -391.861351)
			(xy 358.272062 -391.806849) (xy 358.279818 -391.7529) (xy 358.295173 -391.700605) (xy 358.317813 -391.651027)
			(xy 358.347279 -391.605176) (xy 358.38297 -391.563984) (xy 358.42416 -391.528291) (xy 358.470009 -391.498823)
			(xy 358.519586 -391.47618) (xy 358.571881 -391.460822) (xy 358.625829 -391.453063) (xy 358.65308 -391.452608)
			(xy 358.682163 -391.453153) (xy 358.739657 -391.461975) (xy 358.795146 -391.479419) (xy 358.847346 -391.50508)
			(xy 358.895049 -391.538363) (xy 358.937149 -391.5785) (xy 358.95534 -391.601198) (xy 358.962706 -391.61085)
			(xy 358.983534 -391.62101) (xy 358.995472 -391.62101) (xy 359.005498 -391.620595) (xy 359.024026 -391.612931)
			(xy 359.038209 -391.598758) (xy 359.045888 -391.580235) (xy 359.046272 -391.57021) (xy 359.046272 -391.479532)
			(xy 359.045836 -391.469468) (xy 359.038101 -391.450884) (xy 359.031286 -391.443464) (xy 358.822498 -391.234676)
			(xy 358.815103 -391.227822) (xy 358.796504 -391.220076) (xy 358.78643 -391.21969) (xy 356.30485 -391.21969)
			(xy 356.27564 -391.247376) (xy 356.274624 -391.267696) (xy 356.272823 -391.292742) (xy 356.262604 -391.341905)
			(xy 356.245072 -391.388959) (xy 356.22063 -391.432822) (xy 356.189839 -391.472487) (xy 356.153408 -391.507043)
			(xy 356.112171 -391.535696) (xy 356.067078 -391.557787) (xy 356.019164 -391.572809) (xy 355.969531 -391.580417)
			(xy 355.944424 -391.580878) (xy 355.920652 -391.580461) (xy 355.8736 -391.573641) (xy 355.828009 -391.560153)
			(xy 355.78482 -391.540274) (xy 355.744923 -391.514416) (xy 355.726746 -391.49909) (xy 355.719623 -391.493413)
			(xy 355.702572 -391.487043) (xy 355.693472 -391.486644) (xy 355.661976 -391.486644) (xy 355.652868 -391.48701)
			(xy 355.635801 -391.493374) (xy 355.628702 -391.49909) (xy 355.610543 -391.514442) (xy 355.570649 -391.540314)
			(xy 355.527456 -391.560199) (xy 355.481859 -391.573684) (xy 355.434799 -391.580492) (xy 355.411024 -391.580878)
			(xy 355.384152 -391.580354) (xy 355.331117 -391.571665) (xy 355.280185 -391.554511) (xy 355.232699 -391.529344)
			(xy 355.189909 -391.496827) (xy 355.152942 -391.457816) (xy 355.137466 -391.435844) (xy 355.130862 -391.426446)
			(xy 355.111558 -391.415016) (xy 355.02215 -391.40638) (xy 355.01093 -391.405951) (xy 354.989843 -391.413588)
			(xy 354.98151 -391.421112) (xy 354.392484 -392.010138) (xy 354.385087 -392.016988) (xy 354.366489 -392.024727)
			(xy 354.356416 -392.025124) (xy 344.317066 -392.025124) (xy 344.306999 -392.025554) (xy 344.288406 -392.03328)
			(xy 344.280998 -392.04011) (xy 343.49436 -392.826748) (xy 343.488518 -392.856974) (xy 343.494614 -392.871198)
			(xy 343.502815 -392.891621) (xy 343.514357 -392.934092) (xy 343.520171 -392.977717) (xy 343.520522 -392.999722)
			(xy 343.520011 -393.025708) (xy 343.520011 -393.025709) (xy 344.059766 -393.025709) (xy 344.059766 -392.973735)
			(xy 344.067896 -392.9224) (xy 344.083957 -392.87297) (xy 344.107553 -392.82666) (xy 344.138103 -392.784612)
			(xy 344.174854 -392.747861) (xy 344.216902 -392.717311) (xy 344.263212 -392.693715) (xy 344.312642 -392.677654)
			(xy 344.363977 -392.669524) (xy 344.415951 -392.669524) (xy 344.467286 -392.677654) (xy 344.516716 -392.693715)
			(xy 344.563026 -392.717311) (xy 344.605074 -392.747861) (xy 344.641825 -392.784612) (xy 344.672375 -392.82666)
			(xy 344.695971 -392.87297) (xy 344.712032 -392.9224) (xy 344.720162 -392.973735) (xy 344.720672 -392.999722)
			(xy 344.720162 -393.025709) (xy 345.259662 -393.025709) (xy 345.259662 -392.973735) (xy 345.267792 -392.9224)
			(xy 345.283853 -392.87297) (xy 345.307449 -392.82666) (xy 345.337999 -392.784612) (xy 345.37475 -392.747861)
			(xy 345.416798 -392.717311) (xy 345.463108 -392.693715) (xy 345.512538 -392.677654) (xy 345.563873 -392.669524)
			(xy 345.615847 -392.669524) (xy 345.667182 -392.677654) (xy 345.716612 -392.693715) (xy 345.762922 -392.717311)
			(xy 345.80497 -392.747861) (xy 345.841721 -392.784612) (xy 345.872271 -392.82666) (xy 345.895867 -392.87297)
			(xy 345.911928 -392.9224) (xy 345.920058 -392.973735) (xy 345.920568 -392.999722) (xy 345.920058 -393.025709)
			(xy 346.459812 -393.025709) (xy 346.459812 -392.973735) (xy 346.467942 -392.9224) (xy 346.484003 -392.87297)
			(xy 346.507599 -392.82666) (xy 346.538149 -392.784612) (xy 346.5749 -392.747861) (xy 346.616948 -392.717311)
			(xy 346.663258 -392.693715) (xy 346.712688 -392.677654) (xy 346.764023 -392.669524) (xy 346.815997 -392.669524)
			(xy 346.867332 -392.677654) (xy 346.916762 -392.693715) (xy 346.963072 -392.717311) (xy 347.00512 -392.747861)
			(xy 347.041871 -392.784612) (xy 347.072421 -392.82666) (xy 347.096017 -392.87297) (xy 347.112078 -392.9224)
			(xy 347.120208 -392.973735) (xy 347.120718 -392.999722) (xy 347.120208 -393.025709) (xy 347.659708 -393.025709)
			(xy 347.659708 -392.973735) (xy 347.667838 -392.9224) (xy 347.683899 -392.87297) (xy 347.707495 -392.82666)
			(xy 347.738045 -392.784612) (xy 347.774796 -392.747861) (xy 347.816844 -392.717311) (xy 347.863154 -392.693715)
			(xy 347.912584 -392.677654) (xy 347.963919 -392.669524) (xy 348.015893 -392.669524) (xy 348.067228 -392.677654)
			(xy 348.116658 -392.693715) (xy 348.162968 -392.717311) (xy 348.205016 -392.747861) (xy 348.241767 -392.784612)
			(xy 348.272317 -392.82666) (xy 348.295913 -392.87297) (xy 348.311974 -392.9224) (xy 348.320104 -392.973735)
			(xy 348.320614 -392.999722) (xy 348.320104 -393.025709) (xy 348.859604 -393.025709) (xy 348.859604 -392.973735)
			(xy 348.867734 -392.9224) (xy 348.883795 -392.87297) (xy 348.907391 -392.82666) (xy 348.937941 -392.784612)
			(xy 348.974692 -392.747861) (xy 349.01674 -392.717311) (xy 349.06305 -392.693715) (xy 349.11248 -392.677654)
			(xy 349.163815 -392.669524) (xy 349.215789 -392.669524) (xy 349.267124 -392.677654) (xy 349.316554 -392.693715)
			(xy 349.362864 -392.717311) (xy 349.404912 -392.747861) (xy 349.441663 -392.784612) (xy 349.472213 -392.82666)
			(xy 349.495809 -392.87297) (xy 349.51187 -392.9224) (xy 349.52 -392.973735) (xy 349.52051 -392.999722)
			(xy 349.52 -393.025709) (xy 350.059754 -393.025709) (xy 350.059754 -392.973735) (xy 350.067884 -392.9224)
			(xy 350.083945 -392.87297) (xy 350.107541 -392.82666) (xy 350.138091 -392.784612) (xy 350.174842 -392.747861)
			(xy 350.21689 -392.717311) (xy 350.2632 -392.693715) (xy 350.31263 -392.677654) (xy 350.363965 -392.669524)
			(xy 350.415939 -392.669524) (xy 350.467274 -392.677654) (xy 350.516704 -392.693715) (xy 350.563014 -392.717311)
			(xy 350.605062 -392.747861) (xy 350.641813 -392.784612) (xy 350.672363 -392.82666) (xy 350.695959 -392.87297)
			(xy 350.71202 -392.9224) (xy 350.72015 -392.973735) (xy 350.72066 -392.999722) (xy 350.72015 -393.025709)
			(xy 351.25965 -393.025709) (xy 351.25965 -392.973735) (xy 351.26778 -392.9224) (xy 351.283841 -392.87297)
			(xy 351.307437 -392.82666) (xy 351.337987 -392.784612) (xy 351.374738 -392.747861) (xy 351.416786 -392.717311)
			(xy 351.463096 -392.693715) (xy 351.512526 -392.677654) (xy 351.563861 -392.669524) (xy 351.615835 -392.669524)
			(xy 351.66717 -392.677654) (xy 351.7166 -392.693715) (xy 351.76291 -392.717311) (xy 351.804958 -392.747861)
			(xy 351.841709 -392.784612) (xy 351.872259 -392.82666) (xy 351.895855 -392.87297) (xy 351.911916 -392.9224)
			(xy 351.920046 -392.973735) (xy 351.920556 -392.999722) (xy 351.920046 -393.025709) (xy 352.4598 -393.025709)
			(xy 352.4598 -392.973735) (xy 352.46793 -392.9224) (xy 352.483991 -392.87297) (xy 352.507587 -392.82666)
			(xy 352.538137 -392.784612) (xy 352.574888 -392.747861) (xy 352.616936 -392.717311) (xy 352.663246 -392.693715)
			(xy 352.712676 -392.677654) (xy 352.764011 -392.669524) (xy 352.815985 -392.669524) (xy 352.86732 -392.677654)
			(xy 352.91675 -392.693715) (xy 352.96306 -392.717311) (xy 353.005108 -392.747861) (xy 353.041859 -392.784612)
			(xy 353.072409 -392.82666) (xy 353.096005 -392.87297) (xy 353.112066 -392.9224) (xy 353.120196 -392.973735)
			(xy 353.120706 -392.999722) (xy 353.120196 -393.025709) (xy 353.659696 -393.025709) (xy 353.659696 -392.973735)
			(xy 353.667826 -392.9224) (xy 353.683887 -392.87297) (xy 353.707483 -392.82666) (xy 353.738033 -392.784612)
			(xy 353.774784 -392.747861) (xy 353.816832 -392.717311) (xy 353.863142 -392.693715) (xy 353.912572 -392.677654)
			(xy 353.963907 -392.669524) (xy 354.015881 -392.669524) (xy 354.067216 -392.677654) (xy 354.116646 -392.693715)
			(xy 354.162956 -392.717311) (xy 354.205004 -392.747861) (xy 354.241755 -392.784612) (xy 354.272305 -392.82666)
			(xy 354.295901 -392.87297) (xy 354.311962 -392.9224) (xy 354.320092 -392.973735) (xy 354.320602 -392.999722)
			(xy 354.320092 -393.025709) (xy 354.311962 -393.077044) (xy 354.295901 -393.126474) (xy 354.272305 -393.172784)
			(xy 354.241755 -393.214832) (xy 354.205004 -393.251583) (xy 354.162956 -393.282133) (xy 354.116646 -393.305729)
			(xy 354.067216 -393.32179) (xy 354.015881 -393.32992) (xy 353.963907 -393.32992) (xy 353.912572 -393.32179)
			(xy 353.863142 -393.305729) (xy 353.816832 -393.282133) (xy 353.774784 -393.251583) (xy 353.738033 -393.214832)
			(xy 353.707483 -393.172784) (xy 353.683887 -393.126474) (xy 353.667826 -393.077044) (xy 353.659696 -393.025709)
			(xy 353.120196 -393.025709) (xy 353.112066 -393.077044) (xy 353.096005 -393.126474) (xy 353.072409 -393.172784)
			(xy 353.041859 -393.214832) (xy 353.005108 -393.251583) (xy 352.96306 -393.282133) (xy 352.91675 -393.305729)
			(xy 352.86732 -393.32179) (xy 352.815985 -393.32992) (xy 352.764011 -393.32992) (xy 352.712676 -393.32179)
			(xy 352.663246 -393.305729) (xy 352.616936 -393.282133) (xy 352.574888 -393.251583) (xy 352.538137 -393.214832)
			(xy 352.507587 -393.172784) (xy 352.483991 -393.126474) (xy 352.46793 -393.077044) (xy 352.4598 -393.025709)
			(xy 351.920046 -393.025709) (xy 351.911916 -393.077044) (xy 351.895855 -393.126474) (xy 351.872259 -393.172784)
			(xy 351.841709 -393.214832) (xy 351.804958 -393.251583) (xy 351.76291 -393.282133) (xy 351.7166 -393.305729)
			(xy 351.66717 -393.32179) (xy 351.615835 -393.32992) (xy 351.563861 -393.32992) (xy 351.512526 -393.32179)
			(xy 351.463096 -393.305729) (xy 351.416786 -393.282133) (xy 351.374738 -393.251583) (xy 351.337987 -393.214832)
			(xy 351.307437 -393.172784) (xy 351.283841 -393.126474) (xy 351.26778 -393.077044) (xy 351.25965 -393.025709)
			(xy 350.72015 -393.025709) (xy 350.71202 -393.077044) (xy 350.695959 -393.126474) (xy 350.672363 -393.172784)
			(xy 350.641813 -393.214832) (xy 350.605062 -393.251583) (xy 350.563014 -393.282133) (xy 350.516704 -393.305729)
			(xy 350.467274 -393.32179) (xy 350.415939 -393.32992) (xy 350.363965 -393.32992) (xy 350.31263 -393.32179)
			(xy 350.2632 -393.305729) (xy 350.21689 -393.282133) (xy 350.174842 -393.251583) (xy 350.138091 -393.214832)
			(xy 350.107541 -393.172784) (xy 350.083945 -393.126474) (xy 350.067884 -393.077044) (xy 350.059754 -393.025709)
			(xy 349.52 -393.025709) (xy 349.51187 -393.077044) (xy 349.495809 -393.126474) (xy 349.472213 -393.172784)
			(xy 349.441663 -393.214832) (xy 349.404912 -393.251583) (xy 349.362864 -393.282133) (xy 349.316554 -393.305729)
			(xy 349.267124 -393.32179) (xy 349.215789 -393.32992) (xy 349.163815 -393.32992) (xy 349.11248 -393.32179)
			(xy 349.06305 -393.305729) (xy 349.01674 -393.282133) (xy 348.974692 -393.251583) (xy 348.937941 -393.214832)
			(xy 348.907391 -393.172784) (xy 348.883795 -393.126474) (xy 348.867734 -393.077044) (xy 348.859604 -393.025709)
			(xy 348.320104 -393.025709) (xy 348.311974 -393.077044) (xy 348.295913 -393.126474) (xy 348.272317 -393.172784)
			(xy 348.241767 -393.214832) (xy 348.205016 -393.251583) (xy 348.162968 -393.282133) (xy 348.116658 -393.305729)
			(xy 348.067228 -393.32179) (xy 348.015893 -393.32992) (xy 347.963919 -393.32992) (xy 347.912584 -393.32179)
			(xy 347.863154 -393.305729) (xy 347.816844 -393.282133) (xy 347.774796 -393.251583) (xy 347.738045 -393.214832)
			(xy 347.707495 -393.172784) (xy 347.683899 -393.126474) (xy 347.667838 -393.077044) (xy 347.659708 -393.025709)
			(xy 347.120208 -393.025709) (xy 347.112078 -393.077044) (xy 347.096017 -393.126474) (xy 347.072421 -393.172784)
			(xy 347.041871 -393.214832) (xy 347.00512 -393.251583) (xy 346.963072 -393.282133) (xy 346.916762 -393.305729)
			(xy 346.867332 -393.32179) (xy 346.815997 -393.32992) (xy 346.764023 -393.32992) (xy 346.712688 -393.32179)
			(xy 346.663258 -393.305729) (xy 346.616948 -393.282133) (xy 346.5749 -393.251583) (xy 346.538149 -393.214832)
			(xy 346.507599 -393.172784) (xy 346.484003 -393.126474) (xy 346.467942 -393.077044) (xy 346.459812 -393.025709)
			(xy 345.920058 -393.025709) (xy 345.911928 -393.077044) (xy 345.895867 -393.126474) (xy 345.872271 -393.172784)
			(xy 345.841721 -393.214832) (xy 345.80497 -393.251583) (xy 345.762922 -393.282133) (xy 345.716612 -393.305729)
			(xy 345.667182 -393.32179) (xy 345.615847 -393.32992) (xy 345.563873 -393.32992) (xy 345.512538 -393.32179)
			(xy 345.463108 -393.305729) (xy 345.416798 -393.282133) (xy 345.37475 -393.251583) (xy 345.337999 -393.214832)
			(xy 345.307449 -393.172784) (xy 345.283853 -393.126474) (xy 345.267792 -393.077044) (xy 345.259662 -393.025709)
			(xy 344.720162 -393.025709) (xy 344.712032 -393.077044) (xy 344.695971 -393.126474) (xy 344.672375 -393.172784)
			(xy 344.641825 -393.214832) (xy 344.605074 -393.251583) (xy 344.563026 -393.282133) (xy 344.516716 -393.305729)
			(xy 344.467286 -393.32179) (xy 344.415951 -393.32992) (xy 344.363977 -393.32992) (xy 344.312642 -393.32179)
			(xy 344.263212 -393.305729) (xy 344.216902 -393.282133) (xy 344.174854 -393.251583) (xy 344.138103 -393.214832)
			(xy 344.107553 -393.172784) (xy 344.083957 -393.126474) (xy 344.067896 -393.077044) (xy 344.059766 -393.025709)
			(xy 343.520011 -393.025709) (xy 343.511878 -393.077041) (xy 343.495815 -393.12647) (xy 343.472218 -393.172777)
			(xy 343.441668 -393.214823) (xy 343.404917 -393.251573) (xy 343.36287 -393.282122) (xy 343.316562 -393.305718)
			(xy 343.267133 -393.321779) (xy 343.2158 -393.329911) (xy 343.189814 -393.33043) (xy 343.167808 -393.330087)
			(xy 343.12418 -393.324282) (xy 343.08171 -393.312734) (xy 343.06129 -393.304522) (xy 343.047066 -393.298426)
			(xy 343.01684 -393.304268) (xy 342.683338 -393.63777) (xy 342.675801 -393.646046) (xy 342.668101 -393.667035)
			(xy 342.670051 -393.689307) (xy 342.67521 -393.699238) (xy 342.919812 -394.122402) (xy 342.927178 -394.128244)
			(xy 342.945957 -394.144047) (xy 342.979092 -394.180254) (xy 343.006515 -394.220958) (xy 343.027622 -394.265267)
			(xy 343.041952 -394.312209) (xy 343.04919 -394.360752) (xy 343.049606 -394.385292) (xy 343.049352 -394.397484)
			(xy 343.049098 -394.407136) (xy 343.055194 -394.42517) (xy 343.113868 -394.49248) (xy 343.130632 -394.501116)
			(xy 343.140284 -394.502132) (xy 343.167053 -394.505457) (xy 343.219083 -394.519679) (xy 343.268116 -394.542155)
			(xy 343.312852 -394.57229) (xy 343.352106 -394.609284) (xy 343.384837 -394.652157) (xy 343.410177 -394.699773)
			(xy 343.427456 -394.750869) (xy 343.436214 -394.804093) (xy 343.436702 -394.831062) (xy 343.436139 -394.858344)
			(xy 343.427175 -394.912166) (xy 343.4095 -394.963788) (xy 343.383593 -395.011809) (xy 343.350157 -395.054928)
			(xy 343.33053 -395.073886) (xy 343.323082 -395.081378) (xy 343.314543 -395.100673) (xy 343.31402 -395.111224)
			(xy 343.31402 -395.1859) (xy 343.314611 -395.196433) (xy 343.323147 -395.2157) (xy 343.33053 -395.223238)
			(xy 343.350185 -395.242171) (xy 343.383627 -395.285291) (xy 343.409535 -395.333318) (xy 343.427204 -395.384947)
			(xy 343.436155 -395.438777) (xy 343.436702 -395.466062) (xy 343.436269 -395.49018) (xy 343.429273 -395.537905)
			(xy 343.415425 -395.584109) (xy 343.395017 -395.627814) (xy 343.382092 -395.64818) (xy 343.37625 -395.65707)
			(xy 343.372694 -395.677136) (xy 343.393776 -395.769338) (xy 343.405968 -395.786102) (xy 343.414858 -395.791436)
			(xy 343.435658 -395.804292) (xy 343.473572 -395.835172) (xy 343.506519 -395.871303) (xy 343.533779 -395.911897)
			(xy 343.554757 -395.956067) (xy 343.568994 -396.002846) (xy 343.576179 -396.051213) (xy 343.576656 -396.075662)
			(xy 343.576218 -396.100033) (xy 343.569063 -396.148246) (xy 343.554915 -396.194889) (xy 343.534081 -396.238954)
			(xy 343.507011 -396.279487) (xy 343.47429 -396.315613) (xy 343.455752 -396.33144) (xy 343.446862 -396.338552)
			(xy 343.437464 -396.35811) (xy 343.43467 -396.457424) (xy 343.443306 -396.47749) (xy 343.451688 -396.48511)
			(xy 343.469322 -396.501825) (xy 343.499581 -396.539835) (xy 343.523433 -396.582161) (xy 343.540272 -396.627734)
			(xy 343.545414 -396.65148) (xy 343.54897 -396.669514) (xy 343.57691 -396.692628) (xy 344.115136 -396.692628)
		)
		(stroke
			(width 0)
			(type solid)
		)
		(fill yes)
		(layer "In15.Cu")
		(net "P1V8_CPU0_RT1_1A_1D")
	)
	(gr_poly
		(pts
			(xy 106.881168 -115.71224) (xy 106.889864 -115.711879) (xy 106.906251 -115.70605) (xy 106.91975 -115.695083)
			(xy 106.924602 -115.687856) (xy 106.924856 -115.687348) (xy 106.97591 -115.59794) (xy 106.975656 -115.570762)
			(xy 106.968798 -115.558824) (xy 106.949018 -115.524535) (xy 106.914927 -115.453086) (xy 106.887318 -115.378891)
			(xy 106.866409 -115.302537) (xy 106.852365 -115.224628) (xy 106.845298 -115.145778) (xy 106.844846 -115.106196)
			(xy 106.84535 -115.063848) (xy 106.853401 -114.979534) (xy 106.86943 -114.896368) (xy 106.893291 -114.815101)
			(xy 106.92477 -114.736471) (xy 106.963581 -114.66119) (xy 107.009371 -114.589938) (xy 107.061727 -114.523362)
			(xy 107.120175 -114.462064) (xy 107.184185 -114.406599) (xy 107.253177 -114.35747) (xy 107.326527 -114.315121)
			(xy 107.40357 -114.279937) (xy 107.483609 -114.252235) (xy 107.565918 -114.232267) (xy 107.649753 -114.220214)
			(xy 107.734354 -114.216184) (xy 107.818955 -114.220214) (xy 107.90279 -114.232267) (xy 107.985099 -114.252235)
			(xy 108.065138 -114.279937) (xy 108.142181 -114.315121) (xy 108.215531 -114.35747) (xy 108.284523 -114.406599)
			(xy 108.348533 -114.462064) (xy 108.406981 -114.523362) (xy 108.459337 -114.589938) (xy 108.505127 -114.66119)
			(xy 108.543938 -114.736471) (xy 108.575417 -114.815101) (xy 108.599278 -114.896368) (xy 108.615307 -114.979534)
			(xy 108.623358 -115.063848) (xy 108.623862 -115.106196) (xy 108.62342 -115.145779) (xy 108.616365 -115.224632)
			(xy 108.602327 -115.302544) (xy 108.581418 -115.3789) (xy 108.553804 -115.453095) (xy 108.519703 -115.524541)
			(xy 108.49991 -115.558824) (xy 108.493052 -115.570762) (xy 108.492798 -115.59794) (xy 108.543344 -115.686586)
			(xy 108.544106 -115.687856) (xy 108.548932 -115.695101) (xy 108.562439 -115.706062) (xy 108.578841 -115.711854)
			(xy 108.58754 -115.71224) (xy 119.102378 -115.71224) (xy 119.112251 -115.71177) (xy 119.130538 -115.704316)
			(xy 119.137938 -115.697762) (xy 119.138192 -115.697508) (xy 126.538228 -108.297472) (xy 126.543566 -108.291768)
			(xy 126.550798 -108.27793) (xy 126.552452 -108.270294) (xy 126.682246 -107.54233) (xy 126.683699 -107.531476)
			(xy 126.678291 -107.51028) (xy 126.671832 -107.501436) (xy 126.616714 -107.43311) (xy 126.59741 -107.423204)
			(xy 126.586234 -107.42295) (xy 126.543628 -107.420881) (xy 126.459071 -107.409601) (xy 126.375983 -107.390276)
			(xy 126.295126 -107.363086) (xy 126.217245 -107.328279) (xy 126.143053 -107.286175) (xy 126.073233 -107.237161)
			(xy 126.008427 -107.181688) (xy 125.94923 -107.120265) (xy 125.896186 -107.053456) (xy 125.849781 -106.981876)
			(xy 125.810443 -106.906181) (xy 125.778533 -106.827068) (xy 125.754344 -106.745263) (xy 125.738099 -106.661519)
			(xy 125.729945 -106.576603) (xy 125.729492 -106.53395) (xy 125.729969 -106.492849) (xy 125.737558 -106.410998)
			(xy 125.752666 -106.330196) (xy 125.775166 -106.251133) (xy 125.804864 -106.174484) (xy 125.841507 -106.100901)
			(xy 125.884784 -106.031013) (xy 125.934324 -105.965416) (xy 125.989705 -105.904669) (xy 126.050454 -105.849292)
			(xy 126.116054 -105.799755) (xy 126.185944 -105.756483) (xy 126.259529 -105.719844) (xy 126.336181 -105.69015)
			(xy 126.415245 -105.667655) (xy 126.496048 -105.652551) (xy 126.577899 -105.644967) (xy 126.619 -105.644442)
			(xy 126.665893 -105.645058) (xy 126.759155 -105.654952) (xy 126.850857 -105.674608) (xy 126.895606 -105.688638)
			(xy 126.906274 -105.69194) (xy 126.927864 -105.689654) (xy 127.003302 -105.644442) (xy 127.012384 -105.638423)
			(xy 127.024763 -105.620521) (xy 127.027178 -105.609898) (xy 127.45212 -103.228394) (xy 127.45212 -69.708522)
			(xy 127.451683 -69.698458) (xy 127.443951 -69.679872) (xy 127.437134 -69.672454) (xy 126.204726 -68.440046)
			(xy 126.197614 -68.43268) (xy 126.178818 -68.42506) (xy 124.834396 -68.42506) (xy 124.823377 -68.4256)
			(xy 124.803358 -68.434815) (xy 124.795788 -68.44284) (xy 124.738384 -68.51015) (xy 124.732288 -68.531486)
			(xy 124.734066 -68.542662) (xy 124.739047 -68.576225) (xy 124.74451 -68.643863) (xy 124.744988 -68.67779)
			(xy 124.744988 -68.683632) (xy 124.744422 -68.724673) (xy 124.736673 -68.806392) (xy 124.721427 -68.887049)
			(xy 124.698814 -68.965958) (xy 124.669028 -69.042448) (xy 124.63232 -69.115868) (xy 124.589004 -69.185594)
			(xy 124.539449 -69.251032) (xy 124.484074 -69.311626) (xy 124.423353 -69.36686) (xy 124.3578 -69.416265)
			(xy 124.287975 -69.45942) (xy 124.21447 -69.495958) (xy 124.137911 -69.525568) (xy 124.05895 -69.547998)
			(xy 123.978259 -69.563058) (xy 123.896523 -69.570619) (xy 123.85548 -69.571108) (xy 123.814519 -69.570639)
			(xy 123.732943 -69.563105) (xy 123.652405 -69.548103) (xy 123.573588 -69.525759) (xy 123.49716 -69.496264)
			(xy 123.423766 -69.459866) (xy 123.35403 -69.416875) (xy 123.288543 -69.367654) (xy 123.227858 -69.31262)
			(xy 123.17249 -69.25224) (xy 123.122908 -69.187026) (xy 123.079531 -69.117528) (xy 123.060714 -69.081142)
			(xy 123.056364 -69.073257) (xy 123.043237 -69.060949) (xy 123.026663 -69.053939) (xy 123.008687 -69.053091)
			(xy 123.000008 -69.055488) (xy 122.972028 -69.063758) (xy 122.914371 -69.072689) (xy 122.8852 -69.073268)
			(xy 122.884946 -69.073268) (xy 122.855636 -69.072692) (xy 122.797719 -69.063629) (xy 122.76963 -69.055234)
			(xy 122.766074 -69.054218) (xy 122.757184 -69.052694) (xy 122.750427 -69.051847) (xy 122.736903 -69.053387)
			(xy 122.730514 -69.055742) (xy 122.71248 -69.0626) (xy 122.708173 -69.064433) (xy 122.700254 -69.069422)
			(xy 122.696732 -69.072506) (xy 122.677174 -69.090286) (xy 122.67311 -69.097906) (xy 122.652134 -69.136395)
			(xy 122.603689 -69.209454) (xy 122.548291 -69.277393) (xy 122.486478 -69.339552) (xy 122.41885 -69.395329)
			(xy 122.346063 -69.444181) (xy 122.268822 -69.485635) (xy 122.187878 -69.51929) (xy 122.104016 -69.544817)
			(xy 122.018048 -69.561971) (xy 121.930811 -69.570583) (xy 121.88698 -69.571108) (xy 121.845938 -69.570635)
			(xy 121.764203 -69.563071) (xy 121.683512 -69.548008) (xy 121.604553 -69.525575) (xy 121.527996 -69.495962)
			(xy 121.454493 -69.459422) (xy 121.384669 -69.416266) (xy 121.319119 -69.36686) (xy 121.258399 -69.311624)
			(xy 121.203027 -69.25103) (xy 121.153472 -69.185591) (xy 121.110158 -69.115865) (xy 121.073452 -69.042445)
			(xy 121.043666 -68.965955) (xy 121.021055 -68.887047) (xy 121.005809 -68.806391) (xy 120.99806 -68.724673)
			(xy 120.997472 -68.683632) (xy 120.997472 -68.681346) (xy 120.997821 -68.646528) (xy 121.00329 -68.577106)
			(xy 121.008394 -68.542662) (xy 121.010172 -68.531486) (xy 121.004076 -68.51015) (xy 120.946672 -68.44284)
			(xy 120.939095 -68.434828) (xy 120.919079 -68.425631) (xy 120.908064 -68.42506) (xy 108.044742 -68.42506)
			(xy 108.034678 -68.425495) (xy 108.016094 -68.433231) (xy 108.008674 -68.440046) (xy 106.366267 -70.082453)
			(xy 112.861477 -70.082453) (xy 112.866739 -69.998767) (xy 112.879853 -69.915946) (xy 112.900703 -69.834728)
			(xy 112.929104 -69.755832) (xy 112.964803 -69.679959) (xy 113.007485 -69.607782) (xy 113.056769 -69.539942)
			(xy 113.112219 -69.477041) (xy 113.173342 -69.419638) (xy 113.239596 -69.368242) (xy 113.310393 -69.323308)
			(xy 113.385104 -69.285237) (xy 113.463066 -69.254366) (xy 113.543588 -69.230968) (xy 113.625954 -69.215252)
			(xy 113.709434 -69.207357) (xy 113.75136 -69.206872) (xy 113.794865 -69.207409) (xy 113.881461 -69.215899)
			(xy 113.966814 -69.232802) (xy 114.050109 -69.257957) (xy 114.130551 -69.291122) (xy 114.207371 -69.331983)
			(xy 114.279836 -69.380147) (xy 114.347252 -69.435155) (xy 114.378486 -69.465444) (xy 114.388937 -69.475104)
			(xy 114.413888 -69.488766) (xy 114.441639 -69.495018) (xy 114.470038 -69.493376) (xy 114.496883 -69.483968)
			(xy 114.520094 -69.467522) (xy 114.537869 -69.445313) (xy 114.548833 -69.419064) (xy 114.550952 -69.404992)
			(xy 114.554648 -69.377448) (xy 114.568945 -69.323747) (xy 114.590884 -69.272689) (xy 114.619999 -69.225356)
			(xy 114.655675 -69.182748) (xy 114.697157 -69.145768) (xy 114.743565 -69.115199) (xy 114.793918 -69.091689)
			(xy 114.84715 -69.075734) (xy 114.902134 -69.067673) (xy 114.92992 -69.067172) (xy 114.957169 -69.0677)
			(xy 115.011112 -69.075458) (xy 115.063401 -69.090814) (xy 115.112973 -69.113455) (xy 115.158819 -69.14292)
			(xy 115.200004 -69.17861) (xy 115.235692 -69.219797) (xy 115.265154 -69.265644) (xy 115.287793 -69.315218)
			(xy 115.303146 -69.367508) (xy 115.310902 -69.421451) (xy 115.310902 -69.475949) (xy 115.303146 -69.529892)
			(xy 115.287793 -69.582182) (xy 115.265154 -69.631756) (xy 115.235692 -69.677603) (xy 115.200004 -69.71879)
			(xy 115.158819 -69.75448) (xy 115.112973 -69.783945) (xy 115.063401 -69.806586) (xy 115.011112 -69.821942)
			(xy 114.957169 -69.8297) (xy 114.92992 -69.830188) (xy 114.901216 -69.829685) (xy 114.844454 -69.8211)
			(xy 114.789615 -69.80412) (xy 114.76355 -69.792088) (xy 114.750505 -69.786354) (xy 114.722444 -69.781486)
			(xy 114.69413 -69.784561) (xy 114.667768 -69.79534) (xy 114.645411 -69.812983) (xy 114.6288 -69.836117)
			(xy 114.619227 -69.86294) (xy 114.617438 -69.891364) (xy 114.62004 -69.905372) (xy 114.629797 -69.952519)
			(xy 114.640231 -70.048238) (xy 114.640868 -70.09638) (xy 114.640445 -70.138306) (xy 114.632556 -70.221786)
			(xy 114.616846 -70.304154) (xy 114.593454 -70.384677) (xy 114.562588 -70.462641) (xy 114.524521 -70.537355)
			(xy 114.479593 -70.608155) (xy 114.428201 -70.674412) (xy 114.370802 -70.735539) (xy 114.307905 -70.790994)
			(xy 114.240068 -70.840282) (xy 114.167894 -70.882969) (xy 114.092024 -70.918673) (xy 114.01313 -70.947079)
			(xy 113.931913 -70.967935) (xy 113.849093 -70.981055) (xy 113.765407 -70.986322) (xy 113.681596 -70.983691)
			(xy 113.598405 -70.973184) (xy 113.516571 -70.954895) (xy 113.436822 -70.928986) (xy 113.359866 -70.895686)
			(xy 113.286384 -70.855293) (xy 113.21703 -70.808163) (xy 113.152419 -70.754716) (xy 113.093125 -70.695425)
			(xy 113.039673 -70.630818) (xy 112.992539 -70.561467) (xy 112.95214 -70.487988) (xy 112.918836 -70.411034)
			(xy 112.892921 -70.331287) (xy 112.874626 -70.249455) (xy 112.864114 -70.166264) (xy 112.861477 -70.082453)
			(xy 106.366267 -70.082453) (xy 104.485948 -71.962772) (xy 113.62639 -71.962772) (xy 113.630461 -71.90715)
			(xy 113.642587 -71.852713) (xy 113.66251 -71.800622) (xy 113.689806 -71.751987) (xy 113.723892 -71.707844)
			(xy 113.764041 -71.669135) (xy 113.809399 -71.636684) (xy 113.858999 -71.611183) (xy 113.911783 -71.593176)
			(xy 113.966626 -71.583046) (xy 114.02236 -71.581009) (xy 114.077797 -71.587109) (xy 114.131754 -71.601215)
			(xy 114.183083 -71.623027) (xy 114.230689 -71.652081) (xy 114.273557 -71.687756) (xy 114.310774 -71.729293)
			(xy 114.341547 -71.775806) (xy 114.365219 -71.826303) (xy 114.37742 -71.866856) (xy 117.906437 -71.866856)
			(xy 117.906437 -71.812344) (xy 117.914196 -71.758386) (xy 117.929555 -71.706082) (xy 117.952202 -71.656497)
			(xy 117.981675 -71.610639) (xy 118.017376 -71.569443) (xy 118.058576 -71.533748) (xy 118.104437 -71.50428)
			(xy 118.154025 -71.481639) (xy 118.206331 -71.466286) (xy 118.26029 -71.458534) (xy 118.287546 -71.458074)
			(xy 118.314692 -71.458614) (xy 118.368436 -71.466304) (xy 118.420547 -71.481537) (xy 118.469971 -71.504004)
			(xy 118.515711 -71.533251) (xy 118.556842 -71.568689) (xy 118.592533 -71.6096) (xy 118.622063 -71.655158)
			(xy 118.644835 -71.704443) (xy 118.660389 -71.756458) (xy 118.668411 -71.810154) (xy 118.669054 -71.837296)
			(xy 118.669054 -71.852536) (xy 118.685564 -71.877428) (xy 118.798848 -71.926704) (xy 118.828058 -71.921878)
			(xy 118.839488 -71.911464) (xy 118.870218 -71.883781) (xy 118.936023 -71.833664) (xy 119.006197 -71.789874)
			(xy 119.080134 -71.75279) (xy 119.157195 -71.72273) (xy 119.236714 -71.699956) (xy 119.318005 -71.684663)
			(xy 119.400364 -71.676985) (xy 119.441722 -71.676514) (xy 119.482825 -71.676946) (xy 119.564682 -71.684533)
			(xy 119.645489 -71.69964) (xy 119.724557 -71.722139) (xy 119.801212 -71.751838) (xy 119.8748 -71.788482)
			(xy 119.944692 -71.831761) (xy 120.010294 -71.881303) (xy 120.071044 -71.936687) (xy 120.126425 -71.99744)
			(xy 120.175964 -72.063044) (xy 120.219239 -72.132939) (xy 120.25588 -72.206528) (xy 120.285575 -72.283185)
			(xy 120.30807 -72.362254) (xy 120.323173 -72.443062) (xy 120.330756 -72.524918) (xy 120.33123 -72.566022)
			(xy 120.330715 -72.608489) (xy 120.322618 -72.693035) (xy 120.3065 -72.776425) (xy 120.282508 -72.857899)
			(xy 120.25086 -72.936715) (xy 120.211843 -73.012157) (xy 120.189244 -73.048114) (xy 120.180354 -73.062084)
			(xy 120.181878 -73.094088) (xy 120.261634 -73.195434) (xy 120.292622 -73.204578) (xy 120.308116 -73.199244)
			(xy 120.3435 -73.187295) (xy 120.415827 -73.168653) (xy 120.489462 -73.156143) (xy 120.563887 -73.149855)
			(xy 120.601232 -73.14946) (xy 120.643156 -73.150009) (xy 120.726631 -73.157903) (xy 120.808993 -73.173617)
			(xy 120.88951 -73.197013) (xy 120.967469 -73.227882) (xy 121.042176 -73.265951) (xy 121.11297 -73.310881)
			(xy 121.17922 -73.362274) (xy 121.240341 -73.419674) (xy 121.295788 -73.482571) (xy 121.34507 -73.550407)
			(xy 121.387749 -73.62258) (xy 121.423447 -73.698449) (xy 121.451847 -73.77734) (xy 121.472696 -73.858555)
			(xy 121.4824 -73.919842) (xy 121.620534 -73.919842) (xy 121.621103 -73.891532) (xy 121.629472 -73.835535)
			(xy 121.64602 -73.781388) (xy 121.670382 -73.730278) (xy 121.702025 -73.683326) (xy 121.740255 -73.641562)
			(xy 121.784233 -73.605901) (xy 121.832995 -73.577126) (xy 121.85904 -73.56602) (xy 121.866803 -73.562622)
			(xy 121.87965 -73.551588) (xy 121.884186 -73.54443) (xy 121.908381 -73.503671) (xy 121.964154 -73.427026)
			(xy 122.027767 -73.356752) (xy 122.098496 -73.293645) (xy 122.136662 -73.265538) (xy 122.14479 -73.259442)
			(xy 122.155458 -73.242678) (xy 122.170952 -73.152508) (xy 122.166634 -73.133204) (xy 122.160792 -73.124822)
			(xy 122.135538 -73.087494) (xy 122.091829 -73.008674) (xy 122.056311 -72.925839) (xy 122.029348 -72.839839)
			(xy 122.011217 -72.751553) (xy 122.002104 -72.661886) (xy 122.001534 -72.616822) (xy 122.002038 -72.574474)
			(xy 122.010089 -72.49016) (xy 122.026118 -72.406994) (xy 122.049979 -72.325727) (xy 122.081458 -72.247097)
			(xy 122.120269 -72.171816) (xy 122.166059 -72.100564) (xy 122.218415 -72.033988) (xy 122.276863 -71.97269)
			(xy 122.340873 -71.917225) (xy 122.409865 -71.868096) (xy 122.483215 -71.825747) (xy 122.560258 -71.790563)
			(xy 122.640297 -71.762861) (xy 122.722606 -71.742893) (xy 122.806441 -71.73084) (xy 122.891042 -71.72681)
			(xy 122.975643 -71.73084) (xy 123.059478 -71.742893) (xy 123.141787 -71.762861) (xy 123.221826 -71.790563)
			(xy 123.298869 -71.825747) (xy 123.372219 -71.868096) (xy 123.441211 -71.917225) (xy 123.505221 -71.97269)
			(xy 123.563669 -72.033988) (xy 123.616025 -72.100564) (xy 123.661815 -72.171816) (xy 123.700626 -72.247097)
			(xy 123.732105 -72.325727) (xy 123.755966 -72.406994) (xy 123.771995 -72.49016) (xy 123.780046 -72.574474)
			(xy 123.78055 -72.616822) (xy 123.780134 -72.655042) (xy 123.773572 -72.7312) (xy 123.76049 -72.806513)
			(xy 123.740985 -72.880423) (xy 123.72848 -72.916542) (xy 123.725634 -72.925866) (xy 123.726409 -72.945327)
			(xy 123.730004 -72.954388) (xy 123.74245 -72.982328) (xy 123.746833 -72.99099) (xy 123.760804 -73.004445)
			(xy 123.769628 -73.00849) (xy 123.810113 -73.02549) (xy 123.887784 -73.066457) (xy 123.961042 -73.114877)
			(xy 124.029174 -73.170278) (xy 124.091517 -73.232121) (xy 124.147464 -73.299805) (xy 124.196471 -73.372672)
			(xy 124.238061 -73.450011) (xy 124.27183 -73.531072) (xy 124.29745 -73.615065) (xy 124.31467 -73.701173)
			(xy 124.323325 -73.788559) (xy 124.323856 -73.832466) (xy 124.323301 -73.873567) (xy 124.31572 -73.955417)
			(xy 124.300618 -74.036219) (xy 124.278126 -74.115283) (xy 124.248435 -74.191935) (xy 124.211798 -74.265519)
			(xy 124.168528 -74.33541) (xy 124.118994 -74.40101) (xy 124.063618 -74.46176) (xy 124.002873 -74.517141)
			(xy 123.937278 -74.566682) (xy 123.867391 -74.609958) (xy 123.79381 -74.646602) (xy 123.717161 -74.6763)
			(xy 123.638099 -74.6988) (xy 123.557298 -74.713908) (xy 123.475448 -74.721497) (xy 123.434348 -74.721974)
			(xy 123.39891 -74.721613) (xy 123.328262 -74.715934) (xy 123.25829 -74.704649) (xy 123.223782 -74.696574)
			(xy 123.212796 -74.69454) (xy 123.190931 -74.699034) (xy 123.181618 -74.70521) (xy 123.148887 -74.728685)
			(xy 123.079927 -74.770318) (xy 123.007486 -74.805545) (xy 122.932157 -74.834081) (xy 122.854557 -74.85569)
			(xy 122.775321 -74.870195) (xy 122.695098 -74.877479) (xy 122.654822 -74.87793) (xy 122.611789 -74.877384)
			(xy 122.526126 -74.869058) (xy 122.441667 -74.8525) (xy 122.359201 -74.827865) (xy 122.279498 -74.795384)
			(xy 122.203304 -74.75536) (xy 122.13133 -74.708167) (xy 122.064248 -74.654245) (xy 122.002685 -74.594099)
			(xy 121.947217 -74.528291) (xy 121.898361 -74.457435) (xy 121.856574 -74.382193) (xy 121.822247 -74.303268)
			(xy 121.808494 -74.262488) (xy 121.80556 -74.254582) (xy 121.795453 -74.241098) (xy 121.788682 -74.236072)
			(xy 121.76683 -74.220822) (xy 121.727229 -74.185168) (xy 121.692976 -74.144349) (xy 121.664738 -74.099159)
			(xy 121.643067 -74.050478) (xy 121.628383 -73.999255) (xy 121.620974 -73.946485) (xy 121.620534 -73.919842)
			(xy 121.4824 -73.919842) (xy 121.485809 -73.94137) (xy 121.491071 -74.025053) (xy 121.488434 -74.108859)
			(xy 121.477923 -74.192045) (xy 121.459629 -74.273873) (xy 121.433716 -74.353616) (xy 121.400413 -74.430566)
			(xy 121.360016 -74.504041) (xy 121.312885 -74.573388) (xy 121.259436 -74.637992) (xy 121.200144 -74.697279)
			(xy 121.135537 -74.750723) (xy 121.066186 -74.79785) (xy 120.992709 -74.838241) (xy 120.915756 -74.871538)
			(xy 120.836011 -74.897446) (xy 120.754182 -74.915734) (xy 120.670995 -74.926239) (xy 120.587189 -74.92887)
			(xy 120.503507 -74.923602) (xy 120.420692 -74.910483) (xy 120.339479 -74.889628) (xy 120.26059 -74.861223)
			(xy 120.184723 -74.825519) (xy 120.112554 -74.782835) (xy 120.044721 -74.733548) (xy 119.981828 -74.678096)
			(xy 119.924433 -74.616972) (xy 119.873044 -74.550717) (xy 119.828119 -74.479921) (xy 119.790056 -74.405211)
			(xy 119.759192 -74.32725) (xy 119.735802 -74.246731) (xy 119.720094 -74.164368) (xy 119.712206 -74.080892)
			(xy 119.711724 -74.038968) (xy 119.712241 -73.996502) (xy 119.720339 -73.911955) (xy 119.736457 -73.828566)
			(xy 119.760449 -73.747092) (xy 119.792096 -73.668275) (xy 119.831111 -73.592834) (xy 119.85371 -73.556876)
			(xy 119.8626 -73.542906) (xy 119.861076 -73.510902) (xy 119.78132 -73.409556) (xy 119.750332 -73.400412)
			(xy 119.734838 -73.405746) (xy 119.699458 -73.417707) (xy 119.62713 -73.436347) (xy 119.553493 -73.448853)
			(xy 119.479067 -73.455137) (xy 119.441722 -73.45553) (xy 119.400621 -73.455012) (xy 119.318768 -73.44743)
			(xy 119.237964 -73.432327) (xy 119.158899 -73.409833) (xy 119.082246 -73.38014) (xy 119.00866 -73.343501)
			(xy 118.938769 -73.300228) (xy 118.873168 -73.250691) (xy 118.812418 -73.195313) (xy 118.757037 -73.134566)
			(xy 118.707497 -73.068968) (xy 118.664221 -72.999078) (xy 118.627578 -72.925494) (xy 118.597881 -72.848843)
			(xy 118.575383 -72.769778) (xy 118.560276 -72.688976) (xy 118.55269 -72.607123) (xy 118.552214 -72.566022)
			(xy 118.552763 -72.522063) (xy 118.56145 -72.434576) (xy 118.578732 -72.348374) (xy 118.591076 -72.30618)
			(xy 118.595394 -72.291448) (xy 118.587266 -72.262746) (xy 118.493794 -72.181974) (xy 118.46433 -72.17791)
			(xy 118.450614 -72.184514) (xy 118.424992 -72.196048) (xy 118.37122 -72.212347) (xy 118.31564 -72.220589)
			(xy 118.287546 -72.22109) (xy 118.26029 -72.220666) (xy 118.206331 -72.212914) (xy 118.154025 -72.197561)
			(xy 118.104437 -72.17492) (xy 118.058576 -72.145452) (xy 118.017376 -72.109757) (xy 117.981675 -72.068561)
			(xy 117.952202 -72.022703) (xy 117.929555 -71.973118) (xy 117.914196 -71.920814) (xy 117.906437 -71.866856)
			(xy 114.37742 -71.866856) (xy 114.381287 -71.87971) (xy 114.389407 -71.934886) (xy 114.389916 -71.962772)
			(xy 114.389407 -71.990658) (xy 114.381287 -72.045834) (xy 114.365219 -72.099241) (xy 114.341547 -72.149738)
			(xy 114.310774 -72.196251) (xy 114.273557 -72.237788) (xy 114.230689 -72.273463) (xy 114.183083 -72.302517)
			(xy 114.131754 -72.324329) (xy 114.077797 -72.338435) (xy 114.02236 -72.344535) (xy 113.966626 -72.342498)
			(xy 113.911783 -72.332368) (xy 113.858999 -72.314361) (xy 113.809399 -72.28886) (xy 113.764041 -72.256409)
			(xy 113.723892 -72.2177) (xy 113.689806 -72.173557) (xy 113.66251 -72.124922) (xy 113.642587 -72.072831)
			(xy 113.630461 -72.018394) (xy 113.62639 -71.962772) (xy 104.485948 -71.962772) (xy 99.190372 -77.258348)
			(xy 103.250996 -77.258348) (xy 103.250996 -77.173652) (xy 103.259047 -77.089338) (xy 103.275076 -77.006172)
			(xy 103.298937 -76.924905) (xy 103.330416 -76.846275) (xy 103.369227 -76.770994) (xy 103.415017 -76.699742)
			(xy 103.467373 -76.633166) (xy 103.525821 -76.571868) (xy 103.589831 -76.516403) (xy 103.658823 -76.467274)
			(xy 103.732173 -76.424925) (xy 103.809216 -76.389741) (xy 103.889255 -76.362039) (xy 103.971564 -76.342071)
			(xy 104.055399 -76.330018) (xy 104.14 -76.325988) (xy 104.224601 -76.330018) (xy 104.308436 -76.342071)
			(xy 104.390745 -76.362039) (xy 104.470784 -76.389741) (xy 104.547827 -76.424925) (xy 104.621177 -76.467274)
			(xy 104.690169 -76.516403) (xy 104.754179 -76.571868) (xy 104.812627 -76.633166) (xy 104.864983 -76.699742)
			(xy 104.910773 -76.770994) (xy 104.949584 -76.846275) (xy 104.981063 -76.924905) (xy 105.004924 -77.006172)
			(xy 105.020953 -77.089338) (xy 105.029004 -77.173652) (xy 105.029508 -77.216) (xy 105.029004 -77.258348)
			(xy 105.020953 -77.342662) (xy 105.004924 -77.425828) (xy 104.981063 -77.507095) (xy 104.949584 -77.585725)
			(xy 104.910773 -77.661006) (xy 104.864983 -77.732258) (xy 104.812627 -77.798834) (xy 104.754179 -77.860132)
			(xy 104.690169 -77.915597) (xy 104.621177 -77.964726) (xy 104.547827 -78.007075) (xy 104.470784 -78.042259)
			(xy 104.390745 -78.069961) (xy 104.308436 -78.089929) (xy 104.224601 -78.101982) (xy 104.14 -78.106013)
			(xy 104.055399 -78.101982) (xy 103.971564 -78.089929) (xy 103.889255 -78.069961) (xy 103.809216 -78.042259)
			(xy 103.732173 -78.007075) (xy 103.658823 -77.964726) (xy 103.589831 -77.915597) (xy 103.525821 -77.860132)
			(xy 103.467373 -77.798834) (xy 103.415017 -77.732258) (xy 103.369227 -77.661006) (xy 103.330416 -77.585725)
			(xy 103.298937 -77.507095) (xy 103.275076 -77.425828) (xy 103.259047 -77.342662) (xy 103.250996 -77.258348)
			(xy 99.190372 -77.258348) (xy 98.174372 -78.274348) (xy 105.693714 -78.274348) (xy 105.693714 -78.189652)
			(xy 105.701765 -78.105338) (xy 105.717794 -78.022172) (xy 105.741655 -77.940905) (xy 105.773134 -77.862275)
			(xy 105.811945 -77.786994) (xy 105.857735 -77.715742) (xy 105.910091 -77.649166) (xy 105.968539 -77.587868)
			(xy 106.032549 -77.532403) (xy 106.101541 -77.483274) (xy 106.174891 -77.440925) (xy 106.251934 -77.405741)
			(xy 106.331973 -77.378039) (xy 106.414282 -77.358071) (xy 106.498117 -77.346018) (xy 106.582718 -77.341988)
			(xy 106.667319 -77.346018) (xy 106.751154 -77.358071) (xy 106.833463 -77.378039) (xy 106.913502 -77.405741)
			(xy 106.990545 -77.440925) (xy 107.063895 -77.483274) (xy 107.132887 -77.532403) (xy 107.196897 -77.587868)
			(xy 107.255345 -77.649166) (xy 107.307701 -77.715742) (xy 107.353491 -77.786994) (xy 107.392302 -77.862275)
			(xy 107.423781 -77.940905) (xy 107.447642 -78.022172) (xy 107.463671 -78.105338) (xy 107.471722 -78.189652)
			(xy 107.472226 -78.232) (xy 107.471722 -78.274348) (xy 107.463671 -78.358662) (xy 107.447642 -78.441828)
			(xy 107.423781 -78.523095) (xy 107.392302 -78.601725) (xy 107.353491 -78.677006) (xy 107.307701 -78.748258)
			(xy 107.255345 -78.814834) (xy 107.196897 -78.876132) (xy 107.132887 -78.931597) (xy 107.063895 -78.980726)
			(xy 106.990545 -79.023075) (xy 106.913502 -79.058259) (xy 106.833463 -79.085961) (xy 106.751154 -79.105929)
			(xy 106.667319 -79.117982) (xy 106.582718 -79.122013) (xy 106.498117 -79.117982) (xy 106.414282 -79.105929)
			(xy 106.331973 -79.085961) (xy 106.251934 -79.058259) (xy 106.174891 -79.023075) (xy 106.101541 -78.980726)
			(xy 106.032549 -78.931597) (xy 105.968539 -78.876132) (xy 105.910091 -78.814834) (xy 105.857735 -78.748258)
			(xy 105.811945 -78.677006) (xy 105.773134 -78.601725) (xy 105.741655 -78.523095) (xy 105.717794 -78.441828)
			(xy 105.701765 -78.358662) (xy 105.693714 -78.274348) (xy 98.174372 -78.274348) (xy 98.046286 -78.402434)
			(xy 98.03889 -78.409285) (xy 98.020291 -78.417025) (xy 98.010218 -78.41742) (xy 88.009222 -78.41742)
			(xy 87.999159 -78.417858) (xy 87.980577 -78.425594) (xy 87.973154 -78.432406) (xy 85.60181 -80.80375)
			(xy 99.453954 -80.80375) (xy 99.454406 -80.761051) (xy 99.462585 -80.676047) (xy 99.478874 -80.592217)
			(xy 99.503122 -80.510335) (xy 99.535106 -80.431154) (xy 99.574532 -80.355402) (xy 99.621036 -80.283777)
			(xy 99.67419 -80.21694) (xy 99.733506 -80.155504) (xy 99.798436 -80.100035) (xy 99.868384 -80.051045)
			(xy 99.942704 -80.008985) (xy 100.020714 -79.97424) (xy 100.101695 -79.947132) (xy 100.1849 -79.92791)
			(xy 100.269565 -79.916751) (xy 100.31222 -79.91475) (xy 100.322993 -79.913854) (xy 100.342337 -79.904252)
			(xy 100.349558 -79.896208) (xy 100.367784 -79.874864) (xy 100.40942 -79.83723) (xy 100.456125 -79.806108)
			(xy 100.506888 -79.782169) (xy 100.560611 -79.765932) (xy 100.616136 -79.757746) (xy 100.644198 -79.75727)
			(xy 100.671448 -79.75778) (xy 100.725394 -79.765535) (xy 100.777687 -79.780889) (xy 100.827263 -79.803528)
			(xy 100.873112 -79.832992) (xy 100.914302 -79.868681) (xy 100.949993 -79.909869) (xy 100.97946 -79.955716)
			(xy 101.002103 -80.005291) (xy 101.01746 -80.057583) (xy 101.025219 -80.111528) (xy 101.025706 -80.138778)
			(xy 101.025566 -80.154084) (xy 101.023153 -80.184601) (xy 101.02088 -80.199738) (xy 101.019567 -80.210491)
			(xy 101.025105 -80.231415) (xy 101.031548 -80.240124) (xy 101.058766 -80.274205) (xy 101.080767 -80.30718)
			(xy 111.205772 -80.30718) (xy 111.206385 -80.260785) (xy 111.216021 -80.168498) (xy 111.235209 -80.077714)
			(xy 111.263738 -79.98942) (xy 111.281972 -79.946754) (xy 111.285801 -79.936817) (xy 111.285793 -79.915547)
			(xy 111.281972 -79.905606) (xy 111.263719 -79.862947) (xy 111.235178 -79.774653) (xy 111.215987 -79.683867)
			(xy 111.206356 -79.591576) (xy 111.205772 -79.54518) (xy 111.206286 -79.501835) (xy 111.214733 -79.415557)
			(xy 111.231535 -79.33051) (xy 111.256533 -79.247502) (xy 111.289488 -79.167319) (xy 111.33009 -79.090725)
			(xy 111.377952 -79.018444) (xy 111.432619 -78.951163) (xy 111.493574 -78.889521) (xy 111.526574 -78.861412)
			(xy 111.53521 -78.854046) (xy 111.544862 -78.833726) (xy 111.544862 -78.732634) (xy 111.53521 -78.712314)
			(xy 111.526574 -78.704948) (xy 111.493575 -78.67684) (xy 111.432634 -78.615189) (xy 111.377977 -78.547903)
			(xy 111.330124 -78.47562) (xy 111.289527 -78.399025) (xy 111.256572 -78.318845) (xy 111.231572 -78.235841)
			(xy 111.214763 -78.150798) (xy 111.206305 -78.064524) (xy 111.205772 -78.02118) (xy 111.206286 -77.977835)
			(xy 111.214733 -77.891557) (xy 111.231535 -77.80651) (xy 111.256533 -77.723502) (xy 111.289488 -77.643319)
			(xy 111.33009 -77.566725) (xy 111.377952 -77.494444) (xy 111.432619 -77.427163) (xy 111.493574 -77.365521)
			(xy 111.526574 -77.337412) (xy 111.53521 -77.330046) (xy 111.544862 -77.309726) (xy 111.544862 -77.208634)
			(xy 111.53521 -77.188314) (xy 111.526574 -77.180948) (xy 111.493575 -77.15284) (xy 111.432634 -77.091189)
			(xy 111.377977 -77.023903) (xy 111.330124 -76.95162) (xy 111.289527 -76.875025) (xy 111.256572 -76.794845)
			(xy 111.231572 -76.711841) (xy 111.214763 -76.626798) (xy 111.206305 -76.540524) (xy 111.205772 -76.49718)
			(xy 111.206286 -76.453835) (xy 111.214733 -76.367557) (xy 111.231535 -76.28251) (xy 111.256533 -76.199502)
			(xy 111.289488 -76.119319) (xy 111.33009 -76.042725) (xy 111.377952 -75.970444) (xy 111.432619 -75.903163)
			(xy 111.493574 -75.841521) (xy 111.526574 -75.813412) (xy 111.53521 -75.806046) (xy 111.544862 -75.785726)
			(xy 111.544862 -75.684634) (xy 111.53521 -75.664314) (xy 111.526574 -75.656948) (xy 111.493575 -75.62884)
			(xy 111.432634 -75.567189) (xy 111.377977 -75.499903) (xy 111.330124 -75.42762) (xy 111.289527 -75.351025)
			(xy 111.256572 -75.270845) (xy 111.231572 -75.187841) (xy 111.214763 -75.102798) (xy 111.206305 -75.016524)
			(xy 111.205772 -74.97318) (xy 111.206276 -74.930832) (xy 111.214327 -74.846518) (xy 111.230356 -74.763352)
			(xy 111.254217 -74.682085) (xy 111.285696 -74.603455) (xy 111.324507 -74.528174) (xy 111.370297 -74.456922)
			(xy 111.422653 -74.390346) (xy 111.481101 -74.329048) (xy 111.545111 -74.273583) (xy 111.614103 -74.224454)
			(xy 111.687453 -74.182105) (xy 111.764496 -74.146921) (xy 111.844535 -74.119219) (xy 111.926844 -74.099251)
			(xy 112.010679 -74.087198) (xy 112.09528 -74.083168) (xy 112.179881 -74.087198) (xy 112.263716 -74.099251)
			(xy 112.346025 -74.119219) (xy 112.426064 -74.146921) (xy 112.503107 -74.182105) (xy 112.576457 -74.224454)
			(xy 112.645449 -74.273583) (xy 112.709459 -74.329048) (xy 112.767907 -74.390346) (xy 112.820263 -74.456922)
			(xy 112.866053 -74.528174) (xy 112.904864 -74.603455) (xy 112.936343 -74.682085) (xy 112.960204 -74.763352)
			(xy 112.976233 -74.846518) (xy 112.984284 -74.930832) (xy 112.984788 -74.97318) (xy 112.984259 -75.016525)
			(xy 112.975815 -75.102803) (xy 112.959016 -75.18785) (xy 112.934021 -75.270858) (xy 112.901067 -75.351041)
			(xy 112.860468 -75.427636) (xy 112.812607 -75.499917) (xy 112.75794 -75.567197) (xy 112.696985 -75.628839)
			(xy 112.663986 -75.656948) (xy 112.65535 -75.664314) (xy 112.645698 -75.684634) (xy 112.645698 -75.785726)
			(xy 112.65535 -75.806046) (xy 112.663986 -75.813412) (xy 112.696978 -75.841527) (xy 112.757918 -75.903179)
			(xy 112.812574 -75.970465) (xy 112.860427 -76.042747) (xy 112.901023 -76.119341) (xy 112.933979 -76.199519)
			(xy 112.958981 -76.282522) (xy 112.975792 -76.367564) (xy 112.984253 -76.453837) (xy 112.984788 -76.49718)
			(xy 112.984259 -76.540525) (xy 112.975815 -76.626803) (xy 112.959016 -76.71185) (xy 112.934021 -76.794858)
			(xy 112.901067 -76.875041) (xy 112.860468 -76.951636) (xy 112.812607 -77.023917) (xy 112.75794 -77.091197)
			(xy 112.696985 -77.152839) (xy 112.663986 -77.180948) (xy 112.65535 -77.188314) (xy 112.645698 -77.208634)
			(xy 112.645698 -77.309726) (xy 112.65535 -77.330046) (xy 112.663986 -77.337412) (xy 112.696978 -77.365527)
			(xy 112.757918 -77.427179) (xy 112.812574 -77.494465) (xy 112.860427 -77.566747) (xy 112.901023 -77.643341)
			(xy 112.933979 -77.723519) (xy 112.958981 -77.806522) (xy 112.975792 -77.891564) (xy 112.984253 -77.977837)
			(xy 112.984788 -78.02118) (xy 112.984259 -78.064525) (xy 112.975815 -78.150803) (xy 112.959016 -78.23585)
			(xy 112.934021 -78.318858) (xy 112.901067 -78.399041) (xy 112.860468 -78.475636) (xy 112.812607 -78.547917)
			(xy 112.75794 -78.615197) (xy 112.696985 -78.676839) (xy 112.663986 -78.704948) (xy 112.65535 -78.712314)
			(xy 112.645698 -78.732634) (xy 112.645698 -78.81115) (xy 115.395497 -78.81115) (xy 115.395497 -78.75665)
			(xy 115.403253 -78.702705) (xy 115.418608 -78.650413) (xy 115.441248 -78.600838) (xy 115.470713 -78.55499)
			(xy 115.506403 -78.513801) (xy 115.547591 -78.478112) (xy 115.59344 -78.448647) (xy 115.643015 -78.426007)
			(xy 115.695307 -78.410653) (xy 115.749252 -78.402897) (xy 115.776502 -78.402434) (xy 115.806236 -78.402955)
			(xy 115.864982 -78.412189) (xy 115.921582 -78.430434) (xy 115.974663 -78.457246) (xy 116.022935 -78.491976)
			(xy 116.06523 -78.53378) (xy 116.083334 -78.557374) (xy 116.090971 -78.566569) (xy 116.112293 -78.577302)
			(xy 116.124228 -78.577948) (xy 116.206016 -78.577948) (xy 116.217957 -78.577308) (xy 116.239294 -78.566591)
			(xy 116.24691 -78.557374) (xy 116.265057 -78.533818) (xy 116.307348 -78.492023) (xy 116.355615 -78.457301)
			(xy 116.408687 -78.430492) (xy 116.465277 -78.412247) (xy 116.524013 -78.403008) (xy 116.553742 -78.402434)
			(xy 116.580841 -78.402917) (xy 116.634494 -78.410592) (xy 116.686521 -78.425782) (xy 116.735874 -78.448182)
			(xy 116.781561 -78.47734) (xy 116.822663 -78.51267) (xy 116.858351 -78.55346) (xy 116.873528 -78.575916)
			(xy 116.880894 -78.587092) (xy 116.9035 -78.599284) (xy 117.016276 -78.597506) (xy 117.038628 -78.584552)
			(xy 117.045486 -78.573122) (xy 117.060416 -78.549494) (xy 117.096108 -78.506482) (xy 117.13769 -78.469135)
			(xy 117.184275 -78.438253) (xy 117.234866 -78.414495) (xy 117.288381 -78.398369) (xy 117.343676 -78.39022)
			(xy 117.371622 -78.389734) (xy 117.401354 -78.390313) (xy 117.460097 -78.399535) (xy 117.516696 -78.417768)
			(xy 117.569777 -78.44457) (xy 117.618051 -78.479289) (xy 117.660349 -78.521084) (xy 117.678454 -78.544674)
			(xy 117.686081 -78.553878) (xy 117.707411 -78.564606) (xy 117.719348 -78.565248) (xy 117.801136 -78.565248)
			(xy 117.813078 -78.564619) (xy 117.834415 -78.553894) (xy 117.84203 -78.544674) (xy 117.860165 -78.521108)
			(xy 117.902459 -78.479314) (xy 117.950728 -78.444593) (xy 118.003802 -78.417786) (xy 118.060394 -78.399543)
			(xy 118.119132 -78.390307) (xy 118.148862 -78.389734) (xy 118.178377 -78.39028) (xy 118.2367 -78.399386)
			(xy 118.292918 -78.417386) (xy 118.31955 -78.43012) (xy 118.330726 -78.435708) (xy 118.355364 -78.4352)
			(xy 118.450614 -78.383892) (xy 118.46433 -78.363318) (xy 118.465854 -78.350872) (xy 118.469375 -78.324785)
			(xy 118.482666 -78.273851) (xy 118.502828 -78.225226) (xy 118.52948 -78.179832) (xy 118.562115 -78.13853)
			(xy 118.600115 -78.102104) (xy 118.642759 -78.071243) (xy 118.689239 -78.046534) (xy 118.738672 -78.028444)
			(xy 118.764304 -78.02245) (xy 118.774464 -78.020164) (xy 118.791482 -78.007972) (xy 118.840504 -77.926692)
			(xy 118.843298 -77.905864) (xy 118.840504 -77.895958) (xy 118.833972 -77.870808) (xy 118.826959 -77.819323)
			(xy 118.826534 -77.793342) (xy 118.826995 -77.766088) (xy 118.834747 -77.712135) (xy 118.8501 -77.659835)
			(xy 118.87274 -77.610252) (xy 118.902208 -77.564396) (xy 118.937902 -77.523202) (xy 118.979096 -77.487508)
			(xy 119.024952 -77.45804) (xy 119.074535 -77.4354) (xy 119.126835 -77.420047) (xy 119.180788 -77.412295)
			(xy 119.208042 -77.411834) (xy 119.237343 -77.412348) (xy 119.29526 -77.421285) (xy 119.323358 -77.429614)
			(xy 119.333518 -77.432916) (xy 119.354346 -77.430884) (xy 119.437404 -77.384402) (xy 119.450104 -77.367892)
			(xy 119.452644 -77.357478) (xy 119.460004 -77.330364) (xy 119.48155 -77.278479) (xy 119.510469 -77.230312)
			(xy 119.546136 -77.186906) (xy 119.587781 -77.149197) (xy 119.634505 -77.118) (xy 119.685297 -77.09399)
			(xy 119.739059 -77.077686) (xy 119.794632 -77.069438) (xy 119.822722 -77.068934) (xy 119.851447 -77.069499)
			(xy 119.908248 -77.078116) (xy 119.963115 -77.095153) (xy 120.014807 -77.120223) (xy 120.062156 -77.15276)
			(xy 120.104091 -77.192029) (xy 120.139664 -77.237142) (xy 120.168071 -77.287078) (xy 120.18867 -77.340709)
			(xy 120.19534 -77.368654) (xy 120.198134 -77.3811) (xy 120.21439 -77.40015) (xy 120.31726 -77.440282)
			(xy 120.342152 -77.437488) (xy 120.35282 -77.429868) (xy 120.377 -77.413627) (xy 120.42926 -77.387908)
			(xy 120.48482 -77.370425) (xy 120.542391 -77.361581) (xy 120.571514 -77.361034) (xy 120.598769 -77.361442)
			(xy 120.652724 -77.369202) (xy 120.705026 -77.384562) (xy 120.754609 -77.407209) (xy 120.800464 -77.436683)
			(xy 120.841658 -77.472382) (xy 120.877351 -77.513581) (xy 120.906818 -77.55944) (xy 120.929458 -77.609027)
			(xy 120.94481 -77.661331) (xy 120.952562 -77.715287) (xy 120.953022 -77.742542) (xy 120.952472 -77.771491)
			(xy 120.943704 -77.828723) (xy 120.926392 -77.883974) (xy 120.900931 -77.935975) (xy 120.867908 -77.983533)
			(xy 120.836284 -78.0169) (xy 121.226234 -78.0169) (xy 121.230265 -77.932291) (xy 121.24232 -77.848449)
			(xy 121.26229 -77.766132) (xy 121.289995 -77.686086) (xy 121.325184 -77.609037) (xy 121.367537 -77.535681)
			(xy 121.416672 -77.466684) (xy 121.472143 -77.402669) (xy 121.533448 -77.344218) (xy 121.600032 -77.291859)
			(xy 121.671291 -77.246066) (xy 121.746581 -77.207255) (xy 121.825219 -77.175776) (xy 121.906494 -77.151915)
			(xy 121.989668 -77.135888) (xy 122.07399 -77.12784) (xy 122.116342 -77.127354) (xy 122.135353 -77.127471)
			(xy 122.173339 -77.129125) (xy 122.192288 -77.130656) (xy 122.200938 -77.131019) (xy 122.21769 -77.126703)
			(xy 122.232054 -77.117064) (xy 122.2375 -77.110336) (xy 122.26261 -77.077292) (xy 122.318007 -77.015489)
			(xy 122.378923 -76.959118) (xy 122.444827 -76.90867) (xy 122.515147 -76.864583) (xy 122.589269 -76.827242)
			(xy 122.666549 -76.796972) (xy 122.746313 -76.774035) (xy 122.827868 -76.758632) (xy 122.910504 -76.750897)
			(xy 122.952002 -76.750418) (xy 122.994352 -76.75087) (xy 123.078667 -76.758921) (xy 123.161836 -76.774951)
			(xy 123.243105 -76.798813) (xy 123.321737 -76.830293) (xy 123.39702 -76.869105) (xy 123.468274 -76.914897)
			(xy 123.534852 -76.967254) (xy 123.596152 -77.025704) (xy 123.651618 -77.089715) (xy 123.700748 -77.158709)
			(xy 123.743098 -77.232061) (xy 123.778283 -77.309107) (xy 123.805986 -77.389148) (xy 123.825954 -77.471459)
			(xy 123.838008 -77.555297) (xy 123.842039 -77.6399) (xy 123.838008 -77.724503) (xy 123.825954 -77.808341)
			(xy 123.805986 -77.890652) (xy 123.778283 -77.970693) (xy 123.743098 -78.047739) (xy 123.700748 -78.121091)
			(xy 123.651618 -78.190085) (xy 123.596152 -78.254096) (xy 123.534852 -78.312546) (xy 123.468274 -78.364903)
			(xy 123.39702 -78.410695) (xy 123.321737 -78.449507) (xy 123.243105 -78.480987) (xy 123.161836 -78.504849)
			(xy 123.078667 -78.520879) (xy 122.994352 -78.52893) (xy 122.952002 -78.529434) (xy 122.932991 -78.529314)
			(xy 122.895005 -78.527663) (xy 122.876056 -78.526132) (xy 122.867406 -78.525733) (xy 122.850652 -78.530066)
			(xy 122.836288 -78.539718) (xy 122.830844 -78.546452) (xy 122.805765 -78.57952) (xy 122.750365 -78.641323)
			(xy 122.689445 -78.697693) (xy 122.623537 -78.74814) (xy 122.553214 -78.792225) (xy 122.479088 -78.829564)
			(xy 122.401805 -78.859831) (xy 122.322037 -78.882764) (xy 122.24048 -78.898163) (xy 122.157841 -78.905893)
			(xy 122.116342 -78.90637) (xy 122.07399 -78.90596) (xy 121.989668 -78.897912) (xy 121.906494 -78.881885)
			(xy 121.825219 -78.858024) (xy 121.746581 -78.826545) (xy 121.671291 -78.787734) (xy 121.600032 -78.741941)
			(xy 121.533448 -78.689582) (xy 121.472143 -78.631131) (xy 121.416672 -78.567116) (xy 121.367537 -78.498119)
			(xy 121.325184 -78.424763) (xy 121.289995 -78.347714) (xy 121.26229 -78.267668) (xy 121.24232 -78.185351)
			(xy 121.230265 -78.101509) (xy 121.226234 -78.0169) (xy 120.836284 -78.0169) (xy 120.828079 -78.025557)
			(xy 120.78236 -78.061082) (xy 120.731798 -78.089293) (xy 120.704864 -78.09992) (xy 120.694704 -78.10373)
			(xy 120.679464 -78.118716) (xy 120.643396 -78.208378) (xy 120.644158 -78.229714) (xy 120.64873 -78.239366)
			(xy 120.660746 -78.265393) (xy 120.677725 -78.320144) (xy 120.686312 -78.37682) (xy 120.68683 -78.405482)
			(xy 120.686305 -78.432732) (xy 120.678552 -78.486677) (xy 120.6632 -78.53897) (xy 120.640562 -78.588545)
			(xy 120.6111 -78.634395) (xy 120.575413 -78.675584) (xy 120.534227 -78.711276) (xy 120.48838 -78.740743)
			(xy 120.438807 -78.763386) (xy 120.386516 -78.778743) (xy 120.332572 -78.786502) (xy 120.305322 -78.78699)
			(xy 120.279862 -78.786605) (xy 120.229393 -78.779833) (xy 120.180275 -78.766406) (xy 120.133379 -78.746563)
			(xy 120.089541 -78.720656) (xy 120.04954 -78.689147) (xy 120.03151 -78.671166) (xy 120.024398 -78.6638)
			(xy 120.005856 -78.655926) (xy 119.913908 -78.654402) (xy 119.895112 -78.662022) (xy 119.887746 -78.669134)
			(xy 119.87149 -78.683866) (xy 119.862854 -78.691486) (xy 119.85371 -78.71206) (xy 119.855488 -78.812644)
			(xy 119.865394 -78.832964) (xy 119.874284 -78.840076) (xy 119.896044 -78.85829) (xy 119.934448 -78.900063)
			(xy 119.96624 -78.947065) (xy 119.990719 -78.998258) (xy 120.007345 -79.052512) (xy 120.01575 -79.10863)
			(xy 120.01627 -79.137002) (xy 120.015846 -79.164257) (xy 120.008088 -79.218211) (xy 119.99273 -79.270512)
			(xy 119.970084 -79.320095) (xy 119.940613 -79.365949) (xy 119.904915 -79.407143) (xy 119.863717 -79.442837)
			(xy 119.817859 -79.472304) (xy 119.768274 -79.494944) (xy 119.715972 -79.510297) (xy 119.662017 -79.518049)
			(xy 119.634762 -79.51851) (xy 119.605031 -79.517925) (xy 119.546288 -79.508701) (xy 119.48969 -79.490468)
			(xy 119.43661 -79.463668) (xy 119.388335 -79.428951) (xy 119.346037 -79.387158) (xy 119.32793 -79.36357)
			(xy 119.320301 -79.354366) (xy 119.298973 -79.343637) (xy 119.287036 -79.342996) (xy 119.205248 -79.342996)
			(xy 119.193302 -79.343599) (xy 119.171964 -79.354341) (xy 119.164354 -79.36357) (xy 119.14624 -79.387153)
			(xy 119.103941 -79.428944) (xy 119.055667 -79.463662) (xy 119.002589 -79.490465) (xy 118.945993 -79.508705)
			(xy 118.887253 -79.517939) (xy 118.857522 -79.51851) (xy 118.829894 -79.518011) (xy 118.775214 -79.510069)
			(xy 118.722251 -79.49432) (xy 118.672116 -79.471093) (xy 118.625857 -79.440874) (xy 118.584443 -79.404295)
			(xy 118.548741 -79.362124) (xy 118.519498 -79.315242) (xy 118.497327 -79.26463) (xy 118.482692 -79.211349)
			(xy 118.478808 -79.183992) (xy 118.477284 -79.171292) (xy 118.463314 -79.150972) (xy 118.365778 -79.10068)
			(xy 118.34114 -79.100934) (xy 118.329964 -79.10703) (xy 118.301968 -79.121414) (xy 118.242417 -79.141787)
			(xy 118.180331 -79.152109) (xy 118.148862 -79.15275) (xy 118.119132 -79.152149) (xy 118.060391 -79.142926)
			(xy 118.003794 -79.124695) (xy 117.950714 -79.097898) (xy 117.902438 -79.063184) (xy 117.860138 -79.021396)
			(xy 117.84203 -78.99781) (xy 117.834413 -78.988596) (xy 117.813075 -78.977874) (xy 117.801136 -78.977236)
			(xy 117.719348 -78.977236) (xy 117.707399 -78.977824) (xy 117.686061 -78.988575) (xy 117.678454 -78.99781)
			(xy 117.660351 -79.021401) (xy 117.618048 -79.06319) (xy 117.569771 -79.097906) (xy 117.516692 -79.124708)
			(xy 117.460095 -79.142946) (xy 117.401353 -79.152179) (xy 117.371622 -79.15275) (xy 117.344521 -79.152302)
			(xy 117.290867 -79.144621) (xy 117.238839 -79.129426) (xy 117.189485 -79.10702) (xy 117.143798 -79.077857)
			(xy 117.102698 -79.042522) (xy 117.067011 -79.001726) (xy 117.051836 -78.979268) (xy 117.04447 -78.968092)
			(xy 117.021864 -78.9559) (xy 116.909088 -78.957678) (xy 116.886736 -78.970632) (xy 116.879878 -78.982062)
			(xy 116.864966 -79.005703) (xy 116.829273 -79.048715) (xy 116.787687 -79.086062) (xy 116.741099 -79.116943)
			(xy 116.690505 -79.140699) (xy 116.636986 -79.156822) (xy 116.581689 -79.164966) (xy 116.553742 -79.16545)
			(xy 116.524011 -79.164864) (xy 116.465269 -79.155638) (xy 116.408672 -79.137404) (xy 116.355592 -79.110604)
			(xy 116.307317 -79.075888) (xy 116.265018 -79.034097) (xy 116.24691 -79.01051) (xy 116.239302 -79.001287)
			(xy 116.217958 -78.99057) (xy 116.206016 -78.989936) (xy 116.124228 -78.989936) (xy 116.112278 -78.990513)
			(xy 116.090939 -79.001271) (xy 116.083334 -79.01051) (xy 116.065243 -79.034111) (xy 116.022937 -79.075899)
			(xy 115.974658 -79.110613) (xy 115.921576 -79.137414) (xy 115.864977 -79.15565) (xy 115.806234 -79.16488)
			(xy 115.776502 -79.16545) (xy 115.749252 -79.164903) (xy 115.695307 -79.157147) (xy 115.643015 -79.141793)
			(xy 115.59344 -79.119153) (xy 115.547591 -79.089688) (xy 115.506403 -79.053999) (xy 115.470713 -79.01281)
			(xy 115.441248 -78.966962) (xy 115.418608 -78.917387) (xy 115.403253 -78.865095) (xy 115.395497 -78.81115)
			(xy 112.645698 -78.81115) (xy 112.645698 -78.833726) (xy 112.65535 -78.854046) (xy 112.663986 -78.861412)
			(xy 112.696978 -78.889527) (xy 112.757918 -78.951179) (xy 112.812574 -79.018465) (xy 112.860427 -79.090747)
			(xy 112.901023 -79.167341) (xy 112.933979 -79.247519) (xy 112.958981 -79.330522) (xy 112.975792 -79.415564)
			(xy 112.984253 -79.501837) (xy 112.984788 -79.54518) (xy 112.9842 -79.591575) (xy 112.974557 -79.683864)
			(xy 112.955362 -79.774648) (xy 112.926825 -79.862941) (xy 112.908588 -79.905606) (xy 112.904779 -79.915549)
			(xy 112.904772 -79.936815) (xy 112.908588 -79.946754) (xy 112.926825 -79.989419) (xy 112.955371 -80.077711)
			(xy 112.968013 -80.1375) (xy 120.813595 -80.1375) (xy 120.817625 -80.0529) (xy 120.829679 -79.969066)
			(xy 120.849647 -79.886758) (xy 120.877348 -79.806721) (xy 120.912531 -79.729678) (xy 120.954879 -79.65633)
			(xy 121.004007 -79.587338) (xy 121.059471 -79.523329) (xy 121.120768 -79.464882) (xy 121.187343 -79.412527)
			(xy 121.258593 -79.366736) (xy 121.333873 -79.327926) (xy 121.412502 -79.296447) (xy 121.493767 -79.272585)
			(xy 121.576932 -79.256555) (xy 121.661244 -79.248504) (xy 121.703592 -79.248) (xy 121.745627 -79.248524)
			(xy 121.829321 -79.256458) (xy 121.911893 -79.272255) (xy 121.992605 -79.295774) (xy 122.070737 -79.326807)
			(xy 122.145592 -79.365074) (xy 122.216501 -79.410236) (xy 122.282831 -79.461888) (xy 122.34399 -79.51957)
			(xy 122.399432 -79.582767) (xy 122.424444 -79.616554) (xy 122.432619 -79.62728) (xy 122.453563 -79.644262)
			(xy 122.478223 -79.655167) (xy 122.504878 -79.659231) (xy 122.531668 -79.656173) (xy 122.556721 -79.646206)
			(xy 122.578289 -79.630024) (xy 122.594867 -79.608759) (xy 122.600466 -79.596488) (xy 122.611732 -79.570905)
			(xy 122.640765 -79.523135) (xy 122.676456 -79.48011) (xy 122.71804 -79.442752) (xy 122.764629 -79.411858)
			(xy 122.815226 -79.388091) (xy 122.868748 -79.371958) (xy 122.924051 -79.363804) (xy 122.952002 -79.363316)
			(xy 122.979255 -79.363754) (xy 123.033206 -79.371511) (xy 123.085504 -79.386867) (xy 123.135084 -79.40951)
			(xy 123.180937 -79.438978) (xy 123.222129 -79.474672) (xy 123.257823 -79.515865) (xy 123.287291 -79.561718)
			(xy 123.309933 -79.611298) (xy 123.325289 -79.663596) (xy 123.333046 -79.717547) (xy 123.333046 -79.772053)
			(xy 123.325289 -79.826004) (xy 123.309933 -79.878302) (xy 123.287291 -79.927882) (xy 123.257823 -79.973735)
			(xy 123.222129 -80.014928) (xy 123.180937 -80.050622) (xy 123.135084 -80.08009) (xy 123.085504 -80.102733)
			(xy 123.033206 -80.118089) (xy 122.979255 -80.125846) (xy 122.952002 -80.126332) (xy 122.925202 -80.125856)
			(xy 122.872129 -80.11835) (xy 122.820631 -80.103485) (xy 122.771722 -80.081555) (xy 122.748802 -80.067658)
			(xy 122.737226 -80.060748) (xy 122.711464 -80.052817) (xy 122.684524 -80.051912) (xy 122.658288 -80.058097)
			(xy 122.634589 -80.070938) (xy 122.615081 -80.08954) (xy 122.601129 -80.112603) (xy 122.593705 -80.138516)
			(xy 122.5931 -80.151986) (xy 122.591868 -80.195193) (xy 122.582066 -80.281077) (xy 122.56398 -80.365606)
			(xy 122.537782 -80.447983) (xy 122.503718 -80.52743) (xy 122.462109 -80.603199) (xy 122.413348 -80.674576)
			(xy 122.357895 -80.740887) (xy 122.296272 -80.801507) (xy 122.22906 -80.855865) (xy 122.156893 -80.903449)
			(xy 122.080452 -80.943809) (xy 122.000456 -80.976565) (xy 121.917661 -81.001409) (xy 121.832847 -81.018106)
			(xy 121.746813 -81.026498) (xy 121.703592 -81.027016) (xy 121.661244 -81.026496) (xy 121.576932 -81.018445)
			(xy 121.493767 -81.002415) (xy 121.412502 -80.978553) (xy 121.333873 -80.947074) (xy 121.258593 -80.908264)
			(xy 121.187343 -80.862473) (xy 121.120768 -80.810118) (xy 121.059471 -80.751671) (xy 121.004007 -80.687662)
			(xy 120.954879 -80.61867) (xy 120.912531 -80.545322) (xy 120.877348 -80.468279) (xy 120.849647 -80.388242)
			(xy 120.829679 -80.305934) (xy 120.817625 -80.2221) (xy 120.813595 -80.1375) (xy 112.968013 -80.1375)
			(xy 112.974567 -80.168495) (xy 112.984202 -80.260784) (xy 112.984788 -80.30718) (xy 112.984284 -80.349528)
			(xy 112.976233 -80.433842) (xy 112.960204 -80.517008) (xy 112.936343 -80.598275) (xy 112.904864 -80.676905)
			(xy 112.866053 -80.752186) (xy 112.820263 -80.823438) (xy 112.767907 -80.890014) (xy 112.709459 -80.951312)
			(xy 112.645449 -81.006777) (xy 112.576457 -81.055906) (xy 112.503107 -81.098255) (xy 112.426064 -81.133439)
			(xy 112.346025 -81.161141) (xy 112.263716 -81.181109) (xy 112.179881 -81.193162) (xy 112.09528 -81.197193)
			(xy 112.010679 -81.193162) (xy 111.926844 -81.181109) (xy 111.844535 -81.161141) (xy 111.764496 -81.133439)
			(xy 111.687453 -81.098255) (xy 111.614103 -81.055906) (xy 111.545111 -81.006777) (xy 111.481101 -80.951312)
			(xy 111.422653 -80.890014) (xy 111.370297 -80.823438) (xy 111.324507 -80.752186) (xy 111.285696 -80.676905)
			(xy 111.254217 -80.598275) (xy 111.230356 -80.517008) (xy 111.214327 -80.433842) (xy 111.206276 -80.349528)
			(xy 111.205772 -80.30718) (xy 101.080767 -80.30718) (xy 101.107176 -80.346761) (xy 101.148251 -80.423708)
			(xy 101.181596 -80.504307) (xy 101.20689 -80.587783) (xy 101.223891 -80.673334) (xy 101.232435 -80.760138)
			(xy 101.23297 -80.80375) (xy 101.232466 -80.846098) (xy 101.224415 -80.930412) (xy 101.208386 -81.013578)
			(xy 101.184525 -81.094845) (xy 101.153046 -81.173475) (xy 101.114235 -81.248756) (xy 101.068445 -81.320008)
			(xy 101.016089 -81.386584) (xy 100.957641 -81.447882) (xy 100.893631 -81.503347) (xy 100.880645 -81.512594)
			(xy 107.555534 -81.512594) (xy 107.555534 -81.427898) (xy 107.563585 -81.343584) (xy 107.579614 -81.260418)
			(xy 107.603475 -81.179151) (xy 107.634954 -81.100521) (xy 107.673765 -81.02524) (xy 107.719555 -80.953988)
			(xy 107.771911 -80.887412) (xy 107.830359 -80.826114) (xy 107.894369 -80.770649) (xy 107.963361 -80.72152)
			(xy 108.036711 -80.679171) (xy 108.113754 -80.643987) (xy 108.193793 -80.616285) (xy 108.276102 -80.596317)
			(xy 108.359937 -80.584264) (xy 108.444538 -80.580234) (xy 108.529139 -80.584264) (xy 108.612974 -80.596317)
			(xy 108.695283 -80.616285) (xy 108.775322 -80.643987) (xy 108.852365 -80.679171) (xy 108.925715 -80.72152)
			(xy 108.994707 -80.770649) (xy 109.058717 -80.826114) (xy 109.117165 -80.887412) (xy 109.169521 -80.953988)
			(xy 109.215311 -81.02524) (xy 109.254122 -81.100521) (xy 109.285601 -81.179151) (xy 109.309462 -81.260418)
			(xy 109.325491 -81.343584) (xy 109.333542 -81.427898) (xy 109.334046 -81.470246) (xy 109.333542 -81.512594)
			(xy 109.325491 -81.596908) (xy 109.309462 -81.680074) (xy 109.285601 -81.761341) (xy 109.254122 -81.839971)
			(xy 109.215311 -81.915252) (xy 109.169521 -81.986504) (xy 109.117165 -82.05308) (xy 109.058717 -82.114378)
			(xy 108.994707 -82.169843) (xy 108.925715 -82.218972) (xy 108.852365 -82.261321) (xy 108.775322 -82.296505)
			(xy 108.695283 -82.324207) (xy 108.612974 -82.344175) (xy 108.529139 -82.356228) (xy 108.444538 -82.360259)
			(xy 108.359937 -82.356228) (xy 108.276102 -82.344175) (xy 108.193793 -82.324207) (xy 108.113754 -82.296505)
			(xy 108.036711 -82.261321) (xy 107.963361 -82.218972) (xy 107.894369 -82.169843) (xy 107.830359 -82.114378)
			(xy 107.771911 -82.05308) (xy 107.719555 -81.986504) (xy 107.673765 -81.915252) (xy 107.634954 -81.839971)
			(xy 107.603475 -81.761341) (xy 107.579614 -81.680074) (xy 107.563585 -81.596908) (xy 107.555534 -81.512594)
			(xy 100.880645 -81.512594) (xy 100.824639 -81.552476) (xy 100.751289 -81.594825) (xy 100.674246 -81.630009)
			(xy 100.594207 -81.657711) (xy 100.511898 -81.677679) (xy 100.428063 -81.689732) (xy 100.343462 -81.693763)
			(xy 100.258861 -81.689732) (xy 100.175026 -81.677679) (xy 100.092717 -81.657711) (xy 100.012678 -81.630009)
			(xy 99.935635 -81.594825) (xy 99.862285 -81.552476) (xy 99.793293 -81.503347) (xy 99.729283 -81.447882)
			(xy 99.670835 -81.386584) (xy 99.618479 -81.320008) (xy 99.572689 -81.248756) (xy 99.533878 -81.173475)
			(xy 99.502399 -81.094845) (xy 99.478538 -81.013578) (xy 99.462509 -80.930412) (xy 99.454458 -80.846098)
			(xy 99.453954 -80.80375) (xy 85.60181 -80.80375) (xy 82.32902 -84.07654) (xy 82.32234 -84.083951)
			(xy 82.314769 -84.102387) (xy 82.314288 -84.112354) (xy 82.314288 -90.643456) (xy 117.866922 -90.643456)
			(xy 117.867449 -90.601793) (xy 117.875254 -90.518833) (xy 117.890783 -90.436966) (xy 117.913898 -90.356911)
			(xy 117.944399 -90.279367) (xy 117.982016 -90.205015) (xy 118.026421 -90.134507) (xy 118.077225 -90.068459)
			(xy 118.133982 -90.007452) (xy 118.196196 -89.952019) (xy 118.26332 -89.902647) (xy 118.334766 -89.859768)
			(xy 118.372128 -89.841324) (xy 118.381061 -89.83659) (xy 118.394509 -89.821516) (xy 118.401067 -89.802409)
			(xy 118.40083 -89.792302) (xy 118.400068 -89.767918) (xy 118.400554 -89.740667) (xy 118.40831 -89.686719)
			(xy 118.423665 -89.634424) (xy 118.446307 -89.584847) (xy 118.475773 -89.538997) (xy 118.511464 -89.497806)
			(xy 118.552655 -89.462115) (xy 118.598505 -89.432649) (xy 118.648082 -89.410007) (xy 118.700377 -89.394652)
			(xy 118.754325 -89.386896) (xy 118.808827 -89.386896) (xy 118.862775 -89.394652) (xy 118.91507 -89.410007)
			(xy 118.964647 -89.432649) (xy 119.010497 -89.462115) (xy 119.051688 -89.497806) (xy 119.087379 -89.538997)
			(xy 119.116845 -89.584847) (xy 119.139487 -89.634424) (xy 119.154842 -89.686719) (xy 119.162598 -89.740667)
			(xy 119.163084 -89.767918) (xy 119.162997 -89.779504) (xy 119.161598 -89.802634) (xy 119.16029 -89.814146)
			(xy 119.159488 -89.824212) (xy 119.165029 -89.843619) (xy 119.17758 -89.859425) (xy 119.186198 -89.864692)
			(xy 119.223736 -89.88594) (xy 119.273857 -89.920318) (xy 123.01855 -89.920318) (xy 123.019118 -89.876932)
			(xy 123.027566 -89.790572) (xy 123.044383 -89.705445) (xy 123.06941 -89.622361) (xy 123.102408 -89.542108)
			(xy 123.143064 -89.46545) (xy 123.190991 -89.393115) (xy 123.245735 -89.325791) (xy 123.306774 -89.264117)
			(xy 123.373528 -89.208681) (xy 123.445364 -89.160008) (xy 123.521598 -89.118561) (xy 123.561348 -89.101168)
			(xy 123.571202 -89.096476) (xy 123.585991 -89.080455) (xy 123.592781 -89.059736) (xy 123.592082 -89.048844)
			(xy 123.590999 -89.038337) (xy 123.589855 -89.017243) (xy 123.589796 -89.00668) (xy 123.590282 -88.979429)
			(xy 123.598038 -88.925481) (xy 123.613393 -88.873186) (xy 123.636035 -88.823609) (xy 123.665501 -88.777759)
			(xy 123.701192 -88.736568) (xy 123.742383 -88.700877) (xy 123.788233 -88.671411) (xy 123.83781 -88.648769)
			(xy 123.890105 -88.633414) (xy 123.944053 -88.625658) (xy 123.998555 -88.625658) (xy 124.052503 -88.633414)
			(xy 124.104798 -88.648769) (xy 124.154375 -88.671411) (xy 124.200225 -88.700877) (xy 124.241416 -88.736568)
			(xy 124.277107 -88.777759) (xy 124.306573 -88.823609) (xy 124.329215 -88.873186) (xy 124.34457 -88.925481)
			(xy 124.352326 -88.979429) (xy 124.352812 -89.00668) (xy 124.352475 -89.030426) (xy 124.346613 -89.077554)
			(xy 124.341128 -89.10066) (xy 124.338934 -89.111353) (xy 124.342756 -89.132819) (xy 124.355147 -89.15076)
			(xy 124.364242 -89.156794) (xy 124.399807 -89.178651) (xy 124.467153 -89.227984) (xy 124.52958 -89.283411)
			(xy 124.586538 -89.344444) (xy 124.637526 -89.410546) (xy 124.682096 -89.481135) (xy 124.719854 -89.55559)
			(xy 124.750469 -89.633256) (xy 124.773671 -89.713449) (xy 124.789256 -89.795463) (xy 124.797087 -89.878577)
			(xy 124.797566 -89.920318) (xy 124.797062 -89.962666) (xy 124.789011 -90.04698) (xy 124.772982 -90.130146)
			(xy 124.749121 -90.211413) (xy 124.717642 -90.290043) (xy 124.678831 -90.365324) (xy 124.633041 -90.436576)
			(xy 124.580685 -90.503152) (xy 124.522237 -90.56445) (xy 124.458227 -90.619915) (xy 124.389235 -90.669044)
			(xy 124.315885 -90.711393) (xy 124.238842 -90.746577) (xy 124.158803 -90.774279) (xy 124.076494 -90.794247)
			(xy 123.992659 -90.8063) (xy 123.908058 -90.810331) (xy 123.823457 -90.8063) (xy 123.739622 -90.794247)
			(xy 123.657313 -90.774279) (xy 123.577274 -90.746577) (xy 123.500231 -90.711393) (xy 123.426881 -90.669044)
			(xy 123.357889 -90.619915) (xy 123.293879 -90.56445) (xy 123.235431 -90.503152) (xy 123.183075 -90.436576)
			(xy 123.137285 -90.365324) (xy 123.098474 -90.290043) (xy 123.066995 -90.211413) (xy 123.043134 -90.130146)
			(xy 123.027105 -90.04698) (xy 123.019054 -89.962666) (xy 123.01855 -89.920318) (xy 119.273857 -89.920318)
			(xy 119.294874 -89.934734) (xy 119.360954 -89.990185) (xy 119.421355 -90.051773) (xy 119.47551 -90.11892)
			(xy 119.522909 -90.190994) (xy 119.563109 -90.267319) (xy 119.59573 -90.347177) (xy 119.620466 -90.429818)
			(xy 119.637085 -90.514465) (xy 119.645431 -90.600324) (xy 119.645938 -90.643456) (xy 119.645434 -90.685804)
			(xy 119.637383 -90.770118) (xy 119.621354 -90.853284) (xy 119.597493 -90.934551) (xy 119.566014 -91.013181)
			(xy 119.527203 -91.088462) (xy 119.481413 -91.159714) (xy 119.429057 -91.22629) (xy 119.370609 -91.287588)
			(xy 119.306599 -91.343053) (xy 119.237607 -91.392182) (xy 119.164257 -91.434531) (xy 119.087214 -91.469715)
			(xy 119.007175 -91.497417) (xy 118.924866 -91.517385) (xy 118.841031 -91.529438) (xy 118.75643 -91.533469)
			(xy 118.671829 -91.529438) (xy 118.587994 -91.517385) (xy 118.505685 -91.497417) (xy 118.425646 -91.469715)
			(xy 118.348603 -91.434531) (xy 118.275253 -91.392182) (xy 118.206261 -91.343053) (xy 118.142251 -91.287588)
			(xy 118.083803 -91.22629) (xy 118.031447 -91.159714) (xy 117.985657 -91.088462) (xy 117.946846 -91.013181)
			(xy 117.915367 -90.934551) (xy 117.891506 -90.853284) (xy 117.875477 -90.770118) (xy 117.867426 -90.685804)
			(xy 117.866922 -90.643456) (xy 82.314288 -90.643456) (xy 82.314288 -92.0254) (xy 123.677422 -92.0254)
			(xy 123.677422 -91.940704) (xy 123.685473 -91.85639) (xy 123.701502 -91.773224) (xy 123.725363 -91.691957)
			(xy 123.756842 -91.613327) (xy 123.795653 -91.538046) (xy 123.841443 -91.466794) (xy 123.893799 -91.400218)
			(xy 123.952247 -91.33892) (xy 124.016257 -91.283455) (xy 124.085249 -91.234326) (xy 124.158599 -91.191977)
			(xy 124.235642 -91.156793) (xy 124.315681 -91.129091) (xy 124.39799 -91.109123) (xy 124.481825 -91.09707)
			(xy 124.566426 -91.09304) (xy 124.651027 -91.09707) (xy 124.734862 -91.109123) (xy 124.817171 -91.129091)
			(xy 124.89721 -91.156793) (xy 124.974253 -91.191977) (xy 125.047603 -91.234326) (xy 125.116595 -91.283455)
			(xy 125.180605 -91.33892) (xy 125.239053 -91.400218) (xy 125.291409 -91.466794) (xy 125.337199 -91.538046)
			(xy 125.37601 -91.613327) (xy 125.407489 -91.691957) (xy 125.43135 -91.773224) (xy 125.447379 -91.85639)
			(xy 125.45543 -91.940704) (xy 125.455934 -91.983052) (xy 125.45543 -92.0254) (xy 125.447379 -92.109714)
			(xy 125.43135 -92.19288) (xy 125.407489 -92.274147) (xy 125.37601 -92.352777) (xy 125.337199 -92.428058)
			(xy 125.291409 -92.49931) (xy 125.239053 -92.565886) (xy 125.180605 -92.627184) (xy 125.116595 -92.682649)
			(xy 125.047603 -92.731778) (xy 124.974253 -92.774127) (xy 124.89721 -92.809311) (xy 124.817171 -92.837013)
			(xy 124.734862 -92.856981) (xy 124.651027 -92.869034) (xy 124.566426 -92.873065) (xy 124.481825 -92.869034)
			(xy 124.39799 -92.856981) (xy 124.315681 -92.837013) (xy 124.235642 -92.809311) (xy 124.158599 -92.774127)
			(xy 124.085249 -92.731778) (xy 124.016257 -92.682649) (xy 123.952247 -92.627184) (xy 123.893799 -92.565886)
			(xy 123.841443 -92.49931) (xy 123.795653 -92.428058) (xy 123.756842 -92.352777) (xy 123.725363 -92.274147)
			(xy 123.701502 -92.19288) (xy 123.685473 -92.109714) (xy 123.677422 -92.0254) (xy 82.314288 -92.0254)
			(xy 82.314288 -92.416122) (xy 82.314749 -92.425999) (xy 82.322192 -92.444297) (xy 82.328766 -92.451682)
			(xy 82.385662 -92.509594) (xy 82.403696 -92.517214) (xy 82.413856 -92.517468) (xy 82.45576 -92.518632)
			(xy 82.539084 -92.527874) (xy 82.621169 -92.544914) (xy 82.701286 -92.5696) (xy 82.778726 -92.601714)
			(xy 82.852802 -92.640971) (xy 82.922856 -92.687022) (xy 82.988267 -92.73946) (xy 83.048454 -92.797818)
			(xy 83.102885 -92.86158) (xy 83.151076 -92.93018) (xy 83.192599 -93.003009) (xy 83.227087 -93.079421)
			(xy 83.254234 -93.158739) (xy 83.273798 -93.240259) (xy 83.285606 -93.323258) (xy 83.289554 -93.407)
			(xy 83.285606 -93.490741) (xy 83.273798 -93.57374) (xy 83.254234 -93.65526) (xy 83.227087 -93.734578)
			(xy 83.1926 -93.810991) (xy 83.151076 -93.88382) (xy 83.102885 -93.95242) (xy 83.048455 -94.016181)
			(xy 82.988267 -94.07454) (xy 82.922856 -94.126977) (xy 82.852803 -94.173029) (xy 82.778727 -94.212286)
			(xy 82.701287 -94.2444) (xy 82.621169 -94.269086) (xy 82.539085 -94.286126) (xy 82.455761 -94.295368)
			(xy 82.413856 -94.296484) (xy 82.403696 -94.296738) (xy 82.385662 -94.304358) (xy 82.328766 -94.36227)
			(xy 82.322184 -94.369651) (xy 82.314737 -94.387951) (xy 82.314288 -94.39783) (xy 82.314288 -106.42092)
			(xy 123.636022 -106.42092) (xy 123.640093 -106.365298) (xy 123.652219 -106.310861) (xy 123.672142 -106.25877)
			(xy 123.699438 -106.210135) (xy 123.733524 -106.165992) (xy 123.773673 -106.127283) (xy 123.819031 -106.094832)
			(xy 123.868631 -106.069331) (xy 123.921415 -106.051324) (xy 123.976258 -106.041194) (xy 124.031992 -106.039157)
			(xy 124.087429 -106.045257) (xy 124.141386 -106.059363) (xy 124.192715 -106.081175) (xy 124.240321 -106.110229)
			(xy 124.283189 -106.145904) (xy 124.320406 -106.187441) (xy 124.351179 -106.233954) (xy 124.374851 -106.284451)
			(xy 124.390919 -106.337858) (xy 124.399039 -106.393034) (xy 124.399548 -106.42092) (xy 124.399039 -106.448806)
			(xy 124.390919 -106.503982) (xy 124.374851 -106.557389) (xy 124.351179 -106.607886) (xy 124.320406 -106.654399)
			(xy 124.283189 -106.695936) (xy 124.240321 -106.731611) (xy 124.192715 -106.760665) (xy 124.141386 -106.782477)
			(xy 124.087429 -106.796583) (xy 124.031992 -106.802683) (xy 123.976258 -106.800646) (xy 123.921415 -106.790516)
			(xy 123.868631 -106.772509) (xy 123.819031 -106.747008) (xy 123.773673 -106.714557) (xy 123.733524 -106.675848)
			(xy 123.699438 -106.631705) (xy 123.672142 -106.58307) (xy 123.652219 -106.530979) (xy 123.640093 -106.476542)
			(xy 123.636022 -106.42092) (xy 82.314288 -106.42092) (xy 82.314288 -112.62) (xy 94.597531 -112.62)
			(xy 94.601561 -112.535404) (xy 94.613614 -112.451574) (xy 94.633581 -112.369269) (xy 94.661281 -112.289234)
			(xy 94.696463 -112.212196) (xy 94.738809 -112.13885) (xy 94.787935 -112.069861) (xy 94.843396 -112.005855)
			(xy 94.90469 -111.94741) (xy 94.971263 -111.895057) (xy 95.04251 -111.849268) (xy 95.117787 -111.810459)
			(xy 95.196412 -111.778982) (xy 95.277674 -111.75512) (xy 95.360835 -111.739091) (xy 95.445144 -111.73104)
			(xy 95.48749 -111.730536) (xy 95.525779 -111.730953) (xy 95.602069 -111.737579) (xy 95.677509 -111.750732)
			(xy 95.751541 -111.770313) (xy 95.787718 -111.78286) (xy 95.796156 -111.785502) (xy 95.813824 -111.785502)
			(xy 95.822262 -111.78286) (xy 95.858437 -111.770304) (xy 95.932466 -111.750708) (xy 96.007907 -111.737556)
			(xy 96.084201 -111.730947) (xy 96.12249 -111.730536) (xy 96.160779 -111.730953) (xy 96.237069 -111.737579)
			(xy 96.312509 -111.750732) (xy 96.386541 -111.770313) (xy 96.422718 -111.78286) (xy 96.431156 -111.785502)
			(xy 96.448824 -111.785502) (xy 96.457262 -111.78286) (xy 96.493437 -111.770304) (xy 96.567466 -111.750708)
			(xy 96.642907 -111.737556) (xy 96.719201 -111.730947) (xy 96.75749 -111.730536) (xy 96.797229 -111.73098)
			(xy 96.876391 -111.738062) (xy 96.954606 -111.752171) (xy 97.031253 -111.773195) (xy 97.06864 -111.78667)
			(xy 97.077307 -111.78951) (xy 97.095533 -111.78951) (xy 97.1042 -111.78667) (xy 97.141582 -111.773177)
			(xy 97.218227 -111.752138) (xy 97.296445 -111.738028) (xy 97.37561 -111.730961) (xy 97.41535 -111.730536)
			(xy 97.457703 -111.730934) (xy 97.542025 -111.738981) (xy 97.625201 -111.755008) (xy 97.706477 -111.778868)
			(xy 97.785116 -111.810347) (xy 97.860407 -111.849158) (xy 97.931668 -111.894951) (xy 97.998253 -111.947311)
			(xy 98.059559 -112.005762) (xy 98.115031 -112.069777) (xy 98.164166 -112.138775) (xy 98.206521 -112.212132)
			(xy 98.24171 -112.289182) (xy 98.269415 -112.369229) (xy 98.289386 -112.451547) (xy 98.301441 -112.53539)
			(xy 98.305472 -112.62) (xy 98.301441 -112.70461) (xy 98.289386 -112.788453) (xy 98.269415 -112.870771)
			(xy 98.24171 -112.950818) (xy 98.206521 -113.027868) (xy 98.164166 -113.101225) (xy 98.115031 -113.170223)
			(xy 98.059559 -113.234238) (xy 97.998253 -113.292689) (xy 97.931668 -113.345049) (xy 97.860407 -113.390842)
			(xy 97.785116 -113.429653) (xy 97.706477 -113.461132) (xy 97.625201 -113.484992) (xy 97.542025 -113.501019)
			(xy 97.457703 -113.509066) (xy 97.41535 -113.509552) (xy 97.375611 -113.509127) (xy 97.296448 -113.50204)
			(xy 97.218233 -113.487925) (xy 97.141587 -113.466896) (xy 97.1042 -113.453418) (xy 97.095533 -113.450578)
			(xy 97.077307 -113.450578) (xy 97.06864 -113.453418) (xy 97.031254 -113.466898) (xy 96.954611 -113.487941)
			(xy 96.876394 -113.502054) (xy 96.79723 -113.509125) (xy 96.75749 -113.509552) (xy 96.719202 -113.509112)
			(xy 96.642912 -113.502493) (xy 96.567472 -113.489347) (xy 96.49344 -113.469772) (xy 96.457262 -113.457228)
			(xy 96.448824 -113.454586) (xy 96.431156 -113.454586) (xy 96.422718 -113.457228) (xy 96.386545 -113.469789)
			(xy 96.312515 -113.489384) (xy 96.237073 -113.502534) (xy 96.16078 -113.509142) (xy 96.12249 -113.509552)
			(xy 96.084202 -113.509112) (xy 96.007912 -113.502493) (xy 95.932472 -113.489347) (xy 95.85844 -113.469772)
			(xy 95.822262 -113.457228) (xy 95.813824 -113.454586) (xy 95.796156 -113.454586) (xy 95.787718 -113.457228)
			(xy 95.751545 -113.469789) (xy 95.677515 -113.489384) (xy 95.602073 -113.502534) (xy 95.52578 -113.509142)
			(xy 95.48749 -113.509552) (xy 95.445144 -113.50896) (xy 95.360835 -113.500909) (xy 95.277674 -113.48488)
			(xy 95.196412 -113.461018) (xy 95.117787 -113.429541) (xy 95.04251 -113.390732) (xy 94.971263 -113.344943)
			(xy 94.90469 -113.29259) (xy 94.843396 -113.234145) (xy 94.787935 -113.170139) (xy 94.738809 -113.10115)
			(xy 94.696463 -113.027804) (xy 94.661281 -112.950766) (xy 94.633581 -112.870731) (xy 94.613614 -112.788426)
			(xy 94.601561 -112.704596) (xy 94.597531 -112.62) (xy 82.314288 -112.62) (xy 82.314288 -114.002566)
			(xy 82.314723 -114.012631) (xy 82.322453 -114.031219) (xy 82.329274 -114.038634) (xy 83.987894 -115.697254)
			(xy 83.988402 -115.697762) (xy 83.995786 -115.704336) (xy 84.014085 -115.711767) (xy 84.023962 -115.71224)
		)
		(stroke
			(width 0)
			(type solid)
		)
		(fill yes)
		(layer "In15.Cu")
		(net "P12V_AUX")
	)
	(gr_poly
		(pts
			(xy 424.67784 -397.4592) (xy 424.686449 -397.458862) (xy 424.702701 -397.453173) (xy 424.716169 -397.442443)
			(xy 424.72102 -397.435324) (xy 424.773852 -397.35125) (xy 424.775122 -397.325596) (xy 424.769534 -397.313658)
			(xy 424.757586 -397.287705) (xy 424.74073 -397.233113) (xy 424.732211 -397.176617) (xy 424.731688 -397.14805)
			(xy 424.732152 -397.121174) (xy 424.739707 -397.067957) (xy 424.754661 -397.016328) (xy 424.776718 -396.967311)
			(xy 424.80544 -396.921876) (xy 424.840257 -396.880926) (xy 424.880481 -396.845271) (xy 424.90263 -396.830042)
			(xy 424.913298 -396.82293) (xy 424.925236 -396.800832) (xy 424.926252 -396.691358) (xy 424.914822 -396.669006)
			(xy 424.904154 -396.66164) (xy 424.882769 -396.646297) (xy 424.844027 -396.610674) (xy 424.810549 -396.570063)
			(xy 424.782972 -396.525235) (xy 424.761819 -396.477042) (xy 424.747493 -396.426398) (xy 424.740264 -396.374266)
			(xy 424.739816 -396.34795) (xy 424.740302 -396.320699) (xy 424.748058 -396.266751) (xy 424.763413 -396.214456)
			(xy 424.786055 -396.164879) (xy 424.815521 -396.119029) (xy 424.851212 -396.077838) (xy 424.892403 -396.042147)
			(xy 424.938253 -396.012681) (xy 424.98783 -395.990039) (xy 425.040125 -395.974684) (xy 425.094073 -395.966928)
			(xy 425.148575 -395.966928) (xy 425.202523 -395.974684) (xy 425.254818 -395.990039) (xy 425.304395 -396.012681)
			(xy 425.350245 -396.042147) (xy 425.391436 -396.077838) (xy 425.427127 -396.119029) (xy 425.456593 -396.164879)
			(xy 425.479235 -396.214456) (xy 425.49459 -396.266751) (xy 425.502346 -396.320699) (xy 425.502832 -396.34795)
			(xy 425.502368 -396.374826) (xy 425.494813 -396.428044) (xy 425.479859 -396.479673) (xy 425.457804 -396.528692)
			(xy 425.429083 -396.574127) (xy 425.394266 -396.615078) (xy 425.354044 -396.650735) (xy 425.33189 -396.665958)
			(xy 425.321222 -396.67307) (xy 425.309284 -396.695168) (xy 425.308268 -396.804642) (xy 425.319698 -396.826994)
			(xy 425.330366 -396.83436) (xy 425.351754 -396.8497) (xy 425.390504 -396.88532) (xy 425.423989 -396.92593)
			(xy 425.451572 -396.970757) (xy 425.47273 -397.018952) (xy 425.487059 -397.069598) (xy 425.49429 -397.121733)
			(xy 425.494704 -397.14805) (xy 425.494191 -397.176617) (xy 425.485659 -397.233111) (xy 425.468794 -397.287699)
			(xy 425.456858 -397.313658) (xy 425.45127 -397.325596) (xy 425.45254 -397.35125) (xy 425.505372 -397.435324)
			(xy 425.510207 -397.442465) (xy 425.523658 -397.453241) (xy 425.539933 -397.458911) (xy 425.548552 -397.4592)
			(xy 427.022514 -397.4592) (xy 427.032583 -397.458774) (xy 427.051184 -397.451056) (xy 427.058582 -397.444214)
			(xy 427.38421 -397.118586) (xy 427.391064 -397.111191) (xy 427.398808 -397.092592) (xy 427.399196 -397.082518)
			(xy 427.399196 -394.844524) (xy 427.398763 -394.834827) (xy 427.391576 -394.816814) (xy 427.385226 -394.809472)
			(xy 427.364398 -394.787628) (xy 427.357892 -394.781324) (xy 427.34162 -394.773392) (xy 427.332648 -394.772134)
			(xy 427.304746 -394.768851) (xy 427.250263 -394.755143) (xy 427.198379 -394.733595) (xy 427.150215 -394.704672)
			(xy 427.106812 -394.669001) (xy 427.069108 -394.627352) (xy 427.037918 -394.580625) (xy 427.013916 -394.52983)
			(xy 426.99762 -394.476064) (xy 426.989383 -394.420491) (xy 426.989383 -394.36431) (xy 426.99762 -394.308737)
			(xy 427.013915 -394.254971) (xy 427.037918 -394.204176) (xy 427.069108 -394.157449) (xy 427.106812 -394.115799)
			(xy 427.150215 -394.080128) (xy 427.198379 -394.051206) (xy 427.250262 -394.029657) (xy 427.304745 -394.015949)
			(xy 427.332648 -394.012674) (xy 427.341616 -394.011407) (xy 427.357887 -394.003475) (xy 427.364398 -393.99718)
			(xy 427.385226 -393.975336) (xy 427.391605 -393.968014) (xy 427.398779 -393.949987) (xy 427.399196 -393.940284)
			(xy 427.399196 -392.044682) (xy 427.398769 -392.034613) (xy 427.39105 -392.016014) (xy 427.38421 -392.008614)
			(xy 426.610272 -391.234676) (xy 426.602876 -391.227826) (xy 426.584277 -391.220089) (xy 426.574204 -391.21969)
			(xy 423.405046 -391.21969) (xy 423.375836 -391.247376) (xy 423.37482 -391.267696) (xy 423.373019 -391.292742)
			(xy 423.3628 -391.341905) (xy 423.345268 -391.388958) (xy 423.320826 -391.432821) (xy 423.290035 -391.472486)
			(xy 423.253603 -391.507041) (xy 423.212367 -391.535694) (xy 423.167274 -391.557784) (xy 423.11936 -391.572806)
			(xy 423.069726 -391.580413) (xy 423.04462 -391.580878) (xy 423.020848 -391.58046) (xy 422.973796 -391.57364)
			(xy 422.928206 -391.560151) (xy 422.885017 -391.540273) (xy 422.845121 -391.514414) (xy 422.826942 -391.49909)
			(xy 422.819819 -391.493414) (xy 422.802768 -391.487045) (xy 422.793668 -391.486644) (xy 422.762172 -391.486644)
			(xy 422.753064 -391.487011) (xy 422.735998 -391.493376) (xy 422.728898 -391.49909) (xy 422.710739 -391.514441)
			(xy 422.670844 -391.540313) (xy 422.627652 -391.560197) (xy 422.582055 -391.573682) (xy 422.534995 -391.580489)
			(xy 422.51122 -391.580878) (xy 422.484349 -391.580354) (xy 422.431313 -391.571664) (xy 422.380382 -391.554509)
			(xy 422.332896 -391.529342) (xy 422.290107 -391.496825) (xy 422.253141 -391.457814) (xy 422.237662 -391.435844)
			(xy 422.231058 -391.426446) (xy 422.211754 -391.415016) (xy 422.122346 -391.40638) (xy 422.111126 -391.405952)
			(xy 422.090041 -391.41359) (xy 422.081706 -391.421112) (xy 421.49268 -392.010138) (xy 421.485283 -392.016988)
			(xy 421.466685 -392.024725) (xy 421.456612 -392.025124) (xy 411.417262 -392.025124) (xy 411.407195 -392.025555)
			(xy 411.388603 -392.033281) (xy 411.381194 -392.04011) (xy 410.594556 -392.826748) (xy 410.588714 -392.856974)
			(xy 410.59481 -392.871198) (xy 410.603011 -392.891621) (xy 410.614553 -392.934092) (xy 410.620367 -392.977717)
			(xy 410.620718 -392.999722) (xy 410.620207 -393.025708) (xy 410.620207 -393.025709) (xy 411.159962 -393.025709)
			(xy 411.159962 -392.973735) (xy 411.168092 -392.9224) (xy 411.184153 -392.87297) (xy 411.207749 -392.82666)
			(xy 411.238299 -392.784612) (xy 411.27505 -392.747861) (xy 411.317098 -392.717311) (xy 411.363408 -392.693715)
			(xy 411.412838 -392.677654) (xy 411.464173 -392.669524) (xy 411.516147 -392.669524) (xy 411.567482 -392.677654)
			(xy 411.616912 -392.693715) (xy 411.663222 -392.717311) (xy 411.70527 -392.747861) (xy 411.742021 -392.784612)
			(xy 411.772571 -392.82666) (xy 411.796167 -392.87297) (xy 411.812228 -392.9224) (xy 411.820358 -392.973735)
			(xy 411.820868 -392.999722) (xy 411.820358 -393.025709) (xy 412.359858 -393.025709) (xy 412.359858 -392.973735)
			(xy 412.367988 -392.9224) (xy 412.384049 -392.87297) (xy 412.407645 -392.82666) (xy 412.438195 -392.784612)
			(xy 412.474946 -392.747861) (xy 412.516994 -392.717311) (xy 412.563304 -392.693715) (xy 412.612734 -392.677654)
			(xy 412.664069 -392.669524) (xy 412.716043 -392.669524) (xy 412.767378 -392.677654) (xy 412.816808 -392.693715)
			(xy 412.863118 -392.717311) (xy 412.905166 -392.747861) (xy 412.941917 -392.784612) (xy 412.972467 -392.82666)
			(xy 412.996063 -392.87297) (xy 413.012124 -392.9224) (xy 413.020254 -392.973735) (xy 413.020764 -392.999722)
			(xy 413.020254 -393.025709) (xy 413.560008 -393.025709) (xy 413.560008 -392.973735) (xy 413.568138 -392.9224)
			(xy 413.584199 -392.87297) (xy 413.607795 -392.82666) (xy 413.638345 -392.784612) (xy 413.675096 -392.747861)
			(xy 413.717144 -392.717311) (xy 413.763454 -392.693715) (xy 413.812884 -392.677654) (xy 413.864219 -392.669524)
			(xy 413.916193 -392.669524) (xy 413.967528 -392.677654) (xy 414.016958 -392.693715) (xy 414.063268 -392.717311)
			(xy 414.105316 -392.747861) (xy 414.142067 -392.784612) (xy 414.172617 -392.82666) (xy 414.196213 -392.87297)
			(xy 414.212274 -392.9224) (xy 414.220404 -392.973735) (xy 414.220914 -392.999722) (xy 414.220404 -393.025709)
			(xy 414.759904 -393.025709) (xy 414.759904 -392.973735) (xy 414.768034 -392.9224) (xy 414.784095 -392.87297)
			(xy 414.807691 -392.82666) (xy 414.838241 -392.784612) (xy 414.874992 -392.747861) (xy 414.91704 -392.717311)
			(xy 414.96335 -392.693715) (xy 415.01278 -392.677654) (xy 415.064115 -392.669524) (xy 415.116089 -392.669524)
			(xy 415.167424 -392.677654) (xy 415.216854 -392.693715) (xy 415.263164 -392.717311) (xy 415.305212 -392.747861)
			(xy 415.341963 -392.784612) (xy 415.372513 -392.82666) (xy 415.396109 -392.87297) (xy 415.41217 -392.9224)
			(xy 415.4203 -392.973735) (xy 415.42081 -392.999722) (xy 415.4203 -393.025709) (xy 415.9598 -393.025709)
			(xy 415.9598 -392.973735) (xy 415.96793 -392.9224) (xy 415.983991 -392.87297) (xy 416.007587 -392.82666)
			(xy 416.038137 -392.784612) (xy 416.074888 -392.747861) (xy 416.116936 -392.717311) (xy 416.163246 -392.693715)
			(xy 416.212676 -392.677654) (xy 416.264011 -392.669524) (xy 416.315985 -392.669524) (xy 416.36732 -392.677654)
			(xy 416.41675 -392.693715) (xy 416.46306 -392.717311) (xy 416.505108 -392.747861) (xy 416.541859 -392.784612)
			(xy 416.572409 -392.82666) (xy 416.596005 -392.87297) (xy 416.612066 -392.9224) (xy 416.620196 -392.973735)
			(xy 416.620706 -392.999722) (xy 416.620196 -393.025709) (xy 417.15995 -393.025709) (xy 417.15995 -392.973735)
			(xy 417.16808 -392.9224) (xy 417.184141 -392.87297) (xy 417.207737 -392.82666) (xy 417.238287 -392.784612)
			(xy 417.275038 -392.747861) (xy 417.317086 -392.717311) (xy 417.363396 -392.693715) (xy 417.412826 -392.677654)
			(xy 417.464161 -392.669524) (xy 417.516135 -392.669524) (xy 417.56747 -392.677654) (xy 417.6169 -392.693715)
			(xy 417.66321 -392.717311) (xy 417.705258 -392.747861) (xy 417.742009 -392.784612) (xy 417.772559 -392.82666)
			(xy 417.796155 -392.87297) (xy 417.812216 -392.9224) (xy 417.820346 -392.973735) (xy 417.820856 -392.999722)
			(xy 417.820346 -393.025709) (xy 418.359846 -393.025709) (xy 418.359846 -392.973735) (xy 418.367976 -392.9224)
			(xy 418.384037 -392.87297) (xy 418.407633 -392.82666) (xy 418.438183 -392.784612) (xy 418.474934 -392.747861)
			(xy 418.516982 -392.717311) (xy 418.563292 -392.693715) (xy 418.612722 -392.677654) (xy 418.664057 -392.669524)
			(xy 418.716031 -392.669524) (xy 418.767366 -392.677654) (xy 418.816796 -392.693715) (xy 418.863106 -392.717311)
			(xy 418.905154 -392.747861) (xy 418.941905 -392.784612) (xy 418.972455 -392.82666) (xy 418.996051 -392.87297)
			(xy 419.012112 -392.9224) (xy 419.020242 -392.973735) (xy 419.020752 -392.999722) (xy 419.020242 -393.025709)
			(xy 419.559996 -393.025709) (xy 419.559996 -392.973735) (xy 419.568126 -392.9224) (xy 419.584187 -392.87297)
			(xy 419.607783 -392.82666) (xy 419.638333 -392.784612) (xy 419.675084 -392.747861) (xy 419.717132 -392.717311)
			(xy 419.763442 -392.693715) (xy 419.812872 -392.677654) (xy 419.864207 -392.669524) (xy 419.916181 -392.669524)
			(xy 419.967516 -392.677654) (xy 420.016946 -392.693715) (xy 420.063256 -392.717311) (xy 420.105304 -392.747861)
			(xy 420.142055 -392.784612) (xy 420.172605 -392.82666) (xy 420.196201 -392.87297) (xy 420.212262 -392.9224)
			(xy 420.220392 -392.973735) (xy 420.220902 -392.999722) (xy 420.220392 -393.025709) (xy 420.759892 -393.025709)
			(xy 420.759892 -392.973735) (xy 420.768022 -392.9224) (xy 420.784083 -392.87297) (xy 420.807679 -392.82666)
			(xy 420.838229 -392.784612) (xy 420.87498 -392.747861) (xy 420.917028 -392.717311) (xy 420.963338 -392.693715)
			(xy 421.012768 -392.677654) (xy 421.064103 -392.669524) (xy 421.116077 -392.669524) (xy 421.167412 -392.677654)
			(xy 421.216842 -392.693715) (xy 421.263152 -392.717311) (xy 421.3052 -392.747861) (xy 421.341951 -392.784612)
			(xy 421.372501 -392.82666) (xy 421.396097 -392.87297) (xy 421.412158 -392.9224) (xy 421.420288 -392.973735)
			(xy 421.420798 -392.999722) (xy 421.420288 -393.025709) (xy 421.412158 -393.077044) (xy 421.396097 -393.126474)
			(xy 421.372501 -393.172784) (xy 421.341951 -393.214832) (xy 421.3052 -393.251583) (xy 421.263152 -393.282133)
			(xy 421.216842 -393.305729) (xy 421.167412 -393.32179) (xy 421.116077 -393.32992) (xy 421.064103 -393.32992)
			(xy 421.012768 -393.32179) (xy 420.963338 -393.305729) (xy 420.917028 -393.282133) (xy 420.87498 -393.251583)
			(xy 420.838229 -393.214832) (xy 420.807679 -393.172784) (xy 420.784083 -393.126474) (xy 420.768022 -393.077044)
			(xy 420.759892 -393.025709) (xy 420.220392 -393.025709) (xy 420.212262 -393.077044) (xy 420.196201 -393.126474)
			(xy 420.172605 -393.172784) (xy 420.142055 -393.214832) (xy 420.105304 -393.251583) (xy 420.063256 -393.282133)
			(xy 420.016946 -393.305729) (xy 419.967516 -393.32179) (xy 419.916181 -393.32992) (xy 419.864207 -393.32992)
			(xy 419.812872 -393.32179) (xy 419.763442 -393.305729) (xy 419.717132 -393.282133) (xy 419.675084 -393.251583)
			(xy 419.638333 -393.214832) (xy 419.607783 -393.172784) (xy 419.584187 -393.126474) (xy 419.568126 -393.077044)
			(xy 419.559996 -393.025709) (xy 419.020242 -393.025709) (xy 419.012112 -393.077044) (xy 418.996051 -393.126474)
			(xy 418.972455 -393.172784) (xy 418.941905 -393.214832) (xy 418.905154 -393.251583) (xy 418.863106 -393.282133)
			(xy 418.816796 -393.305729) (xy 418.767366 -393.32179) (xy 418.716031 -393.32992) (xy 418.664057 -393.32992)
			(xy 418.612722 -393.32179) (xy 418.563292 -393.305729) (xy 418.516982 -393.282133) (xy 418.474934 -393.251583)
			(xy 418.438183 -393.214832) (xy 418.407633 -393.172784) (xy 418.384037 -393.126474) (xy 418.367976 -393.077044)
			(xy 418.359846 -393.025709) (xy 417.820346 -393.025709) (xy 417.812216 -393.077044) (xy 417.796155 -393.126474)
			(xy 417.772559 -393.172784) (xy 417.742009 -393.214832) (xy 417.705258 -393.251583) (xy 417.66321 -393.282133)
			(xy 417.6169 -393.305729) (xy 417.56747 -393.32179) (xy 417.516135 -393.32992) (xy 417.464161 -393.32992)
			(xy 417.412826 -393.32179) (xy 417.363396 -393.305729) (xy 417.317086 -393.282133) (xy 417.275038 -393.251583)
			(xy 417.238287 -393.214832) (xy 417.207737 -393.172784) (xy 417.184141 -393.126474) (xy 417.16808 -393.077044)
			(xy 417.15995 -393.025709) (xy 416.620196 -393.025709) (xy 416.612066 -393.077044) (xy 416.596005 -393.126474)
			(xy 416.572409 -393.172784) (xy 416.541859 -393.214832) (xy 416.505108 -393.251583) (xy 416.46306 -393.282133)
			(xy 416.41675 -393.305729) (xy 416.36732 -393.32179) (xy 416.315985 -393.32992) (xy 416.264011 -393.32992)
			(xy 416.212676 -393.32179) (xy 416.163246 -393.305729) (xy 416.116936 -393.282133) (xy 416.074888 -393.251583)
			(xy 416.038137 -393.214832) (xy 416.007587 -393.172784) (xy 415.983991 -393.126474) (xy 415.96793 -393.077044)
			(xy 415.9598 -393.025709) (xy 415.4203 -393.025709) (xy 415.41217 -393.077044) (xy 415.396109 -393.126474)
			(xy 415.372513 -393.172784) (xy 415.341963 -393.214832) (xy 415.305212 -393.251583) (xy 415.263164 -393.282133)
			(xy 415.216854 -393.305729) (xy 415.167424 -393.32179) (xy 415.116089 -393.32992) (xy 415.064115 -393.32992)
			(xy 415.01278 -393.32179) (xy 414.96335 -393.305729) (xy 414.91704 -393.282133) (xy 414.874992 -393.251583)
			(xy 414.838241 -393.214832) (xy 414.807691 -393.172784) (xy 414.784095 -393.126474) (xy 414.768034 -393.077044)
			(xy 414.759904 -393.025709) (xy 414.220404 -393.025709) (xy 414.212274 -393.077044) (xy 414.196213 -393.126474)
			(xy 414.172617 -393.172784) (xy 414.142067 -393.214832) (xy 414.105316 -393.251583) (xy 414.063268 -393.282133)
			(xy 414.016958 -393.305729) (xy 413.967528 -393.32179) (xy 413.916193 -393.32992) (xy 413.864219 -393.32992)
			(xy 413.812884 -393.32179) (xy 413.763454 -393.305729) (xy 413.717144 -393.282133) (xy 413.675096 -393.251583)
			(xy 413.638345 -393.214832) (xy 413.607795 -393.172784) (xy 413.584199 -393.126474) (xy 413.568138 -393.077044)
			(xy 413.560008 -393.025709) (xy 413.020254 -393.025709) (xy 413.012124 -393.077044) (xy 412.996063 -393.126474)
			(xy 412.972467 -393.172784) (xy 412.941917 -393.214832) (xy 412.905166 -393.251583) (xy 412.863118 -393.282133)
			(xy 412.816808 -393.305729) (xy 412.767378 -393.32179) (xy 412.716043 -393.32992) (xy 412.664069 -393.32992)
			(xy 412.612734 -393.32179) (xy 412.563304 -393.305729) (xy 412.516994 -393.282133) (xy 412.474946 -393.251583)
			(xy 412.438195 -393.214832) (xy 412.407645 -393.172784) (xy 412.384049 -393.126474) (xy 412.367988 -393.077044)
			(xy 412.359858 -393.025709) (xy 411.820358 -393.025709) (xy 411.812228 -393.077044) (xy 411.796167 -393.126474)
			(xy 411.772571 -393.172784) (xy 411.742021 -393.214832) (xy 411.70527 -393.251583) (xy 411.663222 -393.282133)
			(xy 411.616912 -393.305729) (xy 411.567482 -393.32179) (xy 411.516147 -393.32992) (xy 411.464173 -393.32992)
			(xy 411.412838 -393.32179) (xy 411.363408 -393.305729) (xy 411.317098 -393.282133) (xy 411.27505 -393.251583)
			(xy 411.238299 -393.214832) (xy 411.207749 -393.172784) (xy 411.184153 -393.126474) (xy 411.168092 -393.077044)
			(xy 411.159962 -393.025709) (xy 410.620207 -393.025709) (xy 410.612074 -393.077041) (xy 410.596011 -393.126469)
			(xy 410.572414 -393.172776) (xy 410.541864 -393.214822) (xy 410.505113 -393.251572) (xy 410.463066 -393.28212)
			(xy 410.416758 -393.305715) (xy 410.367329 -393.321776) (xy 410.315996 -393.329908) (xy 410.29001 -393.33043)
			(xy 410.268004 -393.330087) (xy 410.224376 -393.324282) (xy 410.181906 -393.312733) (xy 410.161486 -393.304522)
			(xy 410.147262 -393.298426) (xy 410.117036 -393.304268) (xy 409.783534 -393.63777) (xy 409.775997 -393.646046)
			(xy 409.768298 -393.667035) (xy 409.770248 -393.689307) (xy 409.775406 -393.699238) (xy 410.020008 -394.122402)
			(xy 410.027374 -394.128244) (xy 410.046153 -394.144047) (xy 410.079289 -394.180254) (xy 410.106711 -394.220958)
			(xy 410.127819 -394.265267) (xy 410.142149 -394.312208) (xy 410.149387 -394.360752) (xy 410.149802 -394.385292)
			(xy 410.149548 -394.397484) (xy 410.149294 -394.407136) (xy 410.15539 -394.42517) (xy 410.214064 -394.49248)
			(xy 410.230828 -394.501116) (xy 410.24048 -394.502132) (xy 410.267249 -394.505457) (xy 410.31928 -394.519678)
			(xy 410.368314 -394.542154) (xy 410.41305 -394.572288) (xy 410.452305 -394.609282) (xy 410.485036 -394.652156)
			(xy 410.510377 -394.699772) (xy 410.527655 -394.750869) (xy 410.536414 -394.804092) (xy 410.536898 -394.831062)
			(xy 410.536335 -394.858344) (xy 410.527371 -394.912166) (xy 410.509696 -394.963787) (xy 410.483789 -395.011808)
			(xy 410.450353 -395.054927) (xy 410.430726 -395.073886) (xy 410.423278 -395.081378) (xy 410.41474 -395.100674)
			(xy 410.414216 -395.111224) (xy 410.414216 -395.1859) (xy 410.414807 -395.196433) (xy 410.423343 -395.215701)
			(xy 410.430726 -395.223238) (xy 410.450381 -395.24217) (xy 410.483824 -395.285291) (xy 410.509732 -395.333318)
			(xy 410.527401 -395.384947) (xy 410.536352 -395.438777) (xy 410.536898 -395.466062) (xy 410.536465 -395.49018)
			(xy 410.529469 -395.537905) (xy 410.51562 -395.584109) (xy 410.495212 -395.627814) (xy 410.482288 -395.64818)
			(xy 410.476446 -395.65707) (xy 410.47289 -395.677136) (xy 410.493972 -395.769338) (xy 410.506164 -395.786102)
			(xy 410.515054 -395.791436) (xy 410.535855 -395.804292) (xy 410.573769 -395.835171) (xy 410.606716 -395.871303)
			(xy 410.633977 -395.911897) (xy 410.654955 -395.956066) (xy 410.669192 -396.002846) (xy 410.676377 -396.051213)
			(xy 410.676852 -396.075662) (xy 410.676414 -396.100033) (xy 410.669259 -396.148246) (xy 410.655111 -396.194889)
			(xy 410.634276 -396.238953) (xy 410.607206 -396.279486) (xy 410.574485 -396.315612) (xy 410.555948 -396.33144)
			(xy 410.547058 -396.338552) (xy 410.53766 -396.35811) (xy 410.534866 -396.457424) (xy 410.543502 -396.47749)
			(xy 410.551884 -396.48511) (xy 410.569518 -396.501824) (xy 410.599778 -396.539835) (xy 410.62363 -396.582161)
			(xy 410.64047 -396.627734) (xy 410.64561 -396.65148) (xy 410.649166 -396.669514) (xy 410.677106 -396.692628)
			(xy 411.215332 -396.692628) (xy 411.243272 -396.669514) (xy 411.246828 -396.65148) (xy 411.252002 -396.627744)
			(xy 411.268853 -396.582182) (xy 411.292699 -396.53986) (xy 411.322942 -396.501843) (xy 411.340554 -396.48511)
			(xy 411.348936 -396.47749) (xy 411.357572 -396.457424) (xy 411.354778 -396.35811) (xy 411.34538 -396.338552)
			(xy 411.33649 -396.33144) (xy 411.317929 -396.315637) (xy 411.285204 -396.27951) (xy 411.258132 -396.238973)
			(xy 411.237299 -396.194903) (xy 411.223158 -396.148254) (xy 411.216012 -396.100035) (xy 411.215586 -396.075662)
			(xy 411.216025 -396.051546) (xy 411.22303 -396.003826) (xy 411.236887 -395.957627) (xy 411.257302 -395.913928)
			(xy 411.270196 -395.893544) (xy 411.276038 -395.884654) (xy 411.279594 -395.864588) (xy 411.258512 -395.772386)
			(xy 411.24632 -395.755622) (xy 411.23743 -395.750288) (xy 411.216629 -395.737432) (xy 411.178714 -395.706552)
			(xy 411.145766 -395.670421) (xy 411.118504 -395.629827) (xy 411.097524 -395.585658) (xy 411.083284 -395.538879)
			(xy 411.076096 -395.490511) (xy 411.075632 -395.466062) (xy 411.076193 -395.438779) (xy 411.085152 -395.384953)
			(xy 411.102822 -395.333327) (xy 411.128723 -395.285299) (xy 411.162153 -395.242172) (xy 411.181804 -395.223238)
			(xy 411.189252 -395.215746) (xy 411.197794 -395.196451) (xy 411.198314 -395.1859) (xy 411.198314 -395.111224)
			(xy 411.197728 -395.100688) (xy 411.189202 -395.08141) (xy 411.181804 -395.073886) (xy 411.162146 -395.054955)
			(xy 411.128697 -395.011836) (xy 411.102783 -394.96381) (xy 411.085109 -394.91218) (xy 411.076153 -394.858348)
			(xy 411.075632 -394.831062) (xy 411.075886 -394.81887) (xy 411.07614 -394.809218) (xy 411.070044 -394.791184)
			(xy 411.01137 -394.723874) (xy 410.994606 -394.715238) (xy 410.9847 -394.714222) (xy 410.957785 -394.710874)
			(xy 410.90548 -394.696534) (xy 410.856217 -394.673849) (xy 410.811318 -394.643427) (xy 410.771986 -394.606085)
			(xy 410.739277 -394.562824) (xy 410.714067 -394.514804) (xy 410.697034 -394.463314) (xy 410.692346 -394.4366)
			(xy 410.690822 -394.427202) (xy 410.418026 -393.95527) (xy 410.41066 -393.949428) (xy 410.39188 -393.933625)
			(xy 410.358745 -393.897419) (xy 410.331323 -393.856715) (xy 410.310216 -393.812405) (xy 410.295889 -393.765464)
			(xy 410.288654 -393.71692) (xy 410.288232 -393.69238) (xy 410.288717 -393.666393) (xy 410.296851 -393.615059)
			(xy 410.312915 -393.56563) (xy 410.336515 -393.519322) (xy 410.367068 -393.477277) (xy 410.403823 -393.440529)
			(xy 410.445874 -393.409983) (xy 410.492185 -393.386392) (xy 410.541618 -393.370337) (xy 410.592953 -393.362212)
			(xy 410.61894 -393.361672) (xy 410.644954 -393.362153) (xy 410.69634 -393.370292) (xy 410.745818 -393.386378)
			(xy 410.792166 -393.410015) (xy 410.834239 -393.44062) (xy 410.871001 -393.477436) (xy 410.901542 -393.519555)
			(xy 410.925111 -393.565938) (xy 410.941123 -393.61544) (xy 410.945584 -393.641072) (xy 410.947108 -393.65047)
			(xy 411.219904 -394.122402) (xy 411.22727 -394.128244) (xy 411.24605 -394.144047) (xy 411.279185 -394.180253)
			(xy 411.306608 -394.220958) (xy 411.327717 -394.265267) (xy 411.342047 -394.312208) (xy 411.349285 -394.360752)
			(xy 411.349698 -394.385292) (xy 411.349444 -394.397484) (xy 411.34919 -394.407136) (xy 411.355286 -394.42517)
			(xy 411.41396 -394.49248) (xy 411.430724 -394.501116) (xy 411.44063 -394.502132) (xy 411.467396 -394.50546)
			(xy 411.519421 -394.519688) (xy 411.568447 -394.542167) (xy 411.613177 -394.572303) (xy 411.652425 -394.609298)
			(xy 411.685151 -394.652169) (xy 411.710487 -394.699783) (xy 411.727762 -394.750876) (xy 411.736519 -394.804095)
			(xy 411.737048 -394.831062) (xy 411.736485 -394.858344) (xy 411.727522 -394.912167) (xy 411.709849 -394.963791)
			(xy 411.683945 -395.011814) (xy 411.650512 -395.054937) (xy 411.630876 -395.073886) (xy 411.623434 -395.081381)
			(xy 411.614904 -395.100676) (xy 411.614366 -395.111224) (xy 411.614366 -395.1859) (xy 411.614958 -395.196431)
			(xy 411.6235 -395.215694) (xy 411.630876 -395.223238) (xy 411.650529 -395.242172) (xy 411.683966 -395.285294)
			(xy 411.70987 -395.333321) (xy 411.727536 -395.38495) (xy 411.736486 -395.438778) (xy 411.737048 -395.466062)
			(xy 411.736615 -395.490179) (xy 411.729618 -395.537904) (xy 411.715768 -395.584107) (xy 411.695357 -395.62781)
			(xy 411.682438 -395.64818) (xy 411.676596 -395.65707) (xy 411.67304 -395.677136) (xy 411.694122 -395.769338)
			(xy 411.706314 -395.786102) (xy 411.715204 -395.791436) (xy 411.736007 -395.80429) (xy 411.773927 -395.835167)
			(xy 411.806879 -395.871297) (xy 411.834144 -395.911891) (xy 411.855126 -395.956061) (xy 411.869365 -396.002842)
			(xy 411.876552 -396.051212) (xy 411.877002 -396.075662) (xy 411.876564 -396.100032) (xy 411.869408 -396.148244)
			(xy 411.855258 -396.194886) (xy 411.834422 -396.238948) (xy 411.807349 -396.279479) (xy 411.774625 -396.315601)
			(xy 411.756098 -396.33144) (xy 411.747208 -396.338552) (xy 411.73781 -396.35811) (xy 411.735016 -396.457424)
			(xy 411.743652 -396.47749) (xy 411.752034 -396.48511) (xy 411.76967 -396.501823) (xy 411.799935 -396.539831)
			(xy 411.823791 -396.582157) (xy 411.840634 -396.62773) (xy 411.84576 -396.65148) (xy 411.849316 -396.669514)
			(xy 411.877256 -396.692628) (xy 412.415228 -396.692628) (xy 412.443168 -396.669514) (xy 412.446724 -396.65148)
			(xy 412.451898 -396.627744) (xy 412.468749 -396.582182) (xy 412.492595 -396.539859) (xy 412.522837 -396.501842)
			(xy 412.54045 -396.48511) (xy 412.548832 -396.47749) (xy 412.557468 -396.457424) (xy 412.554674 -396.35811)
			(xy 412.545276 -396.338552) (xy 412.536386 -396.33144) (xy 412.517826 -396.315637) (xy 412.4851 -396.27951)
			(xy 412.458029 -396.238973) (xy 412.437197 -396.194903) (xy 412.423055 -396.148254) (xy 412.41591 -396.100035)
			(xy 412.415482 -396.075662) (xy 412.415921 -396.051546) (xy 412.422926 -396.003825) (xy 412.436783 -395.957627)
			(xy 412.457197 -395.913928) (xy 412.470092 -395.893544) (xy 412.475934 -395.884654) (xy 412.47949 -395.864588)
			(xy 412.458408 -395.772386) (xy 412.446216 -395.755622) (xy 412.437326 -395.750288) (xy 412.416525 -395.737431)
			(xy 412.378611 -395.706552) (xy 412.345663 -395.67042) (xy 412.318401 -395.629827) (xy 412.297421 -395.585658)
			(xy 412.283182 -395.538879) (xy 412.275994 -395.490511) (xy 412.275528 -395.466062) (xy 412.276089 -395.43878)
			(xy 412.285051 -395.384956) (xy 412.302724 -395.333333) (xy 412.32863 -395.28531) (xy 412.362066 -395.24219)
			(xy 412.3817 -395.223238) (xy 412.389149 -395.215746) (xy 412.397692 -395.196451) (xy 412.39821 -395.1859)
			(xy 412.39821 -395.111224) (xy 412.397624 -395.100688) (xy 412.389097 -395.081411) (xy 412.3817 -395.073886)
			(xy 412.362042 -395.054955) (xy 412.328594 -395.011836) (xy 412.30268 -394.963809) (xy 412.285006 -394.912179)
			(xy 412.27605 -394.858348) (xy 412.275528 -394.831062) (xy 412.275782 -394.81887) (xy 412.276036 -394.809218)
			(xy 412.26994 -394.791184) (xy 412.211266 -394.723874) (xy 412.194502 -394.715238) (xy 412.184596 -394.714222)
			(xy 412.157681 -394.710874) (xy 412.105377 -394.696533) (xy 412.056114 -394.673848) (xy 412.011216 -394.643426)
			(xy 411.971884 -394.606084) (xy 411.939176 -394.562823) (xy 411.913966 -394.514803) (xy 411.896933 -394.463313)
			(xy 411.892242 -394.4366) (xy 411.890718 -394.427202) (xy 411.617668 -393.954762) (xy 411.610556 -393.94892)
			(xy 411.591823 -393.93314) (xy 411.558771 -393.896996) (xy 411.531413 -393.85637) (xy 411.51035 -393.812152)
			(xy 411.496042 -393.76531) (xy 411.488803 -393.716869) (xy 411.488382 -393.69238) (xy 411.488893 -393.666394)
			(xy 411.497026 -393.615061) (xy 411.513089 -393.565632) (xy 411.536685 -393.519325) (xy 411.567235 -393.477279)
			(xy 411.603986 -393.440529) (xy 411.646033 -393.40998) (xy 411.692342 -393.386385) (xy 411.741771 -393.370324)
			(xy 411.793104 -393.362192) (xy 411.81909 -393.361672) (xy 411.845138 -393.362151) (xy 411.896594 -393.370302)
			(xy 411.946135 -393.386418) (xy 411.992536 -393.410103) (xy 412.034651 -393.440769) (xy 412.071437 -393.477659)
			(xy 412.101984 -393.51986) (xy 412.125538 -393.566328) (xy 412.141515 -393.615914) (xy 412.145988 -393.64158)
			(xy 412.147258 -393.650978) (xy 412.171194 -393.69238) (xy 412.688278 -393.69238) (xy 412.688783 -393.666393)
			(xy 412.696916 -393.615059) (xy 412.712979 -393.565629) (xy 412.736576 -393.519321) (xy 412.767127 -393.477274)
			(xy 412.803878 -393.440523) (xy 412.845926 -393.409973) (xy 412.892235 -393.386377) (xy 412.941665 -393.370315)
			(xy 412.992999 -393.362183) (xy 413.018986 -393.361672) (xy 413.044996 -393.362154) (xy 413.096372 -393.370311)
			(xy 413.145838 -393.38641) (xy 413.192174 -393.410054) (xy 413.234237 -393.44066) (xy 413.270991 -393.477473)
			(xy 413.301528 -393.519586) (xy 413.325096 -393.56596) (xy 413.341115 -393.615453) (xy 413.34563 -393.641072)
			(xy 413.347154 -393.65047) (xy 413.61995 -394.122402) (xy 413.627316 -394.128244) (xy 413.646101 -394.144038)
			(xy 413.679217 -394.180257) (xy 413.706626 -394.220967) (xy 413.727725 -394.265276) (xy 413.742054 -394.312215)
			(xy 413.749299 -394.360754) (xy 413.749744 -394.385292) (xy 413.74949 -394.397484) (xy 413.749236 -394.407136)
			(xy 413.755332 -394.42517) (xy 413.814006 -394.49248) (xy 413.83077 -394.501116) (xy 413.840422 -394.502132)
			(xy 413.867186 -394.505473) (xy 413.91921 -394.519699) (xy 413.968235 -394.542177) (xy 414.012965 -394.572312)
			(xy 414.052212 -394.609304) (xy 414.084937 -394.652174) (xy 414.110273 -394.699786) (xy 414.127548 -394.750878)
			(xy 414.136305 -394.804095) (xy 414.13684 -394.831062) (xy 414.13633 -394.857049) (xy 414.1282 -394.908384)
			(xy 414.112139 -394.957814) (xy 414.088543 -395.004124) (xy 414.057993 -395.046172) (xy 414.021242 -395.082923)
			(xy 413.979194 -395.113473) (xy 413.932884 -395.137069) (xy 413.883454 -395.15313) (xy 413.832119 -395.16126)
			(xy 413.780145 -395.16126) (xy 413.72881 -395.15313) (xy 413.67938 -395.137069) (xy 413.63307 -395.113473)
			(xy 413.591022 -395.082923) (xy 413.554271 -395.046172) (xy 413.523721 -395.004124) (xy 413.500125 -394.957814)
			(xy 413.484064 -394.908384) (xy 413.475934 -394.857049) (xy 413.475424 -394.831062) (xy 413.475678 -394.81887)
			(xy 413.475932 -394.809218) (xy 413.469836 -394.791184) (xy 413.411162 -394.723874) (xy 413.394398 -394.715238)
			(xy 413.384746 -394.714222) (xy 413.357838 -394.710862) (xy 413.305552 -394.696496) (xy 413.256308 -394.673795)
			(xy 413.211426 -394.643368) (xy 413.172106 -394.606029) (xy 413.139402 -394.562778) (xy 413.114189 -394.514773)
			(xy 413.097142 -394.463298) (xy 413.092392 -394.4366) (xy 413.090868 -394.427202) (xy 412.818072 -393.95527)
			(xy 412.810706 -393.949428) (xy 412.791961 -393.93359) (xy 412.75884 -393.89738) (xy 412.731427 -393.85668)
			(xy 412.71032 -393.812379) (xy 412.695983 -393.765448) (xy 412.688729 -393.716916) (xy 412.688278 -393.69238)
			(xy 412.171194 -393.69238) (xy 412.4198 -394.122402) (xy 412.427166 -394.128244) (xy 412.445946 -394.144047)
			(xy 412.479082 -394.180253) (xy 412.506505 -394.220957) (xy 412.527614 -394.265266) (xy 412.541944 -394.312208)
			(xy 412.549182 -394.360752) (xy 412.549594 -394.385292) (xy 412.54934 -394.397484) (xy 412.549086 -394.407136)
			(xy 412.555182 -394.42517) (xy 412.613856 -394.49248) (xy 412.63062 -394.501116) (xy 412.640526 -394.502132)
			(xy 412.667293 -394.50546) (xy 412.719318 -394.519687) (xy 412.768345 -394.542166) (xy 412.813075 -394.572302)
			(xy 412.852323 -394.609296) (xy 412.885049 -394.652168) (xy 412.910386 -394.699782) (xy 412.927662 -394.750875)
			(xy 412.936419 -394.804095) (xy 412.936944 -394.831062) (xy 412.936381 -394.858344) (xy 412.927418 -394.912167)
			(xy 412.909745 -394.96379) (xy 412.88384 -395.011814) (xy 412.850407 -395.054936) (xy 412.830772 -395.073886)
			(xy 412.823331 -395.081381) (xy 412.814802 -395.100676) (xy 412.814262 -395.111224) (xy 412.814262 -395.1859)
			(xy 412.814854 -395.196432) (xy 412.823396 -395.215695) (xy 412.830772 -395.223238) (xy 412.850425 -395.242172)
			(xy 412.883863 -395.285294) (xy 412.909767 -395.333321) (xy 412.927434 -395.384949) (xy 412.936383 -395.438778)
			(xy 412.936944 -395.466062) (xy 412.936511 -395.49018) (xy 412.929516 -395.537905) (xy 412.915669 -395.58411)
			(xy 412.895263 -395.627817) (xy 412.882334 -395.64818) (xy 412.876492 -395.65707) (xy 412.872936 -395.677136)
			(xy 412.894018 -395.769338) (xy 412.90621 -395.786102) (xy 412.9151 -395.791436) (xy 412.935903 -395.80429)
			(xy 412.973823 -395.835166) (xy 413.006776 -395.871296) (xy 413.034041 -395.91189) (xy 413.055023 -395.956061)
			(xy 413.069263 -396.002842) (xy 413.07645 -396.051212) (xy 413.076898 -396.075662) (xy 413.076461 -396.100033)
			(xy 413.069305 -396.148247) (xy 413.055159 -396.194892) (xy 413.034327 -396.238958) (xy 413.007259 -396.279494)
			(xy 412.974541 -396.315623) (xy 412.955994 -396.33144) (xy 412.947104 -396.338552) (xy 412.937706 -396.35811)
			(xy 412.934912 -396.457424) (xy 412.943548 -396.47749) (xy 412.95193 -396.48511) (xy 412.969567 -396.501823)
			(xy 412.999832 -396.539831) (xy 413.023688 -396.582157) (xy 413.040531 -396.62773) (xy 413.045656 -396.65148)
			(xy 413.049212 -396.669514) (xy 413.077152 -396.692628) (xy 413.615124 -396.692628) (xy 413.643064 -396.669514)
			(xy 413.64662 -396.65148) (xy 413.651881 -396.627324) (xy 413.669155 -396.581005) (xy 413.693667 -396.538075)
			(xy 413.724776 -396.499655) (xy 413.76167 -396.466751) (xy 413.803383 -396.440222) (xy 413.848827 -396.420761)
			(xy 413.896813 -396.408877) (xy 413.946086 -396.404881) (xy 413.995359 -396.408877) (xy 414.043345 -396.420761)
			(xy 414.088789 -396.440222) (xy 414.130502 -396.466751) (xy 414.167396 -396.499655) (xy 414.198505 -396.538075)
			(xy 414.223017 -396.581005) (xy 414.240291 -396.627324) (xy 414.245552 -396.65148) (xy 414.249108 -396.669514)
			(xy 414.277048 -396.692628) (xy 414.521142 -396.692628) (xy 414.531209 -396.692198) (xy 414.549805 -396.684476)
			(xy 414.55721 -396.677642) (xy 414.721294 -396.513558) (xy 414.728135 -396.506157) (xy 414.735855 -396.487559)
			(xy 414.73628 -396.47749) (xy 414.73628 -396.27937) (xy 414.731454 -396.268956) (xy 414.717926 -396.238546)
			(xy 414.698821 -396.17479) (xy 414.689155 -396.10894) (xy 414.688528 -396.075662) (xy 414.689142 -396.042383)
			(xy 414.698813 -395.976532) (xy 414.717916 -395.912775) (xy 414.731454 -395.882368) (xy 414.73628 -395.871954)
			(xy 414.73628 -395.84884) (xy 414.726374 -395.82852) (xy 414.717484 -395.821154) (xy 414.69524 -395.802479)
			(xy 414.655182 -395.760422) (xy 414.620767 -395.713634) (xy 414.592547 -395.662869) (xy 414.570977 -395.608941)
			(xy 414.556404 -395.552718) (xy 414.54906 -395.495103) (xy 414.548574 -395.466062) (xy 414.549019 -395.437136)
			(xy 414.556312 -395.379746) (xy 414.570777 -395.323731) (xy 414.592183 -395.269986) (xy 414.62019 -395.219365)
			(xy 414.65435 -395.172676) (xy 414.694121 -395.130662) (xy 414.716214 -395.111986) (xy 414.72328 -395.105717)
			(xy 414.732552 -395.089274) (xy 414.734248 -395.079982) (xy 414.738566 -395.048994) (xy 414.739514 -395.039755)
			(xy 414.735484 -395.021642) (xy 414.730692 -395.013688) (xy 414.71766 -394.99329) (xy 414.697062 -394.949488)
			(xy 414.683076 -394.903148) (xy 414.676003 -394.855264) (xy 414.675574 -394.831062) (xy 414.675828 -394.81887)
			(xy 414.676082 -394.809218) (xy 414.669986 -394.791184) (xy 414.611312 -394.723874) (xy 414.594548 -394.715238)
			(xy 414.584642 -394.714222) (xy 414.55773 -394.71087) (xy 414.505432 -394.696523) (xy 414.456177 -394.673833)
			(xy 414.411286 -394.643409) (xy 414.371961 -394.606067) (xy 414.339259 -394.562807) (xy 414.314055 -394.51479)
			(xy 414.297025 -394.463303) (xy 414.292288 -394.4366) (xy 414.290764 -394.427202) (xy 414.017968 -393.95527)
			(xy 414.010602 -393.949428) (xy 413.991825 -393.933623) (xy 413.958695 -393.897415) (xy 413.931278 -393.85671)
			(xy 413.910175 -393.812401) (xy 413.89585 -393.765461) (xy 413.888617 -393.716919) (xy 413.888174 -393.69238)
			(xy 413.888685 -393.666393) (xy 413.896818 -393.61506) (xy 413.91288 -393.565631) (xy 413.936477 -393.519323)
			(xy 413.967027 -393.477276) (xy 414.003778 -393.440526) (xy 414.045825 -393.409976) (xy 414.092133 -393.38638)
			(xy 414.141562 -393.370317) (xy 414.192895 -393.362185) (xy 414.218882 -393.361672) (xy 414.244894 -393.362156)
			(xy 414.296275 -393.3703) (xy 414.345748 -393.386391) (xy 414.39209 -393.41003) (xy 414.434158 -393.440636)
			(xy 414.470914 -393.477452) (xy 414.501451 -393.519569) (xy 414.525015 -393.56595) (xy 414.541025 -393.615448)
			(xy 414.545526 -393.641072) (xy 414.54705 -393.65047) (xy 414.819846 -394.122402) (xy 414.827212 -394.128244)
			(xy 414.84599 -394.144048) (xy 414.879121 -394.180256) (xy 414.906541 -394.220961) (xy 414.927646 -394.26527)
			(xy 414.941974 -394.31221) (xy 414.949211 -394.360753) (xy 414.94964 -394.385292) (xy 414.949386 -394.397484)
			(xy 414.949132 -394.407136) (xy 414.955228 -394.42517) (xy 415.013902 -394.49248) (xy 415.030666 -394.501116)
			(xy 415.040572 -394.502132) (xy 415.067004 -394.505424) (xy 415.11841 -394.519365) (xy 415.166915 -394.541367)
			(xy 415.211267 -394.570859) (xy 415.250317 -394.607079) (xy 415.283056 -394.649091) (xy 415.308638 -394.695808)
			(xy 415.326399 -394.746022) (xy 415.331656 -394.772134) (xy 415.334958 -394.790422) (xy 415.363152 -394.81379)
			(xy 415.536126 -394.81379) (xy 415.546485 -394.813372) (xy 415.56556 -394.805301) (xy 415.579871 -394.790329)
			(xy 415.583878 -394.78077) (xy 415.62274 -394.67663) (xy 415.614866 -394.645896) (xy 415.602674 -394.635482)
			(xy 415.585373 -394.619984) (xy 415.554858 -394.584967) (xy 415.529543 -394.546023) (xy 415.509928 -394.50392)
			(xy 415.496398 -394.459487) (xy 415.492438 -394.4366) (xy 415.490914 -394.427202) (xy 415.218118 -393.95527)
			(xy 415.210752 -393.949428) (xy 415.191973 -393.933625) (xy 415.158838 -393.897419) (xy 415.131417 -393.856714)
			(xy 415.110311 -393.812405) (xy 415.095983 -393.765463) (xy 415.088749 -393.71692) (xy 415.088324 -393.69238)
			(xy 415.088809 -393.666393) (xy 415.096943 -393.615058) (xy 415.113007 -393.565629) (xy 415.136606 -393.51932)
			(xy 415.167159 -393.477274) (xy 415.203914 -393.440526) (xy 415.245965 -393.409979) (xy 415.292277 -393.386387)
			(xy 415.341709 -393.37033) (xy 415.393045 -393.362205) (xy 415.419032 -393.361672) (xy 415.445046 -393.362152)
			(xy 415.496434 -393.37029) (xy 415.545912 -393.386376) (xy 415.592261 -393.410013) (xy 415.634336 -393.440617)
			(xy 415.671098 -393.477433) (xy 415.701641 -393.519553) (xy 415.72521 -393.565936) (xy 415.741223 -393.615438)
			(xy 415.745676 -393.641072) (xy 415.7472 -393.65047) (xy 416.019996 -394.122402) (xy 416.027362 -394.128244)
			(xy 416.046142 -394.144047) (xy 416.079279 -394.180253) (xy 416.106702 -394.220957) (xy 416.127811 -394.265266)
			(xy 416.142142 -394.312208) (xy 416.149379 -394.360752) (xy 416.14979 -394.385292) (xy 416.149536 -394.397484)
			(xy 416.149282 -394.407136) (xy 416.155378 -394.42517) (xy 416.214052 -394.49248) (xy 416.230816 -394.501116)
			(xy 416.240468 -394.502132) (xy 416.2669 -394.505424) (xy 416.318306 -394.519364) (xy 416.366812 -394.541365)
			(xy 416.411165 -394.570858) (xy 416.450215 -394.607078) (xy 416.482955 -394.64909) (xy 416.508537 -394.695807)
			(xy 416.526299 -394.746021) (xy 416.531552 -394.772134) (xy 416.534854 -394.790422) (xy 416.563048 -394.81379)
			(xy 416.736022 -394.81379) (xy 416.74637 -394.813355) (xy 416.765413 -394.805264) (xy 416.779693 -394.790291)
			(xy 416.783774 -394.78077) (xy 416.822636 -394.67663) (xy 416.814762 -394.645896) (xy 416.80257 -394.635482)
			(xy 416.78527 -394.619984) (xy 416.754754 -394.584966) (xy 416.72944 -394.546023) (xy 416.709825 -394.50392)
			(xy 416.696295 -394.459487) (xy 416.692334 -394.4366) (xy 416.69081 -394.427202) (xy 416.418014 -393.95527)
			(xy 416.410648 -393.949428) (xy 416.391869 -393.933625) (xy 416.358735 -393.897419) (xy 416.331314 -393.856714)
			(xy 416.310208 -393.812405) (xy 416.295881 -393.765463) (xy 416.288647 -393.71692) (xy 416.28822 -393.69238)
			(xy 416.288705 -393.666393) (xy 416.296839 -393.615058) (xy 416.312903 -393.565628) (xy 416.336502 -393.51932)
			(xy 416.367055 -393.477273) (xy 416.40381 -393.440524) (xy 416.445861 -393.409977) (xy 416.492172 -393.386385)
			(xy 416.541605 -393.370327) (xy 416.59294 -393.362201) (xy 416.618928 -393.361672) (xy 416.644942 -393.362152)
			(xy 416.69633 -393.370289) (xy 416.74581 -393.386375) (xy 416.792159 -393.410011) (xy 416.834234 -393.440615)
			(xy 416.870997 -393.477432) (xy 416.90154 -393.519551) (xy 416.925109 -393.565935) (xy 416.941123 -393.615438)
			(xy 416.945572 -393.641072) (xy 416.947096 -393.65047) (xy 417.219892 -394.122402) (xy 417.227258 -394.128244)
			(xy 417.246038 -394.144047) (xy 417.279175 -394.180252) (xy 417.306599 -394.220957) (xy 417.327708 -394.265266)
			(xy 417.342039 -394.312208) (xy 417.349277 -394.360752) (xy 417.349686 -394.385292) (xy 417.349432 -394.397484)
			(xy 417.349178 -394.407136) (xy 417.355274 -394.42517) (xy 417.413948 -394.49248) (xy 417.430712 -394.501116)
			(xy 417.440618 -394.502132) (xy 417.467385 -394.50546) (xy 417.519411 -394.519686) (xy 417.568439 -394.542164)
			(xy 417.613171 -394.5723) (xy 417.65242 -394.609294) (xy 417.685147 -394.652166) (xy 417.710484 -394.69978)
			(xy 417.727761 -394.750874) (xy 417.736518 -394.804094) (xy 417.737036 -394.831062) (xy 417.736629 -394.854801)
			(xy 417.729843 -394.901791) (xy 417.716406 -394.947327) (xy 417.696594 -394.990473) (xy 417.670815 -395.030342)
			(xy 417.655502 -395.048486) (xy 417.649152 -395.055852) (xy 417.642802 -395.073632) (xy 417.645342 -395.15288)
			(xy 417.646091 -395.162476) (xy 417.653798 -395.180098) (xy 417.660328 -395.18717) (xy 418.34308 -395.869922)
			(xy 418.350938 -395.876982) (xy 418.370617 -395.884597) (xy 418.38118 -395.884654) (xy 418.467032 -395.880844)
			(xy 418.485574 -395.8717) (xy 418.492686 -395.863318) (xy 418.500814 -395.85392) (xy 418.48786 -395.797278)
			(xy 418.484715 -395.786344) (xy 418.470621 -395.76852) (xy 418.460682 -395.762988) (xy 418.437246 -395.750927)
			(xy 418.394203 -395.720514) (xy 418.356527 -395.68366) (xy 418.325171 -395.641298) (xy 418.300931 -395.5945)
			(xy 418.284417 -395.544449) (xy 418.27605 -395.492414) (xy 418.275516 -395.466062) (xy 418.276077 -395.43878)
			(xy 418.285038 -395.384956) (xy 418.302711 -395.333332) (xy 418.328617 -395.285309) (xy 418.362052 -395.242188)
			(xy 418.381688 -395.223238) (xy 418.389138 -395.215746) (xy 418.397683 -395.196451) (xy 418.398198 -395.1859)
			(xy 418.398198 -395.111224) (xy 418.397612 -395.100689) (xy 418.389084 -395.081413) (xy 418.381688 -395.073886)
			(xy 418.362031 -395.054955) (xy 418.328583 -395.011835) (xy 418.302671 -394.963809) (xy 418.284997 -394.912179)
			(xy 418.276042 -394.858348) (xy 418.275516 -394.831062) (xy 418.27577 -394.81887) (xy 418.276024 -394.809218)
			(xy 418.269928 -394.791184) (xy 418.211254 -394.723874) (xy 418.19449 -394.715238) (xy 418.184584 -394.714222)
			(xy 418.157669 -394.710873) (xy 418.105367 -394.696531) (xy 418.056106 -394.673845) (xy 418.011209 -394.643422)
			(xy 417.971879 -394.60608) (xy 417.939172 -394.562819) (xy 417.913964 -394.5148) (xy 417.896931 -394.463311)
			(xy 417.89223 -394.4366) (xy 417.890706 -394.427202) (xy 417.617656 -393.954762) (xy 417.610544 -393.94892)
			(xy 417.591812 -393.93314) (xy 417.55876 -393.896995) (xy 417.531404 -393.856369) (xy 417.510341 -393.812151)
			(xy 417.496034 -393.765309) (xy 417.488795 -393.716869) (xy 417.48837 -393.69238) (xy 417.488881 -393.666393)
			(xy 417.497014 -393.61506) (xy 417.513076 -393.565631) (xy 417.536673 -393.519322) (xy 417.567223 -393.477275)
			(xy 417.603973 -393.440524) (xy 417.646021 -393.409974) (xy 417.692329 -393.386377) (xy 417.741758 -393.370314)
			(xy 417.793091 -393.362181) (xy 417.819078 -393.361672) (xy 417.845127 -393.36215) (xy 417.896584 -393.370299)
			(xy 417.946126 -393.386415) (xy 417.992529 -393.410099) (xy 418.034646 -393.440765) (xy 418.071433 -393.477654)
			(xy 418.101982 -393.519856) (xy 418.125537 -393.566325) (xy 418.141515 -393.615912) (xy 418.145976 -393.64158)
			(xy 418.147246 -393.650978) (xy 418.419788 -394.122402) (xy 418.427154 -394.128244) (xy 418.445934 -394.144047)
			(xy 418.479072 -394.180252) (xy 418.506496 -394.220956) (xy 418.527605 -394.265266) (xy 418.541936 -394.312207)
			(xy 418.549174 -394.360752) (xy 418.549582 -394.385292) (xy 418.549328 -394.397484) (xy 418.549074 -394.407136)
			(xy 418.55517 -394.42517) (xy 418.613844 -394.49248) (xy 418.630608 -394.501116) (xy 418.640514 -394.502132)
			(xy 418.667281 -394.505459) (xy 418.719308 -394.519685) (xy 418.768337 -394.542163) (xy 418.813069 -394.572299)
			(xy 418.852319 -394.609293) (xy 418.885046 -394.652165) (xy 418.910384 -394.699779) (xy 418.92766 -394.750874)
			(xy 418.936417 -394.804094) (xy 418.936932 -394.831062) (xy 418.936369 -394.858344) (xy 418.927406 -394.912167)
			(xy 418.909732 -394.96379) (xy 418.883827 -395.011812) (xy 418.850393 -395.054934) (xy 418.83076 -395.073886)
			(xy 418.82332 -395.081382) (xy 418.814793 -395.100676) (xy 418.81425 -395.111224) (xy 418.81425 -395.1859)
			(xy 418.814842 -395.196432) (xy 418.823382 -395.215696) (xy 418.83076 -395.223238) (xy 418.850413 -395.242171)
			(xy 418.883853 -395.285293) (xy 418.909758 -395.33332) (xy 418.927425 -395.384949) (xy 418.936375 -395.438778)
			(xy 418.936932 -395.466062) (xy 418.936499 -395.49018) (xy 418.929504 -395.537905) (xy 418.915656 -395.58411)
			(xy 418.89525 -395.627816) (xy 418.882322 -395.64818) (xy 418.87648 -395.65707) (xy 418.872924 -395.677136)
			(xy 418.894006 -395.769338) (xy 418.906198 -395.786102) (xy 418.915088 -395.791436) (xy 418.935892 -395.80429)
			(xy 418.973813 -395.835165) (xy 419.006767 -395.871295) (xy 419.034033 -395.911889) (xy 419.055016 -395.956059)
			(xy 419.069257 -396.002841) (xy 419.076443 -396.051211) (xy 419.076886 -396.075662) (xy 419.076417 -396.100856)
			(xy 419.068786 -396.150662) (xy 419.053693 -396.198736) (xy 419.031488 -396.243967) (xy 419.01745 -396.264892)
			(xy 419.009322 -396.276576) (xy 419.00729 -396.30477) (xy 419.05555 -396.397226) (xy 419.060177 -396.405307)
			(xy 419.074057 -396.417695) (xy 419.091458 -396.42428) (xy 419.100762 -396.424658) (xy 419.591744 -396.424658)
			(xy 419.601042 -396.424248) (xy 419.618424 -396.417642) (xy 419.632336 -396.405302) (xy 419.636956 -396.397226)
			(xy 419.685216 -396.30477) (xy 419.683184 -396.276576) (xy 419.675056 -396.264892) (xy 419.661042 -396.243953)
			(xy 419.638839 -396.198726) (xy 419.623747 -396.150656) (xy 419.616116 -396.100854) (xy 419.61562 -396.075662)
			(xy 419.616059 -396.051546) (xy 419.623065 -396.003826) (xy 419.636923 -395.957628) (xy 419.65734 -395.913931)
			(xy 419.67023 -395.893544) (xy 419.676072 -395.884654) (xy 419.679628 -395.864588) (xy 419.658546 -395.772386)
			(xy 419.646354 -395.755622) (xy 419.637464 -395.750288) (xy 419.616661 -395.737433) (xy 419.578743 -395.706555)
			(xy 419.545791 -395.670425) (xy 419.518526 -395.629831) (xy 419.497544 -395.585662) (xy 419.483302 -395.538881)
			(xy 419.476113 -395.490512) (xy 419.475666 -395.466062) (xy 419.476227 -395.438779) (xy 419.485187 -395.384954)
			(xy 419.502858 -395.333329) (xy 419.528761 -395.285303) (xy 419.562193 -395.242179) (xy 419.581838 -395.223238)
			(xy 419.589282 -395.215744) (xy 419.597818 -395.196449) (xy 419.598348 -395.1859) (xy 419.598348 -395.111224)
			(xy 419.59776 -395.10069) (xy 419.589226 -395.081419) (xy 419.581838 -395.073886) (xy 419.562183 -395.054953)
			(xy 419.528741 -395.011832) (xy 419.502833 -394.963805) (xy 419.485162 -394.912176) (xy 419.476208 -394.858347)
			(xy 419.475666 -394.831062) (xy 419.47592 -394.81887) (xy 419.476174 -394.809218) (xy 419.470078 -394.791184)
			(xy 419.411404 -394.723874) (xy 419.39464 -394.715238) (xy 419.384734 -394.714222) (xy 419.357822 -394.710869)
			(xy 419.305525 -394.696521) (xy 419.256272 -394.673831) (xy 419.211381 -394.643407) (xy 419.172058 -394.606064)
			(xy 419.139356 -394.562804) (xy 419.114153 -394.514788) (xy 419.097124 -394.463302) (xy 419.09238 -394.4366)
			(xy 419.090856 -394.427202) (xy 418.81806 -393.95527) (xy 418.810694 -393.949428) (xy 418.791918 -393.933623)
			(xy 418.758788 -393.897415) (xy 418.731372 -393.85671) (xy 418.71027 -393.812401) (xy 418.695945 -393.76546)
			(xy 418.688712 -393.716919) (xy 418.688266 -393.69238) (xy 418.688777 -393.666393) (xy 418.69691 -393.61506)
			(xy 418.712972 -393.56563) (xy 418.736569 -393.519321) (xy 418.767118 -393.477274) (xy 418.803869 -393.440522)
			(xy 418.845916 -393.409972) (xy 418.892224 -393.386375) (xy 418.941654 -393.370311) (xy 418.992987 -393.362177)
			(xy 419.018974 -393.361672) (xy 419.044986 -393.362155) (xy 419.096369 -393.370298) (xy 419.145842 -393.386388)
			(xy 419.192185 -393.410027) (xy 419.234254 -393.440633) (xy 419.271012 -393.477449) (xy 419.301549 -393.519567)
			(xy 419.325114 -393.565948) (xy 419.341125 -393.615447) (xy 419.345618 -393.641072) (xy 419.347142 -393.65047)
			(xy 419.619938 -394.122402) (xy 419.627304 -394.128244) (xy 419.646082 -394.144048) (xy 419.679214 -394.180256)
			(xy 419.706635 -394.22096) (xy 419.727741 -394.265269) (xy 419.742069 -394.31221) (xy 419.749306 -394.360752)
			(xy 419.749732 -394.385292) (xy 419.749478 -394.397484) (xy 419.749224 -394.407136) (xy 419.75532 -394.42517)
			(xy 419.813994 -394.49248) (xy 419.830758 -394.501116) (xy 419.840664 -394.502132) (xy 419.867434 -394.505456)
			(xy 419.919467 -394.519675) (xy 419.968503 -394.54215) (xy 420.013242 -394.572284) (xy 420.052498 -394.609278)
			(xy 420.085231 -394.652151) (xy 420.110573 -394.699768) (xy 420.127853 -394.750867) (xy 420.136612 -394.804092)
			(xy 420.137082 -394.831062) (xy 420.136519 -394.858344) (xy 420.127554 -394.912165) (xy 420.109879 -394.963786)
			(xy 420.083971 -395.011807) (xy 420.050534 -395.054924) (xy 420.03091 -395.073886) (xy 420.023464 -395.081379)
			(xy 420.014929 -395.100674) (xy 420.0144 -395.111224) (xy 420.0144 -395.1859) (xy 420.014991 -395.196433)
			(xy 420.023525 -395.215703) (xy 420.03091 -395.223238) (xy 420.050566 -395.24217) (xy 420.08401 -395.28529)
			(xy 420.109919 -395.333317) (xy 420.127589 -395.384946) (xy 420.136541 -395.438777) (xy 420.137082 -395.466062)
			(xy 420.136649 -395.490179) (xy 420.129653 -395.537904) (xy 420.115804 -395.584108) (xy 420.095394 -395.627813)
			(xy 420.082472 -395.64818) (xy 420.07663 -395.65707) (xy 420.073074 -395.677136) (xy 420.094156 -395.769338)
			(xy 420.106348 -395.786102) (xy 420.115238 -395.791436) (xy 420.136039 -395.804292) (xy 420.173955 -395.83517)
			(xy 420.206904 -395.871301) (xy 420.234166 -395.911895) (xy 420.255146 -395.956065) (xy 420.269384 -396.002845)
			(xy 420.276569 -396.051212) (xy 420.277036 -396.075662) (xy 420.276567 -396.100856) (xy 420.268934 -396.150661)
			(xy 420.25384 -396.198734) (xy 420.231632 -396.243963) (xy 420.2176 -396.264892) (xy 420.209472 -396.276576)
			(xy 420.20744 -396.30477) (xy 420.2557 -396.397226) (xy 420.260325 -396.405312) (xy 420.274203 -396.417714)
			(xy 420.291605 -396.424316) (xy 420.300912 -396.424658) (xy 420.79164 -396.424658) (xy 420.800928 -396.424233)
			(xy 420.818285 -396.417605) (xy 420.832169 -396.40526) (xy 420.836852 -396.397226) (xy 420.885112 -396.30477)
			(xy 420.88308 -396.276576) (xy 420.874952 -396.264892) (xy 420.860938 -396.243953) (xy 420.838735 -396.198726)
			(xy 420.823644 -396.150656) (xy 420.816013 -396.100854) (xy 420.815516 -396.075662) (xy 420.815955 -396.051546)
			(xy 420.822961 -396.003826) (xy 420.836819 -395.957628) (xy 420.857235 -395.91393) (xy 420.870126 -395.893544)
			(xy 420.875968 -395.884654) (xy 420.879524 -395.864588) (xy 420.858442 -395.772386) (xy 420.84625 -395.755622)
			(xy 420.83736 -395.750288) (xy 420.816558 -395.737433) (xy 420.77864 -395.706555) (xy 420.745688 -395.670424)
			(xy 420.718423 -395.629831) (xy 420.697441 -395.585661) (xy 420.6832 -395.538881) (xy 420.676011 -395.490512)
			(xy 420.675562 -395.466062) (xy 420.676123 -395.438779) (xy 420.685083 -395.384954) (xy 420.702754 -395.333329)
			(xy 420.728656 -395.285303) (xy 420.762088 -395.242178) (xy 420.781734 -395.223238) (xy 420.789178 -395.215744)
			(xy 420.797715 -395.196449) (xy 420.798244 -395.1859) (xy 420.798244 -395.111224) (xy 420.797656 -395.10069)
			(xy 420.789122 -395.08142) (xy 420.781734 -395.073886) (xy 420.762079 -395.054953) (xy 420.728637 -395.011832)
			(xy 420.70273 -394.963805) (xy 420.685059 -394.912176) (xy 420.676105 -394.858347) (xy 420.675562 -394.831062)
			(xy 420.675816 -394.81887) (xy 420.67607 -394.809218) (xy 420.669974 -394.791184) (xy 420.6113 -394.723874)
			(xy 420.594536 -394.715238) (xy 420.58463 -394.714222) (xy 420.557718 -394.710869) (xy 420.505422 -394.696521)
			(xy 420.456169 -394.67383) (xy 420.411279 -394.643405) (xy 420.371956 -394.606063) (xy 420.339255 -394.562803)
			(xy 420.314052 -394.514787) (xy 420.297023 -394.463301) (xy 420.292276 -394.4366) (xy 420.290752 -394.427202)
			(xy 420.017702 -393.954762) (xy 420.01059 -393.94892) (xy 419.991856 -393.933141) (xy 419.9588 -393.896998)
			(xy 419.931439 -393.856373) (xy 419.910374 -393.812154) (xy 419.896064 -393.765311) (xy 419.888825 -393.71687)
			(xy 419.888416 -393.69238) (xy 419.888901 -393.666392) (xy 419.897035 -393.615058) (xy 419.913099 -393.565627)
			(xy 419.936698 -393.519319) (xy 419.967251 -393.477272) (xy 420.004005 -393.440522) (xy 420.046056 -393.409975)
			(xy 420.092368 -393.386382) (xy 420.141801 -393.370324) (xy 420.193136 -393.362197) (xy 420.219124 -393.361672)
			(xy 420.245171 -393.362154) (xy 420.296622 -393.370308) (xy 420.346159 -393.386428) (xy 420.392556 -393.410115)
			(xy 420.434666 -393.440782) (xy 420.471448 -393.477671) (xy 420.501991 -393.519871) (xy 420.525542 -393.566337)
			(xy 420.541517 -393.615921) (xy 420.546022 -393.64158) (xy 420.547292 -393.650978) (xy 420.571228 -393.69238)
			(xy 421.088312 -393.69238) (xy 421.088783 -393.666391) (xy 421.096917 -393.615054) (xy 421.112982 -393.565622)
			(xy 421.136582 -393.519311) (xy 421.167137 -393.477262) (xy 421.203892 -393.44051) (xy 421.245945 -393.409961)
			(xy 421.292259 -393.386367) (xy 421.341693 -393.370308) (xy 421.393031 -393.36218) (xy 421.41902 -393.361672)
			(xy 421.445031 -393.362123) (xy 421.496408 -393.370285) (xy 421.545875 -393.386389) (xy 421.592211 -393.410037)
			(xy 421.634274 -393.440647) (xy 421.671027 -393.477464) (xy 421.701564 -393.51958) (xy 421.707542 -393.531344)
			(xy 423.057066 -393.531344) (xy 423.057503 -393.506448) (xy 423.064954 -393.457218) (xy 423.079693 -393.409658)
			(xy 423.101388 -393.364842) (xy 423.129551 -393.323781) (xy 423.14622 -393.305284) (xy 423.152824 -393.298426)
			(xy 423.159682 -393.281408) (xy 423.161968 -393.195048) (xy 423.155872 -393.177522) (xy 423.149776 -393.17041)
			(xy 423.135018 -393.152415) (xy 423.110187 -393.113055) (xy 423.091123 -393.0706) (xy 423.078203 -393.025891)
			(xy 423.071683 -392.979811) (xy 423.07129 -392.956542) (xy 423.0718 -392.930555) (xy 423.07993 -392.87922)
			(xy 423.095991 -392.82979) (xy 423.119587 -392.78348) (xy 423.150137 -392.741432) (xy 423.186888 -392.704681)
			(xy 423.228936 -392.674131) (xy 423.275246 -392.650535) (xy 423.324676 -392.634474) (xy 423.376011 -392.626344)
			(xy 423.427985 -392.626344) (xy 423.47932 -392.634474) (xy 423.52875 -392.650535) (xy 423.57506 -392.674131)
			(xy 423.617108 -392.704681) (xy 423.653859 -392.741432) (xy 423.684409 -392.78348) (xy 423.708005 -392.82979)
			(xy 423.724066 -392.87922) (xy 423.732196 -392.930555) (xy 423.732706 -392.956542) (xy 423.732268 -392.981438)
			(xy 423.724819 -393.030669) (xy 423.71008 -393.078229) (xy 423.688385 -393.123045) (xy 423.660222 -393.164106)
			(xy 423.643552 -393.182602) (xy 423.636948 -393.18946) (xy 423.63009 -393.206478) (xy 423.627804 -393.292838)
			(xy 423.6339 -393.310364) (xy 423.639996 -393.317476) (xy 423.657617 -393.339139) (xy 423.686071 -393.387182)
			(xy 423.706074 -393.439314) (xy 423.712132 -393.466574) (xy 423.71391 -393.475718) (xy 423.723816 -393.491466)
			(xy 423.79265 -393.543536) (xy 423.81043 -393.548616) (xy 423.819828 -393.547854) (xy 423.850562 -393.546584)
			(xy 423.878331 -393.547088) (xy 423.933285 -393.555118) (xy 423.960036 -393.562586) (xy 423.969434 -393.56538)
			(xy 423.988738 -393.563856) (xy 424.068494 -393.523978) (xy 424.081194 -393.5095) (xy 424.08475 -393.50061)
			(xy 424.095683 -393.472474) (xy 424.125141 -393.419789) (xy 424.16252 -393.372394) (xy 424.184318 -393.351512)
			(xy 424.191719 -393.34399) (xy 424.200243 -393.32471) (xy 424.200828 -393.314174) (xy 424.200828 -393.239498)
			(xy 424.200305 -393.228948) (xy 424.191765 -393.209653) (xy 424.184318 -393.20216) (xy 424.165223 -393.184041)
			(xy 424.131745 -393.143418) (xy 424.104177 -393.098574) (xy 424.083041 -393.050363) (xy 424.06874 -392.999703)
			(xy 424.061546 -392.947557) (xy 424.061128 -392.921236) (xy 424.061614 -392.893985) (xy 424.06937 -392.840037)
			(xy 424.084725 -392.787742) (xy 424.107367 -392.738165) (xy 424.136833 -392.692315) (xy 424.172524 -392.651124)
			(xy 424.213715 -392.615433) (xy 424.259565 -392.585967) (xy 424.309142 -392.563325) (xy 424.361437 -392.54797)
			(xy 424.415385 -392.540214) (xy 424.469887 -392.540214) (xy 424.523835 -392.54797) (xy 424.57613 -392.563325)
			(xy 424.625707 -392.585967) (xy 424.671557 -392.615433) (xy 424.712748 -392.651124) (xy 424.748439 -392.692315)
			(xy 424.777905 -392.738165) (xy 424.800547 -392.787742) (xy 424.815902 -392.840037) (xy 424.823658 -392.893985)
			(xy 424.824144 -392.921236) (xy 424.823681 -392.947551) (xy 424.816461 -392.999685) (xy 424.802149 -393.050332)
			(xy 424.781016 -393.098534) (xy 424.753463 -393.143376) (xy 424.720013 -393.184009) (xy 424.700954 -393.20216)
			(xy 424.693576 -393.209702) (xy 424.685036 -393.228966) (xy 424.684444 -393.239498) (xy 424.684444 -393.314174)
			(xy 424.684961 -393.324725) (xy 424.693503 -393.344021) (xy 424.700954 -393.351512) (xy 424.72003 -393.36965)
			(xy 424.75351 -393.410269) (xy 424.781083 -393.455108) (xy 424.802222 -393.503315) (xy 424.816526 -393.553973)
			(xy 424.823724 -393.606116) (xy 424.824144 -393.632436) (xy 424.823713 -393.659808) (xy 424.815889 -393.713989)
			(xy 424.800392 -393.766493) (xy 424.777542 -393.816239) (xy 424.747809 -393.862204) (xy 424.730164 -393.883134)
			(xy 424.724068 -393.890246) (xy 424.717718 -393.907264) (xy 424.717718 -393.992608) (xy 424.724068 -394.009626)
			(xy 424.730164 -394.016738) (xy 424.74784 -394.037642) (xy 424.777564 -394.083615) (xy 424.800408 -394.133366)
			(xy 424.815902 -394.185872) (xy 424.823727 -394.240055) (xy 424.823724 -394.2948) (xy 424.81589 -394.348981)
			(xy 424.800389 -394.401485) (xy 424.777538 -394.451233) (xy 424.747808 -394.497201) (xy 424.730164 -394.518134)
			(xy 424.724068 -394.525246) (xy 424.717718 -394.542264) (xy 424.717718 -394.627608) (xy 424.724068 -394.644626)
			(xy 424.730164 -394.651738) (xy 424.74784 -394.672642) (xy 424.777564 -394.718615) (xy 424.800408 -394.768366)
			(xy 424.815902 -394.820872) (xy 424.823727 -394.875055) (xy 424.823724 -394.9298) (xy 424.81589 -394.983981)
			(xy 424.800389 -395.036485) (xy 424.777538 -395.086233) (xy 424.747808 -395.132201) (xy 424.736801 -395.14526)
			(xy 426.479714 -395.14526) (xy 426.483785 -395.089638) (xy 426.495911 -395.035201) (xy 426.515834 -394.98311)
			(xy 426.54313 -394.934475) (xy 426.577216 -394.890332) (xy 426.617365 -394.851623) (xy 426.662723 -394.819172)
			(xy 426.712323 -394.793671) (xy 426.765107 -394.775664) (xy 426.81995 -394.765534) (xy 426.875684 -394.763497)
			(xy 426.931121 -394.769597) (xy 426.985078 -394.783703) (xy 427.036407 -394.805515) (xy 427.084013 -394.834569)
			(xy 427.126881 -394.870244) (xy 427.164098 -394.911781) (xy 427.194871 -394.958294) (xy 427.218543 -395.008791)
			(xy 427.234611 -395.062198) (xy 427.242731 -395.117374) (xy 427.24324 -395.14526) (xy 427.242731 -395.173146)
			(xy 427.234611 -395.228322) (xy 427.218543 -395.281729) (xy 427.194871 -395.332226) (xy 427.164098 -395.378739)
			(xy 427.126881 -395.420276) (xy 427.084013 -395.455951) (xy 427.036407 -395.485005) (xy 426.985078 -395.506817)
			(xy 426.931121 -395.520923) (xy 426.875684 -395.527023) (xy 426.81995 -395.524986) (xy 426.765107 -395.514856)
			(xy 426.712323 -395.496849) (xy 426.662723 -395.471348) (xy 426.617365 -395.438897) (xy 426.577216 -395.400188)
			(xy 426.54313 -395.356045) (xy 426.515834 -395.30741) (xy 426.495911 -395.255319) (xy 426.483785 -395.200882)
			(xy 426.479714 -395.14526) (xy 424.736801 -395.14526) (xy 424.730164 -395.153134) (xy 424.724068 -395.160246)
			(xy 424.717718 -395.177264) (xy 424.717718 -395.262608) (xy 424.724068 -395.279626) (xy 424.730164 -395.286738)
			(xy 424.747782 -395.307687) (xy 424.777498 -395.353655) (xy 424.800339 -395.403398) (xy 424.815835 -395.455895)
			(xy 424.823668 -395.510068) (xy 424.824144 -395.537436) (xy 424.823658 -395.564687) (xy 424.815902 -395.618635)
			(xy 424.800547 -395.67093) (xy 424.777905 -395.720507) (xy 424.748439 -395.766357) (xy 424.712748 -395.807548)
			(xy 424.671557 -395.843239) (xy 424.625707 -395.872705) (xy 424.57613 -395.895347) (xy 424.523835 -395.910702)
			(xy 424.469887 -395.918458) (xy 424.415385 -395.918458) (xy 424.361437 -395.910702) (xy 424.309142 -395.895347)
			(xy 424.259565 -395.872705) (xy 424.213715 -395.843239) (xy 424.172524 -395.807548) (xy 424.136833 -395.766357)
			(xy 424.107367 -395.720507) (xy 424.084725 -395.67093) (xy 424.06937 -395.618635) (xy 424.061614 -395.564687)
			(xy 424.061128 -395.537436) (xy 424.061608 -395.510066) (xy 424.069422 -395.455887) (xy 424.084907 -395.403384)
			(xy 424.107746 -395.353637) (xy 424.137468 -395.30767) (xy 424.155108 -395.286738) (xy 424.161204 -395.279626)
			(xy 424.167554 -395.262608) (xy 424.167554 -395.177264) (xy 424.161204 -395.160246) (xy 424.155108 -395.153134)
			(xy 424.133266 -395.126945) (xy 424.098254 -395.068434) (xy 424.085512 -395.036802) (xy 424.08221 -395.028166)
			(xy 424.070272 -395.01445) (xy 423.994834 -394.974064) (xy 423.9768 -394.971524) (xy 423.967656 -394.97381)
			(xy 423.946546 -394.978332) (xy 423.903645 -394.983174) (xy 423.882058 -394.983462) (xy 423.854802 -394.983084)
			(xy 423.800846 -394.97532) (xy 423.748543 -394.959956) (xy 423.69896 -394.937306) (xy 423.653105 -394.907829)
			(xy 423.611911 -394.872126) (xy 423.576218 -394.830925) (xy 423.546752 -394.785063) (xy 423.524113 -394.735474)
			(xy 423.508761 -394.683168) (xy 423.50101 -394.62921) (xy 423.50055 -394.601954) (xy 423.501053 -394.574245)
			(xy 423.509081 -394.519411) (xy 423.524962 -394.466317) (xy 423.54836 -394.416081) (xy 423.578783 -394.36976)
			(xy 423.596816 -394.348716) (xy 423.60342 -394.341096) (xy 423.610024 -394.322554) (xy 423.605706 -394.231622)
			(xy 423.597578 -394.213842) (xy 423.590212 -394.206984) (xy 423.569745 -394.187121) (xy 423.534322 -394.142423)
			(xy 423.505943 -394.092952) (xy 423.48524 -394.039811) (xy 423.472674 -393.98418) (xy 423.47007 -393.955778)
			(xy 423.469308 -393.94638) (xy 423.461434 -393.929616) (xy 423.399712 -393.869418) (xy 423.382694 -393.862052)
			(xy 423.373296 -393.861798) (xy 423.348078 -393.860219) (xy 423.298526 -393.850339) (xy 423.251053 -393.833039)
			(xy 423.206762 -393.808721) (xy 423.166684 -393.777952) (xy 423.131751 -393.741446) (xy 423.102775 -393.700053)
			(xy 423.080431 -393.654735) (xy 423.065237 -393.606546) (xy 423.057547 -393.556608) (xy 423.057066 -393.531344)
			(xy 421.707542 -393.531344) (xy 421.725131 -393.565957) (xy 421.741149 -393.615451) (xy 421.745664 -393.641072)
			(xy 421.747188 -393.65047) (xy 422.019984 -394.122402) (xy 422.02735 -394.128244) (xy 422.046142 -394.144029)
			(xy 422.079256 -394.180251) (xy 422.106663 -394.220963) (xy 422.127761 -394.265274) (xy 422.142089 -394.312213)
			(xy 422.149333 -394.360753) (xy 422.149778 -394.385292) (xy 422.149524 -394.396976) (xy 422.14927 -394.406882)
			(xy 422.15562 -394.424916) (xy 422.214802 -394.491972) (xy 422.232074 -394.500862) (xy 422.241726 -394.501624)
			(xy 422.26606 -394.504284) (xy 422.31361 -394.515917) (xy 422.358927 -394.534429) (xy 422.401022 -394.559415)
			(xy 422.438977 -394.590329) (xy 422.471963 -394.626498) (xy 422.499261 -394.667132) (xy 422.520275 -394.711344)
			(xy 422.534547 -394.758169) (xy 422.541764 -394.806586) (xy 422.542208 -394.831062) (xy 422.541698 -394.857049)
			(xy 422.533568 -394.908384) (xy 422.517507 -394.957814) (xy 422.493911 -395.004124) (xy 422.463361 -395.046172)
			(xy 422.42661 -395.082923) (xy 422.384562 -395.113473) (xy 422.338252 -395.137069) (xy 422.288822 -395.15313)
			(xy 422.237487 -395.16126) (xy 422.185513 -395.16126) (xy 422.134178 -395.15313) (xy 422.084748 -395.137069)
			(xy 422.038438 -395.113473) (xy 421.99639 -395.082923) (xy 421.959639 -395.046172) (xy 421.929089 -395.004124)
			(xy 421.905493 -394.957814) (xy 421.889432 -394.908384) (xy 421.881302 -394.857049) (xy 421.880792 -394.831062)
			(xy 421.881046 -394.819378) (xy 421.8813 -394.809472) (xy 421.87495 -394.791438) (xy 421.815768 -394.724382)
			(xy 421.798496 -394.715492) (xy 421.788844 -394.71473) (xy 421.764656 -394.7121) (xy 421.71739 -394.700553)
			(xy 421.672323 -394.682213) (xy 421.630426 -394.657475) (xy 421.5926 -394.626871) (xy 421.55966 -394.591062)
			(xy 421.532315 -394.550817) (xy 421.511155 -394.507003) (xy 421.496634 -394.460565) (xy 421.492426 -394.4366)
			(xy 421.490902 -394.427202) (xy 421.218106 -393.95527) (xy 421.21074 -393.949428) (xy 421.191981 -393.933606)
			(xy 421.158864 -393.897391) (xy 421.131454 -393.856687) (xy 421.110351 -393.812383) (xy 421.096015 -393.765451)
			(xy 421.088762 -393.716916) (xy 421.088312 -393.69238) (xy 420.571228 -393.69238) (xy 420.819834 -394.122402)
			(xy 420.8272 -394.128244) (xy 420.845978 -394.144048) (xy 420.879111 -394.180255) (xy 420.906532 -394.22096)
			(xy 420.927638 -394.265269) (xy 420.941967 -394.31221) (xy 420.949204 -394.360752) (xy 420.949628 -394.385292)
			(xy 420.949374 -394.397484) (xy 420.94912 -394.407136) (xy 420.955216 -394.42517) (xy 421.01389 -394.49248)
			(xy 421.030654 -394.501116) (xy 421.04056 -394.502132) (xy 421.06733 -394.505455) (xy 421.119364 -394.519675)
			(xy 421.1684 -394.542149) (xy 421.21314 -394.572283) (xy 421.252396 -394.609276) (xy 421.28513 -394.65215)
			(xy 421.310472 -394.699768) (xy 421.327752 -394.750866) (xy 421.336511 -394.804091) (xy 421.336978 -394.831062)
			(xy 421.336415 -394.858344) (xy 421.32745 -394.912165) (xy 421.309774 -394.963786) (xy 421.283866 -395.011806)
			(xy 421.250429 -395.054923) (xy 421.230806 -395.073886) (xy 421.223361 -395.081379) (xy 421.214826 -395.100674)
			(xy 421.214296 -395.111224) (xy 421.214296 -395.1859) (xy 421.214887 -395.196433) (xy 421.22342 -395.215703)
			(xy 421.230806 -395.223238) (xy 421.250462 -395.24217) (xy 421.283907 -395.28529) (xy 421.309816 -395.333317)
			(xy 421.327487 -395.384946) (xy 421.336438 -395.438777) (xy 421.336978 -395.466062) (xy 421.336545 -395.490179)
			(xy 421.329549 -395.537904) (xy 421.315699 -395.584108) (xy 421.29529 -395.627812) (xy 421.282368 -395.64818)
			(xy 421.276526 -395.65707) (xy 421.27297 -395.677136) (xy 421.294052 -395.769338) (xy 421.306244 -395.786102)
			(xy 421.315134 -395.791436) (xy 421.335936 -395.804291) (xy 421.373852 -395.83517) (xy 421.406801 -395.871301)
			(xy 421.434064 -395.911894) (xy 421.455043 -395.956064) (xy 421.469281 -396.002844) (xy 421.476467 -396.051212)
			(xy 421.476932 -396.075662) (xy 421.476463 -396.100856) (xy 421.46883 -396.150661) (xy 421.453736 -396.198734)
			(xy 421.431528 -396.243963) (xy 421.417496 -396.264892) (xy 421.409368 -396.276576) (xy 421.407336 -396.30477)
			(xy 421.455596 -396.397226) (xy 421.460221 -396.405312) (xy 421.474098 -396.417716) (xy 421.4915 -396.424318)
			(xy 421.500808 -396.424658) (xy 423.113454 -396.424658) (xy 423.116502 -396.427706) (xy 423.2148 -396.43177)
			(xy 423.232834 -396.425674) (xy 423.2402 -396.419324) (xy 423.258207 -396.404524) (xy 423.297597 -396.379605)
			(xy 423.340099 -396.360471) (xy 423.384869 -396.3475) (xy 423.431017 -396.340951) (xy 423.454322 -396.340584)
			(xy 423.480591 -396.341091) (xy 423.532467 -396.349401) (xy 423.582378 -396.365808) (xy 423.629066 -396.3899)
			(xy 423.671358 -396.42107) (xy 423.70819 -396.458535) (xy 423.738636 -396.501352) (xy 423.761929 -396.548444)
			(xy 423.777484 -396.598627) (xy 423.781728 -396.624556) (xy 423.782998 -396.633446) (xy 423.79138 -396.64894)
			(xy 423.85234 -396.704566) (xy 423.86885 -396.711424) (xy 423.87774 -396.711678) (xy 423.902924 -396.713309)
			(xy 423.9524 -396.723253) (xy 423.999791 -396.740599) (xy 424.043995 -396.764945) (xy 424.083987 -396.795724)
			(xy 424.118837 -396.832224) (xy 424.147737 -396.873594) (xy 424.170015 -396.918876) (xy 424.185154 -396.967017)
			(xy 424.192803 -397.016899) (xy 424.193208 -397.042132) (xy 424.192723 -397.067454) (xy 424.185 -397.117504)
			(xy 424.169738 -397.165793) (xy 424.147294 -397.211191) (xy 424.118193 -397.252638) (xy 424.101006 -397.27124)
			(xy 424.093894 -397.278606) (xy 424.086782 -397.296894) (xy 424.087544 -397.378174) (xy 424.088105 -397.388005)
			(xy 424.095692 -397.406156) (xy 424.102276 -397.41348) (xy 424.13301 -397.444214) (xy 424.140405 -397.451068)
			(xy 424.159004 -397.458813) (xy 424.169078 -397.4592)
		)
		(stroke
			(width 0)
			(type solid)
		)
		(fill yes)
		(layer "In15.Cu")
		(net "P1V8_CPU0_RT2_1A_1D")
	)
	(gr_poly
		(pts
			(xy 209.830924 -38.876732) (xy 209.840931 -38.87624) (xy 209.85942 -38.868578) (xy 209.873573 -38.854427)
			(xy 209.881239 -38.835939) (xy 209.881724 -38.825932) (xy 209.881724 -37.916612) (xy 209.881724 -37.914834)
			(xy 209.88147 -37.90696) (xy 209.876644 -37.893244) (xy 209.872326 -37.886894) (xy 209.849655 -37.854565)
			(xy 209.809491 -37.786575) (xy 209.775521 -37.715288) (xy 209.748013 -37.641268) (xy 209.727185 -37.565097)
			(xy 209.7132 -37.487379) (xy 209.706169 -37.408725) (xy 209.705702 -37.369242) (xy 209.705702 -37.368734)
			(xy 209.706464 -37.331904) (xy 209.706972 -37.31895) (xy 209.695542 -37.295836) (xy 209.61604 -37.239956)
			(xy 209.607389 -37.234427) (xy 209.587337 -37.230093) (xy 209.577178 -37.231574) (xy 209.567018 -37.233606)
			(xy 209.562446 -37.235384) (xy 209.540158 -37.24374) (xy 209.49403 -37.255489) (xy 209.4468 -37.261416)
			(xy 209.423 -37.2618) (xy 209.422746 -37.2618) (xy 209.395492 -37.26134) (xy 209.341537 -37.253588)
			(xy 209.289235 -37.238237) (xy 209.23965 -37.215597) (xy 209.193792 -37.186131) (xy 209.152594 -37.150438)
			(xy 209.116897 -37.109245) (xy 209.087425 -37.063391) (xy 209.064779 -37.013809) (xy 209.049421 -36.961508)
			(xy 209.041663 -36.907554) (xy 209.041663 -36.853046) (xy 209.049421 -36.799092) (xy 209.064779 -36.746791)
			(xy 209.087425 -36.697209) (xy 209.116897 -36.651355) (xy 209.152594 -36.610162) (xy 209.193792 -36.574469)
			(xy 209.23965 -36.545003) (xy 209.289235 -36.522363) (xy 209.341537 -36.507012) (xy 209.395492 -36.49926)
			(xy 209.422746 -36.498784) (xy 209.449135 -36.499228) (xy 209.50141 -36.506497) (xy 209.552183 -36.520904)
			(xy 209.600485 -36.542174) (xy 209.645394 -36.569901) (xy 209.68605 -36.603554) (xy 209.704178 -36.622736)
			(xy 209.706718 -36.625276) (xy 209.713993 -36.631899) (xy 209.732099 -36.639548) (xy 209.751752 -36.639849)
			(xy 209.761074 -36.636706) (xy 209.849212 -36.602416) (xy 209.857131 -36.599012) (xy 209.870252 -36.587852)
			(xy 209.874866 -36.580572) (xy 209.881724 -36.568634) (xy 209.881724 -35.801808) (xy 209.881251 -35.791056)
			(xy 209.872444 -35.771441) (xy 209.864706 -35.763962) (xy 209.80019 -35.706304) (xy 209.77987 -35.6997)
			(xy 209.768948 -35.70097) (xy 209.75863 -35.702033) (xy 209.737918 -35.703178) (xy 209.727546 -35.703256)
			(xy 209.700288 -35.702796) (xy 209.646325 -35.695044) (xy 209.594015 -35.67969) (xy 209.544423 -35.657047)
			(xy 209.498558 -35.627576) (xy 209.457354 -35.591878) (xy 209.421651 -35.550679) (xy 209.392175 -35.504818)
			(xy 209.369527 -35.455228) (xy 209.354166 -35.40292) (xy 209.346407 -35.348958) (xy 209.346407 -35.294442)
			(xy 209.354166 -35.24048) (xy 209.369527 -35.188172) (xy 209.392175 -35.138582) (xy 209.421651 -35.092721)
			(xy 209.457354 -35.051522) (xy 209.498558 -35.015824) (xy 209.544423 -34.986353) (xy 209.594015 -34.96371)
			(xy 209.646325 -34.948356) (xy 209.700288 -34.940604) (xy 209.727546 -34.94024) (xy 209.737918 -34.940317)
			(xy 209.75863 -34.941462) (xy 209.768948 -34.942526) (xy 209.77987 -34.943796) (xy 209.80019 -34.937192)
			(xy 209.864706 -34.879534) (xy 209.872333 -34.871971) (xy 209.881147 -34.852412) (xy 209.881724 -34.841688)
			(xy 209.881724 -30.568138) (xy 209.874104 -30.549342) (xy 209.866738 -30.54223) (xy 209.43697 -30.112462)
			(xy 209.435446 -30.110938) (xy 209.435192 -30.110938) (xy 209.426065 -30.103331) (xy 209.403282 -30.096691)
			(xy 209.391504 -30.098238) (xy 209.38236 -30.100016) (xy 209.378296 -30.10154) (xy 209.341388 -30.114651)
			(xy 209.265774 -30.135105) (xy 209.188656 -30.148834) (xy 209.110629 -30.155733) (xy 209.071464 -30.15615)
			(xy 209.07121 -30.15615) (xy 209.030444 -30.155692) (xy 208.949255 -30.148235) (xy 208.869088 -30.133381)
			(xy 208.790616 -30.111257) (xy 208.714497 -30.082047) (xy 208.64137 -30.045996) (xy 208.571846 -30.003406)
			(xy 208.506511 -29.954635) (xy 208.445911 -29.900092) (xy 208.390554 -29.840234) (xy 208.340905 -29.775563)
			(xy 208.297381 -29.706622) (xy 208.278476 -29.670502) (xy 208.274158 -29.661866) (xy 208.254092 -29.643832)
			(xy 208.250668 -29.640906) (xy 208.243004 -29.636177) (xy 208.238852 -29.634434) (xy 208.220564 -29.627068)
			(xy 208.213791 -29.62464) (xy 208.199466 -29.623337) (xy 208.19237 -29.624528) (xy 208.183988 -29.626052)
			(xy 208.179924 -29.627322) (xy 208.179416 -29.627576) (xy 208.14946 -29.637169) (xy 208.08742 -29.647514)
			(xy 208.055972 -29.64815) (xy 208.05521 -29.64815) (xy 208.027821 -29.647647) (xy 207.973614 -29.639743)
			(xy 207.921099 -29.624154) (xy 207.871359 -29.601202) (xy 207.825421 -29.571361) (xy 207.804512 -29.553662)
			(xy 207.797336 -29.547945) (xy 207.780152 -29.541555) (xy 207.770984 -29.541216) (xy 201.520806 -29.541216)
			(xy 201.510735 -29.540795) (xy 201.492127 -29.533083) (xy 201.484738 -29.52623) (xy 192.62471 -20.666202)
			(xy 192.617312 -20.659354) (xy 192.598714 -20.651615) (xy 192.588642 -20.651216) (xy 187.421774 -20.651216)
			(xy 187.394596 -20.67179) (xy 187.387428 -20.698851) (xy 187.370141 -20.752103) (xy 187.360052 -20.778216)
			(xy 187.384546 -20.790029) (xy 187.430209 -20.819559) (xy 187.471221 -20.85527) (xy 187.50675 -20.896438)
			(xy 187.536079 -20.94223) (xy 187.558614 -20.991721) (xy 187.573899 -21.043908) (xy 187.581625 -21.097736)
			(xy 187.582048 -21.124926) (xy 187.58156 -21.152194) (xy 187.573795 -21.206174) (xy 187.558427 -21.258499)
			(xy 187.535769 -21.308105) (xy 187.506283 -21.353982) (xy 187.470567 -21.395195) (xy 187.42935 -21.430907)
			(xy 187.38347 -21.460389) (xy 187.333862 -21.483041) (xy 187.281535 -21.498404) (xy 187.227554 -21.506163)
			(xy 187.200286 -21.506688) (xy 187.172906 -21.506216) (xy 187.118709 -21.498388) (xy 187.066186 -21.482896)
			(xy 187.016417 -21.460056) (xy 186.970422 -21.430339) (xy 186.929146 -21.394354) (xy 186.893437 -21.352839)
			(xy 186.864027 -21.306648) (xy 186.852306 -21.281898) (xy 186.835805 -21.288124) (xy 186.802394 -21.299429)
			(xy 186.785504 -21.304504) (xy 186.773058 -21.313394) (xy 186.746388 -21.3487) (xy 186.741308 -21.362924)
			(xy 186.741054 -21.370798) (xy 186.73955 -21.397328) (xy 186.730111 -21.449621) (xy 186.713505 -21.500098)
			(xy 186.690054 -21.547781) (xy 186.660212 -21.591748) (xy 186.624556 -21.631147) (xy 186.583776 -21.665216)
			(xy 186.538663 -21.693294) (xy 186.490089 -21.71484) (xy 186.438995 -21.729434) (xy 186.386369 -21.736796)
			(xy 186.3598 -21.73732) (xy 186.332726 -21.736846) (xy 186.279121 -21.729188) (xy 186.227138 -21.714026)
			(xy 186.177823 -21.691664) (xy 186.132165 -21.662552) (xy 186.091084 -21.627276) (xy 186.055405 -21.586544)
			(xy 186.040268 -21.564092) (xy 186.015597 -21.581421) (xy 185.961945 -21.608916) (xy 185.904644 -21.627653)
			(xy 185.845113 -21.637169) (xy 185.81497 -21.637752) (xy 185.788361 -21.637289) (xy 185.73566 -21.629893)
			(xy 185.684497 -21.615249) (xy 185.635864 -21.59364) (xy 185.590703 -21.565486) (xy 185.549891 -21.531332)
			(xy 185.514218 -21.491841) (xy 185.484376 -21.447778) (xy 185.460944 -21.399997) (xy 185.444375 -21.349424)
			(xy 185.439304 -21.3233) (xy 185.395646 -21.331616) (xy 185.307214 -21.340525) (xy 185.262774 -21.34108)
			(xy 185.26252 -21.34108) (xy 185.221174 -21.34061) (xy 185.138839 -21.332938) (xy 185.05757 -21.31766)
			(xy 184.97807 -21.294906) (xy 184.901025 -21.264873) (xy 184.827099 -21.22782) (xy 184.75693 -21.184067)
			(xy 184.691124 -21.133992) (xy 184.630249 -21.078026) (xy 184.574829 -21.016653) (xy 184.525344 -20.950402)
			(xy 184.48222 -20.879845) (xy 184.445829 -20.805591) (xy 184.416486 -20.72828) (xy 184.405016 -20.688554)
			(xy 184.400444 -20.67179) (xy 184.373266 -20.651216) (xy 181.662578 -20.651216) (xy 181.652177 -20.651717)
			(xy 181.633085 -20.659978) (xy 181.618837 -20.675134) (xy 181.614826 -20.684744) (xy 181.57698 -20.790154)
			(xy 181.585362 -20.820888) (xy 181.598062 -20.831302) (xy 181.627493 -20.856048) (xy 181.682433 -20.909856)
			(xy 181.732522 -20.968207) (xy 181.755288 -20.999196) (xy 181.758844 -21.004276) (xy 181.76748 -21.011642)
			(xy 181.803294 -21.030692) (xy 181.815486 -21.030946) (xy 181.857514 -21.032209) (xy 181.941067 -21.041682)
			(xy 182.023353 -21.058996) (xy 182.103639 -21.083996) (xy 182.181209 -21.116458) (xy 182.25537 -21.156094)
			(xy 182.32546 -21.20255) (xy 182.390855 -21.255411) (xy 182.421276 -21.284438) (xy 182.429231 -21.291477)
			(xy 182.449095 -21.298931) (xy 182.470276 -21.297712) (xy 182.47995 -21.293328) (xy 182.517499 -21.274717)
			(xy 182.595413 -21.243831) (xy 182.675889 -21.22042) (xy 182.758212 -21.204692) (xy 182.84165 -21.196786)
			(xy 182.883556 -21.1963) (xy 182.884318 -21.1963) (xy 182.929467 -21.196856) (xy 183.019301 -21.206003)
			(xy 183.107746 -21.224203) (xy 183.193893 -21.251266) (xy 183.276856 -21.286916) (xy 183.355782 -21.330785)
			(xy 183.429858 -21.382423) (xy 183.464454 -21.411438) (xy 183.471058 -21.41728) (xy 183.495442 -21.426424)
			(xy 183.49979 -21.427965) (xy 183.508864 -21.429622) (xy 183.513476 -21.429726) (xy 183.524652 -21.429726)
			(xy 183.529264 -21.429622) (xy 183.538335 -21.427956) (xy 183.542686 -21.426424) (xy 183.56707 -21.41728)
			(xy 183.573674 -21.411438) (xy 183.608269 -21.382422) (xy 183.682346 -21.330787) (xy 183.761272 -21.28692)
			(xy 183.844236 -21.251273) (xy 183.930383 -21.224212) (xy 184.018828 -21.206015) (xy 184.108661 -21.196871)
			(xy 184.15381 -21.1963) (xy 184.154064 -21.1963) (xy 184.195168 -21.196759) (xy 184.277026 -21.204341)
			(xy 184.357835 -21.219444) (xy 184.436905 -21.241938) (xy 184.513563 -21.271633) (xy 184.587154 -21.308275)
			(xy 184.65705 -21.35155) (xy 184.722654 -21.40109) (xy 184.783408 -21.456472) (xy 184.838792 -21.517224)
			(xy 184.888334 -21.582827) (xy 184.931612 -21.652722) (xy 184.968255 -21.726311) (xy 184.997953 -21.802968)
			(xy 185.02045 -21.882038) (xy 185.035555 -21.962846) (xy 185.04314 -22.044704) (xy 185.043572 -22.085808)
			(xy 185.043485 -22.101507) (xy 185.042343 -22.132883) (xy 185.041286 -22.148546) (xy 185.040524 -22.159722)
			(xy 185.046874 -22.176486) (xy 185.054494 -22.187154) (xy 185.059574 -22.191472) (xy 185.12282 -22.243796)
			(xy 185.131231 -22.25014) (xy 185.151432 -22.256042) (xy 185.161936 -22.255226) (xy 185.168794 -22.25421)
			(xy 185.171842 -22.253448) (xy 185.208913 -22.244084) (xy 185.284249 -22.230985) (xy 185.360431 -22.224406)
			(xy 185.398664 -22.223984) (xy 185.399172 -22.223984) (xy 185.440276 -22.224443) (xy 185.522134 -22.232026)
			(xy 185.602943 -22.247129) (xy 185.682013 -22.269624) (xy 185.758671 -22.299319) (xy 185.832262 -22.335961)
			(xy 185.902158 -22.379236) (xy 185.967762 -22.428776) (xy 186.028516 -22.484158) (xy 186.083901 -22.54491)
			(xy 186.133443 -22.610513) (xy 186.176722 -22.680407) (xy 186.213366 -22.753996) (xy 186.243064 -22.830652)
			(xy 186.265563 -22.909722) (xy 186.280669 -22.99053) (xy 186.288255 -23.072388) (xy 186.28868 -23.113492)
			(xy 186.288278 -23.150241) (xy 186.282171 -23.223486) (xy 186.276488 -23.259796) (xy 186.273948 -23.274528)
			(xy 186.285632 -23.301706) (xy 186.386724 -23.37054) (xy 186.416188 -23.371302) (xy 186.428888 -23.363682)
			(xy 186.463416 -23.343536) (xy 186.53543 -23.308813) (xy 186.610267 -23.280688) (xy 186.687325 -23.259389)
			(xy 186.765983 -23.245087) (xy 186.845606 -23.237897) (xy 186.88558 -23.237444) (xy 186.885834 -23.237444)
			(xy 186.917838 -23.238206) (xy 186.918346 -23.238206) (xy 186.9313 -23.23846) (xy 186.95035 -23.23084)
			(xy 186.957716 -23.223728) (xy 187.010294 -23.172674) (xy 187.017355 -23.165226) (xy 187.025364 -23.146351)
			(xy 187.025788 -23.136098) (xy 187.025788 -23.127208) (xy 187.026271 -23.085282) (xy 187.034162 -23.001803)
			(xy 187.049873 -22.919437) (xy 187.073266 -22.838915) (xy 187.104133 -22.760952) (xy 187.1422 -22.686239)
			(xy 187.18713 -22.615441) (xy 187.238522 -22.549185) (xy 187.295922 -22.48806) (xy 187.358819 -22.432608)
			(xy 187.426656 -22.383321) (xy 187.49883 -22.340636) (xy 187.574701 -22.304934) (xy 187.653595 -22.27653)
			(xy 187.734812 -22.255676) (xy 187.81763 -22.242559) (xy 187.901316 -22.237293) (xy 187.985126 -22.239927)
			(xy 188.068316 -22.250436) (xy 188.150148 -22.268727) (xy 188.229896 -22.294638) (xy 188.306851 -22.327939)
			(xy 188.38033 -22.368335) (xy 188.449682 -22.415466) (xy 188.514291 -22.468915) (xy 188.573583 -22.528206)
			(xy 188.627032 -22.592815) (xy 188.674163 -22.662166) (xy 188.714559 -22.735646) (xy 188.74786 -22.812601)
			(xy 188.773772 -22.892348) (xy 188.792063 -22.97418) (xy 188.802573 -23.05737) (xy 188.805207 -23.14118)
			(xy 188.799942 -23.224866) (xy 188.786824 -23.307685) (xy 188.765971 -23.388901) (xy 188.737568 -23.467795)
			(xy 188.701865 -23.543666) (xy 188.659182 -23.615841) (xy 188.609895 -23.683678) (xy 188.554443 -23.746575)
			(xy 188.493318 -23.803975) (xy 188.427062 -23.855368) (xy 188.356264 -23.900298) (xy 188.281552 -23.938365)
			(xy 188.203589 -23.969233) (xy 188.123067 -23.992626) (xy 188.040701 -24.008338) (xy 187.957222 -24.016229)
			(xy 187.915296 -24.016716) (xy 187.883292 -24.015954) (xy 187.882784 -24.015954) (xy 187.86983 -24.0157)
			(xy 187.85078 -24.02332) (xy 187.843414 -24.030432) (xy 187.790836 -24.081486) (xy 187.783793 -24.088941)
			(xy 187.775817 -24.107815) (xy 187.775342 -24.118062) (xy 187.775342 -24.126952) (xy 187.774839 -24.169235)
			(xy 187.766809 -24.25342) (xy 187.750827 -24.336462) (xy 187.727036 -24.417613) (xy 187.695652 -24.49614)
			(xy 187.656958 -24.571335) (xy 187.611302 -24.642518) (xy 187.585604 -24.6761) (xy 187.579508 -24.683974)
			(xy 187.576714 -24.693372) (xy 187.575398 -24.698208) (xy 187.574508 -24.70819) (xy 187.574936 -24.713184)
			(xy 187.583572 -24.79294) (xy 187.59297 -24.810466) (xy 187.60059 -24.816816) (xy 187.621711 -24.835015)
			(xy 187.658922 -24.876531) (xy 187.689687 -24.923025) (xy 187.713349 -24.973506) (xy 187.729404 -25.026897)
			(xy 187.737508 -25.082056) (xy 187.738004 -25.109932) (xy 187.737438 -25.13935) (xy 187.728376 -25.197484)
			(xy 187.710516 -25.253544) (xy 187.697872 -25.280112) (xy 187.693454 -25.290206) (xy 187.692759 -25.312205)
			(xy 187.701278 -25.332501) (xy 187.709048 -25.34031) (xy 187.739037 -25.368338) (xy 187.794291 -25.429046)
			(xy 187.843716 -25.494589) (xy 187.886891 -25.564407) (xy 187.923448 -25.637907) (xy 187.953076 -25.714463)
			(xy 187.975522 -25.793423) (xy 187.990597 -25.874117) (xy 187.998171 -25.955855) (xy 187.998608 -25.9969)
			(xy 187.998104 -26.039248) (xy 187.990053 -26.123562) (xy 187.974024 -26.206728) (xy 187.950163 -26.287995)
			(xy 187.918684 -26.366625) (xy 187.879873 -26.441906) (xy 187.834083 -26.513158) (xy 187.781727 -26.579734)
			(xy 187.723279 -26.641032) (xy 187.659269 -26.696497) (xy 187.590277 -26.745626) (xy 187.516927 -26.787975)
			(xy 187.439884 -26.823159) (xy 187.359845 -26.850861) (xy 187.277536 -26.870829) (xy 187.193701 -26.882882)
			(xy 187.1091 -26.886913) (xy 187.024499 -26.882882) (xy 186.940664 -26.870829) (xy 186.858355 -26.850861)
			(xy 186.778316 -26.823159) (xy 186.701273 -26.787975) (xy 186.627923 -26.745626) (xy 186.558931 -26.696497)
			(xy 186.494921 -26.641032) (xy 186.436473 -26.579734) (xy 186.384117 -26.513158) (xy 186.338327 -26.441906)
			(xy 186.299516 -26.366625) (xy 186.268037 -26.287995) (xy 186.244176 -26.206728) (xy 186.228147 -26.123562)
			(xy 186.220096 -26.039248) (xy 186.219592 -25.9969) (xy 186.219592 -25.996646) (xy 186.220082 -25.954752)
			(xy 186.22798 -25.871336) (xy 186.24369 -25.789034) (xy 186.267073 -25.708574) (xy 186.297923 -25.630671)
			(xy 186.335965 -25.556017) (xy 186.358022 -25.520396) (xy 186.358022 -25.520142) (xy 186.363102 -25.512014)
			(xy 186.36488 -25.50287) (xy 186.365765 -25.498221) (xy 186.366021 -25.488763) (xy 186.365388 -25.484074)
			(xy 186.353704 -25.41778) (xy 186.352276 -25.410677) (xy 186.345943 -25.397653) (xy 186.341258 -25.392126)
			(xy 186.334908 -25.385776) (xy 186.332368 -25.383744) (xy 186.310198 -25.365548) (xy 186.271051 -25.323632)
			(xy 186.238621 -25.276328) (xy 186.213639 -25.224702) (xy 186.196668 -25.169917) (xy 186.188091 -25.113209)
			(xy 186.187588 -25.084532) (xy 186.188188 -25.053592) (xy 186.19818 -24.992523) (xy 186.217907 -24.933872)
			(xy 186.246851 -24.879177) (xy 186.265058 -24.854154) (xy 186.270112 -24.846744) (xy 186.275315 -24.829594)
			(xy 186.275218 -24.820626) (xy 186.27344 -24.789892) (xy 186.273186 -24.788876) (xy 186.271998 -24.780055)
			(xy 186.264468 -24.763941) (xy 186.258454 -24.75738) (xy 186.22777 -24.726112) (xy 186.172038 -24.658515)
			(xy 186.123223 -24.585764) (xy 186.081798 -24.508566) (xy 186.048165 -24.427669) (xy 186.022649 -24.343857)
			(xy 186.005498 -24.257942) (xy 185.996878 -24.170757) (xy 185.996326 -24.126952) (xy 185.996726 -24.090202)
			(xy 186.00283 -24.016957) (xy 186.008518 -23.980648) (xy 186.011058 -23.965916) (xy 185.999374 -23.938738)
			(xy 185.898282 -23.869904) (xy 185.868818 -23.869142) (xy 185.856118 -23.876762) (xy 185.821589 -23.896908)
			(xy 185.749576 -23.931629) (xy 185.674738 -23.959753) (xy 185.59768 -23.981051) (xy 185.519023 -23.995353)
			(xy 185.439399 -24.002543) (xy 185.399426 -24.003) (xy 185.399172 -24.003) (xy 185.35807 -24.002524)
			(xy 185.276218 -23.994937) (xy 185.195415 -23.97983) (xy 185.116351 -23.957332) (xy 185.0397 -23.927634)
			(xy 184.966115 -23.890992) (xy 184.896226 -23.847716) (xy 184.830628 -23.798176) (xy 184.76988 -23.742795)
			(xy 184.714501 -23.682045) (xy 184.664964 -23.616444) (xy 184.621691 -23.546553) (xy 184.585051 -23.472967)
			(xy 184.555357 -23.396315) (xy 184.532862 -23.31725) (xy 184.517758 -23.236446) (xy 184.510174 -23.154594)
			(xy 184.509664 -23.113492) (xy 184.509751 -23.097793) (xy 184.510893 -23.066417) (xy 184.51195 -23.050754)
			(xy 184.512712 -23.039578) (xy 184.508902 -23.029164) (xy 184.506394 -23.023008) (xy 184.498677 -23.01219)
			(xy 184.493662 -23.007828) (xy 184.420256 -22.947122) (xy 184.39638 -22.941788) (xy 184.384442 -22.94509)
			(xy 184.346892 -22.954701) (xy 184.270551 -22.968146) (xy 184.19333 -22.974902) (xy 184.154572 -22.975316)
			(xy 184.15381 -22.975316) (xy 184.108661 -22.974761) (xy 184.018827 -22.965616) (xy 183.930381 -22.947418)
			(xy 183.844234 -22.920354) (xy 183.761271 -22.884703) (xy 183.682346 -22.840833) (xy 183.60827 -22.789193)
			(xy 183.573674 -22.760178) (xy 183.56707 -22.754336) (xy 183.542686 -22.745192) (xy 183.538338 -22.743648)
			(xy 183.529265 -22.741986) (xy 183.524652 -22.74189) (xy 183.513476 -22.74189) (xy 183.508864 -22.741991)
			(xy 183.499791 -22.743653) (xy 183.495442 -22.745192) (xy 183.471058 -22.754336) (xy 183.464454 -22.760178)
			(xy 183.429859 -22.789194) (xy 183.355782 -22.840831) (xy 183.276856 -22.8847) (xy 183.193893 -22.920349)
			(xy 183.107746 -22.947412) (xy 183.019301 -22.965611) (xy 182.929467 -22.974758) (xy 182.884318 -22.975316)
			(xy 182.884064 -22.975316) (xy 182.840999 -22.974808) (xy 182.755271 -22.966479) (xy 182.670751 -22.949901)
			(xy 182.588229 -22.92523) (xy 182.508478 -22.892698) (xy 182.432245 -22.852609) (xy 182.360245 -22.805338)
			(xy 182.293152 -22.751329) (xy 182.262018 -22.72157) (xy 182.254064 -22.714531) (xy 182.2342 -22.707079)
			(xy 182.21302 -22.7083) (xy 182.203344 -22.71268) (xy 182.165794 -22.731291) (xy 182.087881 -22.762176)
			(xy 182.007405 -22.785586) (xy 181.925082 -22.801314) (xy 181.841644 -22.809219) (xy 181.799738 -22.809708)
			(xy 181.79923 -22.809708) (xy 181.75701 -22.809212) (xy 181.672949 -22.801215) (xy 181.590023 -22.785291)
			(xy 181.508979 -22.761582) (xy 181.430546 -22.730302) (xy 181.355429 -22.691732) (xy 181.284304 -22.646219)
			(xy 181.217811 -22.594172) (xy 181.156547 -22.53606) (xy 181.101064 -22.472406) (xy 181.076092 -22.43836)
			(xy 181.072536 -22.43328) (xy 181.0639 -22.425914) (xy 181.028086 -22.406864) (xy 181.015894 -22.40661)
			(xy 180.97275 -22.405308) (xy 180.887002 -22.395373) (xy 180.80262 -22.377179) (xy 180.720397 -22.350896)
			(xy 180.641106 -22.316773) (xy 180.565494 -22.275129) (xy 180.494271 -22.226357) (xy 180.428108 -22.170915)
			(xy 180.367626 -22.109325) (xy 180.313394 -22.042166) (xy 180.265923 -21.970069) (xy 180.225659 -21.893713)
			(xy 180.19298 -21.813816) (xy 180.168195 -21.73113) (xy 180.151535 -21.646431) (xy 180.143159 -21.560517)
			(xy 180.142642 -21.517356) (xy 180.143183 -21.473811) (xy 180.151717 -21.387141) (xy 180.168679 -21.30172)
			(xy 180.193906 -21.218364) (xy 180.227158 -21.137873) (xy 180.268116 -21.061016) (xy 180.316388 -20.988529)
			(xy 180.371512 -20.921105) (xy 180.432961 -20.859391) (xy 180.466238 -20.831302) (xy 180.478684 -20.821142)
			(xy 180.487066 -20.790154) (xy 180.449474 -20.684998) (xy 180.445489 -20.675352) (xy 180.431251 -20.660121)
			(xy 180.412144 -20.651777) (xy 180.401722 -20.651216) (xy 176.237646 -20.651216) (xy 176.21885 -20.658836)
			(xy 176.211738 -20.666202) (xy 175.35271 -21.52523) (xy 175.345867 -21.53263) (xy 175.338142 -21.551228)
			(xy 175.337724 -21.561298) (xy 175.337724 -24.7548) (xy 183.389512 -24.7548) (xy 183.393542 -24.670199)
			(xy 183.405596 -24.586364) (xy 183.425565 -24.504054) (xy 183.453267 -24.424016) (xy 183.488453 -24.346973)
			(xy 183.530802 -24.273624) (xy 183.579933 -24.204633) (xy 183.635399 -24.140624) (xy 183.696698 -24.082178)
			(xy 183.763276 -24.029823) (xy 183.834529 -23.984034) (xy 183.909812 -23.945226) (xy 183.988443 -23.91375)
			(xy 184.06971 -23.889891) (xy 184.152878 -23.873866) (xy 184.237191 -23.865818) (xy 184.27954 -23.865332)
			(xy 184.323025 -23.865878) (xy 184.40958 -23.874377) (xy 184.494893 -23.891279) (xy 184.57815 -23.916424)
			(xy 184.658556 -23.949572) (xy 184.735345 -23.990405) (xy 184.807784 -24.038536) (xy 184.875181 -24.093504)
			(xy 184.936895 -24.154786) (xy 184.992335 -24.221796) (xy 185.040973 -24.293895) (xy 185.082346 -24.370395)
			(xy 185.116057 -24.450567) (xy 185.129424 -24.49195) (xy 185.132472 -24.50211) (xy 185.145934 -24.518112)
			(xy 185.231024 -24.560022) (xy 185.251598 -24.561038) (xy 185.261758 -24.557228) (xy 185.293836 -24.546102)
			(xy 185.360655 -24.534091) (xy 185.3946 -24.533352) (xy 185.421848 -24.533918) (xy 185.47579 -24.541674)
			(xy 185.52808 -24.557027) (xy 185.577652 -24.579666) (xy 185.623497 -24.609129) (xy 185.664683 -24.644817)
			(xy 185.700371 -24.686003) (xy 185.729834 -24.731848) (xy 185.752473 -24.78142) (xy 185.767826 -24.83371)
			(xy 185.775582 -24.887652) (xy 185.775582 -24.942148) (xy 185.767826 -24.99609) (xy 185.752473 -25.04838)
			(xy 185.729834 -25.097952) (xy 185.700371 -25.143797) (xy 185.664683 -25.184983) (xy 185.623497 -25.220671)
			(xy 185.577652 -25.250134) (xy 185.52808 -25.272773) (xy 185.47579 -25.288126) (xy 185.421848 -25.295882)
			(xy 185.3946 -25.296368) (xy 185.364065 -25.29577) (xy 185.303774 -25.286048) (xy 185.2458 -25.266852)
			(xy 185.191621 -25.238671) (xy 185.166762 -25.22093) (xy 185.166508 -25.220676) (xy 185.157983 -25.214988)
			(xy 185.138067 -25.210254) (xy 185.1279 -25.211532) (xy 185.055002 -25.223978) (xy 185.044805 -25.226206)
			(xy 185.027365 -25.237637) (xy 185.02122 -25.246076) (xy 185.000822 -25.27623) (xy 184.955809 -25.333453)
			(xy 184.931304 -25.360376) (xy 184.925419 -25.367183) (xy 184.918482 -25.383776) (xy 184.917717 -25.401744)
			(xy 184.920128 -25.410414) (xy 184.947052 -25.494742) (xy 184.950139 -25.503232) (xy 184.961248 -25.51746)
			(xy 184.976623 -25.52692) (xy 184.985406 -25.529032) (xy 185.013715 -25.535361) (xy 185.068105 -25.555526)
			(xy 185.118815 -25.583693) (xy 185.164676 -25.619213) (xy 185.204629 -25.661267) (xy 185.237755 -25.708886)
			(xy 185.263289 -25.760971) (xy 185.280643 -25.816322) (xy 185.289416 -25.873662) (xy 185.289952 -25.902666)
			(xy 185.289466 -25.929917) (xy 185.28171 -25.983865) (xy 185.266355 -26.03616) (xy 185.243713 -26.085737)
			(xy 185.214247 -26.131587) (xy 185.178556 -26.172778) (xy 185.137365 -26.208469) (xy 185.091515 -26.237935)
			(xy 185.041938 -26.260577) (xy 184.989643 -26.275932) (xy 184.935695 -26.283688) (xy 184.881193 -26.283688)
			(xy 184.827245 -26.275932) (xy 184.77495 -26.260577) (xy 184.725373 -26.237935) (xy 184.679523 -26.208469)
			(xy 184.638332 -26.172778) (xy 184.602641 -26.131587) (xy 184.573175 -26.085737) (xy 184.550533 -26.03616)
			(xy 184.535178 -25.983865) (xy 184.527422 -25.929917) (xy 184.526936 -25.902666) (xy 184.526936 -25.902412)
			(xy 184.527297 -25.879202) (xy 184.532941 -25.833127) (xy 184.544123 -25.788074) (xy 184.552082 -25.766268)
			(xy 184.557162 -25.753314) (xy 184.55259 -25.72639) (xy 184.478422 -25.636728) (xy 184.452768 -25.62733)
			(xy 184.439052 -25.62987) (xy 184.399523 -25.63665) (xy 184.319644 -25.643897) (xy 184.27954 -25.644348)
			(xy 184.237191 -25.643782) (xy 184.152878 -25.635734) (xy 184.06971 -25.619709) (xy 183.988443 -25.59585)
			(xy 183.909812 -25.564374) (xy 183.834529 -25.525566) (xy 183.763276 -25.479777) (xy 183.696698 -25.427422)
			(xy 183.635399 -25.368976) (xy 183.579933 -25.304967) (xy 183.530802 -25.235976) (xy 183.488453 -25.162627)
			(xy 183.453267 -25.085584) (xy 183.425565 -25.005546) (xy 183.405596 -24.923236) (xy 183.393542 -24.839401)
			(xy 183.389512 -24.7548) (xy 175.337724 -24.7548) (xy 175.337724 -25.92324) (xy 180.826662 -25.92324)
			(xy 180.830733 -25.867618) (xy 180.842859 -25.813181) (xy 180.862782 -25.76109) (xy 180.890078 -25.712455)
			(xy 180.924164 -25.668312) (xy 180.964313 -25.629603) (xy 181.009671 -25.597152) (xy 181.059271 -25.571651)
			(xy 181.112055 -25.553644) (xy 181.166898 -25.543514) (xy 181.222632 -25.541477) (xy 181.278069 -25.547577)
			(xy 181.332026 -25.561683) (xy 181.383355 -25.583495) (xy 181.430961 -25.612549) (xy 181.473829 -25.648224)
			(xy 181.511046 -25.689761) (xy 181.541819 -25.736274) (xy 181.565491 -25.786771) (xy 181.581559 -25.840178)
			(xy 181.589679 -25.895354) (xy 181.590188 -25.92324) (xy 181.589679 -25.951126) (xy 181.581559 -26.006302)
			(xy 181.565491 -26.059709) (xy 181.541819 -26.110206) (xy 181.511046 -26.156719) (xy 181.473829 -26.198256)
			(xy 181.430961 -26.233931) (xy 181.383355 -26.262985) (xy 181.332026 -26.284797) (xy 181.278069 -26.298903)
			(xy 181.222632 -26.305003) (xy 181.166898 -26.302966) (xy 181.112055 -26.292836) (xy 181.059271 -26.274829)
			(xy 181.009671 -26.249328) (xy 180.964313 -26.216877) (xy 180.924164 -26.178168) (xy 180.890078 -26.134025)
			(xy 180.862782 -26.08539) (xy 180.842859 -26.033299) (xy 180.830733 -25.978862) (xy 180.826662 -25.92324)
			(xy 175.337724 -25.92324) (xy 175.337724 -26.791158) (xy 184.526936 -26.791158) (xy 184.527316 -26.763902)
			(xy 184.53508 -26.709946) (xy 184.550443 -26.657644) (xy 184.573094 -26.60806) (xy 184.602571 -26.562205)
			(xy 184.638273 -26.521012) (xy 184.679474 -26.485319) (xy 184.725336 -26.455853) (xy 184.774924 -26.433213)
			(xy 184.82723 -26.417861) (xy 184.881188 -26.41011) (xy 184.908444 -26.40965) (xy 184.937037 -26.410185)
			(xy 184.993579 -26.418738) (xy 185.048213 -26.435633) (xy 185.099714 -26.46049) (xy 185.14693 -26.492752)
			(xy 185.188803 -26.531699) (xy 185.224397 -26.576457) (xy 185.252914 -26.626025) (xy 185.26379 -26.652474)
			(xy 185.267453 -26.660897) (xy 185.279702 -26.674567) (xy 185.287666 -26.679144) (xy 185.323734 -26.69794)
			(xy 185.34253 -26.699972) (xy 185.351928 -26.697432) (xy 185.390385 -26.687281) (xy 185.468649 -26.67307)
			(xy 185.547869 -26.665902) (xy 185.58764 -26.665428) (xy 185.628744 -26.665829) (xy 185.710602 -26.673417)
			(xy 185.79141 -26.688527) (xy 185.870479 -26.711028) (xy 185.947135 -26.740728) (xy 186.020723 -26.777375)
			(xy 186.090616 -26.820655) (xy 186.156218 -26.8702) (xy 186.216968 -26.925586) (xy 186.272349 -26.986341)
			(xy 186.321888 -27.051947) (xy 186.365162 -27.121843) (xy 186.401803 -27.195435) (xy 186.431496 -27.272093)
			(xy 186.453991 -27.351164) (xy 186.469093 -27.431974) (xy 186.476675 -27.513832) (xy 186.477148 -27.554936)
			(xy 186.476644 -27.597284) (xy 186.470386 -27.662816) (xy 187.403482 -27.662816) (xy 187.403482 -27.57812)
			(xy 187.411533 -27.493806) (xy 187.427562 -27.41064) (xy 187.451423 -27.329373) (xy 187.482902 -27.250743)
			(xy 187.521713 -27.175462) (xy 187.567503 -27.10421) (xy 187.619859 -27.037634) (xy 187.678307 -26.976336)
			(xy 187.742317 -26.920871) (xy 187.811309 -26.871742) (xy 187.884659 -26.829393) (xy 187.961702 -26.794209)
			(xy 188.041741 -26.766507) (xy 188.12405 -26.746539) (xy 188.207885 -26.734486) (xy 188.292486 -26.730456)
			(xy 188.377087 -26.734486) (xy 188.460922 -26.746539) (xy 188.543231 -26.766507) (xy 188.62327 -26.794209)
			(xy 188.700313 -26.829393) (xy 188.773663 -26.871742) (xy 188.842655 -26.920871) (xy 188.906665 -26.976336)
			(xy 188.965113 -27.037634) (xy 189.017469 -27.10421) (xy 189.063259 -27.175462) (xy 189.10207 -27.250743)
			(xy 189.133549 -27.329373) (xy 189.15741 -27.41064) (xy 189.173439 -27.493806) (xy 189.18149 -27.57812)
			(xy 189.181994 -27.620468) (xy 189.18149 -27.662816) (xy 189.173439 -27.74713) (xy 189.15741 -27.830296)
			(xy 189.133549 -27.911563) (xy 189.10207 -27.990193) (xy 189.063259 -28.065474) (xy 189.017469 -28.136726)
			(xy 188.965113 -28.203302) (xy 188.906665 -28.2646) (xy 188.842655 -28.320065) (xy 188.773663 -28.369194)
			(xy 188.700313 -28.411543) (xy 188.62327 -28.446727) (xy 188.543231 -28.474429) (xy 188.460922 -28.494397)
			(xy 188.377087 -28.50645) (xy 188.292486 -28.510481) (xy 188.207885 -28.50645) (xy 188.12405 -28.494397)
			(xy 188.041741 -28.474429) (xy 187.961702 -28.446727) (xy 187.884659 -28.411543) (xy 187.811309 -28.369194)
			(xy 187.742317 -28.320065) (xy 187.678307 -28.2646) (xy 187.619859 -28.203302) (xy 187.567503 -28.136726)
			(xy 187.521713 -28.065474) (xy 187.482902 -27.990193) (xy 187.451423 -27.911563) (xy 187.427562 -27.830296)
			(xy 187.411533 -27.74713) (xy 187.403482 -27.662816) (xy 186.470386 -27.662816) (xy 186.468593 -27.681598)
			(xy 186.452564 -27.764764) (xy 186.428703 -27.846031) (xy 186.397224 -27.924661) (xy 186.358413 -27.999942)
			(xy 186.312623 -28.071194) (xy 186.260267 -28.13777) (xy 186.201819 -28.199068) (xy 186.137809 -28.254533)
			(xy 186.068817 -28.303662) (xy 185.995467 -28.346011) (xy 185.918424 -28.381195) (xy 185.838385 -28.408897)
			(xy 185.756076 -28.428865) (xy 185.672241 -28.440918) (xy 185.58764 -28.444949) (xy 185.503039 -28.440918)
			(xy 185.419204 -28.428865) (xy 185.336895 -28.408897) (xy 185.256856 -28.381195) (xy 185.179813 -28.346011)
			(xy 185.106463 -28.303662) (xy 185.037471 -28.254533) (xy 184.973461 -28.199068) (xy 184.915013 -28.13777)
			(xy 184.862657 -28.071194) (xy 184.816867 -27.999942) (xy 184.778056 -27.924661) (xy 184.746577 -27.846031)
			(xy 184.722716 -27.764764) (xy 184.706687 -27.681598) (xy 184.698636 -27.597284) (xy 184.698132 -27.554936)
			(xy 184.698584 -27.514584) (xy 184.705892 -27.434212) (xy 184.720453 -27.354833) (xy 184.742145 -27.277099)
			(xy 184.756044 -27.239214) (xy 184.771284 -27.20213) (xy 184.752996 -27.154886) (xy 184.749426 -27.146414)
			(xy 184.737309 -27.132606) (xy 184.729374 -27.127962) (xy 184.703591 -27.113609) (xy 184.656363 -27.078237)
			(xy 184.615148 -27.036011) (xy 184.58093 -26.98794) (xy 184.554527 -26.93517) (xy 184.536569 -26.878964)
			(xy 184.527485 -26.820661) (xy 184.526936 -26.791158) (xy 175.337724 -26.791158) (xy 175.337724 -29.23286)
			(xy 175.338994 -29.238448) (xy 175.34763 -29.283152) (xy 175.34763 -29.283914) (xy 175.349154 -29.291788)
			(xy 175.352202 -29.298138) (xy 175.354154 -29.301754) (xy 175.359004 -29.308386) (xy 175.361854 -29.311346)
			(xy 175.576738 -29.52623) (xy 175.584135 -29.533078) (xy 175.602734 -29.54081) (xy 175.612806 -29.541216)
			(xy 175.66005 -29.541216) (xy 175.670052 -29.54072) (xy 175.68853 -29.533052) (xy 175.702671 -29.518901)
			(xy 175.710327 -29.500419) (xy 175.71085 -29.490416) (xy 175.71085 -29.483812) (xy 175.709072 -29.477462)
			(xy 175.699874 -29.441271) (xy 175.68701 -29.36771) (xy 175.680533 -29.293313) (xy 175.680116 -29.255974)
			(xy 175.680116 -29.254704) (xy 175.680503 -29.21698) (xy 175.687058 -29.141817) (xy 175.700142 -29.067513)
			(xy 175.719658 -28.994633) (xy 175.732186 -28.959048) (xy 175.73371 -28.954984) (xy 175.735234 -28.946602)
			(xy 175.735925 -28.942183) (xy 175.735927 -28.93324) (xy 175.735234 -28.928822) (xy 175.73371 -28.92044)
			(xy 175.732186 -28.916376) (xy 175.719687 -28.880815) (xy 175.700186 -28.807999) (xy 175.6871 -28.733761)
			(xy 175.680529 -28.658665) (xy 175.680116 -28.620974) (xy 175.680116 -28.620212) (xy 175.680619 -28.577786)
			(xy 175.688935 -28.493342) (xy 175.705489 -28.41012) (xy 175.730119 -28.328922) (xy 175.762591 -28.250528)
			(xy 175.80259 -28.175695) (xy 175.849731 -28.105143) (xy 175.903561 -28.039552) (xy 175.963561 -27.979553)
			(xy 176.029153 -27.925724) (xy 176.099706 -27.878583) (xy 176.174539 -27.838585) (xy 176.252933 -27.806115)
			(xy 176.334132 -27.781486) (xy 176.417354 -27.764934) (xy 176.501798 -27.756619) (xy 176.544224 -27.756104)
			(xy 176.544478 -27.756104) (xy 176.588244 -27.756657) (xy 176.675328 -27.765507) (xy 176.76107 -27.78312)
			(xy 176.844591 -27.809315) (xy 176.925034 -27.843822) (xy 176.963578 -27.864562) (xy 176.969166 -27.867864)
			(xy 176.981866 -27.870912) (xy 176.988016 -27.872276) (xy 177.000608 -27.872276) (xy 177.006758 -27.870912)
			(xy 177.019458 -27.867864) (xy 177.025046 -27.864562) (xy 177.063588 -27.843818) (xy 177.144034 -27.809317)
			(xy 177.227556 -27.783124) (xy 177.313297 -27.765506) (xy 177.40038 -27.756644) (xy 177.444146 -27.756104)
			(xy 177.487913 -27.756655) (xy 177.574997 -27.765503) (xy 177.660741 -27.783113) (xy 177.744263 -27.809305)
			(xy 177.824708 -27.84381) (xy 177.863246 -27.864562) (xy 177.868834 -27.867864) (xy 177.881534 -27.870912)
			(xy 177.887684 -27.872276) (xy 177.900276 -27.872276) (xy 177.906426 -27.870912) (xy 177.919126 -27.867864)
			(xy 177.924714 -27.864562) (xy 177.959745 -27.845642) (xy 178.032625 -27.813574) (xy 178.108145 -27.788345)
			(xy 178.185666 -27.77017) (xy 178.26453 -27.759204) (xy 178.344068 -27.755538) (xy 178.423606 -27.759204)
			(xy 178.50247 -27.77017) (xy 178.579991 -27.788345) (xy 178.655511 -27.813574) (xy 178.728391 -27.845642)
			(xy 178.763422 -27.864562) (xy 178.76901 -27.867864) (xy 178.78171 -27.870912) (xy 178.78786 -27.872276)
			(xy 178.800452 -27.872276) (xy 178.806602 -27.870912) (xy 178.818286 -27.868118) (xy 178.824128 -27.864816)
			(xy 178.86274 -27.843961) (xy 178.943368 -27.809301) (xy 179.027092 -27.782989) (xy 179.113053 -27.765297)
			(xy 179.200363 -27.756408) (xy 179.244244 -27.75585) (xy 179.284948 -27.75632) (xy 179.365996 -27.763979)
			(xy 179.445964 -27.779225) (xy 179.524144 -27.801922) (xy 179.599844 -27.831869) (xy 179.672393 -27.868802)
			(xy 179.741148 -27.912393) (xy 179.805499 -27.962255) (xy 179.864877 -28.017947) (xy 179.918755 -28.078976)
			(xy 179.966656 -28.1448) (xy 180.008156 -28.214837) (xy 180.042886 -28.288465) (xy 180.07054 -28.365033)
			(xy 180.090872 -28.443861) (xy 180.103701 -28.524253) (xy 180.106828 -28.56484) (xy 180.107844 -28.581096)
			(xy 180.128418 -28.606242) (xy 180.252878 -28.639516) (xy 180.283358 -28.628086) (xy 180.292502 -28.61437)
			(xy 180.317151 -28.578061) (xy 180.372542 -28.509985) (xy 180.434369 -28.447695) (xy 180.502031 -28.391799)
			(xy 180.574869 -28.342838) (xy 180.652176 -28.301291) (xy 180.7332 -28.26756) (xy 180.817151 -28.241974)
			(xy 180.903215 -28.224782) (xy 180.990554 -28.216151) (xy 181.034436 -28.21559) (xy 181.07373 -28.216023)
			(xy 181.152012 -28.222958) (xy 181.229378 -28.23677) (xy 181.305223 -28.257353) (xy 181.378958 -28.284544)
			(xy 181.414674 -28.300934) (xy 181.420008 -28.303474) (xy 181.430168 -28.305506) (xy 181.435456 -28.306506)
			(xy 181.446216 -28.306506) (xy 181.451504 -28.305506) (xy 181.461664 -28.303474) (xy 181.466998 -28.300934)
			(xy 181.502708 -28.28453) (xy 181.576444 -28.257338) (xy 181.652291 -28.236756) (xy 181.729658 -28.222942)
			(xy 181.807941 -28.216006) (xy 181.847236 -28.21559) (xy 181.88835 -28.216067) (xy 181.970227 -28.223656)
			(xy 182.051054 -28.238768) (xy 182.130143 -28.261273) (xy 182.206817 -28.290978) (xy 182.280424 -28.327631)
			(xy 182.350336 -28.370919) (xy 182.415955 -28.420473) (xy 182.442807 -28.444952) (xy 186.494418 -28.444952)
			(xy 186.498489 -28.38933) (xy 186.510615 -28.334893) (xy 186.530538 -28.282802) (xy 186.557834 -28.234167)
			(xy 186.59192 -28.190024) (xy 186.632069 -28.151315) (xy 186.677427 -28.118864) (xy 186.727027 -28.093363)
			(xy 186.779811 -28.075356) (xy 186.834654 -28.065226) (xy 186.890388 -28.063189) (xy 186.945825 -28.069289)
			(xy 186.999782 -28.083395) (xy 187.051111 -28.105207) (xy 187.098717 -28.134261) (xy 187.141585 -28.169936)
			(xy 187.178802 -28.211473) (xy 187.209575 -28.257986) (xy 187.233247 -28.308483) (xy 187.249315 -28.36189)
			(xy 187.257435 -28.417066) (xy 187.257944 -28.444952) (xy 187.257435 -28.472838) (xy 187.249315 -28.528014)
			(xy 187.233247 -28.581421) (xy 187.209575 -28.631918) (xy 187.178802 -28.678431) (xy 187.141585 -28.719968)
			(xy 187.098717 -28.755643) (xy 187.051111 -28.784697) (xy 186.999782 -28.806509) (xy 186.945825 -28.820615)
			(xy 186.890388 -28.826715) (xy 186.834654 -28.824678) (xy 186.779811 -28.814548) (xy 186.727027 -28.796541)
			(xy 186.677427 -28.77104) (xy 186.632069 -28.738589) (xy 186.59192 -28.69988) (xy 186.557834 -28.655737)
			(xy 186.530538 -28.607102) (xy 186.510615 -28.555011) (xy 186.498489 -28.500574) (xy 186.494418 -28.444952)
			(xy 182.442807 -28.444952) (xy 182.476722 -28.475869) (xy 182.53212 -28.536636) (xy 182.581674 -28.602254)
			(xy 182.624963 -28.672165) (xy 182.661617 -28.745772) (xy 182.691323 -28.822446) (xy 182.713829 -28.901534)
			(xy 182.728942 -28.982361) (xy 182.736533 -29.064238) (xy 182.736998 -29.105352) (xy 182.736424 -29.150191)
			(xy 182.727376 -29.239413) (xy 182.709406 -29.327273) (xy 182.682697 -29.412882) (xy 182.665624 -29.454348)
			(xy 182.663585 -29.459436) (xy 182.661539 -29.470202) (xy 182.66156 -29.475684) (xy 182.661814 -29.484066)
			(xy 182.672482 -29.509466) (xy 182.676677 -29.518627) (xy 182.690842 -29.532936) (xy 182.700886 -29.537152)
			(xy 189.111128 -29.537152) (xy 189.111128 -29.536644) (xy 189.11165 -29.49284) (xy 189.120257 -29.405656)
			(xy 189.137382 -29.319739) (xy 189.162859 -29.235918) (xy 189.196444 -29.155003) (xy 189.23781 -29.077777)
			(xy 189.26175 -29.04109) (xy 189.266488 -29.033413) (xy 189.270801 -29.015909) (xy 189.268782 -28.997996)
			(xy 189.265052 -28.989782) (xy 189.246617 -28.952393) (xy 189.216001 -28.87485) (xy 189.192784 -28.79478)
			(xy 189.177168 -28.712887) (xy 189.169293 -28.629892) (xy 189.168786 -28.588208) (xy 189.169286 -28.545261)
			(xy 189.177583 -28.459767) (xy 189.194081 -28.375472) (xy 189.218628 -28.293159) (xy 189.250993 -28.213594)
			(xy 189.290876 -28.13752) (xy 189.337906 -28.065644) (xy 189.391644 -27.998636) (xy 189.451591 -27.937118)
			(xy 189.517187 -27.881665) (xy 189.587823 -27.832793) (xy 189.662841 -27.790955) (xy 189.741541 -27.756543)
			(xy 189.823192 -27.729877) (xy 189.865 -27.720036) (xy 189.877192 -27.717496) (xy 189.896242 -27.701494)
			(xy 189.937136 -27.601672) (xy 189.935104 -27.577034) (xy 189.928246 -27.566366) (xy 189.905975 -27.530587)
			(xy 189.867522 -27.455587) (xy 189.836332 -27.377288) (xy 189.812685 -27.296391) (xy 189.796793 -27.21362)
			(xy 189.788798 -27.129717) (xy 189.788292 -27.087576) (xy 189.788292 -27.087068) (xy 189.788782 -27.045955)
			(xy 189.796372 -26.964079) (xy 189.811483 -26.883252) (xy 189.833987 -26.804165) (xy 189.863692 -26.727491)
			(xy 189.900344 -26.653885) (xy 189.943632 -26.583975) (xy 189.993184 -26.518356) (xy 190.04858 -26.45759)
			(xy 190.109346 -26.402193) (xy 190.174963 -26.352639) (xy 190.244873 -26.309351) (xy 190.318478 -26.272698)
			(xy 190.395152 -26.242991) (xy 190.474239 -26.220486) (xy 190.555065 -26.205374) (xy 190.636941 -26.197783)
			(xy 190.678054 -26.197306) (xy 190.678308 -26.197306) (xy 190.72097 -26.197804) (xy 190.805902 -26.205981)
			(xy 190.889661 -26.222249) (xy 190.971479 -26.24646) (xy 191.050603 -26.278392) (xy 191.126308 -26.317749)
			(xy 191.197899 -26.364173) (xy 191.264717 -26.417235) (xy 191.295782 -26.44648) (xy 191.302894 -26.453338)
			(xy 191.319912 -26.46045) (xy 191.396874 -26.46299) (xy 191.406108 -26.462877) (xy 191.423562 -26.456897)
			(xy 191.43091 -26.451306) (xy 191.431164 -26.451052) (xy 191.431418 -26.451052) (xy 191.452156 -26.434232)
			(xy 191.497405 -26.405886) (xy 191.54616 -26.384115) (xy 191.597471 -26.369344) (xy 191.650339 -26.36186)
			(xy 191.677036 -26.36139) (xy 191.704304 -26.361891) (xy 191.758285 -26.369656) (xy 191.810611 -26.385024)
			(xy 191.860218 -26.40768) (xy 191.906096 -26.437166) (xy 191.947312 -26.472879) (xy 191.983027 -26.514094)
			(xy 192.012514 -26.559971) (xy 192.035172 -26.609578) (xy 192.050541 -26.661904) (xy 192.058308 -26.715884)
			(xy 192.058798 -26.743152) (xy 192.058278 -26.772098) (xy 192.049518 -26.829325) (xy 192.032221 -26.884573)
			(xy 192.006784 -26.936579) (xy 191.973789 -26.984149) (xy 191.933993 -27.026195) (xy 191.911478 -27.044396)
			(xy 191.902719 -27.05196) (xy 191.892535 -27.072717) (xy 191.89192 -27.084274) (xy 191.89192 -27.16403)
			(xy 191.892524 -27.175594) (xy 191.902694 -27.196366) (xy 191.911478 -27.203908) (xy 191.93401 -27.22209)
			(xy 191.973815 -27.264132) (xy 192.006812 -27.311704) (xy 192.032244 -27.363715) (xy 192.049527 -27.418971)
			(xy 192.058265 -27.476204) (xy 192.058798 -27.505152) (xy 192.058289 -27.533059) (xy 192.050134 -27.588275)
			(xy 192.042542 -27.615134) (xy 192.038952 -27.628364) (xy 192.038346 -27.655763) (xy 192.045051 -27.682337)
			(xy 192.058582 -27.70617) (xy 192.077966 -27.725545) (xy 192.101805 -27.739066) (xy 192.128382 -27.745759)
			(xy 192.155782 -27.745141) (xy 192.169034 -27.741626) (xy 192.19851 -27.733099) (xy 192.25838 -27.719624)
			(xy 192.288668 -27.714702) (xy 192.303162 -27.71204) (xy 192.329806 -27.699474) (xy 192.351752 -27.679823)
			(xy 192.367172 -27.654724) (xy 192.374783 -27.626265) (xy 192.373949 -27.596819) (xy 192.364741 -27.568836)
			(xy 192.35674 -27.55646) (xy 192.331758 -27.51926) (xy 192.288527 -27.440765) (xy 192.253405 -27.358322)
			(xy 192.226747 -27.272767) (xy 192.208823 -27.184965) (xy 192.199816 -27.095806) (xy 192.19926 -27.051)
			(xy 192.199687 -27.010359) (xy 192.207109 -26.929417) (xy 192.221881 -26.849488) (xy 192.243881 -26.77124)
			(xy 192.272926 -26.695325) (xy 192.308773 -26.622374) (xy 192.329562 -26.58745) (xy 192.336401 -26.575383)
			(xy 192.344013 -26.548726) (xy 192.344167 -26.521003) (xy 192.336854 -26.494262) (xy 192.322613 -26.470477)
			(xy 192.302495 -26.451402) (xy 192.277985 -26.438447) (xy 192.264538 -26.43505) (xy 192.222547 -26.425354)
			(xy 192.140515 -26.398925) (xy 192.061423 -26.364688) (xy 191.986012 -26.322963) (xy 191.914989 -26.274142)
			(xy 191.84902 -26.218681) (xy 191.788723 -26.157101) (xy 191.734664 -26.089979) (xy 191.687348 -26.017945)
			(xy 191.64722 -25.941672) (xy 191.614656 -25.861876) (xy 191.58996 -25.779306) (xy 191.573364 -25.694734)
			(xy 191.565024 -25.608954) (xy 191.564514 -25.565862) (xy 191.564647 -25.541812) (xy 191.567188 -25.49378)
			(xy 191.569594 -25.46985) (xy 191.569594 -25.469596) (xy 191.570175 -25.46032) (xy 191.565496 -25.442348)
			(xy 191.56045 -25.434544) (xy 191.538606 -25.40381) (xy 191.523112 -25.393396) (xy 191.514222 -25.391364)
			(xy 191.472747 -25.381211) (xy 191.391786 -25.354065) (xy 191.313796 -25.319289) (xy 191.239497 -25.277201)
			(xy 191.169571 -25.22819) (xy 191.104662 -25.172705) (xy 191.045366 -25.111258) (xy 190.992229 -25.044414)
			(xy 190.94574 -24.972787) (xy 190.906325 -24.897035) (xy 190.874348 -24.817857) (xy 190.850103 -24.73598)
			(xy 190.833813 -24.652156) (xy 190.825627 -24.567158) (xy 190.82512 -24.524462) (xy 190.825583 -24.482788)
			(xy 190.833396 -24.399807) (xy 190.848931 -24.31792) (xy 190.872053 -24.237844) (xy 190.902558 -24.160279)
			(xy 190.94018 -24.085905) (xy 190.984589 -24.015373) (xy 191.035396 -23.949302) (xy 191.092157 -23.888268)
			(xy 191.154374 -23.832808) (xy 191.221503 -23.783406) (xy 191.292956 -23.740495) (xy 191.368107 -23.70445)
			(xy 191.407034 -23.689564) (xy 191.416178 -23.686262) (xy 191.430402 -23.673816) (xy 191.466216 -23.603712)
			(xy 191.470186 -23.595062) (xy 191.472013 -23.576132) (xy 191.469772 -23.566882) (xy 191.459113 -23.527516)
			(xy 191.444204 -23.447327) (xy 191.436712 -23.366109) (xy 191.436244 -23.325328) (xy 191.436244 -23.324566)
			(xy 191.436748 -23.282218) (xy 191.444799 -23.197904) (xy 191.460828 -23.114738) (xy 191.484689 -23.033471)
			(xy 191.516168 -22.954841) (xy 191.554979 -22.87956) (xy 191.600769 -22.808308) (xy 191.653125 -22.741732)
			(xy 191.711573 -22.680434) (xy 191.775583 -22.624969) (xy 191.844575 -22.57584) (xy 191.917925 -22.533491)
			(xy 191.994968 -22.498307) (xy 192.075007 -22.470605) (xy 192.157316 -22.450637) (xy 192.241151 -22.438584)
			(xy 192.325752 -22.434554) (xy 192.410353 -22.438584) (xy 192.494188 -22.450637) (xy 192.576497 -22.470605)
			(xy 192.656536 -22.498307) (xy 192.733579 -22.533491) (xy 192.806929 -22.57584) (xy 192.875921 -22.624969)
			(xy 192.939931 -22.680434) (xy 192.998379 -22.741732) (xy 193.050735 -22.808308) (xy 193.096525 -22.87956)
			(xy 193.135336 -22.954841) (xy 193.166815 -23.033471) (xy 193.190676 -23.114738) (xy 193.206705 -23.197904)
			(xy 193.214756 -23.282218) (xy 193.21526 -23.324566) (xy 193.21526 -23.32482) (xy 193.214715 -23.367484)
			(xy 193.206548 -23.45242) (xy 193.190282 -23.536183) (xy 193.166065 -23.618003) (xy 193.134121 -23.697126)
			(xy 193.094744 -23.772825) (xy 193.048296 -23.844403) (xy 192.995204 -23.911202) (xy 192.935957 -23.972607)
			(xy 192.903856 -24.000714) (xy 192.896468 -24.008963) (xy 192.888974 -24.029778) (xy 192.889378 -24.040846)
			(xy 192.896998 -24.134318) (xy 192.909444 -24.154638) (xy 192.920112 -24.161242) (xy 192.955021 -24.183235)
			(xy 193.021015 -24.232764) (xy 193.082141 -24.28819) (xy 193.137874 -24.349037) (xy 193.187735 -24.414781)
			(xy 193.231296 -24.484858) (xy 193.268184 -24.558667) (xy 193.298081 -24.635573) (xy 193.32073 -24.714917)
			(xy 193.335938 -24.796016) (xy 193.343573 -24.878175) (xy 193.344038 -24.919432) (xy 193.344038 -24.91994)
			(xy 193.343605 -24.958903) (xy 193.336775 -25.03653) (xy 193.32318 -25.113262) (xy 193.302924 -25.188511)
			(xy 193.289936 -25.225248) (xy 193.287255 -25.233743) (xy 193.287271 -25.251545) (xy 193.289936 -25.260046)
			(xy 193.302934 -25.29678) (xy 193.323183 -25.372031) (xy 193.336777 -25.448763) (xy 193.34361 -25.52639)
			(xy 193.344038 -25.565354) (xy 193.344038 -25.565862) (xy 193.343594 -25.606503) (xy 193.336175 -25.687444)
			(xy 193.321406 -25.767372) (xy 193.299409 -25.84562) (xy 193.270367 -25.921536) (xy 193.234523 -25.994487)
			(xy 193.213736 -26.029412) (xy 193.206822 -26.041439) (xy 193.199221 -26.06811) (xy 193.199077 -26.095843)
			(xy 193.206402 -26.122592) (xy 193.220656 -26.146382) (xy 193.240786 -26.165459) (xy 193.265308 -26.178415)
			(xy 193.27876 -26.181812) (xy 193.320741 -26.191545) (xy 193.402772 -26.217972) (xy 193.481863 -26.252207)
			(xy 193.557272 -26.29393) (xy 193.628294 -26.342748) (xy 193.694263 -26.398206) (xy 193.75456 -26.459783)
			(xy 193.80862 -26.526902) (xy 193.855936 -26.598933) (xy 193.896066 -26.675203) (xy 193.928632 -26.754995)
			(xy 193.95333 -26.837562) (xy 193.969929 -26.922131) (xy 193.978272 -27.007909) (xy 193.978784 -27.051)
			(xy 193.978261 -27.093056) (xy 193.970323 -27.176792) (xy 193.954518 -27.259405) (xy 193.930987 -27.340158)
			(xy 193.899939 -27.41833) (xy 193.861653 -27.493223) (xy 193.81647 -27.564168) (xy 193.764793 -27.630532)
			(xy 193.707084 -27.691724) (xy 193.643857 -27.747195) (xy 193.575677 -27.796453) (xy 193.503153 -27.839055)
			(xy 193.426932 -27.874624) (xy 193.347694 -27.90284) (xy 193.266147 -27.923452) (xy 193.224658 -27.930348)
			(xy 193.210176 -27.933045) (xy 193.183548 -27.945617) (xy 193.161615 -27.965265) (xy 193.146201 -27.990355)
			(xy 193.138588 -28.018801) (xy 193.13941 -28.048236) (xy 193.148597 -28.076213) (xy 193.156586 -28.08859)
			(xy 193.181593 -28.125774) (xy 193.22482 -28.204273) (xy 193.259938 -28.286719) (xy 193.286591 -28.372278)
			(xy 193.30451 -28.460082) (xy 193.313512 -28.549243) (xy 193.314066 -28.59405) (xy 193.313562 -28.636411)
			(xy 193.305509 -28.720748) (xy 193.289475 -28.803938) (xy 193.265607 -28.885228) (xy 193.234119 -28.96388)
			(xy 193.195297 -29.039183) (xy 193.149494 -29.110455) (xy 193.097123 -29.177051) (xy 193.038658 -29.238366)
			(xy 192.97463 -29.293847) (xy 192.905618 -29.34299) (xy 192.832248 -29.38535) (xy 192.755183 -29.420545)
			(xy 192.675121 -29.448254) (xy 192.592788 -29.468228) (xy 192.508929 -29.480285) (xy 192.424304 -29.484317)
			(xy 192.339679 -29.480285) (xy 192.25582 -29.468228) (xy 192.173487 -29.448254) (xy 192.093425 -29.420545)
			(xy 192.01636 -29.38535) (xy 191.94299 -29.34299) (xy 191.873978 -29.293847) (xy 191.80995 -29.238366)
			(xy 191.751485 -29.177051) (xy 191.699114 -29.110455) (xy 191.653311 -29.039183) (xy 191.614489 -28.96388)
			(xy 191.583001 -28.885228) (xy 191.559133 -28.803938) (xy 191.543099 -28.720748) (xy 191.535046 -28.636411)
			(xy 191.534542 -28.59405) (xy 191.534542 -28.593796) (xy 191.53504 -28.551927) (xy 191.542923 -28.468562)
			(xy 191.5586 -28.386305) (xy 191.581934 -28.305884) (xy 191.612717 -28.228009) (xy 191.650677 -28.15337)
			(xy 191.69548 -28.082626) (xy 191.720724 -28.04922) (xy 191.728714 -28.038091) (xy 191.739141 -28.012771)
			(xy 191.742445 -27.985589) (xy 191.738389 -27.958509) (xy 191.727265 -27.933488) (xy 191.709878 -27.912334)
			(xy 191.687483 -27.896577) (xy 191.661701 -27.887355) (xy 191.64808 -27.885898) (xy 191.620067 -27.883205)
			(xy 191.565201 -27.870693) (xy 191.512763 -27.850271) (xy 191.463886 -27.822381) (xy 191.419627 -27.787625)
			(xy 191.399922 -27.767534) (xy 191.399414 -27.767026) (xy 191.392454 -27.760383) (xy 191.374958 -27.752418)
			(xy 191.365378 -27.751532) (xy 191.295782 -27.747976) (xy 191.285966 -27.747964) (xy 191.267423 -27.754347)
			(xy 191.259714 -27.760422) (xy 191.22611 -27.788751) (xy 191.154255 -27.839374) (xy 191.077762 -27.882672)
			(xy 190.997375 -27.918223) (xy 190.913877 -27.945681) (xy 190.871094 -27.955748) (xy 190.858648 -27.958542)
			(xy 190.839852 -27.974544) (xy 190.798958 -28.074366) (xy 190.801244 -28.09875) (xy 190.807848 -28.109164)
			(xy 190.830141 -28.144954) (xy 190.868609 -28.219995) (xy 190.899805 -28.298338) (xy 190.92345 -28.379281)
			(xy 190.939332 -28.462097) (xy 190.947308 -28.546045) (xy 190.947802 -28.588208) (xy 190.947802 -28.588716)
			(xy 190.947271 -28.63252) (xy 190.938668 -28.719703) (xy 190.921545 -28.805621) (xy 190.896069 -28.889442)
			(xy 190.862486 -28.970357) (xy 190.82112 -29.047583) (xy 190.79718 -29.08427) (xy 190.792396 -29.091923)
			(xy 190.788095 -29.109441) (xy 190.790136 -29.127364) (xy 190.793878 -29.135578) (xy 190.812337 -29.172956)
			(xy 190.842948 -29.250502) (xy 190.86616 -29.330575) (xy 190.88177 -29.41247) (xy 190.88964 -29.495468)
			(xy 190.890144 -29.537152) (xy 190.88964 -29.5795) (xy 190.881589 -29.663814) (xy 190.86556 -29.74698)
			(xy 190.841699 -29.828247) (xy 190.81022 -29.906877) (xy 190.771409 -29.982158) (xy 190.725619 -30.05341)
			(xy 190.673263 -30.119986) (xy 190.660093 -30.133798) (xy 197.596506 -30.133798) (xy 197.59695 -30.092694)
			(xy 197.604536 -30.010838) (xy 197.619641 -29.93003) (xy 197.642139 -29.850962) (xy 197.671836 -29.774306)
			(xy 197.708479 -29.700717) (xy 197.751756 -29.630823) (xy 197.801298 -29.565221) (xy 197.856681 -29.50447)
			(xy 197.917433 -29.449088) (xy 197.983037 -29.399547) (xy 198.052931 -29.356272) (xy 198.12652 -29.31963)
			(xy 198.203177 -29.289934) (xy 198.282246 -29.267438) (xy 198.363054 -29.252333) (xy 198.44491 -29.24475)
			(xy 198.486014 -29.24429) (xy 198.524302 -29.244732) (xy 198.600592 -29.251352) (xy 198.676032 -29.264497)
			(xy 198.750064 -29.284071) (xy 198.786242 -29.296614) (xy 198.794679 -29.299265) (xy 198.812349 -29.299265)
			(xy 198.820786 -29.296614) (xy 198.856959 -29.284053) (xy 198.930989 -29.264458) (xy 199.006431 -29.251308)
			(xy 199.082724 -29.2447) (xy 199.121014 -29.24429) (xy 199.159302 -29.244732) (xy 199.235592 -29.251352)
			(xy 199.311032 -29.264497) (xy 199.385064 -29.284071) (xy 199.421242 -29.296614) (xy 199.429679 -29.299265)
			(xy 199.447349 -29.299265) (xy 199.455786 -29.296614) (xy 199.491959 -29.284053) (xy 199.565989 -29.264458)
			(xy 199.641431 -29.251308) (xy 199.717724 -29.2447) (xy 199.756014 -29.24429) (xy 199.794302 -29.244732)
			(xy 199.870592 -29.251352) (xy 199.946032 -29.264497) (xy 200.020064 -29.284071) (xy 200.056242 -29.296614)
			(xy 200.064679 -29.299265) (xy 200.082349 -29.299265) (xy 200.090786 -29.296614) (xy 200.126959 -29.284053)
			(xy 200.200989 -29.264458) (xy 200.276431 -29.251308) (xy 200.352724 -29.2447) (xy 200.391014 -29.24429)
			(xy 200.431701 -29.244705) (xy 200.512736 -29.25213) (xy 200.592753 -29.266926) (xy 200.671084 -29.28897)
			(xy 200.747075 -29.318076) (xy 200.820089 -29.354002) (xy 200.889516 -29.396447) (xy 200.954776 -29.445056)
			(xy 201.015323 -29.499423) (xy 201.07065 -29.559094) (xy 201.120296 -29.623569) (xy 201.163845 -29.692309)
			(xy 201.200933 -29.76474) (xy 201.216514 -29.802328) (xy 201.222864 -29.818076) (xy 201.251312 -29.835602)
			(xy 201.269854 -29.833824) (xy 201.287604 -29.832497) (xy 201.323175 -29.831101) (xy 201.340974 -29.83103)
			(xy 201.382078 -29.831477) (xy 201.463935 -29.83906) (xy 201.544743 -29.854164) (xy 201.623813 -29.87666)
			(xy 201.70047 -29.906356) (xy 201.774059 -29.942998) (xy 201.843954 -29.986275) (xy 201.909557 -30.035816)
			(xy 201.970309 -30.091199) (xy 202.025692 -30.151952) (xy 202.075232 -30.217556) (xy 202.118507 -30.287451)
			(xy 202.155149 -30.361041) (xy 202.184844 -30.437698) (xy 202.207339 -30.516768) (xy 202.222442 -30.597577)
			(xy 202.230024 -30.679434) (xy 202.230482 -30.720538) (xy 202.23007 -30.761642) (xy 202.222481 -30.843499)
			(xy 202.207372 -30.924306) (xy 202.184872 -31.003375) (xy 202.155172 -31.08003) (xy 202.118526 -31.153618)
			(xy 202.075246 -31.223511) (xy 202.025702 -31.289112) (xy 201.970317 -31.349863) (xy 201.909563 -31.405243)
			(xy 201.843958 -31.454782) (xy 201.774062 -31.498057) (xy 201.700471 -31.534698) (xy 201.623814 -31.564392)
			(xy 201.544744 -31.586887) (xy 201.463935 -31.60199) (xy 201.382078 -31.609573) (xy 201.340974 -31.610046)
			(xy 201.302686 -31.609605) (xy 201.226396 -31.602985) (xy 201.150956 -31.589839) (xy 201.076924 -31.570265)
			(xy 201.040746 -31.557722) (xy 201.032309 -31.555071) (xy 201.014639 -31.555071) (xy 201.006202 -31.557722)
			(xy 200.97003 -31.570287) (xy 200.896 -31.589881) (xy 200.820558 -31.60303) (xy 200.744264 -31.609636)
			(xy 200.705974 -31.610046) (xy 200.667686 -31.609605) (xy 200.591396 -31.602985) (xy 200.515956 -31.589839)
			(xy 200.441924 -31.570265) (xy 200.405746 -31.557722) (xy 200.397309 -31.555071) (xy 200.379639 -31.555071)
			(xy 200.371202 -31.557722) (xy 200.33503 -31.570287) (xy 200.261 -31.589881) (xy 200.185558 -31.60303)
			(xy 200.109264 -31.609636) (xy 200.070974 -31.610046) (xy 200.032686 -31.609605) (xy 199.956396 -31.602985)
			(xy 199.880956 -31.589839) (xy 199.806924 -31.570265) (xy 199.770746 -31.557722) (xy 199.762309 -31.555071)
			(xy 199.744639 -31.555071) (xy 199.736202 -31.557722) (xy 199.70003 -31.570287) (xy 199.626 -31.589881)
			(xy 199.550558 -31.60303) (xy 199.474264 -31.609636) (xy 199.435974 -31.610046) (xy 199.395289 -31.609531)
			(xy 199.314259 -31.602114) (xy 199.234244 -31.587326) (xy 199.155915 -31.565292) (xy 199.079926 -31.536194)
			(xy 199.006913 -31.500276) (xy 198.937486 -31.45784) (xy 198.872226 -31.409239) (xy 198.811678 -31.35488)
			(xy 198.756348 -31.295217) (xy 198.7067 -31.23075) (xy 198.663148 -31.162017) (xy 198.626057 -31.089593)
			(xy 198.610474 -31.052008) (xy 198.604124 -31.03626) (xy 198.575676 -31.018734) (xy 198.557134 -31.020512)
			(xy 198.539384 -31.021833) (xy 198.503813 -31.023233) (xy 198.486014 -31.023306) (xy 198.444911 -31.022834)
			(xy 198.363056 -31.015251) (xy 198.282249 -31.000146) (xy 198.203181 -30.977651) (xy 198.126526 -30.947955)
			(xy 198.052938 -30.911314) (xy 197.983044 -30.868039) (xy 197.917442 -30.818499) (xy 197.856691 -30.763118)
			(xy 197.801309 -30.702367) (xy 197.751768 -30.636765) (xy 197.708492 -30.566873) (xy 197.671849 -30.493285)
			(xy 197.642153 -30.41663) (xy 197.619656 -30.337563) (xy 197.604551 -30.256756) (xy 197.596966 -30.174901)
			(xy 197.596506 -30.133798) (xy 190.660093 -30.133798) (xy 190.614815 -30.181284) (xy 190.550805 -30.236749)
			(xy 190.481813 -30.285878) (xy 190.408463 -30.328227) (xy 190.33142 -30.363411) (xy 190.251381 -30.391113)
			(xy 190.169072 -30.411081) (xy 190.085237 -30.423134) (xy 190.000636 -30.427165) (xy 189.916035 -30.423134)
			(xy 189.8322 -30.411081) (xy 189.749891 -30.391113) (xy 189.669852 -30.363411) (xy 189.592809 -30.328227)
			(xy 189.519459 -30.285878) (xy 189.450467 -30.236749) (xy 189.386457 -30.181284) (xy 189.328009 -30.119986)
			(xy 189.275653 -30.05341) (xy 189.229863 -29.982158) (xy 189.191052 -29.906877) (xy 189.159573 -29.828247)
			(xy 189.135712 -29.74698) (xy 189.119683 -29.663814) (xy 189.111632 -29.5795) (xy 189.111128 -29.537152)
			(xy 182.700886 -29.537152) (xy 182.709407 -29.540729) (xy 182.719472 -29.541216) (xy 187.314586 -29.541216)
			(xy 187.324649 -29.541655) (xy 187.343229 -29.549393) (xy 187.350654 -29.556202) (xy 189.264616 -31.470092)
			(xy 193.210434 -31.470092) (xy 193.21092 -31.442841) (xy 193.218676 -31.388893) (xy 193.234031 -31.336598)
			(xy 193.256673 -31.287021) (xy 193.286139 -31.241171) (xy 193.32183 -31.19998) (xy 193.363021 -31.164289)
			(xy 193.408871 -31.134823) (xy 193.458448 -31.112181) (xy 193.510743 -31.096826) (xy 193.564691 -31.08907)
			(xy 193.619193 -31.08907) (xy 193.673141 -31.096826) (xy 193.725436 -31.112181) (xy 193.775013 -31.134823)
			(xy 193.820863 -31.164289) (xy 193.862054 -31.19998) (xy 193.897745 -31.241171) (xy 193.927211 -31.287021)
			(xy 193.949853 -31.336598) (xy 193.965208 -31.388893) (xy 193.972964 -31.442841) (xy 193.97345 -31.470092)
			(xy 193.97345 -31.470346) (xy 193.973009 -31.496175) (xy 193.966011 -31.547359) (xy 193.952177 -31.597131)
			(xy 193.931758 -31.644585) (xy 193.905129 -31.688852) (xy 193.872774 -31.729124) (xy 193.854324 -31.747206)
			(xy 193.84645 -31.754572) (xy 193.838322 -31.773876) (xy 193.839338 -31.858966) (xy 193.839462 -31.864203)
			(xy 193.841648 -31.874447) (xy 193.843656 -31.879286) (xy 193.847974 -31.888684) (xy 193.855848 -31.89605)
			(xy 193.856102 -31.896304) (xy 193.875282 -31.914433) (xy 193.908934 -31.95509) (xy 193.93666 -31.999998)
			(xy 193.95793 -32.0483) (xy 193.972338 -32.099073) (xy 193.979609 -32.151347) (xy 193.980054 -32.177736)
			(xy 193.979507 -32.206652) (xy 193.970787 -32.263823) (xy 193.953536 -32.319022) (xy 193.928149 -32.370984)
			(xy 193.89521 -32.418519) (xy 193.855472 -32.460536) (xy 193.832988 -32.478726) (xy 193.824177 -32.48633)
			(xy 193.813996 -32.507233) (xy 193.81343 -32.518858) (xy 193.81343 -32.598614) (xy 193.813965 -32.610247)
			(xy 193.824156 -32.631157) (xy 193.832988 -32.638746) (xy 193.855443 -32.656971) (xy 193.895181 -32.698983)
			(xy 193.928123 -32.746511) (xy 193.953517 -32.798466) (xy 193.970779 -32.853657) (xy 193.979515 -32.910822)
			(xy 193.980054 -32.939736) (xy 193.979568 -32.966987) (xy 193.971812 -33.020935) (xy 193.956457 -33.07323)
			(xy 193.933815 -33.122807) (xy 193.904349 -33.168657) (xy 193.868658 -33.209848) (xy 193.827467 -33.245539)
			(xy 193.781617 -33.275005) (xy 193.73204 -33.297647) (xy 193.679745 -33.313002) (xy 193.625797 -33.320758)
			(xy 193.571295 -33.320758) (xy 193.517347 -33.313002) (xy 193.465052 -33.297647) (xy 193.415475 -33.275005)
			(xy 193.369625 -33.245539) (xy 193.328434 -33.209848) (xy 193.292743 -33.168657) (xy 193.263277 -33.122807)
			(xy 193.240635 -33.07323) (xy 193.22528 -33.020935) (xy 193.217524 -32.966987) (xy 193.217038 -32.939736)
			(xy 193.217568 -32.910819) (xy 193.226292 -32.853648) (xy 193.243547 -32.798449) (xy 193.268936 -32.746487)
			(xy 193.301879 -32.698953) (xy 193.341619 -32.656936) (xy 193.364104 -32.638746) (xy 193.372881 -32.63111)
			(xy 193.383081 -32.610231) (xy 193.383662 -32.598614) (xy 193.383662 -32.518858) (xy 193.383146 -32.507223)
			(xy 193.372942 -32.486313) (xy 193.364104 -32.478726) (xy 193.341634 -32.460519) (xy 193.301898 -32.418503)
			(xy 193.268957 -32.370971) (xy 193.243566 -32.319013) (xy 193.226307 -32.263818) (xy 193.217575 -32.206651)
			(xy 193.217038 -32.177736) (xy 193.217038 -32.177482) (xy 193.217502 -32.151653) (xy 193.224495 -32.100471)
			(xy 193.238325 -32.050699) (xy 193.25874 -32.003246) (xy 193.285365 -31.958978) (xy 193.317716 -31.918705)
			(xy 193.336164 -31.900622) (xy 193.344038 -31.893256) (xy 193.352166 -31.873952) (xy 193.35115 -31.788862)
			(xy 193.351011 -31.783626) (xy 193.348834 -31.773382) (xy 193.346832 -31.768542) (xy 193.342514 -31.759144)
			(xy 193.33464 -31.751778) (xy 193.334386 -31.751524) (xy 193.315217 -31.733384) (xy 193.281564 -31.692729)
			(xy 193.253837 -31.647823) (xy 193.232565 -31.599523) (xy 193.218154 -31.548753) (xy 193.21088 -31.49648)
			(xy 193.210434 -31.470092) (xy 189.264616 -31.470092) (xy 191.991155 -34.196528) (xy 208.182208 -34.196528)
			(xy 208.186279 -34.140906) (xy 208.198405 -34.086469) (xy 208.218328 -34.034378) (xy 208.245624 -33.985743)
			(xy 208.27971 -33.9416) (xy 208.319859 -33.902891) (xy 208.365217 -33.87044) (xy 208.414817 -33.844939)
			(xy 208.467601 -33.826932) (xy 208.522444 -33.816802) (xy 208.578178 -33.814765) (xy 208.633615 -33.820865)
			(xy 208.687572 -33.834971) (xy 208.738901 -33.856783) (xy 208.786507 -33.885837) (xy 208.829375 -33.921512)
			(xy 208.866592 -33.963049) (xy 208.897365 -34.009562) (xy 208.921037 -34.060059) (xy 208.937105 -34.113466)
			(xy 208.945225 -34.168642) (xy 208.945734 -34.196528) (xy 208.945225 -34.224414) (xy 208.937105 -34.27959)
			(xy 208.921037 -34.332997) (xy 208.897365 -34.383494) (xy 208.866592 -34.430007) (xy 208.829375 -34.471544)
			(xy 208.786507 -34.507219) (xy 208.738901 -34.536273) (xy 208.687572 -34.558085) (xy 208.633615 -34.572191)
			(xy 208.578178 -34.578291) (xy 208.522444 -34.576254) (xy 208.467601 -34.566124) (xy 208.414817 -34.548117)
			(xy 208.365217 -34.522616) (xy 208.319859 -34.490165) (xy 208.27971 -34.451456) (xy 208.245624 -34.407313)
			(xy 208.218328 -34.358678) (xy 208.198405 -34.306587) (xy 208.186279 -34.25215) (xy 208.182208 -34.196528)
			(xy 191.991155 -34.196528) (xy 193.316831 -35.522154) (xy 206.00162 -35.522154) (xy 206.002124 -35.479806)
			(xy 206.010175 -35.395492) (xy 206.026204 -35.312326) (xy 206.050065 -35.231059) (xy 206.081544 -35.152429)
			(xy 206.120355 -35.077148) (xy 206.166145 -35.005896) (xy 206.218501 -34.93932) (xy 206.276949 -34.878022)
			(xy 206.340959 -34.822557) (xy 206.409951 -34.773428) (xy 206.483301 -34.731079) (xy 206.560344 -34.695895)
			(xy 206.640383 -34.668193) (xy 206.722692 -34.648225) (xy 206.806527 -34.636172) (xy 206.891128 -34.632142)
			(xy 206.975729 -34.636172) (xy 207.059564 -34.648225) (xy 207.141873 -34.668193) (xy 207.221912 -34.695895)
			(xy 207.298955 -34.731079) (xy 207.372305 -34.773428) (xy 207.441297 -34.822557) (xy 207.505307 -34.878022)
			(xy 207.563755 -34.93932) (xy 207.616111 -35.005896) (xy 207.661901 -35.077148) (xy 207.700712 -35.152429)
			(xy 207.732191 -35.231059) (xy 207.756052 -35.312326) (xy 207.772081 -35.395492) (xy 207.780132 -35.479806)
			(xy 207.780636 -35.522154) (xy 207.780113 -35.566205) (xy 207.771407 -35.653875) (xy 207.754076 -35.740255)
			(xy 207.728289 -35.824498) (xy 207.6943 -35.905779) (xy 207.652441 -35.983302) (xy 207.603122 -36.056305)
			(xy 207.546828 -36.124076) (xy 207.484109 -36.185948) (xy 207.450182 -36.21405) (xy 207.443245 -36.220141)
			(xy 207.43386 -36.236019) (xy 207.431894 -36.245038) (xy 207.431132 -36.254182) (xy 207.431894 -36.333176)
			(xy 207.432055 -36.338899) (xy 207.434627 -36.350052) (xy 207.436974 -36.355274) (xy 207.439544 -36.360212)
			(xy 207.446454 -36.368936) (xy 207.45069 -36.372546) (xy 207.451198 -36.3728) (xy 207.451452 -36.373054)
			(xy 207.482743 -36.398287) (xy 207.541149 -36.453524) (xy 207.594332 -36.513806) (xy 207.641859 -36.578642)
			(xy 207.68334 -36.647502) (xy 207.718438 -36.719824) (xy 207.746866 -36.795019) (xy 207.768393 -36.872472)
			(xy 207.782842 -36.951552) (xy 207.790096 -37.031613) (xy 207.790542 -37.071808) (xy 207.790038 -37.114156)
			(xy 207.781987 -37.19847) (xy 207.765958 -37.281636) (xy 207.742097 -37.362903) (xy 207.710618 -37.441533)
			(xy 207.671807 -37.516814) (xy 207.626017 -37.588066) (xy 207.573661 -37.654642) (xy 207.515213 -37.71594)
			(xy 207.451203 -37.771405) (xy 207.382211 -37.820534) (xy 207.308861 -37.862883) (xy 207.231818 -37.898067)
			(xy 207.151779 -37.925769) (xy 207.06947 -37.945737) (xy 206.985635 -37.95779) (xy 206.901034 -37.961821)
			(xy 206.816433 -37.95779) (xy 206.732598 -37.945737) (xy 206.650289 -37.925769) (xy 206.57025 -37.898067)
			(xy 206.493207 -37.862883) (xy 206.419857 -37.820534) (xy 206.350865 -37.771405) (xy 206.286855 -37.71594)
			(xy 206.228407 -37.654642) (xy 206.176051 -37.588066) (xy 206.130261 -37.516814) (xy 206.09145 -37.441533)
			(xy 206.059971 -37.362903) (xy 206.03611 -37.281636) (xy 206.020081 -37.19847) (xy 206.01203 -37.114156)
			(xy 206.011526 -37.071808) (xy 206.012109 -37.027759) (xy 206.020808 -36.940091) (xy 206.038132 -36.853713)
			(xy 206.063912 -36.769471) (xy 206.097894 -36.68819) (xy 206.139746 -36.610668) (xy 206.189057 -36.537663)
			(xy 206.245344 -36.469891) (xy 206.308057 -36.408016) (xy 206.34198 -36.379912) (xy 206.348941 -36.373845)
			(xy 206.35831 -36.357949) (xy 206.360268 -36.348924) (xy 206.36103 -36.33978) (xy 206.360268 -36.260786)
			(xy 206.36009 -36.255065) (xy 206.35753 -36.243911) (xy 206.355188 -36.238688) (xy 206.352634 -36.233741)
			(xy 206.345713 -36.225023) (xy 206.341472 -36.221416) (xy 206.340964 -36.221162) (xy 206.34071 -36.220908)
			(xy 206.309393 -36.195707) (xy 206.250988 -36.140466) (xy 206.197807 -36.080179) (xy 206.150283 -36.015339)
			(xy 206.108805 -35.946475) (xy 206.073709 -35.874149) (xy 206.045284 -35.798952) (xy 206.023761 -35.721495)
			(xy 206.009315 -35.642413) (xy 206.002065 -35.56235) (xy 206.00162 -35.522154) (xy 193.316831 -35.522154)
			(xy 194.083432 -36.288726) (xy 194.090829 -36.295575) (xy 194.109428 -36.30331) (xy 194.1195 -36.303712)
			(xy 195.190872 -36.303712) (xy 195.198131 -36.303415) (xy 195.212055 -36.299289) (xy 195.218304 -36.295584)
			(xy 195.245736 -36.278058) (xy 195.254626 -36.268152) (xy 195.257674 -36.261802) (xy 195.270101 -36.238071)
			(xy 195.300607 -36.194038) (xy 195.336974 -36.154707) (xy 195.378487 -36.120851) (xy 195.424329 -36.093136)
			(xy 195.473597 -36.072109) (xy 195.525324 -36.058183) (xy 195.578489 -36.051631) (xy 195.632049 -36.052583)
			(xy 195.684949 -36.061019) (xy 195.736147 -36.076775) (xy 195.784637 -36.09954) (xy 195.829465 -36.128865)
			(xy 195.869749 -36.164175) (xy 195.904696 -36.204774) (xy 195.933618 -36.249863) (xy 195.945252 -36.273994)
			(xy 195.951602 -36.28771) (xy 195.976494 -36.303712) (xy 196.67347 -36.303712) (xy 196.683534 -36.304148)
			(xy 196.702119 -36.311882) (xy 196.709538 -36.318698) (xy 199.252586 -38.861746) (xy 199.253094 -38.862254)
			(xy 199.260477 -38.86883) (xy 199.278777 -38.876265) (xy 199.288654 -38.876732)
		)
		(stroke
			(width 0)
			(type solid)
		)
		(fill yes)
		(layer "In15.Cu")
		(net "P12V_SCM_R")
	)
	(gr_poly
		(pts
			(xy 168.677844 -389.0772) (xy 168.686453 -389.076862) (xy 168.702704 -389.071171) (xy 168.71617 -389.060442)
			(xy 168.721024 -389.053324) (xy 168.773856 -388.96925) (xy 168.775126 -388.943596) (xy 168.769538 -388.931658)
			(xy 168.75759 -388.905705) (xy 168.740734 -388.851113) (xy 168.732214 -388.794617) (xy 168.731692 -388.76605)
			(xy 168.732156 -388.739175) (xy 168.739711 -388.685957) (xy 168.754666 -388.634328) (xy 168.776722 -388.585311)
			(xy 168.805444 -388.539877) (xy 168.840262 -388.498927) (xy 168.880485 -388.463273) (xy 168.902634 -388.448042)
			(xy 168.913302 -388.44093) (xy 168.92524 -388.418832) (xy 168.926256 -388.309358) (xy 168.914826 -388.287006)
			(xy 168.904158 -388.27964) (xy 168.882773 -388.264297) (xy 168.84403 -388.228674) (xy 168.810552 -388.188063)
			(xy 168.782975 -388.143235) (xy 168.761822 -388.095042) (xy 168.747495 -388.044398) (xy 168.740266 -387.992266)
			(xy 168.73982 -387.96595) (xy 168.740306 -387.938699) (xy 168.748062 -387.884751) (xy 168.763417 -387.832456)
			(xy 168.786059 -387.782879) (xy 168.815525 -387.737029) (xy 168.851216 -387.695838) (xy 168.892407 -387.660147)
			(xy 168.938257 -387.630681) (xy 168.987834 -387.608039) (xy 169.040129 -387.592684) (xy 169.094077 -387.584928)
			(xy 169.148579 -387.584928) (xy 169.202527 -387.592684) (xy 169.254822 -387.608039) (xy 169.304399 -387.630681)
			(xy 169.350249 -387.660147) (xy 169.39144 -387.695838) (xy 169.427131 -387.737029) (xy 169.456597 -387.782879)
			(xy 169.479239 -387.832456) (xy 169.494594 -387.884751) (xy 169.50235 -387.938699) (xy 169.502836 -387.96595)
			(xy 169.502372 -387.992825) (xy 169.494816 -388.04604) (xy 169.479859 -388.097667) (xy 169.4578 -388.146681)
			(xy 169.429075 -388.192111) (xy 169.394254 -388.233056) (xy 169.354026 -388.268704) (xy 169.331894 -388.283958)
			(xy 169.321226 -388.29107) (xy 169.309288 -388.313168) (xy 169.308272 -388.422642) (xy 169.319702 -388.444994)
			(xy 169.33037 -388.45236) (xy 169.351758 -388.467701) (xy 169.390508 -388.50332) (xy 169.423992 -388.54393)
			(xy 169.451575 -388.588758) (xy 169.472732 -388.636952) (xy 169.487062 -388.687598) (xy 169.494292 -388.739733)
			(xy 169.494708 -388.76605) (xy 169.494195 -388.794617) (xy 169.485664 -388.851111) (xy 169.468799 -388.905699)
			(xy 169.456862 -388.931658) (xy 169.451274 -388.943596) (xy 169.452544 -388.96925) (xy 169.505376 -389.053324)
			(xy 169.510211 -389.060465) (xy 169.523662 -389.07124) (xy 169.539937 -389.076908) (xy 169.548556 -389.0772)
			(xy 171.022518 -389.0772) (xy 171.032587 -389.076773) (xy 171.051186 -389.069054) (xy 171.058586 -389.062214)
			(xy 171.384214 -388.736586) (xy 171.391068 -388.729191) (xy 171.39881 -388.710592) (xy 171.3992 -388.700518)
			(xy 171.3992 -386.462524) (xy 171.398767 -386.452827) (xy 171.39158 -386.434814) (xy 171.38523 -386.427472)
			(xy 171.364402 -386.405628) (xy 171.357897 -386.399323) (xy 171.341624 -386.39139) (xy 171.332652 -386.390134)
			(xy 171.30475 -386.386857) (xy 171.250269 -386.373157) (xy 171.198386 -386.351613) (xy 171.150225 -386.322693)
			(xy 171.106827 -386.28702) (xy 171.06913 -386.245367) (xy 171.037952 -386.198636) (xy 171.013966 -386.147836)
			(xy 170.997691 -386.094067) (xy 170.989479 -386.038493) (xy 170.98899 -386.010404) (xy 170.989414 -385.98491)
			(xy 170.996201 -385.934377) (xy 171.009656 -385.885197) (xy 171.019216 -385.86156) (xy 171.025312 -385.847336)
			(xy 171.01947 -385.81711) (xy 170.479466 -385.277106) (xy 170.472611 -385.269711) (xy 170.464864 -385.251112)
			(xy 170.46448 -385.241038) (xy 170.46448 -382.980692) (xy 170.464055 -382.970623) (xy 170.456336 -382.952022)
			(xy 170.449494 -382.944624) (xy 170.357546 -382.852676) (xy 170.350148 -382.84583) (xy 170.331549 -382.838103)
			(xy 170.321478 -382.83769) (xy 167.40505 -382.83769) (xy 167.37584 -382.865376) (xy 167.374824 -382.885696)
			(xy 167.373023 -382.910742) (xy 167.362804 -382.959905) (xy 167.345272 -383.006959) (xy 167.32083 -383.050822)
			(xy 167.290039 -383.090487) (xy 167.253608 -383.125043) (xy 167.212371 -383.153696) (xy 167.167278 -383.175787)
			(xy 167.119364 -383.190809) (xy 167.069731 -383.198417) (xy 167.044624 -383.198878) (xy 167.020852 -383.198461)
			(xy 166.9738 -383.191641) (xy 166.928209 -383.178153) (xy 166.88502 -383.158274) (xy 166.845123 -383.132416)
			(xy 166.826946 -383.11709) (xy 166.819823 -383.111413) (xy 166.802772 -383.105043) (xy 166.793672 -383.104644)
			(xy 166.762176 -383.104644) (xy 166.753068 -383.10501) (xy 166.736001 -383.111374) (xy 166.728902 -383.11709)
			(xy 166.710743 -383.132442) (xy 166.670849 -383.158314) (xy 166.627656 -383.178199) (xy 166.582059 -383.191684)
			(xy 166.534999 -383.198492) (xy 166.511224 -383.198878) (xy 166.484352 -383.198354) (xy 166.431317 -383.189665)
			(xy 166.380385 -383.172511) (xy 166.332899 -383.147344) (xy 166.290109 -383.114827) (xy 166.253142 -383.075816)
			(xy 166.237666 -383.053844) (xy 166.231062 -383.044446) (xy 166.211758 -383.033016) (xy 166.12235 -383.02438)
			(xy 166.11113 -383.023951) (xy 166.090043 -383.031588) (xy 166.08171 -383.039112) (xy 165.492684 -383.628138)
			(xy 165.485287 -383.634988) (xy 165.466689 -383.642727) (xy 165.456616 -383.643124) (xy 155.417266 -383.643124)
			(xy 155.407199 -383.643554) (xy 155.388606 -383.65128) (xy 155.381198 -383.65811) (xy 154.59456 -384.444748)
			(xy 154.588718 -384.474974) (xy 154.594814 -384.489198) (xy 154.603015 -384.509621) (xy 154.614557 -384.552092)
			(xy 154.620371 -384.595717) (xy 154.620722 -384.617722) (xy 154.620211 -384.643708) (xy 154.620211 -384.643709)
			(xy 155.159966 -384.643709) (xy 155.159966 -384.591735) (xy 155.168096 -384.5404) (xy 155.184157 -384.49097)
			(xy 155.207753 -384.44466) (xy 155.238303 -384.402612) (xy 155.275054 -384.365861) (xy 155.317102 -384.335311)
			(xy 155.363412 -384.311715) (xy 155.412842 -384.295654) (xy 155.464177 -384.287524) (xy 155.516151 -384.287524)
			(xy 155.567486 -384.295654) (xy 155.616916 -384.311715) (xy 155.663226 -384.335311) (xy 155.705274 -384.365861)
			(xy 155.742025 -384.402612) (xy 155.772575 -384.44466) (xy 155.796171 -384.49097) (xy 155.812232 -384.5404)
			(xy 155.820362 -384.591735) (xy 155.820872 -384.617722) (xy 155.820362 -384.643709) (xy 156.359862 -384.643709)
			(xy 156.359862 -384.591735) (xy 156.367992 -384.5404) (xy 156.384053 -384.49097) (xy 156.407649 -384.44466)
			(xy 156.438199 -384.402612) (xy 156.47495 -384.365861) (xy 156.516998 -384.335311) (xy 156.563308 -384.311715)
			(xy 156.612738 -384.295654) (xy 156.664073 -384.287524) (xy 156.716047 -384.287524) (xy 156.767382 -384.295654)
			(xy 156.816812 -384.311715) (xy 156.863122 -384.335311) (xy 156.90517 -384.365861) (xy 156.941921 -384.402612)
			(xy 156.972471 -384.44466) (xy 156.996067 -384.49097) (xy 157.012128 -384.5404) (xy 157.020258 -384.591735)
			(xy 157.020768 -384.617722) (xy 157.020258 -384.643709) (xy 157.560012 -384.643709) (xy 157.560012 -384.591735)
			(xy 157.568142 -384.5404) (xy 157.584203 -384.49097) (xy 157.607799 -384.44466) (xy 157.638349 -384.402612)
			(xy 157.6751 -384.365861) (xy 157.717148 -384.335311) (xy 157.763458 -384.311715) (xy 157.812888 -384.295654)
			(xy 157.864223 -384.287524) (xy 157.916197 -384.287524) (xy 157.967532 -384.295654) (xy 158.016962 -384.311715)
			(xy 158.063272 -384.335311) (xy 158.10532 -384.365861) (xy 158.142071 -384.402612) (xy 158.172621 -384.44466)
			(xy 158.196217 -384.49097) (xy 158.212278 -384.5404) (xy 158.220408 -384.591735) (xy 158.220918 -384.617722)
			(xy 158.220408 -384.643709) (xy 158.759908 -384.643709) (xy 158.759908 -384.591735) (xy 158.768038 -384.5404)
			(xy 158.784099 -384.49097) (xy 158.807695 -384.44466) (xy 158.838245 -384.402612) (xy 158.874996 -384.365861)
			(xy 158.917044 -384.335311) (xy 158.963354 -384.311715) (xy 159.012784 -384.295654) (xy 159.064119 -384.287524)
			(xy 159.116093 -384.287524) (xy 159.167428 -384.295654) (xy 159.216858 -384.311715) (xy 159.263168 -384.335311)
			(xy 159.305216 -384.365861) (xy 159.341967 -384.402612) (xy 159.372517 -384.44466) (xy 159.396113 -384.49097)
			(xy 159.412174 -384.5404) (xy 159.420304 -384.591735) (xy 159.420814 -384.617722) (xy 159.420304 -384.643709)
			(xy 159.959804 -384.643709) (xy 159.959804 -384.591735) (xy 159.967934 -384.5404) (xy 159.983995 -384.49097)
			(xy 160.007591 -384.44466) (xy 160.038141 -384.402612) (xy 160.074892 -384.365861) (xy 160.11694 -384.335311)
			(xy 160.16325 -384.311715) (xy 160.21268 -384.295654) (xy 160.264015 -384.287524) (xy 160.315989 -384.287524)
			(xy 160.367324 -384.295654) (xy 160.416754 -384.311715) (xy 160.463064 -384.335311) (xy 160.505112 -384.365861)
			(xy 160.541863 -384.402612) (xy 160.572413 -384.44466) (xy 160.596009 -384.49097) (xy 160.61207 -384.5404)
			(xy 160.6202 -384.591735) (xy 160.62071 -384.617722) (xy 160.6202 -384.643709) (xy 161.159954 -384.643709)
			(xy 161.159954 -384.591735) (xy 161.168084 -384.5404) (xy 161.184145 -384.49097) (xy 161.207741 -384.44466)
			(xy 161.238291 -384.402612) (xy 161.275042 -384.365861) (xy 161.31709 -384.335311) (xy 161.3634 -384.311715)
			(xy 161.41283 -384.295654) (xy 161.464165 -384.287524) (xy 161.516139 -384.287524) (xy 161.567474 -384.295654)
			(xy 161.616904 -384.311715) (xy 161.663214 -384.335311) (xy 161.705262 -384.365861) (xy 161.742013 -384.402612)
			(xy 161.772563 -384.44466) (xy 161.796159 -384.49097) (xy 161.81222 -384.5404) (xy 161.82035 -384.591735)
			(xy 161.82086 -384.617722) (xy 161.82035 -384.643709) (xy 162.35985 -384.643709) (xy 162.35985 -384.591735)
			(xy 162.36798 -384.5404) (xy 162.384041 -384.49097) (xy 162.407637 -384.44466) (xy 162.438187 -384.402612)
			(xy 162.474938 -384.365861) (xy 162.516986 -384.335311) (xy 162.563296 -384.311715) (xy 162.612726 -384.295654)
			(xy 162.664061 -384.287524) (xy 162.716035 -384.287524) (xy 162.76737 -384.295654) (xy 162.8168 -384.311715)
			(xy 162.86311 -384.335311) (xy 162.905158 -384.365861) (xy 162.941909 -384.402612) (xy 162.972459 -384.44466)
			(xy 162.996055 -384.49097) (xy 163.012116 -384.5404) (xy 163.020246 -384.591735) (xy 163.020756 -384.617722)
			(xy 163.020246 -384.643709) (xy 163.56 -384.643709) (xy 163.56 -384.591735) (xy 163.56813 -384.5404)
			(xy 163.584191 -384.49097) (xy 163.607787 -384.44466) (xy 163.638337 -384.402612) (xy 163.675088 -384.365861)
			(xy 163.717136 -384.335311) (xy 163.763446 -384.311715) (xy 163.812876 -384.295654) (xy 163.864211 -384.287524)
			(xy 163.916185 -384.287524) (xy 163.96752 -384.295654) (xy 164.01695 -384.311715) (xy 164.06326 -384.335311)
			(xy 164.105308 -384.365861) (xy 164.142059 -384.402612) (xy 164.172609 -384.44466) (xy 164.196205 -384.49097)
			(xy 164.212266 -384.5404) (xy 164.220396 -384.591735) (xy 164.220906 -384.617722) (xy 164.220396 -384.643709)
			(xy 164.759896 -384.643709) (xy 164.759896 -384.591735) (xy 164.768026 -384.5404) (xy 164.784087 -384.49097)
			(xy 164.807683 -384.44466) (xy 164.838233 -384.402612) (xy 164.874984 -384.365861) (xy 164.917032 -384.335311)
			(xy 164.963342 -384.311715) (xy 165.012772 -384.295654) (xy 165.064107 -384.287524) (xy 165.116081 -384.287524)
			(xy 165.167416 -384.295654) (xy 165.216846 -384.311715) (xy 165.263156 -384.335311) (xy 165.305204 -384.365861)
			(xy 165.341955 -384.402612) (xy 165.372505 -384.44466) (xy 165.396101 -384.49097) (xy 165.412162 -384.5404)
			(xy 165.420292 -384.591735) (xy 165.420802 -384.617722) (xy 165.420292 -384.643709) (xy 165.412162 -384.695044)
			(xy 165.396101 -384.744474) (xy 165.372505 -384.790784) (xy 165.341955 -384.832832) (xy 165.305204 -384.869583)
			(xy 165.263156 -384.900133) (xy 165.216846 -384.923729) (xy 165.167416 -384.93979) (xy 165.116081 -384.94792)
			(xy 165.064107 -384.94792) (xy 165.012772 -384.93979) (xy 164.963342 -384.923729) (xy 164.917032 -384.900133)
			(xy 164.874984 -384.869583) (xy 164.838233 -384.832832) (xy 164.807683 -384.790784) (xy 164.784087 -384.744474)
			(xy 164.768026 -384.695044) (xy 164.759896 -384.643709) (xy 164.220396 -384.643709) (xy 164.212266 -384.695044)
			(xy 164.196205 -384.744474) (xy 164.172609 -384.790784) (xy 164.142059 -384.832832) (xy 164.105308 -384.869583)
			(xy 164.06326 -384.900133) (xy 164.01695 -384.923729) (xy 163.96752 -384.93979) (xy 163.916185 -384.94792)
			(xy 163.864211 -384.94792) (xy 163.812876 -384.93979) (xy 163.763446 -384.923729) (xy 163.717136 -384.900133)
			(xy 163.675088 -384.869583) (xy 163.638337 -384.832832) (xy 163.607787 -384.790784) (xy 163.584191 -384.744474)
			(xy 163.56813 -384.695044) (xy 163.56 -384.643709) (xy 163.020246 -384.643709) (xy 163.012116 -384.695044)
			(xy 162.996055 -384.744474) (xy 162.972459 -384.790784) (xy 162.941909 -384.832832) (xy 162.905158 -384.869583)
			(xy 162.86311 -384.900133) (xy 162.8168 -384.923729) (xy 162.76737 -384.93979) (xy 162.716035 -384.94792)
			(xy 162.664061 -384.94792) (xy 162.612726 -384.93979) (xy 162.563296 -384.923729) (xy 162.516986 -384.900133)
			(xy 162.474938 -384.869583) (xy 162.438187 -384.832832) (xy 162.407637 -384.790784) (xy 162.384041 -384.744474)
			(xy 162.36798 -384.695044) (xy 162.35985 -384.643709) (xy 161.82035 -384.643709) (xy 161.81222 -384.695044)
			(xy 161.796159 -384.744474) (xy 161.772563 -384.790784) (xy 161.742013 -384.832832) (xy 161.705262 -384.869583)
			(xy 161.663214 -384.900133) (xy 161.616904 -384.923729) (xy 161.567474 -384.93979) (xy 161.516139 -384.94792)
			(xy 161.464165 -384.94792) (xy 161.41283 -384.93979) (xy 161.3634 -384.923729) (xy 161.31709 -384.900133)
			(xy 161.275042 -384.869583) (xy 161.238291 -384.832832) (xy 161.207741 -384.790784) (xy 161.184145 -384.744474)
			(xy 161.168084 -384.695044) (xy 161.159954 -384.643709) (xy 160.6202 -384.643709) (xy 160.61207 -384.695044)
			(xy 160.596009 -384.744474) (xy 160.572413 -384.790784) (xy 160.541863 -384.832832) (xy 160.505112 -384.869583)
			(xy 160.463064 -384.900133) (xy 160.416754 -384.923729) (xy 160.367324 -384.93979) (xy 160.315989 -384.94792)
			(xy 160.264015 -384.94792) (xy 160.21268 -384.93979) (xy 160.16325 -384.923729) (xy 160.11694 -384.900133)
			(xy 160.074892 -384.869583) (xy 160.038141 -384.832832) (xy 160.007591 -384.790784) (xy 159.983995 -384.744474)
			(xy 159.967934 -384.695044) (xy 159.959804 -384.643709) (xy 159.420304 -384.643709) (xy 159.412174 -384.695044)
			(xy 159.396113 -384.744474) (xy 159.372517 -384.790784) (xy 159.341967 -384.832832) (xy 159.305216 -384.869583)
			(xy 159.263168 -384.900133) (xy 159.216858 -384.923729) (xy 159.167428 -384.93979) (xy 159.116093 -384.94792)
			(xy 159.064119 -384.94792) (xy 159.012784 -384.93979) (xy 158.963354 -384.923729) (xy 158.917044 -384.900133)
			(xy 158.874996 -384.869583) (xy 158.838245 -384.832832) (xy 158.807695 -384.790784) (xy 158.784099 -384.744474)
			(xy 158.768038 -384.695044) (xy 158.759908 -384.643709) (xy 158.220408 -384.643709) (xy 158.212278 -384.695044)
			(xy 158.196217 -384.744474) (xy 158.172621 -384.790784) (xy 158.142071 -384.832832) (xy 158.10532 -384.869583)
			(xy 158.063272 -384.900133) (xy 158.016962 -384.923729) (xy 157.967532 -384.93979) (xy 157.916197 -384.94792)
			(xy 157.864223 -384.94792) (xy 157.812888 -384.93979) (xy 157.763458 -384.923729) (xy 157.717148 -384.900133)
			(xy 157.6751 -384.869583) (xy 157.638349 -384.832832) (xy 157.607799 -384.790784) (xy 157.584203 -384.744474)
			(xy 157.568142 -384.695044) (xy 157.560012 -384.643709) (xy 157.020258 -384.643709) (xy 157.012128 -384.695044)
			(xy 156.996067 -384.744474) (xy 156.972471 -384.790784) (xy 156.941921 -384.832832) (xy 156.90517 -384.869583)
			(xy 156.863122 -384.900133) (xy 156.816812 -384.923729) (xy 156.767382 -384.93979) (xy 156.716047 -384.94792)
			(xy 156.664073 -384.94792) (xy 156.612738 -384.93979) (xy 156.563308 -384.923729) (xy 156.516998 -384.900133)
			(xy 156.47495 -384.869583) (xy 156.438199 -384.832832) (xy 156.407649 -384.790784) (xy 156.384053 -384.744474)
			(xy 156.367992 -384.695044) (xy 156.359862 -384.643709) (xy 155.820362 -384.643709) (xy 155.812232 -384.695044)
			(xy 155.796171 -384.744474) (xy 155.772575 -384.790784) (xy 155.742025 -384.832832) (xy 155.705274 -384.869583)
			(xy 155.663226 -384.900133) (xy 155.616916 -384.923729) (xy 155.567486 -384.93979) (xy 155.516151 -384.94792)
			(xy 155.464177 -384.94792) (xy 155.412842 -384.93979) (xy 155.363412 -384.923729) (xy 155.317102 -384.900133)
			(xy 155.275054 -384.869583) (xy 155.238303 -384.832832) (xy 155.207753 -384.790784) (xy 155.184157 -384.744474)
			(xy 155.168096 -384.695044) (xy 155.159966 -384.643709) (xy 154.620211 -384.643709) (xy 154.612078 -384.695041)
			(xy 154.596015 -384.74447) (xy 154.572418 -384.790777) (xy 154.541868 -384.832823) (xy 154.505117 -384.869573)
			(xy 154.46307 -384.900122) (xy 154.416762 -384.923718) (xy 154.367333 -384.939779) (xy 154.316 -384.947911)
			(xy 154.290014 -384.94843) (xy 154.268008 -384.948087) (xy 154.22438 -384.942282) (xy 154.18191 -384.930734)
			(xy 154.16149 -384.922522) (xy 154.147266 -384.916426) (xy 154.11704 -384.922268) (xy 153.783538 -385.25577)
			(xy 153.776001 -385.264046) (xy 153.768301 -385.285035) (xy 153.770251 -385.307307) (xy 153.77541 -385.317238)
			(xy 154.020012 -385.740402) (xy 154.027378 -385.746244) (xy 154.046157 -385.762047) (xy 154.079292 -385.798254)
			(xy 154.106715 -385.838958) (xy 154.127822 -385.883267) (xy 154.142152 -385.930209) (xy 154.14939 -385.978752)
			(xy 154.149806 -386.003292) (xy 154.149552 -386.015484) (xy 154.149298 -386.025136) (xy 154.155394 -386.04317)
			(xy 154.214068 -386.11048) (xy 154.230832 -386.119116) (xy 154.240484 -386.120132) (xy 154.267253 -386.123457)
			(xy 154.319283 -386.137679) (xy 154.368316 -386.160155) (xy 154.413052 -386.19029) (xy 154.452306 -386.227284)
			(xy 154.485037 -386.270157) (xy 154.510377 -386.317773) (xy 154.527656 -386.368869) (xy 154.536414 -386.422093)
			(xy 154.536902 -386.449062) (xy 154.536339 -386.476344) (xy 154.527375 -386.530166) (xy 154.5097 -386.581788)
			(xy 154.483793 -386.629809) (xy 154.450357 -386.672928) (xy 154.43073 -386.691886) (xy 154.423282 -386.699378)
			(xy 154.414743 -386.718673) (xy 154.41422 -386.729224) (xy 154.41422 -386.8039) (xy 154.414811 -386.814433)
			(xy 154.423347 -386.8337) (xy 154.43073 -386.841238) (xy 154.450385 -386.860171) (xy 154.483827 -386.903291)
			(xy 154.509735 -386.951318) (xy 154.527404 -387.002947) (xy 154.536355 -387.056777) (xy 154.536902 -387.084062)
			(xy 154.536469 -387.10818) (xy 154.529473 -387.155905) (xy 154.515625 -387.202109) (xy 154.495217 -387.245814)
			(xy 154.482292 -387.26618) (xy 154.47645 -387.27507) (xy 154.472894 -387.295136) (xy 154.493976 -387.387338)
			(xy 154.506168 -387.404102) (xy 154.515058 -387.409436) (xy 154.535858 -387.422292) (xy 154.573772 -387.453172)
			(xy 154.606719 -387.489303) (xy 154.633979 -387.529897) (xy 154.654957 -387.574067) (xy 154.669194 -387.620846)
			(xy 154.676379 -387.669213) (xy 154.676856 -387.693662) (xy 154.676418 -387.718033) (xy 154.669263 -387.766246)
			(xy 154.655115 -387.812889) (xy 154.634281 -387.856954) (xy 154.607211 -387.897487) (xy 154.57449 -387.933613)
			(xy 154.555952 -387.94944) (xy 154.547062 -387.956552) (xy 154.537664 -387.97611) (xy 154.53487 -388.075424)
			(xy 154.543506 -388.09549) (xy 154.551888 -388.10311) (xy 154.569522 -388.119825) (xy 154.599781 -388.157835)
			(xy 154.623633 -388.200161) (xy 154.640472 -388.245734) (xy 154.645614 -388.26948) (xy 154.64917 -388.287514)
			(xy 154.67711 -388.310628) (xy 155.215336 -388.310628) (xy 155.243276 -388.287514) (xy 155.246832 -388.26948)
			(xy 155.252006 -388.245744) (xy 155.268857 -388.200182) (xy 155.292704 -388.15786) (xy 155.322946 -388.119844)
			(xy 155.340558 -388.10311) (xy 155.34894 -388.09549) (xy 155.357576 -388.075424) (xy 155.354782 -387.97611)
			(xy 155.345384 -387.956552) (xy 155.336494 -387.94944) (xy 155.317933 -387.933637) (xy 155.285207 -387.897511)
			(xy 155.258135 -387.856974) (xy 155.237302 -387.812904) (xy 155.22316 -387.766254) (xy 155.216015 -387.718035)
			(xy 155.21559 -387.693662) (xy 155.216029 -387.669546) (xy 155.223034 -387.621826) (xy 155.236891 -387.575627)
			(xy 155.257306 -387.531929) (xy 155.2702 -387.511544) (xy 155.276042 -387.502654) (xy 155.279598 -387.482588)
			(xy 155.258516 -387.390386) (xy 155.246324 -387.373622) (xy 155.237434 -387.368288) (xy 155.216633 -387.355432)
			(xy 155.178718 -387.324553) (xy 155.145769 -387.288421) (xy 155.118506 -387.247828) (xy 155.097526 -387.203659)
			(xy 155.083286 -387.156879) (xy 155.076098 -387.108512) (xy 155.075636 -387.084062) (xy 155.076197 -387.056779)
			(xy 155.085156 -387.002953) (xy 155.102826 -386.951327) (xy 155.128727 -386.9033) (xy 155.162158 -386.860173)
			(xy 155.181808 -386.841238) (xy 155.189256 -386.833745) (xy 155.197797 -386.814451) (xy 155.198318 -386.8039)
			(xy 155.198318 -386.729224) (xy 155.197732 -386.718688) (xy 155.189206 -386.69941) (xy 155.181808 -386.691886)
			(xy 155.162155 -386.672952) (xy 155.128715 -386.62983) (xy 155.10281 -386.581803) (xy 155.08514 -386.530175)
			(xy 155.076187 -386.476346) (xy 155.075636 -386.449062) (xy 155.07589 -386.43687) (xy 155.076144 -386.427218)
			(xy 155.070048 -386.409184) (xy 155.011374 -386.341874) (xy 154.99461 -386.333238) (xy 154.984704 -386.332222)
			(xy 154.957788 -386.328874) (xy 154.905483 -386.314535) (xy 154.85622 -386.29185) (xy 154.81132 -386.261429)
			(xy 154.771988 -386.224086) (xy 154.739278 -386.180825) (xy 154.714068 -386.132805) (xy 154.697034 -386.081314)
			(xy 154.69235 -386.0546) (xy 154.690826 -386.045202) (xy 154.41803 -385.57327) (xy 154.410664 -385.567428)
			(xy 154.391884 -385.551625) (xy 154.358748 -385.51542) (xy 154.331326 -385.474715) (xy 154.310219 -385.430406)
			(xy 154.295891 -385.383464) (xy 154.288657 -385.33492) (xy 154.288236 -385.31038) (xy 154.288721 -385.284393)
			(xy 154.296855 -385.233059) (xy 154.312919 -385.18363) (xy 154.336519 -385.137323) (xy 154.367072 -385.095278)
			(xy 154.403827 -385.05853) (xy 154.445878 -385.027985) (xy 154.49219 -385.004395) (xy 154.541622 -384.98834)
			(xy 154.592957 -384.980216) (xy 154.618944 -384.979672) (xy 154.644957 -384.980153) (xy 154.696344 -384.988292)
			(xy 154.745821 -385.004379) (xy 154.792168 -385.028017) (xy 154.834241 -385.058621) (xy 154.871002 -385.095438)
			(xy 154.901543 -385.137557) (xy 154.925111 -385.183939) (xy 154.941124 -385.233441) (xy 154.945588 -385.259072)
			(xy 154.947112 -385.26847) (xy 155.219908 -385.740402) (xy 155.227274 -385.746244) (xy 155.246053 -385.762047)
			(xy 155.279189 -385.798254) (xy 155.306611 -385.838958) (xy 155.327719 -385.883267) (xy 155.342049 -385.930208)
			(xy 155.349287 -385.978752) (xy 155.349702 -386.003292) (xy 155.349448 -386.015484) (xy 155.349194 -386.025136)
			(xy 155.35529 -386.04317) (xy 155.413964 -386.11048) (xy 155.430728 -386.119116) (xy 155.440634 -386.120132)
			(xy 155.4674 -386.123461) (xy 155.519424 -386.137689) (xy 155.56845 -386.160168) (xy 155.613179 -386.190305)
			(xy 155.652427 -386.227299) (xy 155.685152 -386.27017) (xy 155.710488 -386.317783) (xy 155.727763 -386.368876)
			(xy 155.736519 -386.422095) (xy 155.737052 -386.449062) (xy 155.736489 -386.476344) (xy 155.727526 -386.530168)
			(xy 155.709853 -386.581791) (xy 155.683949 -386.629815) (xy 155.650517 -386.672937) (xy 155.63088 -386.691886)
			(xy 155.623438 -386.699381) (xy 155.614907 -386.718675) (xy 155.61437 -386.729224) (xy 155.61437 -386.8039)
			(xy 155.61496 -386.814434) (xy 155.62349 -386.833707) (xy 155.63088 -386.841238) (xy 155.650532 -386.860172)
			(xy 155.68397 -386.903294) (xy 155.709873 -386.951321) (xy 155.727539 -387.00295) (xy 155.736489 -387.056778)
			(xy 155.737052 -387.084062) (xy 155.736619 -387.108179) (xy 155.729622 -387.155904) (xy 155.715772 -387.202107)
			(xy 155.695361 -387.245811) (xy 155.682442 -387.26618) (xy 155.6766 -387.27507) (xy 155.673044 -387.295136)
			(xy 155.694126 -387.387338) (xy 155.706318 -387.404102) (xy 155.715208 -387.409436) (xy 155.736011 -387.42229)
			(xy 155.77393 -387.453167) (xy 155.806882 -387.489297) (xy 155.834147 -387.529891) (xy 155.855128 -387.574061)
			(xy 155.869367 -387.620842) (xy 155.876554 -387.669212) (xy 155.877006 -387.693662) (xy 155.876568 -387.718032)
			(xy 155.869412 -387.766245) (xy 155.855262 -387.812886) (xy 155.834426 -387.856949) (xy 155.807353 -387.897479)
			(xy 155.77463 -387.933601) (xy 155.756102 -387.94944) (xy 155.747212 -387.956552) (xy 155.737814 -387.97611)
			(xy 155.73502 -388.075424) (xy 155.743656 -388.09549) (xy 155.752038 -388.10311) (xy 155.769674 -388.119823)
			(xy 155.799939 -388.157831) (xy 155.823794 -388.200158) (xy 155.840636 -388.245731) (xy 155.845764 -388.26948)
			(xy 155.84932 -388.287514) (xy 155.87726 -388.310628) (xy 156.415232 -388.310628) (xy 156.443172 -388.287514)
			(xy 156.446728 -388.26948) (xy 156.451902 -388.245744) (xy 156.468753 -388.200182) (xy 156.492599 -388.15786)
			(xy 156.522842 -388.119843) (xy 156.540454 -388.10311) (xy 156.548836 -388.09549) (xy 156.557472 -388.075424)
			(xy 156.554678 -387.97611) (xy 156.54528 -387.956552) (xy 156.53639 -387.94944) (xy 156.517829 -387.933637)
			(xy 156.485104 -387.89751) (xy 156.458032 -387.856973) (xy 156.437199 -387.812903) (xy 156.423058 -387.766254)
			(xy 156.415912 -387.718035) (xy 156.415486 -387.693662) (xy 156.415925 -387.669546) (xy 156.42293 -387.621826)
			(xy 156.436787 -387.575627) (xy 156.457202 -387.531928) (xy 156.470096 -387.511544) (xy 156.475938 -387.502654)
			(xy 156.479494 -387.482588) (xy 156.458412 -387.390386) (xy 156.44622 -387.373622) (xy 156.43733 -387.368288)
			(xy 156.416529 -387.355432) (xy 156.378614 -387.324552) (xy 156.345666 -387.288421) (xy 156.318404 -387.247827)
			(xy 156.297424 -387.203658) (xy 156.283184 -387.156879) (xy 156.275996 -387.108511) (xy 156.275532 -387.084062)
			(xy 156.276093 -387.056779) (xy 156.285052 -387.002953) (xy 156.302722 -386.951327) (xy 156.328623 -386.903299)
			(xy 156.362053 -386.860172) (xy 156.381704 -386.841238) (xy 156.389152 -386.833746) (xy 156.397694 -386.814451)
			(xy 156.398214 -386.8039) (xy 156.398214 -386.729224) (xy 156.397628 -386.718688) (xy 156.389102 -386.69941)
			(xy 156.381704 -386.691886) (xy 156.362046 -386.672955) (xy 156.328597 -386.629836) (xy 156.302683 -386.58181)
			(xy 156.285009 -386.53018) (xy 156.276053 -386.476348) (xy 156.275532 -386.449062) (xy 156.275786 -386.43687)
			(xy 156.27604 -386.427218) (xy 156.269944 -386.409184) (xy 156.21127 -386.341874) (xy 156.194506 -386.333238)
			(xy 156.1846 -386.332222) (xy 156.157685 -386.328874) (xy 156.10538 -386.314534) (xy 156.056117 -386.291849)
			(xy 156.011218 -386.261427) (xy 155.971886 -386.224085) (xy 155.939177 -386.180824) (xy 155.913967 -386.132804)
			(xy 155.896934 -386.081314) (xy 155.892246 -386.0546) (xy 155.890722 -386.045202) (xy 155.617672 -385.572762)
			(xy 155.61056 -385.56692) (xy 155.591827 -385.55114) (xy 155.558774 -385.514996) (xy 155.531416 -385.47437)
			(xy 155.510353 -385.430152) (xy 155.496045 -385.38331) (xy 155.488806 -385.334869) (xy 155.488386 -385.31038)
			(xy 155.488897 -385.284394) (xy 155.49703 -385.233061) (xy 155.513093 -385.183633) (xy 155.53669 -385.137326)
			(xy 155.56724 -385.09528) (xy 155.603991 -385.05853) (xy 155.646038 -385.027982) (xy 155.692346 -385.004387)
			(xy 155.741775 -384.988327) (xy 155.793108 -384.980196) (xy 155.819094 -384.979672) (xy 155.845142 -384.980151)
			(xy 155.896597 -384.988302) (xy 155.946138 -385.00442) (xy 155.992539 -385.028104) (xy 156.034653 -385.058771)
			(xy 156.071438 -385.09566) (xy 156.101985 -385.137861) (xy 156.125539 -385.184329) (xy 156.141515 -385.233915)
			(xy 156.145992 -385.25958) (xy 156.147262 -385.268978) (xy 156.171198 -385.31038) (xy 156.688282 -385.31038)
			(xy 156.688783 -385.284393) (xy 156.696916 -385.233059) (xy 156.712979 -385.183629) (xy 156.736577 -385.13732)
			(xy 156.767128 -385.095272) (xy 156.80388 -385.058521) (xy 156.845928 -385.027972) (xy 156.892238 -385.004376)
			(xy 156.941668 -384.988314) (xy 156.993003 -384.980182) (xy 157.01899 -384.979672) (xy 157.045 -384.980151)
			(xy 157.096376 -384.988308) (xy 157.145842 -385.004407) (xy 157.192178 -385.028052) (xy 157.234241 -385.058658)
			(xy 157.270995 -385.095472) (xy 157.301532 -385.137585) (xy 157.325101 -385.18396) (xy 157.341119 -385.233452)
			(xy 157.345634 -385.259072) (xy 157.347158 -385.26847) (xy 157.619954 -385.740402) (xy 157.62732 -385.746244)
			(xy 157.646106 -385.762037) (xy 157.679222 -385.798256) (xy 157.70663 -385.838966) (xy 157.72773 -385.883276)
			(xy 157.742058 -385.930214) (xy 157.749303 -385.978754) (xy 157.749748 -386.003292) (xy 157.749494 -386.015484)
			(xy 157.74924 -386.025136) (xy 157.755336 -386.04317) (xy 157.81401 -386.11048) (xy 157.830774 -386.119116)
			(xy 157.840426 -386.120132) (xy 157.867191 -386.12347) (xy 157.919214 -386.137696) (xy 157.96824 -386.160175)
			(xy 158.012969 -386.19031) (xy 158.052216 -386.227303) (xy 158.084941 -386.270174) (xy 158.110277 -386.317786)
			(xy 158.127552 -386.368878) (xy 158.136309 -386.422095) (xy 158.136844 -386.449062) (xy 158.136334 -386.475049)
			(xy 158.128204 -386.526384) (xy 158.112143 -386.575814) (xy 158.088547 -386.622124) (xy 158.057997 -386.664172)
			(xy 158.021246 -386.700923) (xy 157.979198 -386.731473) (xy 157.932888 -386.755069) (xy 157.883458 -386.77113)
			(xy 157.832123 -386.77926) (xy 157.780149 -386.77926) (xy 157.728814 -386.77113) (xy 157.679384 -386.755069)
			(xy 157.633074 -386.731473) (xy 157.591026 -386.700923) (xy 157.554275 -386.664172) (xy 157.523725 -386.622124)
			(xy 157.500129 -386.575814) (xy 157.484068 -386.526384) (xy 157.475938 -386.475049) (xy 157.475428 -386.449062)
			(xy 157.475682 -386.43687) (xy 157.475936 -386.427218) (xy 157.46984 -386.409184) (xy 157.411166 -386.341874)
			(xy 157.394402 -386.333238) (xy 157.38475 -386.332222) (xy 157.357842 -386.328859) (xy 157.305556 -386.314493)
			(xy 157.256313 -386.291793) (xy 157.21143 -386.261367) (xy 157.172111 -386.224028) (xy 157.139406 -386.180777)
			(xy 157.114193 -386.132772) (xy 157.097146 -386.081298) (xy 157.092396 -386.0546) (xy 157.090872 -386.045202)
			(xy 156.818076 -385.57327) (xy 156.81071 -385.567428) (xy 156.791965 -385.551589) (xy 156.758845 -385.51538)
			(xy 156.731431 -385.474679) (xy 156.710324 -385.430379) (xy 156.695987 -385.383448) (xy 156.688733 -385.334916)
			(xy 156.688282 -385.31038) (xy 156.171198 -385.31038) (xy 156.419804 -385.740402) (xy 156.42717 -385.746244)
			(xy 156.44595 -385.762047) (xy 156.479085 -385.798253) (xy 156.506508 -385.838958) (xy 156.527617 -385.883267)
			(xy 156.541947 -385.930208) (xy 156.549185 -385.978752) (xy 156.549598 -386.003292) (xy 156.549344 -386.015484)
			(xy 156.54909 -386.025136) (xy 156.555186 -386.04317) (xy 156.61386 -386.11048) (xy 156.630624 -386.119116)
			(xy 156.64053 -386.120132) (xy 156.667296 -386.12346) (xy 156.719321 -386.137688) (xy 156.768347 -386.160167)
			(xy 156.813077 -386.190303) (xy 156.852325 -386.227298) (xy 156.885051 -386.270169) (xy 156.910387 -386.317783)
			(xy 156.927662 -386.368876) (xy 156.936419 -386.422095) (xy 156.936948 -386.449062) (xy 156.936385 -386.476344)
			(xy 156.927422 -386.530167) (xy 156.909749 -386.581791) (xy 156.883845 -386.629814) (xy 156.850412 -386.672937)
			(xy 156.830776 -386.691886) (xy 156.823334 -386.699381) (xy 156.814804 -386.718676) (xy 156.814266 -386.729224)
			(xy 156.814266 -386.8039) (xy 156.814858 -386.814431) (xy 156.8234 -386.833694) (xy 156.830776 -386.841238)
			(xy 156.850429 -386.860172) (xy 156.883866 -386.903294) (xy 156.90977 -386.951321) (xy 156.927436 -387.00295)
			(xy 156.936386 -387.056778) (xy 156.936948 -387.084062) (xy 156.936515 -387.108179) (xy 156.929518 -387.155904)
			(xy 156.915668 -387.202107) (xy 156.895257 -387.24581) (xy 156.882338 -387.26618) (xy 156.876496 -387.27507)
			(xy 156.87294 -387.295136) (xy 156.894022 -387.387338) (xy 156.906214 -387.404102) (xy 156.915104 -387.409436)
			(xy 156.935907 -387.42229) (xy 156.973827 -387.453167) (xy 157.006779 -387.489297) (xy 157.034044 -387.529891)
			(xy 157.055026 -387.574061) (xy 157.069265 -387.620842) (xy 157.076452 -387.669212) (xy 157.076902 -387.693662)
			(xy 157.076464 -387.718032) (xy 157.069308 -387.766244) (xy 157.055158 -387.812886) (xy 157.034322 -387.856948)
			(xy 157.007249 -387.897479) (xy 156.974525 -387.933601) (xy 156.955998 -387.94944) (xy 156.947108 -387.956552)
			(xy 156.93771 -387.97611) (xy 156.934916 -388.075424) (xy 156.943552 -388.09549) (xy 156.951934 -388.10311)
			(xy 156.96957 -388.119823) (xy 156.999835 -388.157831) (xy 157.023691 -388.200157) (xy 157.040534 -388.24573)
			(xy 157.04566 -388.26948) (xy 157.049216 -388.287514) (xy 157.077156 -388.310628) (xy 157.615128 -388.310628)
			(xy 157.643068 -388.287514) (xy 157.646624 -388.26948) (xy 157.651885 -388.245324) (xy 157.669159 -388.199005)
			(xy 157.693671 -388.156075) (xy 157.72478 -388.117655) (xy 157.761674 -388.084751) (xy 157.803387 -388.058222)
			(xy 157.848831 -388.038761) (xy 157.896817 -388.026877) (xy 157.94609 -388.022881) (xy 157.995363 -388.026877)
			(xy 158.043349 -388.038761) (xy 158.088793 -388.058222) (xy 158.130506 -388.084751) (xy 158.1674 -388.117655)
			(xy 158.198509 -388.156075) (xy 158.223021 -388.199005) (xy 158.240295 -388.245324) (xy 158.245556 -388.26948)
			(xy 158.249112 -388.287514) (xy 158.277052 -388.310628) (xy 158.521146 -388.310628) (xy 158.531213 -388.310197)
			(xy 158.549808 -388.302474) (xy 158.557214 -388.295642) (xy 158.721298 -388.131558) (xy 158.728138 -388.124157)
			(xy 158.735858 -388.105559) (xy 158.736284 -388.09549) (xy 158.736284 -387.89737) (xy 158.731458 -387.886956)
			(xy 158.71793 -387.856546) (xy 158.698825 -387.792791) (xy 158.689159 -387.72694) (xy 158.688532 -387.693662)
			(xy 158.689146 -387.660383) (xy 158.698817 -387.594532) (xy 158.717921 -387.530775) (xy 158.731458 -387.500368)
			(xy 158.736284 -387.489954) (xy 158.736284 -387.46684) (xy 158.726378 -387.44652) (xy 158.717488 -387.439154)
			(xy 158.695243 -387.420479) (xy 158.655185 -387.378422) (xy 158.62077 -387.331635) (xy 158.59255 -387.280869)
			(xy 158.57098 -387.226942) (xy 158.556406 -387.170718) (xy 158.549063 -387.113103) (xy 158.548578 -387.084062)
			(xy 158.549023 -387.055136) (xy 158.556316 -386.997746) (xy 158.570781 -386.941732) (xy 158.592187 -386.887986)
			(xy 158.620194 -386.837365) (xy 158.654355 -386.790677) (xy 158.694126 -386.748663) (xy 158.716218 -386.729986)
			(xy 158.723283 -386.723716) (xy 158.732555 -386.707274) (xy 158.734252 -386.697982) (xy 158.73857 -386.666994)
			(xy 158.739518 -386.657756) (xy 158.735482 -386.639646) (xy 158.730696 -386.631688) (xy 158.717664 -386.61129)
			(xy 158.697065 -386.567488) (xy 158.68308 -386.521148) (xy 158.676007 -386.473264) (xy 158.675578 -386.449062)
			(xy 158.675832 -386.43687) (xy 158.676086 -386.427218) (xy 158.66999 -386.409184) (xy 158.611316 -386.341874)
			(xy 158.594552 -386.333238) (xy 158.584646 -386.332222) (xy 158.557733 -386.32887) (xy 158.505435 -386.314524)
			(xy 158.45618 -386.291834) (xy 158.411288 -386.26141) (xy 158.371963 -386.224068) (xy 158.33926 -386.180808)
			(xy 158.314056 -386.132791) (xy 158.297026 -386.081304) (xy 158.292292 -386.0546) (xy 158.290768 -386.045202)
			(xy 158.017972 -385.57327) (xy 158.010606 -385.567428) (xy 157.991829 -385.551624) (xy 157.958699 -385.515416)
			(xy 157.931281 -385.474711) (xy 157.910178 -385.430401) (xy 157.895853 -385.383461) (xy 157.88862 -385.334919)
			(xy 157.888178 -385.31038) (xy 157.888689 -385.284393) (xy 157.896822 -385.233061) (xy 157.912885 -385.183632)
			(xy 157.936481 -385.137324) (xy 157.967031 -385.095277) (xy 158.003782 -385.058527) (xy 158.045829 -385.027978)
			(xy 158.092137 -385.004382) (xy 158.141566 -384.988321) (xy 158.192899 -384.980189) (xy 158.218886 -384.979672)
			(xy 158.244897 -384.980156) (xy 158.296279 -384.988301) (xy 158.345751 -385.004392) (xy 158.392092 -385.028032)
			(xy 158.43416 -385.058637) (xy 158.470915 -385.095453) (xy 158.501452 -385.137571) (xy 158.525016 -385.183951)
			(xy 158.541026 -385.233449) (xy 158.54553 -385.259072) (xy 158.547054 -385.26847) (xy 158.81985 -385.740402)
			(xy 158.827216 -385.746244) (xy 158.845993 -385.762049) (xy 158.879125 -385.798256) (xy 158.906544 -385.838961)
			(xy 158.927649 -385.88327) (xy 158.941977 -385.930211) (xy 158.949214 -385.978753) (xy 158.949644 -386.003292)
			(xy 158.94939 -386.015484) (xy 158.949136 -386.025136) (xy 158.955232 -386.04317) (xy 159.013906 -386.11048)
			(xy 159.03067 -386.119116) (xy 159.040576 -386.120132) (xy 159.067008 -386.123424) (xy 159.118413 -386.137366)
			(xy 159.166918 -386.159368) (xy 159.211269 -386.18886) (xy 159.250319 -386.225081) (xy 159.283058 -386.267093)
			(xy 159.308638 -386.313809) (xy 159.3264 -386.364022) (xy 159.33166 -386.390134) (xy 159.334962 -386.408422)
			(xy 159.363156 -386.43179) (xy 159.53613 -386.43179) (xy 159.546489 -386.431372) (xy 159.565562 -386.4233)
			(xy 159.579871 -386.408327) (xy 159.583882 -386.39877) (xy 159.622744 -386.29463) (xy 159.61487 -386.263896)
			(xy 159.602678 -386.253482) (xy 159.585377 -386.237984) (xy 159.554861 -386.202967) (xy 159.529546 -386.164024)
			(xy 159.509931 -386.121921) (xy 159.496401 -386.077487) (xy 159.492442 -386.0546) (xy 159.490918 -386.045202)
			(xy 159.218122 -385.57327) (xy 159.210756 -385.567428) (xy 159.191977 -385.551625) (xy 159.158841 -385.515419)
			(xy 159.13142 -385.474715) (xy 159.110313 -385.430405) (xy 159.095986 -385.383463) (xy 159.088752 -385.33492)
			(xy 159.088328 -385.31038) (xy 159.088813 -385.284393) (xy 159.096947 -385.233059) (xy 159.113011 -385.183629)
			(xy 159.13661 -385.137321) (xy 159.167164 -385.095276) (xy 159.203918 -385.058527) (xy 159.245969 -385.027981)
			(xy 159.292281 -385.00439) (xy 159.341713 -384.988334) (xy 159.393049 -384.980208) (xy 159.419036 -384.979672)
			(xy 159.44505 -384.980152) (xy 159.496437 -384.988291) (xy 159.545915 -385.004377) (xy 159.592263 -385.028014)
			(xy 159.634338 -385.058618) (xy 159.6711 -385.095435) (xy 159.701642 -385.137554) (xy 159.72521 -385.183937)
			(xy 159.741223 -385.233439) (xy 159.74568 -385.259072) (xy 159.747204 -385.26847) (xy 160.02 -385.740402)
			(xy 160.027366 -385.746244) (xy 160.046146 -385.762047) (xy 160.079282 -385.798253) (xy 160.106705 -385.838957)
			(xy 160.127814 -385.883266) (xy 160.142144 -385.930208) (xy 160.149382 -385.978752) (xy 160.149794 -386.003292)
			(xy 160.14954 -386.015484) (xy 160.149286 -386.025136) (xy 160.155382 -386.04317) (xy 160.214056 -386.11048)
			(xy 160.23082 -386.119116) (xy 160.240472 -386.120132) (xy 160.266904 -386.123424) (xy 160.31831 -386.137365)
			(xy 160.366815 -386.159367) (xy 160.411167 -386.188859) (xy 160.450217 -386.225079) (xy 160.482956 -386.267091)
			(xy 160.508538 -386.313808) (xy 160.526299 -386.364022) (xy 160.531556 -386.390134) (xy 160.534858 -386.408422)
			(xy 160.563052 -386.43179) (xy 160.736026 -386.43179) (xy 160.746385 -386.431372) (xy 160.76546 -386.423301)
			(xy 160.779771 -386.408329) (xy 160.783778 -386.39877) (xy 160.82264 -386.29463) (xy 160.814766 -386.263896)
			(xy 160.802574 -386.253482) (xy 160.785273 -386.237984) (xy 160.754758 -386.202967) (xy 160.729443 -386.164023)
			(xy 160.709828 -386.12192) (xy 160.696298 -386.077487) (xy 160.692338 -386.0546) (xy 160.690814 -386.045202)
			(xy 160.418018 -385.57327) (xy 160.410652 -385.567428) (xy 160.391873 -385.551625) (xy 160.358738 -385.515419)
			(xy 160.331317 -385.474714) (xy 160.310211 -385.430405) (xy 160.295883 -385.383463) (xy 160.288649 -385.33492)
			(xy 160.288224 -385.31038) (xy 160.288709 -385.284393) (xy 160.296843 -385.233058) (xy 160.312907 -385.183629)
			(xy 160.336506 -385.13732) (xy 160.367059 -385.095274) (xy 160.403814 -385.058526) (xy 160.445865 -385.027979)
			(xy 160.492177 -385.004387) (xy 160.541609 -384.98833) (xy 160.592945 -384.980205) (xy 160.618932 -384.979672)
			(xy 160.644946 -384.980152) (xy 160.696334 -384.98829) (xy 160.745812 -385.004376) (xy 160.792161 -385.028013)
			(xy 160.834236 -385.058617) (xy 160.870998 -385.095433) (xy 160.901541 -385.137553) (xy 160.92511 -385.183936)
			(xy 160.941123 -385.233438) (xy 160.945576 -385.259072) (xy 160.9471 -385.26847) (xy 161.219896 -385.740402)
			(xy 161.227262 -385.746244) (xy 161.246042 -385.762047) (xy 161.279179 -385.798253) (xy 161.306602 -385.838957)
			(xy 161.327711 -385.883266) (xy 161.342042 -385.930208) (xy 161.349279 -385.978752) (xy 161.34969 -386.003292)
			(xy 161.349436 -386.015484) (xy 161.349182 -386.025136) (xy 161.355278 -386.04317) (xy 161.413952 -386.11048)
			(xy 161.430716 -386.119116) (xy 161.440622 -386.120132) (xy 161.467389 -386.12346) (xy 161.519414 -386.137686)
			(xy 161.568442 -386.160165) (xy 161.613173 -386.190301) (xy 161.652422 -386.227295) (xy 161.685148 -386.270167)
			(xy 161.710485 -386.317781) (xy 161.727761 -386.368875) (xy 161.736518 -386.422094) (xy 161.73704 -386.449062)
			(xy 161.736633 -386.472801) (xy 161.729847 -386.519791) (xy 161.71641 -386.565327) (xy 161.696599 -386.608474)
			(xy 161.670819 -386.648343) (xy 161.655506 -386.666486) (xy 161.649156 -386.673852) (xy 161.642806 -386.691632)
			(xy 161.645346 -386.77088) (xy 161.646095 -386.780476) (xy 161.653803 -386.798097) (xy 161.660332 -386.80517)
			(xy 162.343084 -387.487922) (xy 162.350942 -387.494981) (xy 162.370621 -387.502595) (xy 162.381184 -387.502654)
			(xy 162.467036 -387.498844) (xy 162.485578 -387.4897) (xy 162.49269 -387.481318) (xy 162.500818 -387.47192)
			(xy 162.487864 -387.415278) (xy 162.484713 -387.40435) (xy 162.470606 -387.386549) (xy 162.460686 -387.380988)
			(xy 162.43725 -387.368927) (xy 162.394206 -387.338515) (xy 162.35653 -387.301661) (xy 162.325174 -387.259299)
			(xy 162.300933 -387.2125) (xy 162.284419 -387.16245) (xy 162.276052 -387.110414) (xy 162.27552 -387.084062)
			(xy 162.276081 -387.05678) (xy 162.285042 -387.002956) (xy 162.302715 -386.951332) (xy 162.328621 -386.903309)
			(xy 162.362057 -386.860189) (xy 162.381692 -386.841238) (xy 162.389142 -386.833746) (xy 162.397686 -386.814451)
			(xy 162.398202 -386.8039) (xy 162.398202 -386.729224) (xy 162.397616 -386.718689) (xy 162.389088 -386.699412)
			(xy 162.381692 -386.691886) (xy 162.362034 -386.672955) (xy 162.328587 -386.629835) (xy 162.302674 -386.581809)
			(xy 162.285 -386.530179) (xy 162.276045 -386.476348) (xy 162.27552 -386.449062) (xy 162.275774 -386.43687)
			(xy 162.276028 -386.427218) (xy 162.269932 -386.409184) (xy 162.211258 -386.341874) (xy 162.194494 -386.333238)
			(xy 162.184588 -386.332222) (xy 162.157673 -386.328873) (xy 162.10537 -386.314532) (xy 162.056109 -386.291846)
			(xy 162.011211 -386.261424) (xy 161.971881 -386.224081) (xy 161.939173 -386.180821) (xy 161.913965 -386.132801)
			(xy 161.896932 -386.081312) (xy 161.892234 -386.0546) (xy 161.89071 -386.045202) (xy 161.61766 -385.572762)
			(xy 161.610548 -385.56692) (xy 161.591816 -385.55114) (xy 161.558764 -385.514995) (xy 161.531407 -385.474369)
			(xy 161.510344 -385.430151) (xy 161.496037 -385.383309) (xy 161.488798 -385.334869) (xy 161.488374 -385.31038)
			(xy 161.488885 -385.284393) (xy 161.497018 -385.23306) (xy 161.51308 -385.183631) (xy 161.536677 -385.137323)
			(xy 161.567227 -385.095276) (xy 161.603978 -385.058526) (xy 161.646025 -385.027976) (xy 161.692333 -385.00438)
			(xy 161.741762 -384.988317) (xy 161.793095 -384.980185) (xy 161.819082 -384.979672) (xy 161.845131 -384.98015)
			(xy 161.896587 -384.9883) (xy 161.946129 -385.004416) (xy 161.992532 -385.0281) (xy 162.034647 -385.058766)
			(xy 162.071434 -385.095656) (xy 162.101983 -385.137857) (xy 162.125537 -385.184326) (xy 162.141515 -385.233913)
			(xy 162.14598 -385.25958) (xy 162.14725 -385.268978) (xy 162.419792 -385.740402) (xy 162.427158 -385.746244)
			(xy 162.445938 -385.762047) (xy 162.479075 -385.798252) (xy 162.506499 -385.838957) (xy 162.527608 -385.883266)
			(xy 162.541939 -385.930208) (xy 162.549177 -385.978752) (xy 162.549586 -386.003292) (xy 162.549332 -386.015484)
			(xy 162.549078 -386.025136) (xy 162.555174 -386.04317) (xy 162.613848 -386.11048) (xy 162.630612 -386.119116)
			(xy 162.640518 -386.120132) (xy 162.667285 -386.12346) (xy 162.719311 -386.137686) (xy 162.768339 -386.160164)
			(xy 162.813071 -386.1903) (xy 162.85232 -386.227294) (xy 162.885047 -386.270166) (xy 162.910384 -386.31778)
			(xy 162.927661 -386.368874) (xy 162.936418 -386.422094) (xy 162.936936 -386.449062) (xy 162.936373 -386.476344)
			(xy 162.92741 -386.530167) (xy 162.909736 -386.58179) (xy 162.883831 -386.629813) (xy 162.850398 -386.672934)
			(xy 162.830764 -386.691886) (xy 162.823324 -386.699381) (xy 162.814796 -386.718676) (xy 162.814254 -386.729224)
			(xy 162.814254 -386.8039) (xy 162.814846 -386.814432) (xy 162.823387 -386.833696) (xy 162.830764 -386.841238)
			(xy 162.850417 -386.860172) (xy 162.883856 -386.903293) (xy 162.909761 -386.95132) (xy 162.927428 -387.002949)
			(xy 162.936378 -387.056778) (xy 162.936936 -387.084062) (xy 162.936503 -387.10818) (xy 162.929508 -387.155905)
			(xy 162.915661 -387.20211) (xy 162.895254 -387.245816) (xy 162.882326 -387.26618) (xy 162.876484 -387.27507)
			(xy 162.872928 -387.295136) (xy 162.89401 -387.387338) (xy 162.906202 -387.404102) (xy 162.915092 -387.409436)
			(xy 162.935896 -387.42229) (xy 162.973817 -387.453166) (xy 163.00677 -387.489295) (xy 163.034036 -387.529889)
			(xy 163.055019 -387.57406) (xy 163.069259 -387.620841) (xy 163.076445 -387.669211) (xy 163.07689 -387.693662)
			(xy 163.076421 -387.718855) (xy 163.068787 -387.76866) (xy 163.053691 -387.816732) (xy 163.031481 -387.86196)
			(xy 163.017454 -387.882892) (xy 163.009326 -387.894576) (xy 163.007294 -387.92277) (xy 163.055554 -388.015226)
			(xy 163.060181 -388.023306) (xy 163.074061 -388.035694) (xy 163.091462 -388.042277) (xy 163.100766 -388.042658)
			(xy 163.591748 -388.042658) (xy 163.601045 -388.042248) (xy 163.618427 -388.03564) (xy 163.632337 -388.0233)
			(xy 163.63696 -388.015226) (xy 163.68522 -387.92277) (xy 163.683188 -387.894576) (xy 163.67506 -387.882892)
			(xy 163.661046 -387.861953) (xy 163.638842 -387.816726) (xy 163.623751 -387.768656) (xy 163.616119 -387.718854)
			(xy 163.615624 -387.693662) (xy 163.616063 -387.669546) (xy 163.623069 -387.621826) (xy 163.636927 -387.575628)
			(xy 163.657344 -387.531931) (xy 163.670234 -387.511544) (xy 163.676076 -387.502654) (xy 163.679632 -387.482588)
			(xy 163.65855 -387.390386) (xy 163.646358 -387.373622) (xy 163.637468 -387.368288) (xy 163.616665 -387.355433)
			(xy 163.578746 -387.324556) (xy 163.545794 -387.288425) (xy 163.518529 -387.247832) (xy 163.497546 -387.203662)
			(xy 163.483304 -387.156881) (xy 163.476115 -387.108512) (xy 163.47567 -387.084062) (xy 163.476231 -387.056779)
			(xy 163.485191 -387.002954) (xy 163.502862 -386.951329) (xy 163.528765 -386.903303) (xy 163.562198 -386.860179)
			(xy 163.581842 -386.841238) (xy 163.589298 -386.833749) (xy 163.597851 -386.814453) (xy 163.598352 -386.8039)
			(xy 163.598352 -386.729224) (xy 163.597765 -386.71869) (xy 163.589231 -386.699419) (xy 163.581842 -386.691886)
			(xy 163.562187 -386.672953) (xy 163.528744 -386.629832) (xy 163.502836 -386.581806) (xy 163.485165 -386.530177)
			(xy 163.476211 -386.476347) (xy 163.47567 -386.449062) (xy 163.475924 -386.43687) (xy 163.476178 -386.427218)
			(xy 163.470082 -386.409184) (xy 163.411408 -386.341874) (xy 163.394644 -386.333238) (xy 163.384738 -386.332222)
			(xy 163.357826 -386.32887) (xy 163.305529 -386.314522) (xy 163.256274 -386.291832) (xy 163.211383 -386.261408)
			(xy 163.17206 -386.224065) (xy 163.139358 -386.180806) (xy 163.114154 -386.132789) (xy 163.097124 -386.081303)
			(xy 163.092384 -386.0546) (xy 163.09086 -386.045202) (xy 162.818064 -385.57327) (xy 162.810698 -385.567428)
			(xy 162.791921 -385.551623) (xy 162.758792 -385.515415) (xy 162.731375 -385.47471) (xy 162.710273 -385.430401)
			(xy 162.695948 -385.383461) (xy 162.688715 -385.334919) (xy 162.68827 -385.31038) (xy 162.688781 -385.284393)
			(xy 162.696914 -385.23306) (xy 162.712976 -385.183631) (xy 162.736573 -385.137322) (xy 162.767123 -385.095275)
			(xy 162.803873 -385.058524) (xy 162.845921 -385.027974) (xy 162.892229 -385.004377) (xy 162.941658 -384.988314)
			(xy 162.992991 -384.980181) (xy 163.018978 -384.979672) (xy 163.04499 -384.980155) (xy 163.096372 -384.988299)
			(xy 163.145845 -385.004389) (xy 163.192188 -385.028029) (xy 163.234256 -385.058634) (xy 163.271013 -385.09545)
			(xy 163.30155 -385.137568) (xy 163.325115 -385.183949) (xy 163.341125 -385.233447) (xy 163.345622 -385.259072)
			(xy 163.347146 -385.26847) (xy 163.619942 -385.740402) (xy 163.627308 -385.746244) (xy 163.646086 -385.762048)
			(xy 163.679218 -385.798256) (xy 163.706638 -385.838961) (xy 163.727743 -385.88327) (xy 163.742072 -385.93021)
			(xy 163.749309 -385.978752) (xy 163.749736 -386.003292) (xy 163.749482 -386.015484) (xy 163.749228 -386.025136)
			(xy 163.755324 -386.04317) (xy 163.813998 -386.11048) (xy 163.830762 -386.119116) (xy 163.840668 -386.120132)
			(xy 163.867438 -386.123456) (xy 163.91947 -386.137676) (xy 163.968505 -386.160151) (xy 164.013244 -386.190285)
			(xy 164.0525 -386.227279) (xy 164.085232 -386.270153) (xy 164.110574 -386.317769) (xy 164.127853 -386.368867)
			(xy 164.136612 -386.422092) (xy 164.137086 -386.449062) (xy 164.136523 -386.476344) (xy 164.127558 -386.530166)
			(xy 164.109883 -386.581787) (xy 164.083975 -386.629807) (xy 164.050539 -386.672925) (xy 164.030914 -386.691886)
			(xy 164.023468 -386.699379) (xy 164.014931 -386.718674) (xy 164.014404 -386.729224) (xy 164.014404 -386.8039)
			(xy 164.014995 -386.814433) (xy 164.023529 -386.833702) (xy 164.030914 -386.841238) (xy 164.05057 -386.86017)
			(xy 164.084014 -386.90329) (xy 164.109922 -386.951317) (xy 164.127592 -387.002947) (xy 164.136544 -387.056777)
			(xy 164.137086 -387.084062) (xy 164.136653 -387.108179) (xy 164.129657 -387.155904) (xy 164.115808 -387.202108)
			(xy 164.095399 -387.245813) (xy 164.082476 -387.26618) (xy 164.076634 -387.27507) (xy 164.073078 -387.295136)
			(xy 164.09416 -387.387338) (xy 164.106352 -387.404102) (xy 164.115242 -387.409436) (xy 164.136043 -387.422292)
			(xy 164.173959 -387.45317) (xy 164.206907 -387.489301) (xy 164.234169 -387.529895) (xy 164.255148 -387.574065)
			(xy 164.269386 -387.620845) (xy 164.276571 -387.669212) (xy 164.27704 -387.693662) (xy 164.276571 -387.718856)
			(xy 164.268938 -387.768661) (xy 164.253844 -387.816734) (xy 164.231637 -387.861964) (xy 164.217604 -387.882892)
			(xy 164.209476 -387.894576) (xy 164.207444 -387.92277) (xy 164.255704 -388.015226) (xy 164.260329 -388.023312)
			(xy 164.274207 -388.035713) (xy 164.291609 -388.042313) (xy 164.300916 -388.042658) (xy 164.791644 -388.042658)
			(xy 164.800942 -388.042248) (xy 164.818324 -388.035642) (xy 164.832236 -388.023302) (xy 164.836856 -388.015226)
			(xy 164.885116 -387.92277) (xy 164.883084 -387.894576) (xy 164.874956 -387.882892) (xy 164.860942 -387.861953)
			(xy 164.838739 -387.816726) (xy 164.823647 -387.768656) (xy 164.816016 -387.718854) (xy 164.81552 -387.693662)
			(xy 164.815959 -387.669546) (xy 164.822965 -387.621826) (xy 164.836823 -387.575628) (xy 164.85724 -387.531931)
			(xy 164.87013 -387.511544) (xy 164.875972 -387.502654) (xy 164.879528 -387.482588) (xy 164.858446 -387.390386)
			(xy 164.846254 -387.373622) (xy 164.837364 -387.368288) (xy 164.816561 -387.355433) (xy 164.778643 -387.324555)
			(xy 164.745691 -387.288425) (xy 164.718426 -387.247831) (xy 164.697444 -387.203662) (xy 164.683202 -387.156881)
			(xy 164.676013 -387.108512) (xy 164.675566 -387.084062) (xy 164.676127 -387.056779) (xy 164.685087 -387.002954)
			(xy 164.702758 -386.951329) (xy 164.728661 -386.903303) (xy 164.762093 -386.860179) (xy 164.781738 -386.841238)
			(xy 164.789182 -386.833744) (xy 164.797718 -386.814449) (xy 164.798248 -386.8039) (xy 164.798248 -386.729224)
			(xy 164.79766 -386.71869) (xy 164.789126 -386.699419) (xy 164.781738 -386.691886) (xy 164.762083 -386.672953)
			(xy 164.728641 -386.629832) (xy 164.702733 -386.581805) (xy 164.685062 -386.530176) (xy 164.676108 -386.476347)
			(xy 164.675566 -386.449062) (xy 164.67582 -386.43687) (xy 164.676074 -386.427218) (xy 164.669978 -386.409184)
			(xy 164.611304 -386.341874) (xy 164.59454 -386.333238) (xy 164.584634 -386.332222) (xy 164.557722 -386.328869)
			(xy 164.505425 -386.314521) (xy 164.456172 -386.291831) (xy 164.411281 -386.261407) (xy 164.371958 -386.224064)
			(xy 164.339256 -386.180804) (xy 164.314053 -386.132788) (xy 164.297024 -386.081302) (xy 164.29228 -386.0546)
			(xy 164.290756 -386.045202) (xy 164.017706 -385.572762) (xy 164.010594 -385.56692) (xy 163.99186 -385.551141)
			(xy 163.958803 -385.514998) (xy 163.931442 -385.474373) (xy 163.910377 -385.430155) (xy 163.896067 -385.383312)
			(xy 163.888827 -385.33487) (xy 163.88842 -385.31038) (xy 163.888905 -385.284393) (xy 163.897039 -385.233058)
			(xy 163.913103 -385.183628) (xy 163.936702 -385.13732) (xy 163.967255 -385.095273) (xy 164.00401 -385.058524)
			(xy 164.046061 -385.027977) (xy 164.092372 -385.004385) (xy 164.141805 -384.988327) (xy 164.19314 -384.980201)
			(xy 164.219128 -384.979672) (xy 164.245175 -384.980154) (xy 164.296625 -384.988309) (xy 164.346162 -385.00443)
			(xy 164.392558 -385.028116) (xy 164.434668 -385.058783) (xy 164.471449 -385.095673) (xy 164.501992 -385.137872)
			(xy 164.525542 -385.184338) (xy 164.541517 -385.233922) (xy 164.546026 -385.25958) (xy 164.547296 -385.268978)
			(xy 164.571232 -385.31038) (xy 165.088316 -385.31038) (xy 165.088757 -385.284389) (xy 165.096892 -385.233047)
			(xy 165.112958 -385.183611) (xy 165.136561 -385.137296) (xy 165.167118 -385.095243) (xy 165.203877 -385.058489)
			(xy 165.245933 -385.027937) (xy 165.292251 -385.004341) (xy 165.34169 -384.988281) (xy 165.393033 -384.980153)
			(xy 165.419024 -384.979672) (xy 165.445035 -384.98012) (xy 165.496413 -384.988282) (xy 165.545879 -385.004386)
			(xy 165.592215 -385.028035) (xy 165.634278 -385.058645) (xy 165.671031 -385.095463) (xy 165.701568 -385.137579)
			(xy 165.707546 -385.149344) (xy 167.05707 -385.149344) (xy 167.057506 -385.124448) (xy 167.064957 -385.075218)
			(xy 167.079696 -385.027658) (xy 167.101392 -384.982842) (xy 167.129555 -384.941781) (xy 167.146224 -384.923284)
			(xy 167.152828 -384.916426) (xy 167.159686 -384.899408) (xy 167.161972 -384.813048) (xy 167.155876 -384.795522)
			(xy 167.14978 -384.78841) (xy 167.135023 -384.770415) (xy 167.110192 -384.731054) (xy 167.091127 -384.6886)
			(xy 167.078207 -384.643891) (xy 167.071687 -384.597811) (xy 167.071294 -384.574542) (xy 167.071814 -384.548554)
			(xy 167.079939 -384.497216) (xy 167.095996 -384.447782) (xy 167.119588 -384.401469) (xy 167.150136 -384.359417)
			(xy 167.186887 -384.322662) (xy 167.228935 -384.292109) (xy 167.275245 -384.268511) (xy 167.324677 -384.252448)
			(xy 167.376014 -384.244317) (xy 167.402002 -384.243834) (xy 167.428512 -384.244325) (xy 167.480851 -384.252798)
			(xy 167.531168 -384.26951) (xy 167.578175 -384.294035) (xy 167.620669 -384.325743) (xy 167.639492 -384.344418)
			(xy 167.646858 -384.352038) (xy 167.666416 -384.359912) (xy 167.762428 -384.35788) (xy 167.781478 -384.34899)
			(xy 167.78859 -384.340862) (xy 167.809626 -384.318047) (xy 167.857713 -384.278828) (xy 167.911513 -384.247909)
			(xy 167.969608 -384.226104) (xy 167.999918 -384.21945) (xy 168.010586 -384.217418) (xy 168.027858 -384.204972)
			(xy 168.077896 -384.121914) (xy 168.080436 -384.100832) (xy 168.077388 -384.090418) (xy 168.069828 -384.063551)
			(xy 168.061664 -384.008341) (xy 168.061132 -383.980436) (xy 168.061618 -383.953185) (xy 168.069374 -383.899237)
			(xy 168.084729 -383.846942) (xy 168.107371 -383.797365) (xy 168.136837 -383.751515) (xy 168.172528 -383.710324)
			(xy 168.213719 -383.674633) (xy 168.259569 -383.645167) (xy 168.309146 -383.622525) (xy 168.361441 -383.60717)
			(xy 168.415389 -383.599414) (xy 168.469891 -383.599414) (xy 168.523839 -383.60717) (xy 168.576134 -383.622525)
			(xy 168.625711 -383.645167) (xy 168.671561 -383.674633) (xy 168.712752 -383.710324) (xy 168.748443 -383.751515)
			(xy 168.777909 -383.797365) (xy 168.800551 -383.846942) (xy 168.815906 -383.899237) (xy 168.823662 -383.953185)
			(xy 168.824148 -383.980436) (xy 168.823561 -384.009578) (xy 168.81469 -384.067184) (xy 168.79716 -384.122771)
			(xy 168.77138 -384.175044) (xy 168.737948 -384.222788) (xy 168.697644 -384.264891) (xy 168.651404 -384.300374)
			(xy 168.600305 -384.328411) (xy 168.545536 -384.348349) (xy 168.517062 -384.354578) (xy 168.506394 -384.35661)
			(xy 168.489122 -384.369056) (xy 168.439084 -384.452114) (xy 168.436544 -384.473196) (xy 168.439592 -384.48361)
			(xy 168.447157 -384.510475) (xy 168.455318 -384.565687) (xy 168.455848 -384.593592) (xy 168.455467 -384.617943)
			(xy 168.449247 -384.666246) (xy 168.43692 -384.713361) (xy 168.428162 -384.736086) (xy 168.423844 -384.746754)
			(xy 168.425368 -384.769614) (xy 168.475406 -384.859022) (xy 168.494202 -384.87223) (xy 168.505632 -384.874262)
			(xy 168.531999 -384.87913) (xy 168.583126 -384.895285) (xy 168.631485 -384.918442) (xy 168.676124 -384.948145)
			(xy 168.716162 -384.983808) (xy 168.75081 -385.024728) (xy 168.779384 -385.070097) (xy 168.801322 -385.119022)
			(xy 168.81619 -385.170537) (xy 168.823695 -385.223627) (xy 168.824148 -385.250436) (xy 168.823716 -385.277808)
			(xy 168.815892 -385.331989) (xy 168.800395 -385.384493) (xy 168.777546 -385.434239) (xy 168.747813 -385.480204)
			(xy 168.730168 -385.501134) (xy 168.724072 -385.508246) (xy 168.717722 -385.525264) (xy 168.717722 -385.610608)
			(xy 168.724072 -385.627626) (xy 168.730168 -385.634738) (xy 168.747844 -385.655642) (xy 168.777568 -385.701615)
			(xy 168.800411 -385.751366) (xy 168.815905 -385.803872) (xy 168.82373 -385.858055) (xy 168.823727 -385.912799)
			(xy 168.815894 -385.966981) (xy 168.800392 -386.019485) (xy 168.777542 -386.069233) (xy 168.747811 -386.115201)
			(xy 168.730168 -386.136134) (xy 168.724072 -386.143246) (xy 168.717722 -386.160264) (xy 168.717722 -386.245608)
			(xy 168.724072 -386.262626) (xy 168.730168 -386.269738) (xy 168.747844 -386.290642) (xy 168.777568 -386.336615)
			(xy 168.800411 -386.386366) (xy 168.815905 -386.438872) (xy 168.82373 -386.493055) (xy 168.823727 -386.547799)
			(xy 168.815894 -386.601981) (xy 168.800392 -386.654485) (xy 168.777542 -386.704233) (xy 168.747811 -386.750201)
			(xy 168.736804 -386.76326) (xy 170.479718 -386.76326) (xy 170.483789 -386.707638) (xy 170.495915 -386.653201)
			(xy 170.515838 -386.60111) (xy 170.543134 -386.552475) (xy 170.57722 -386.508332) (xy 170.617369 -386.469623)
			(xy 170.662727 -386.437172) (xy 170.712327 -386.411671) (xy 170.765111 -386.393664) (xy 170.819954 -386.383534)
			(xy 170.875688 -386.381497) (xy 170.931125 -386.387597) (xy 170.985082 -386.401703) (xy 171.036411 -386.423515)
			(xy 171.084017 -386.452569) (xy 171.126885 -386.488244) (xy 171.164102 -386.529781) (xy 171.194875 -386.576294)
			(xy 171.218547 -386.626791) (xy 171.234615 -386.680198) (xy 171.242735 -386.735374) (xy 171.243244 -386.76326)
			(xy 171.242735 -386.791146) (xy 171.234615 -386.846322) (xy 171.218547 -386.899729) (xy 171.194875 -386.950226)
			(xy 171.164102 -386.996739) (xy 171.126885 -387.038276) (xy 171.084017 -387.073951) (xy 171.036411 -387.103005)
			(xy 170.985082 -387.124817) (xy 170.931125 -387.138923) (xy 170.875688 -387.145023) (xy 170.819954 -387.142986)
			(xy 170.765111 -387.132856) (xy 170.712327 -387.114849) (xy 170.662727 -387.089348) (xy 170.617369 -387.056897)
			(xy 170.57722 -387.018188) (xy 170.543134 -386.974045) (xy 170.515838 -386.92541) (xy 170.495915 -386.873319)
			(xy 170.483789 -386.818882) (xy 170.479718 -386.76326) (xy 168.736804 -386.76326) (xy 168.730168 -386.771134)
			(xy 168.724072 -386.778246) (xy 168.717722 -386.795264) (xy 168.717722 -386.880608) (xy 168.724072 -386.897626)
			(xy 168.730168 -386.904738) (xy 168.747787 -386.925687) (xy 168.777503 -386.971654) (xy 168.800343 -387.021398)
			(xy 168.815839 -387.073895) (xy 168.823672 -387.128068) (xy 168.824148 -387.155436) (xy 168.823662 -387.182687)
			(xy 168.815906 -387.236635) (xy 168.800551 -387.28893) (xy 168.777909 -387.338507) (xy 168.748443 -387.384357)
			(xy 168.712752 -387.425548) (xy 168.671561 -387.461239) (xy 168.625711 -387.490705) (xy 168.576134 -387.513347)
			(xy 168.523839 -387.528702) (xy 168.469891 -387.536458) (xy 168.415389 -387.536458) (xy 168.361441 -387.528702)
			(xy 168.309146 -387.513347) (xy 168.259569 -387.490705) (xy 168.213719 -387.461239) (xy 168.172528 -387.425548)
			(xy 168.136837 -387.384357) (xy 168.107371 -387.338507) (xy 168.084729 -387.28893) (xy 168.069374 -387.236635)
			(xy 168.061618 -387.182687) (xy 168.061132 -387.155436) (xy 168.061611 -387.128066) (xy 168.069425 -387.073887)
			(xy 168.08491 -387.021384) (xy 168.107749 -386.971637) (xy 168.137472 -386.92567) (xy 168.155112 -386.904738)
			(xy 168.161208 -386.897626) (xy 168.167558 -386.880608) (xy 168.167558 -386.795264) (xy 168.161208 -386.778246)
			(xy 168.155112 -386.771134) (xy 168.137477 -386.750198) (xy 168.107764 -386.704227) (xy 168.084927 -386.65448)
			(xy 168.069435 -386.60198) (xy 168.061606 -386.547805) (xy 168.061132 -386.520436) (xy 168.061685 -386.490959)
			(xy 168.07075 -386.432706) (xy 168.088669 -386.376541) (xy 168.115015 -386.323801) (xy 168.149162 -386.275743)
			(xy 168.169336 -386.254244) (xy 168.175849 -386.246893) (xy 168.183306 -386.228745) (xy 168.183814 -386.218938)
			(xy 168.183814 -386.165598) (xy 168.176448 -386.15874) (xy 168.169099 -386.152225) (xy 168.150949 -386.14477)
			(xy 168.141142 -386.144262) (xy 168.109138 -386.144262) (xy 168.099323 -386.144736) (xy 168.081159 -386.152191)
			(xy 168.073832 -386.15874) (xy 168.052317 -386.178896) (xy 168.004262 -386.213044) (xy 167.951526 -386.239394)
			(xy 167.895366 -386.257319) (xy 167.837116 -386.266392) (xy 167.80764 -386.266944) (xy 167.780388 -386.266411)
			(xy 167.726438 -386.25866) (xy 167.67414 -386.243309) (xy 167.624559 -386.220671) (xy 167.578706 -386.191207)
			(xy 167.537512 -386.155516) (xy 167.501817 -386.114326) (xy 167.472349 -386.068476) (xy 167.449705 -386.018898)
			(xy 167.434349 -385.966601) (xy 167.426591 -385.912652) (xy 167.426591 -385.858148) (xy 167.434349 -385.804199)
			(xy 167.449705 -385.751902) (xy 167.472349 -385.702324) (xy 167.501817 -385.656474) (xy 167.537512 -385.615284)
			(xy 167.578706 -385.579593) (xy 167.624559 -385.550129) (xy 167.67414 -385.527491) (xy 167.726438 -385.51214)
			(xy 167.780388 -385.504389) (xy 167.80764 -385.503928) (xy 167.837116 -385.504497) (xy 167.895369 -385.513558)
			(xy 167.951534 -385.531473) (xy 168.004273 -385.557816) (xy 168.052332 -385.59196) (xy 168.073832 -385.612132)
			(xy 168.081158 -385.618678) (xy 168.099325 -385.626115) (xy 168.109138 -385.62661) (xy 168.162478 -385.62661)
			(xy 168.169336 -385.619244) (xy 168.175849 -385.611893) (xy 168.183306 -385.593745) (xy 168.183814 -385.583938)
			(xy 168.183814 -385.551934) (xy 168.183349 -385.542117) (xy 168.175889 -385.523954) (xy 168.169336 -385.516628)
			(xy 168.149174 -385.495118) (xy 168.115028 -385.447061) (xy 168.08868 -385.394325) (xy 168.070756 -385.338163)
			(xy 168.061683 -385.279912) (xy 168.061132 -385.250436) (xy 168.061523 -385.226086) (xy 168.067739 -385.177783)
			(xy 168.080062 -385.130667) (xy 168.088818 -385.107942) (xy 168.093136 -385.097274) (xy 168.091612 -385.074414)
			(xy 168.041574 -384.985006) (xy 168.022778 -384.971798) (xy 168.011348 -384.969766) (xy 167.985914 -384.965063)
			(xy 167.936519 -384.94972) (xy 167.889646 -384.927853) (xy 167.846152 -384.899861) (xy 167.806833 -384.866255)
			(xy 167.772408 -384.827652) (xy 167.757602 -384.806444) (xy 167.750708 -384.797151) (xy 167.730732 -384.785515)
			(xy 167.719248 -384.784092) (xy 167.686736 -384.781806) (xy 167.67523 -384.781589) (xy 167.65386 -384.790057)
			(xy 167.645588 -384.798062) (xy 167.643556 -384.800602) (xy 167.636952 -384.80746) (xy 167.630094 -384.824478)
			(xy 167.627808 -384.910838) (xy 167.633904 -384.928364) (xy 167.64 -384.935476) (xy 167.654763 -384.953467)
			(xy 167.67959 -384.99283) (xy 167.698652 -385.035285) (xy 167.711571 -385.079995) (xy 167.718092 -385.126075)
			(xy 167.718486 -385.149344) (xy 167.717976 -385.175331) (xy 167.709846 -385.226666) (xy 167.693785 -385.276096)
			(xy 167.670189 -385.322406) (xy 167.639639 -385.364454) (xy 167.602888 -385.401205) (xy 167.56084 -385.431755)
			(xy 167.51453 -385.455351) (xy 167.4651 -385.471412) (xy 167.413765 -385.479542) (xy 167.361791 -385.479542)
			(xy 167.310456 -385.471412) (xy 167.261026 -385.455351) (xy 167.214716 -385.431755) (xy 167.172668 -385.401205)
			(xy 167.135917 -385.364454) (xy 167.105367 -385.322406) (xy 167.081771 -385.276096) (xy 167.06571 -385.226666)
			(xy 167.05758 -385.175331) (xy 167.05707 -385.149344) (xy 165.707546 -385.149344) (xy 165.725135 -385.183957)
			(xy 165.741153 -385.233451) (xy 165.745668 -385.259072) (xy 165.747192 -385.26847) (xy 166.019988 -385.740402)
			(xy 166.027354 -385.746244) (xy 166.046147 -385.762029) (xy 166.079261 -385.798251) (xy 166.106667 -385.838963)
			(xy 166.127765 -385.883274) (xy 166.142093 -385.930213) (xy 166.149337 -385.978753) (xy 166.149782 -386.003292)
			(xy 166.149528 -386.014976) (xy 166.149274 -386.024882) (xy 166.155624 -386.042916) (xy 166.214806 -386.109972)
			(xy 166.232078 -386.118862) (xy 166.24173 -386.119624) (xy 166.266065 -386.122281) (xy 166.313614 -386.133915)
			(xy 166.358931 -386.152427) (xy 166.401026 -386.177413) (xy 166.438981 -386.208328) (xy 166.471968 -386.244497)
			(xy 166.499266 -386.285131) (xy 166.52028 -386.329343) (xy 166.534551 -386.376169) (xy 166.541768 -386.424586)
			(xy 166.542212 -386.449062) (xy 166.541702 -386.475049) (xy 166.533572 -386.526384) (xy 166.517511 -386.575814)
			(xy 166.493915 -386.622124) (xy 166.463365 -386.664172) (xy 166.426614 -386.700923) (xy 166.384566 -386.731473)
			(xy 166.338256 -386.755069) (xy 166.288826 -386.77113) (xy 166.237491 -386.77926) (xy 166.185517 -386.77926)
			(xy 166.134182 -386.77113) (xy 166.084752 -386.755069) (xy 166.038442 -386.731473) (xy 165.996394 -386.700923)
			(xy 165.959643 -386.664172) (xy 165.929093 -386.622124) (xy 165.905497 -386.575814) (xy 165.889436 -386.526384)
			(xy 165.881306 -386.475049) (xy 165.880796 -386.449062) (xy 165.88105 -386.437378) (xy 165.881304 -386.427472)
			(xy 165.874954 -386.409438) (xy 165.815772 -386.342382) (xy 165.7985 -386.333492) (xy 165.788848 -386.33273)
			(xy 165.76466 -386.330097) (xy 165.717395 -386.31855) (xy 165.672328 -386.300211) (xy 165.63043 -386.275473)
			(xy 165.592604 -386.24487) (xy 165.559664 -386.209061) (xy 165.532319 -386.168816) (xy 165.511159 -386.125003)
			(xy 165.496638 -386.078565) (xy 165.49243 -386.0546) (xy 165.490906 -386.045202) (xy 165.21811 -385.57327)
			(xy 165.210744 -385.567428) (xy 165.191986 -385.551605) (xy 165.158869 -385.515391) (xy 165.131459 -385.474686)
			(xy 165.110355 -385.430383) (xy 165.096019 -385.383451) (xy 165.088766 -385.334916) (xy 165.088316 -385.31038)
			(xy 164.571232 -385.31038) (xy 164.819838 -385.740402) (xy 164.827204 -385.746244) (xy 164.845982 -385.762048)
			(xy 164.879114 -385.798256) (xy 164.906535 -385.83896) (xy 164.927641 -385.883269) (xy 164.941969 -385.93021)
			(xy 164.949206 -385.978752) (xy 164.949632 -386.003292) (xy 164.949378 -386.015484) (xy 164.949124 -386.025136)
			(xy 164.95522 -386.04317) (xy 165.013894 -386.11048) (xy 165.030658 -386.119116) (xy 165.040564 -386.120132)
			(xy 165.067334 -386.123456) (xy 165.119367 -386.137675) (xy 165.168403 -386.16015) (xy 165.213142 -386.190284)
			(xy 165.252398 -386.227278) (xy 165.285131 -386.270151) (xy 165.310473 -386.317768) (xy 165.327753 -386.368867)
			(xy 165.336512 -386.422092) (xy 165.336982 -386.449062) (xy 165.336419 -386.476344) (xy 165.327454 -386.530165)
			(xy 165.309779 -386.581786) (xy 165.283871 -386.629807) (xy 165.250434 -386.672924) (xy 165.23081 -386.691886)
			(xy 165.223364 -386.699379) (xy 165.214829 -386.718674) (xy 165.2143 -386.729224) (xy 165.2143 -386.8039)
			(xy 165.214891 -386.814433) (xy 165.223425 -386.833703) (xy 165.23081 -386.841238) (xy 165.250466 -386.86017)
			(xy 165.28391 -386.90329) (xy 165.309819 -386.951317) (xy 165.327489 -387.002946) (xy 165.336441 -387.056777)
			(xy 165.336982 -387.084062) (xy 165.336549 -387.108179) (xy 165.329553 -387.155904) (xy 165.315704 -387.202108)
			(xy 165.295294 -387.245813) (xy 165.282372 -387.26618) (xy 165.27653 -387.27507) (xy 165.272974 -387.295136)
			(xy 165.294056 -387.387338) (xy 165.306248 -387.404102) (xy 165.315138 -387.409436) (xy 165.335939 -387.422292)
			(xy 165.373855 -387.45317) (xy 165.406804 -387.489301) (xy 165.434066 -387.529895) (xy 165.455046 -387.574065)
			(xy 165.469284 -387.620845) (xy 165.476469 -387.669212) (xy 165.476936 -387.693662) (xy 165.476467 -387.718856)
			(xy 165.468834 -387.768661) (xy 165.45374 -387.816734) (xy 165.431532 -387.861963) (xy 165.4175 -387.882892)
			(xy 165.409372 -387.894576) (xy 165.40734 -387.92277) (xy 165.4556 -388.015226) (xy 165.460225 -388.023312)
			(xy 165.474103 -388.035714) (xy 165.491505 -388.042316) (xy 165.500812 -388.042658) (xy 167.113458 -388.042658)
			(xy 167.11676 -388.04596) (xy 167.215058 -388.04977) (xy 167.232838 -388.043674) (xy 167.240204 -388.037324)
			(xy 167.258241 -388.022526) (xy 167.297687 -387.997614) (xy 167.340241 -387.978487) (xy 167.385059 -387.965526)
			(xy 167.431253 -387.958986) (xy 167.45458 -387.958584) (xy 167.480851 -387.959088) (xy 167.532732 -387.967392)
			(xy 167.582648 -387.983796) (xy 167.629342 -388.007885) (xy 167.67164 -388.039055) (xy 167.708478 -388.07652)
			(xy 167.738928 -388.119338) (xy 167.762225 -388.166433) (xy 167.777782 -388.216619) (xy 167.781986 -388.242556)
			(xy 167.783256 -388.251446) (xy 167.791638 -388.26694) (xy 167.852598 -388.322566) (xy 167.869108 -388.329424)
			(xy 167.877998 -388.329678) (xy 167.903179 -388.331313) (xy 167.952648 -388.341264) (xy 168.000031 -388.358615)
			(xy 168.044228 -388.382963) (xy 168.084212 -388.413744) (xy 168.119056 -388.450242) (xy 168.14795 -388.49161)
			(xy 168.170223 -388.536888) (xy 168.185359 -388.585025) (xy 168.193005 -388.634902) (xy 168.193466 -388.660132)
			(xy 168.192978 -388.685489) (xy 168.185232 -388.735608) (xy 168.169926 -388.783957) (xy 168.147418 -388.829403)
			(xy 168.118238 -388.870881) (xy 168.10101 -388.889494) (xy 168.094152 -388.896606) (xy 168.086786 -388.915148)
			(xy 168.087548 -388.996174) (xy 168.088127 -389.006094) (xy 168.095848 -389.024381) (xy 168.102534 -389.031734)
			(xy 168.133014 -389.062214) (xy 168.140409 -389.069068) (xy 168.159008 -389.07681) (xy 168.169082 -389.0772)
		)
		(stroke
			(width 0)
			(type solid)
		)
		(fill yes)
		(layer "In15.Cu")
		(net "P1V8_CPU1_RT2_1A_1D")
	)
	(gr_poly
		(pts
			(xy 201.766932 -399.318988) (xy 201.776999 -399.318559) (xy 201.795594 -399.310835) (xy 201.803 -399.304002)
			(xy 203.3778 -397.729202) (xy 203.385198 -397.722355) (xy 203.403796 -397.71462) (xy 203.413868 -397.714216)
			(xy 206.779876 -397.714216) (xy 206.78994 -397.714653) (xy 206.808523 -397.722389) (xy 206.815944 -397.729202)
			(xy 208.390744 -399.304002) (xy 208.398145 -399.310841) (xy 208.416743 -399.318559) (xy 208.426812 -399.318988)
			(xy 212.484462 -399.318988) (xy 212.494527 -399.318553) (xy 212.513114 -399.310822) (xy 212.52053 -399.304002)
			(xy 213.827868 -397.996664) (xy 213.835267 -397.989821) (xy 213.853866 -397.982101) (xy 213.863936 -397.981678)
			(xy 217.608912 -397.981678) (xy 217.618982 -397.982103) (xy 217.637585 -397.989818) (xy 217.64498 -397.996664)
			(xy 218.952318 -399.304002) (xy 218.959718 -399.310845) (xy 218.978316 -399.318573) (xy 218.988386 -399.318988)
			(xy 223.134936 -399.318988) (xy 223.145003 -399.318558) (xy 223.163597 -399.310833) (xy 223.171004 -399.304002)
			(xy 224.45599 -398.019016) (xy 224.463387 -398.012166) (xy 224.481985 -398.004425) (xy 224.492058 -398.00403)
			(xy 228.370892 -398.00403) (xy 228.380962 -398.004452) (xy 228.399566 -398.012168) (xy 228.40696 -398.019016)
			(xy 229.691946 -399.304002) (xy 229.699347 -399.310841) (xy 229.717945 -399.318558) (xy 229.728014 -399.318988)
			(xy 234.185968 -399.318988) (xy 234.196032 -399.318552) (xy 234.214618 -399.310819) (xy 234.222036 -399.304002)
			(xy 238.249206 -395.276832) (xy 238.256041 -395.26943) (xy 238.26375 -395.250831) (xy 238.264192 -395.240764)
			(xy 238.264192 -385.388358) (xy 238.264446 -385.388104) (xy 238.264446 -382.976882) (xy 238.264874 -382.966814)
			(xy 238.272598 -382.948219) (xy 238.279432 -382.940814) (xy 238.33328 -382.886966) (xy 238.34068 -382.880125)
			(xy 238.359279 -382.872409) (xy 238.369348 -382.87198) (xy 278.08047 -382.87198) (xy 278.090534 -382.871544)
			(xy 278.109118 -382.863809) (xy 278.116538 -382.856994) (xy 278.196294 -382.777238) (xy 278.203131 -382.769837)
			(xy 278.210844 -382.751238) (xy 278.21128 -382.74117) (xy 278.21128 -382.71704) (xy 278.211373 -382.712021)
			(xy 278.213294 -382.70217) (xy 278.21509 -382.697482) (xy 278.222456 -382.68021) (xy 278.224257 -382.675524)
			(xy 278.226178 -382.665671) (xy 278.226266 -382.660652) (xy 278.226266 -374.886982) (xy 278.225724 -374.876997)
			(xy 278.218002 -374.858573) (xy 278.21128 -374.851168) (xy 276.943058 -373.582692) (xy 276.935657 -373.575853)
			(xy 276.917059 -373.568135) (xy 276.90699 -373.567706) (xy 240.053622 -373.567706) (xy 240.040414 -373.571516)
			(xy 240.034318 -373.575072) (xy 240.028212 -373.578572) (xy 240.014682 -373.582435) (xy 240.007648 -373.582692)
			(xy 201.640694 -373.582692) (xy 201.630624 -373.583116) (xy 201.61202 -373.590831) (xy 201.604626 -373.597678)
			(xy 200.497694 -374.70461) (xy 200.49085 -374.712009) (xy 200.48312 -374.730607) (xy 200.482708 -374.740678)
			(xy 200.482708 -377.104148) (xy 200.483064 -377.112847) (xy 200.488886 -377.129243) (xy 200.499846 -377.142757)
			(xy 200.507092 -377.147582) (xy 200.550422 -377.174925) (xy 200.630899 -377.238343) (xy 200.66762 -377.274074)
			(xy 200.94321 -377.549664) (xy 200.972843 -377.580022) (xy 201.026679 -377.645592) (xy 201.073831 -377.716122)
			(xy 201.113844 -377.790933) (xy 201.146335 -377.869305) (xy 201.17099 -377.950483) (xy 201.187571 -378.033687)
			(xy 201.19592 -378.118114) (xy 201.196448 -378.160534) (xy 201.195948 -378.202171) (xy 201.187931 -378.285059)
			(xy 201.171975 -378.366791) (xy 201.148228 -378.446608) (xy 201.11691 -378.523769) (xy 201.078312 -378.597558)
			(xy 201.032792 -378.667291) (xy 200.980773 -378.732319) (xy 200.922738 -378.79204) (xy 200.859225 -378.845899)
			(xy 200.790824 -378.893396) (xy 200.71817 -378.93409) (xy 200.641937 -378.967604) (xy 200.562832 -378.993626)
			(xy 200.522332 -379.003306) (xy 200.504806 -379.00737) (xy 200.482708 -379.034802) (xy 200.482708 -380.68377)
			(xy 200.483249 -380.693719) (xy 200.490918 -380.712088) (xy 200.50497 -380.726187) (xy 200.51395 -380.730506)
			(xy 200.528428 -380.736602) (xy 200.5584 -380.73076) (xy 202.412854 -378.876052) (xy 202.419349 -378.868916)
			(xy 202.426928 -378.851188) (xy 202.427443 -378.831914) (xy 202.424538 -378.822712) (xy 202.387962 -378.722382)
			(xy 202.364594 -378.704348) (xy 202.349862 -378.703078) (xy 202.308786 -378.699051) (xy 202.227565 -378.684342)
			(xy 202.148057 -378.662172) (xy 202.070945 -378.632731) (xy 201.996892 -378.596273) (xy 201.926535 -378.553111)
			(xy 201.860479 -378.503616) (xy 201.799293 -378.448214) (xy 201.743503 -378.387382) (xy 201.693589 -378.321643)
			(xy 201.649979 -378.251562) (xy 201.61305 -378.177743) (xy 201.583119 -378.10082) (xy 201.560443 -378.021454)
			(xy 201.545217 -377.940329) (xy 201.537572 -377.858143) (xy 201.537062 -377.816872) (xy 201.537538 -377.77577)
			(xy 201.545125 -377.693916) (xy 201.560232 -377.613112) (xy 201.58273 -377.534046) (xy 201.612427 -377.457393)
			(xy 201.649069 -377.383808) (xy 201.692345 -377.313916) (xy 201.741884 -377.248316) (xy 201.797265 -377.187566)
			(xy 201.858015 -377.132186) (xy 201.923615 -377.082646) (xy 201.993506 -377.03937) (xy 202.067092 -377.002727)
			(xy 202.143744 -376.97303) (xy 202.22281 -376.950532) (xy 202.303614 -376.935425) (xy 202.385468 -376.927838)
			(xy 202.42657 -376.927364) (xy 202.467843 -376.927831) (xy 202.550033 -376.935475) (xy 202.631162 -376.950702)
			(xy 202.710532 -376.973379) (xy 202.787459 -377.003312) (xy 202.861282 -377.040243) (xy 202.931366 -377.083854)
			(xy 202.997109 -377.133771) (xy 203.057944 -377.189564) (xy 203.113348 -377.250753) (xy 203.162845 -377.316812)
			(xy 203.20601 -377.387172) (xy 203.24247 -377.461229) (xy 203.271912 -377.538345) (xy 203.294083 -377.617857)
			(xy 203.308793 -377.699082) (xy 203.312776 -377.740164) (xy 203.314046 -377.754896) (xy 203.33208 -377.778264)
			(xy 203.43241 -377.81484) (xy 203.441606 -377.81777) (xy 203.460885 -377.817255) (xy 203.478608 -377.80965)
			(xy 203.48575 -377.803156) (xy 203.844144 -377.445016) (xy 203.870915 -377.418851) (xy 203.928764 -377.371334)
			(xy 203.990992 -377.329717) (xy 204.057001 -377.2944) (xy 204.126153 -377.265724) (xy 204.197783 -377.243965)
			(xy 204.271202 -377.229333) (xy 204.345701 -377.221968) (xy 204.383132 -377.221496) (xy 204.70876 -377.221496)
			(xy 204.719575 -377.221059) (xy 204.739317 -377.21224) (xy 204.74686 -377.204478) (xy 204.774943 -377.173425)
			(xy 204.83604 -377.11617) (xy 204.902246 -377.064909) (xy 204.972975 -377.020095) (xy 205.047603 -376.982126)
			(xy 205.125467 -376.951336) (xy 205.205881 -376.927999) (xy 205.288131 -376.91232) (xy 205.37149 -376.904439)
			(xy 205.413356 -376.903996) (xy 205.45446 -376.904454) (xy 205.536319 -376.912036) (xy 205.617129 -376.927138)
			(xy 205.6962 -376.949632) (xy 205.772858 -376.979327) (xy 205.84645 -377.015968) (xy 205.916347 -377.059243)
			(xy 205.981952 -377.108783) (xy 206.042706 -377.164165) (xy 206.098091 -377.224917) (xy 206.147634 -377.29052)
			(xy 206.190913 -377.360415) (xy 206.227557 -377.434005) (xy 206.257255 -377.510662) (xy 206.279753 -377.589733)
			(xy 206.294859 -377.670542) (xy 206.302444 -377.7524) (xy 206.302864 -377.793504) (xy 206.302279 -377.8399)
			(xy 206.292645 -377.93219) (xy 206.27345 -378.022975) (xy 206.244905 -378.111266) (xy 206.226664 -378.15393)
			(xy 206.222846 -378.16387) (xy 206.222847 -378.185137) (xy 206.226664 -378.195078) (xy 206.244902 -378.237743)
			(xy 206.273442 -378.326036) (xy 206.292638 -378.41682) (xy 206.302283 -378.509108) (xy 206.302864 -378.555504)
			(xy 206.302404 -378.596606) (xy 206.294818 -378.67846) (xy 206.279712 -378.759265) (xy 206.257215 -378.838331)
			(xy 206.227518 -378.914984) (xy 206.190875 -378.98857) (xy 206.147598 -379.058461) (xy 206.098058 -379.124061)
			(xy 206.042675 -379.184809) (xy 205.981924 -379.240188) (xy 205.916321 -379.289726) (xy 205.846428 -379.332998)
			(xy 205.77284 -379.369638) (xy 205.696186 -379.39933) (xy 205.617118 -379.421823) (xy 205.536313 -379.436925)
			(xy 205.454458 -379.444506) (xy 205.413356 -379.445012) (xy 205.373341 -379.444562) (xy 205.293635 -379.437351)
			(xy 205.214899 -379.423008) (xy 205.137771 -379.401651) (xy 205.062872 -379.373451) (xy 204.99081 -379.338636)
			(xy 204.922167 -379.297488) (xy 204.857498 -379.250341) (xy 204.827124 -379.224286) (xy 204.811884 -379.211078)
			(xy 204.771752 -379.212348) (xy 201.363326 -382.621028) (xy 201.356499 -382.628393) (xy 201.348751 -382.646906)
			(xy 201.348687 -382.666974) (xy 201.35215 -382.6764) (xy 201.358246 -382.690878) (xy 201.383392 -382.707896)
			(xy 202.479656 -382.707896) (xy 202.489647 -382.707366) (xy 202.50809 -382.699664) (xy 202.51547 -382.69291)
			(xy 203.975208 -381.233426) (xy 204.001997 -381.20729) (xy 204.059857 -381.159812) (xy 204.122092 -381.118233)
			(xy 204.188103 -381.082953) (xy 204.257253 -381.054313) (xy 204.328878 -381.032588) (xy 204.402286 -381.017987)
			(xy 204.476773 -381.010652) (xy 204.514196 -381.01016) (xy 206.53502 -381.01016) (xy 206.563722 -380.985522)
			(xy 206.566516 -380.966726) (xy 206.573034 -380.926334) (xy 206.59252 -380.846865) (xy 206.619206 -380.769515)
			(xy 206.635604 -380.73203) (xy 206.639633 -380.722076) (xy 206.639783 -380.700622) (xy 206.635858 -380.690628)
			(xy 206.617627 -380.647995) (xy 206.589097 -380.559765) (xy 206.569904 -380.469045) (xy 206.560258 -380.37682)
			(xy 206.559658 -380.330456) (xy 206.560126 -380.289534) (xy 206.567649 -380.208038) (xy 206.582628 -380.127577)
			(xy 206.604934 -380.048832) (xy 206.634381 -379.97247) (xy 206.670719 -379.899136) (xy 206.71364 -379.829451)
			(xy 206.762781 -379.764003) (xy 206.817728 -379.703347) (xy 206.878014 -379.647995) (xy 206.943131 -379.598416)
			(xy 207.012527 -379.555028) (xy 207.048862 -379.536198) (xy 207.061816 -379.529594) (xy 207.076802 -379.50521)
			(xy 207.07604 -379.384814) (xy 207.061054 -379.360684) (xy 207.047846 -379.354334) (xy 207.010927 -379.335722)
			(xy 206.940372 -379.292611) (xy 206.874123 -379.243136) (xy 206.812753 -379.187725) (xy 206.756791 -379.126857)
			(xy 206.70672 -379.061058) (xy 206.662973 -378.990894) (xy 206.625928 -378.916973) (xy 206.595904 -378.839933)
			(xy 206.573162 -378.760438) (xy 206.557896 -378.679175) (xy 206.550239 -378.596846) (xy 206.549752 -378.555504)
			(xy 206.550337 -378.509108) (xy 206.559969 -378.416817) (xy 206.579161 -378.326032) (xy 206.607703 -378.237739)
			(xy 206.625952 -378.195078) (xy 206.629771 -378.185138) (xy 206.629773 -378.163869) (xy 206.625952 -378.15393)
			(xy 206.607713 -378.111266) (xy 206.579172 -378.022972) (xy 206.559975 -377.932189) (xy 206.550328 -377.8399)
			(xy 206.549752 -377.793504) (xy 206.550256 -377.751156) (xy 206.558307 -377.666842) (xy 206.574336 -377.583676)
			(xy 206.598197 -377.502409) (xy 206.629676 -377.423779) (xy 206.668487 -377.348498) (xy 206.714277 -377.277246)
			(xy 206.766633 -377.21067) (xy 206.825081 -377.149372) (xy 206.889091 -377.093907) (xy 206.958083 -377.044778)
			(xy 207.031433 -377.002429) (xy 207.108476 -376.967245) (xy 207.188515 -376.939543) (xy 207.270824 -376.919575)
			(xy 207.354659 -376.907522) (xy 207.43926 -376.903492) (xy 207.523861 -376.907522) (xy 207.607696 -376.919575)
			(xy 207.690005 -376.939543) (xy 207.770044 -376.967245) (xy 207.847087 -377.002429) (xy 207.920437 -377.044778)
			(xy 207.989429 -377.093907) (xy 208.053439 -377.149372) (xy 208.111887 -377.21067) (xy 208.164243 -377.277246)
			(xy 208.210033 -377.348498) (xy 208.248844 -377.423779) (xy 208.280323 -377.502409) (xy 208.304184 -377.583676)
			(xy 208.320213 -377.666842) (xy 208.328264 -377.751156) (xy 208.328768 -377.793504) (xy 208.328183 -377.8399)
			(xy 208.318549 -377.93219) (xy 208.299355 -378.022975) (xy 208.270809 -378.111266) (xy 208.252568 -378.15393)
			(xy 208.24875 -378.16387) (xy 208.248751 -378.185137) (xy 208.252568 -378.195078) (xy 208.270806 -378.237743)
			(xy 208.299346 -378.326036) (xy 208.318542 -378.41682) (xy 208.328187 -378.509108) (xy 208.328768 -378.555504)
			(xy 208.328297 -378.596424) (xy 208.320769 -378.677918) (xy 208.305787 -378.758376) (xy 208.283477 -378.837117)
			(xy 208.254027 -378.913476) (xy 208.217688 -378.986806) (xy 208.174765 -379.056488) (xy 208.125623 -379.121933)
			(xy 208.070677 -379.182586) (xy 208.010391 -379.237935) (xy 207.945275 -379.287512) (xy 207.87588 -379.330897)
			(xy 207.839564 -379.349762) (xy 207.82661 -379.356366) (xy 207.811624 -379.38075) (xy 207.812386 -379.501146)
			(xy 207.827372 -379.525276) (xy 207.84058 -379.531626) (xy 207.877499 -379.550238) (xy 207.948055 -379.59335)
			(xy 208.014304 -379.642825) (xy 208.075675 -379.698236) (xy 208.131638 -379.759104) (xy 208.18171 -379.824903)
			(xy 208.225459 -379.895066) (xy 208.262506 -379.968987) (xy 208.292532 -380.046027) (xy 208.315277 -380.125522)
			(xy 208.330546 -380.206784) (xy 208.338207 -380.289114) (xy 208.338674 -380.330456) (xy 208.338049 -380.377688)
			(xy 208.328037 -380.47162) (xy 208.30813 -380.563962) (xy 208.278554 -380.653677) (xy 208.25968 -380.696978)
			(xy 208.255654 -380.706932) (xy 208.255507 -380.728385) (xy 208.259426 -380.73838) (xy 208.275111 -380.774912)
			(xy 208.300668 -380.850203) (xy 208.319402 -380.927474) (xy 208.32572 -380.966726) (xy 208.328514 -380.985522)
			(xy 208.357216 -381.01016) (xy 208.566004 -381.01016) (xy 208.594452 -380.985522) (xy 208.597246 -380.966472)
			(xy 208.603521 -380.92669) (xy 208.622334 -380.848375) (xy 208.648148 -380.77208) (xy 208.664048 -380.735078)
			(xy 208.667867 -380.725138) (xy 208.667869 -380.703869) (xy 208.664048 -380.69393) (xy 208.645809 -380.651266)
			(xy 208.617268 -380.562972) (xy 208.598071 -380.472188) (xy 208.588425 -380.3799) (xy 208.587848 -380.333504)
			(xy 208.588311 -380.292249) (xy 208.595945 -380.210093) (xy 208.611156 -380.128997) (xy 208.633815 -380.049659)
			(xy 208.663725 -379.972761) (xy 208.700631 -379.898964) (xy 208.744213 -379.828904) (xy 208.794099 -379.763182)
			(xy 208.849858 -379.702364) (xy 208.911011 -379.646973) (xy 208.977033 -379.597484) (xy 209.047355 -379.554325)
			(xy 209.084164 -379.53569) (xy 209.092466 -379.531126) (xy 209.105198 -379.517114) (xy 209.111983 -379.499438)
			(xy 209.112358 -379.48997) (xy 209.112358 -379.399038) (xy 209.112017 -379.389566) (xy 209.105222 -379.371888)
			(xy 209.09247 -379.357883) (xy 209.084164 -379.353318) (xy 209.047368 -379.334661) (xy 208.977058 -379.291489)
			(xy 208.911046 -379.241993) (xy 208.849902 -379.186598) (xy 208.794148 -379.12578) (xy 208.744265 -379.060061)
			(xy 208.700681 -378.990006) (xy 208.66377 -378.916216) (xy 208.633849 -378.839326) (xy 208.611176 -378.759996)
			(xy 208.595945 -378.678907) (xy 208.588288 -378.596757) (xy 208.587848 -378.555504) (xy 208.588433 -378.509108)
			(xy 208.598066 -378.416818) (xy 208.61726 -378.326033) (xy 208.645805 -378.237741) (xy 208.664048 -378.195078)
			(xy 208.667867 -378.185138) (xy 208.667869 -378.163869) (xy 208.664048 -378.15393) (xy 208.645809 -378.111266)
			(xy 208.617268 -378.022972) (xy 208.598071 -377.932188) (xy 208.588425 -377.8399) (xy 208.587848 -377.793504)
			(xy 208.588352 -377.751156) (xy 208.596403 -377.666842) (xy 208.612432 -377.583676) (xy 208.636293 -377.502409)
			(xy 208.667772 -377.423779) (xy 208.706583 -377.348498) (xy 208.752373 -377.277246) (xy 208.804729 -377.21067)
			(xy 208.863177 -377.149372) (xy 208.927187 -377.093907) (xy 208.996179 -377.044778) (xy 209.069529 -377.002429)
			(xy 209.146572 -376.967245) (xy 209.226611 -376.939543) (xy 209.30892 -376.919575) (xy 209.392755 -376.907522)
			(xy 209.477356 -376.903492) (xy 209.561957 -376.907522) (xy 209.645792 -376.919575) (xy 209.728101 -376.939543)
			(xy 209.80814 -376.967245) (xy 209.885183 -377.002429) (xy 209.958533 -377.044778) (xy 210.027525 -377.093907)
			(xy 210.091535 -377.149372) (xy 210.149983 -377.21067) (xy 210.202339 -377.277246) (xy 210.248129 -377.348498)
			(xy 210.28694 -377.423779) (xy 210.318419 -377.502409) (xy 210.34228 -377.583676) (xy 210.358309 -377.666842)
			(xy 210.36636 -377.751156) (xy 210.366864 -377.793504) (xy 210.366279 -377.8399) (xy 210.356645 -377.93219)
			(xy 210.33745 -378.022975) (xy 210.308905 -378.111266) (xy 210.290664 -378.15393) (xy 210.286846 -378.16387)
			(xy 210.286847 -378.185137) (xy 210.290664 -378.195078) (xy 210.308902 -378.237743) (xy 210.337442 -378.326036)
			(xy 210.356638 -378.41682) (xy 210.366283 -378.509108) (xy 210.366864 -378.555504) (xy 210.366401 -378.596759)
			(xy 210.358766 -378.678915) (xy 210.343554 -378.760011) (xy 210.320895 -378.839348) (xy 210.290985 -378.916246)
			(xy 210.254079 -378.990042) (xy 210.210497 -379.060103) (xy 210.160611 -379.125824) (xy 210.104852 -379.186643)
			(xy 210.0437 -379.242034) (xy 209.977678 -379.291523) (xy 209.907357 -379.334682) (xy 209.870548 -379.353318)
			(xy 209.862245 -379.357881) (xy 209.849513 -379.371894) (xy 209.842729 -379.38957) (xy 209.842354 -379.399038)
			(xy 209.842354 -379.48997) (xy 209.842696 -379.49944) (xy 209.849494 -379.517116) (xy 209.862248 -379.531115)
			(xy 209.870548 -379.53569) (xy 209.909134 -379.555283) (xy 209.982682 -379.600898) (xy 210.051457 -379.653434)
			(xy 210.114809 -379.712396) (xy 210.143852 -379.744478) (xy 210.151218 -379.752606) (xy 210.17103 -379.761496)
			(xy 210.185254 -379.761496) (xy 210.222685 -379.761953) (xy 210.297186 -379.769318) (xy 210.370605 -379.78395)
			(xy 210.442236 -379.805711) (xy 210.511388 -379.834389) (xy 210.577396 -379.869709) (xy 210.639623 -379.91133)
			(xy 210.69747 -379.958852) (xy 210.724242 -379.985016) (xy 211.201254 -380.462028) (xy 211.227393 -380.488816)
			(xy 211.274879 -380.546674) (xy 211.316466 -380.608907) (xy 211.351753 -380.674917) (xy 211.380401 -380.744067)
			(xy 211.402134 -380.815692) (xy 211.416743 -380.889103) (xy 211.424087 -380.963591) (xy 211.42452 -381.001016)
			(xy 211.42452 -381.3058) (xy 242.544088 -381.3058) (xy 242.548118 -381.221198) (xy 242.560172 -381.137363)
			(xy 242.58014 -381.055053) (xy 242.607842 -380.975014) (xy 242.643027 -380.897971) (xy 242.685376 -380.824621)
			(xy 242.734505 -380.755628) (xy 242.789971 -380.691619) (xy 242.851269 -380.633171) (xy 242.917846 -380.580815)
			(xy 242.989099 -380.535024) (xy 243.064381 -380.496214) (xy 243.143012 -380.464736) (xy 243.224278 -380.440874)
			(xy 243.307445 -380.424846) (xy 243.391759 -380.416796) (xy 243.434108 -380.416308) (xy 243.474162 -380.41672)
			(xy 243.553944 -380.423932) (xy 243.632755 -380.438288) (xy 243.709956 -380.459672) (xy 243.784921 -380.48791)
			(xy 243.857045 -380.522773) (xy 243.925741 -380.56398) (xy 243.990455 -380.611197) (xy 244.020848 -380.637288)
			(xy 244.027964 -380.642979) (xy 244.045018 -380.649358) (xy 244.054122 -380.649734) (xy 244.084094 -380.649734)
			(xy 244.093196 -380.64935) (xy 244.110247 -380.64297) (xy 244.117368 -380.637288) (xy 244.147764 -380.611201)
			(xy 244.212475 -380.563983) (xy 244.281171 -380.522776) (xy 244.353294 -380.487914) (xy 244.42826 -380.459679)
			(xy 244.505461 -380.4383) (xy 244.584272 -380.423951) (xy 244.664055 -380.416748) (xy 244.704108 -380.416308)
			(xy 244.746457 -380.41678) (xy 244.830771 -380.424832) (xy 244.913939 -380.440862) (xy 244.995206 -380.464724)
			(xy 245.073836 -380.496204) (xy 245.149119 -380.535015) (xy 245.220371 -380.580807) (xy 245.286948 -380.633164)
			(xy 245.348247 -380.691613) (xy 245.403712 -380.755624) (xy 245.452841 -380.824617) (xy 245.49519 -380.897967)
			(xy 245.530375 -380.975012) (xy 245.558077 -381.055051) (xy 245.578045 -381.137362) (xy 245.590098 -381.221198)
			(xy 245.594129 -381.3058) (xy 248.479103 -381.3058) (xy 248.483133 -381.221202) (xy 248.495186 -381.13737)
			(xy 248.515153 -381.055064) (xy 248.542853 -380.975028) (xy 248.578036 -380.897988) (xy 248.620382 -380.82464)
			(xy 248.669508 -380.75565) (xy 248.72497 -380.691642) (xy 248.786265 -380.633196) (xy 248.852838 -380.58084)
			(xy 248.924086 -380.53505) (xy 248.999364 -380.496239) (xy 249.07799 -380.46476) (xy 249.159252 -380.440897)
			(xy 249.242415 -380.424866) (xy 249.326725 -380.416813) (xy 249.369072 -380.416308) (xy 249.409125 -380.416742)
			(xy 249.488907 -380.423951) (xy 249.567717 -380.438304) (xy 249.644918 -380.459684) (xy 249.719884 -380.487919)
			(xy 249.792007 -380.52278) (xy 249.860704 -380.563984) (xy 249.925418 -380.611198) (xy 249.955812 -380.637288)
			(xy 249.962939 -380.642963) (xy 249.979984 -380.649352) (xy 249.989086 -380.649734) (xy 250.019058 -380.649734)
			(xy 250.028158 -380.649333) (xy 250.045209 -380.642965) (xy 250.052332 -380.637288) (xy 250.082702 -380.61117)
			(xy 250.147418 -380.563954) (xy 250.216118 -380.522751) (xy 250.288245 -380.487892) (xy 250.363214 -380.459661)
			(xy 250.440419 -380.438287) (xy 250.519233 -380.423943) (xy 250.599018 -380.416745) (xy 250.639072 -380.416308)
			(xy 250.681423 -380.416763) (xy 250.765741 -380.424812) (xy 250.848913 -380.440839) (xy 250.930184 -380.4647)
			(xy 251.008819 -380.496179) (xy 251.084106 -380.53499) (xy 251.155362 -380.580782) (xy 251.221943 -380.63314)
			(xy 251.283246 -380.691589) (xy 251.338714 -380.755602) (xy 251.387847 -380.824597) (xy 251.430199 -380.897951)
			(xy 251.465386 -380.974998) (xy 251.49309 -381.055041) (xy 251.513059 -381.137355) (xy 251.525114 -381.221194)
			(xy 251.529144 -381.3058) (xy 254.413988 -381.3058) (xy 254.418018 -381.221197) (xy 254.430073 -381.13736)
			(xy 254.450042 -381.055048) (xy 254.477745 -380.975008) (xy 254.512931 -380.897963) (xy 254.555281 -380.824612)
			(xy 254.604413 -380.755619) (xy 254.65988 -380.691609) (xy 254.721181 -380.633161) (xy 254.78776 -380.580805)
			(xy 254.859015 -380.535015) (xy 254.934299 -380.496206) (xy 255.012932 -380.464729) (xy 255.094201 -380.440869)
			(xy 255.17737 -380.424842) (xy 255.261686 -380.416794) (xy 255.304036 -380.416308) (xy 255.344089 -380.416764)
			(xy 255.42387 -380.42397) (xy 255.502679 -380.43832) (xy 255.57988 -380.459697) (xy 255.654846 -380.487929)
			(xy 255.726969 -380.522787) (xy 255.795667 -380.563988) (xy 255.860382 -380.6112) (xy 255.890776 -380.637288)
			(xy 255.897884 -380.64299) (xy 255.914944 -380.649363) (xy 255.92405 -380.649734) (xy 255.954022 -380.649734)
			(xy 255.963125 -380.649364) (xy 255.980176 -380.642974) (xy 255.987296 -380.637288) (xy 256.017681 -380.611187)
			(xy 256.082394 -380.56397) (xy 256.151091 -380.522765) (xy 256.223216 -380.487904) (xy 256.298184 -380.459671)
			(xy 256.375386 -380.438295) (xy 256.454199 -380.423948) (xy 256.533982 -380.416747) (xy 256.574036 -380.416308)
			(xy 256.616384 -380.416781) (xy 256.700697 -380.424835) (xy 256.783862 -380.440867) (xy 256.865127 -380.464732)
			(xy 256.943755 -380.496212) (xy 257.019035 -380.535025) (xy 257.090285 -380.580817) (xy 257.15686 -380.633174)
			(xy 257.218156 -380.691623) (xy 257.273619 -380.755633) (xy 257.322747 -380.824625) (xy 257.365094 -380.897975)
			(xy 257.400277 -380.975018) (xy 257.427978 -381.055056) (xy 257.447945 -381.137365) (xy 257.459999 -381.2212)
			(xy 257.464029 -381.3058) (xy 260.349004 -381.3058) (xy 260.353033 -381.2212) (xy 260.365087 -381.137367)
			(xy 260.385055 -381.055059) (xy 260.412756 -380.975022) (xy 260.44794 -380.89798) (xy 260.490287 -380.824632)
			(xy 260.539415 -380.755641) (xy 260.594879 -380.691632) (xy 260.656176 -380.633186) (xy 260.722751 -380.58083)
			(xy 260.794002 -380.53504) (xy 260.869282 -380.496231) (xy 260.947911 -380.464753) (xy 261.029175 -380.440891)
			(xy 261.11234 -380.424862) (xy 261.196652 -380.416812) (xy 261.239 -380.416308) (xy 261.279054 -380.416725)
			(xy 261.358836 -380.423936) (xy 261.437646 -380.438292) (xy 261.514847 -380.459674) (xy 261.589813 -380.487912)
			(xy 261.661936 -380.522775) (xy 261.730633 -380.563981) (xy 261.795346 -380.611197) (xy 261.82574 -380.637288)
			(xy 261.832859 -380.642975) (xy 261.84991 -380.649357) (xy 261.859014 -380.649734) (xy 261.888986 -380.649734)
			(xy 261.898088 -380.649346) (xy 261.915138 -380.642969) (xy 261.92226 -380.637288) (xy 261.952659 -380.611204)
			(xy 262.01737 -380.563986) (xy 262.086065 -380.522779) (xy 262.158188 -380.487916) (xy 262.233153 -380.459681)
			(xy 262.310354 -380.438302) (xy 262.389165 -380.423952) (xy 262.468947 -380.416748) (xy 262.509 -380.416308)
			(xy 262.551349 -380.41678) (xy 262.635664 -380.424831) (xy 262.718832 -380.44086) (xy 262.8001 -380.464722)
			(xy 262.878731 -380.496202) (xy 262.954014 -380.535013) (xy 263.025267 -380.580804) (xy 263.091845 -380.633161)
			(xy 263.153144 -380.69161) (xy 263.20861 -380.755621) (xy 263.25774 -380.824614) (xy 263.300089 -380.897965)
			(xy 263.335274 -380.97501) (xy 263.362976 -381.05505) (xy 263.382945 -381.137361) (xy 263.394998 -381.221197)
			(xy 263.399029 -381.3058) (xy 266.284003 -381.3058) (xy 266.288033 -381.221203) (xy 266.300086 -381.137371)
			(xy 266.320053 -381.055065) (xy 266.347753 -380.97503) (xy 266.382935 -380.89799) (xy 266.42528 -380.824643)
			(xy 266.474406 -380.755653) (xy 266.529867 -380.691645) (xy 266.591161 -380.633198) (xy 266.657734 -380.580843)
			(xy 266.728981 -380.535052) (xy 266.804258 -380.496242) (xy 266.882884 -380.464762) (xy 266.964146 -380.440898)
			(xy 267.047308 -380.424867) (xy 267.131617 -380.416813) (xy 267.173964 -380.416308) (xy 267.214017 -380.416747)
			(xy 267.293799 -380.423955) (xy 267.372609 -380.438307) (xy 267.449809 -380.459687) (xy 267.524775 -380.487921)
			(xy 267.596899 -380.522782) (xy 267.665596 -380.563985) (xy 267.73031 -380.611199) (xy 267.760704 -380.637288)
			(xy 267.767804 -380.643002) (xy 267.78487 -380.649368) (xy 267.793978 -380.649734) (xy 267.82395 -380.649734)
			(xy 267.83305 -380.649329) (xy 267.850101 -380.642964) (xy 267.857224 -380.637288) (xy 267.887598 -380.611174)
			(xy 267.952313 -380.563958) (xy 268.021012 -380.522754) (xy 268.093138 -380.487895) (xy 268.168107 -380.459664)
			(xy 268.245312 -380.438289) (xy 268.324125 -380.423944) (xy 268.40391 -380.416746) (xy 268.443964 -380.416308)
			(xy 268.486315 -380.416762) (xy 268.570634 -380.424811) (xy 268.653806 -380.440838) (xy 268.735078 -380.464698)
			(xy 268.813714 -380.496177) (xy 268.889001 -380.534987) (xy 268.960258 -380.580779) (xy 269.02684 -380.633137)
			(xy 269.088143 -380.691587) (xy 269.143612 -380.755599) (xy 269.192746 -380.824595) (xy 269.235098 -380.897949)
			(xy 269.270285 -380.974996) (xy 269.297989 -381.055039) (xy 269.317959 -381.137354) (xy 269.330014 -381.221194)
			(xy 269.334044 -381.3058) (xy 272.218888 -381.3058) (xy 272.222918 -381.221197) (xy 272.234972 -381.137361)
			(xy 272.254941 -381.05505) (xy 272.282644 -380.97501) (xy 272.31783 -380.897965) (xy 272.36018 -380.824615)
			(xy 272.409311 -380.755622) (xy 272.464777 -380.691612) (xy 272.526078 -380.633164) (xy 272.592656 -380.580808)
			(xy 272.66391 -380.535018) (xy 272.739194 -380.496208) (xy 272.817826 -380.464731) (xy 272.899095 -380.44087)
			(xy 272.982263 -380.424843) (xy 273.066579 -380.416795) (xy 273.108928 -380.416308) (xy 273.148981 -380.416769)
			(xy 273.228761 -380.423974) (xy 273.307571 -380.438323) (xy 273.384772 -380.4597) (xy 273.459737 -380.487931)
			(xy 273.531861 -380.522788) (xy 273.600559 -380.563989) (xy 273.665274 -380.6112) (xy 273.695668 -380.637288)
			(xy 273.702779 -380.642987) (xy 273.719837 -380.649362) (xy 273.728942 -380.649734) (xy 273.758914 -380.649734)
			(xy 273.768017 -380.64936) (xy 273.785068 -380.642973) (xy 273.792188 -380.637288) (xy 273.822576 -380.611191)
			(xy 273.887289 -380.563974) (xy 273.955986 -380.522768) (xy 274.02811 -380.487907) (xy 274.103077 -380.459673)
			(xy 274.180279 -380.438296) (xy 274.259091 -380.423949) (xy 274.338874 -380.416747) (xy 274.378928 -380.416308)
			(xy 274.421276 -380.416781) (xy 274.505589 -380.424834) (xy 274.588755 -380.440866) (xy 274.670021 -380.46473)
			(xy 274.74865 -380.49621) (xy 274.82393 -380.535022) (xy 274.895181 -380.580814) (xy 274.961756 -380.633171)
			(xy 275.023053 -380.69162) (xy 275.078517 -380.75563) (xy 275.127645 -380.824623) (xy 275.169993 -380.897973)
			(xy 275.205176 -380.975016) (xy 275.232878 -381.055055) (xy 275.252845 -381.137364) (xy 275.264899 -381.221199)
			(xy 275.268929 -381.3058) (xy 275.264899 -381.390401) (xy 275.252845 -381.474236) (xy 275.232878 -381.556545)
			(xy 275.205176 -381.636584) (xy 275.169993 -381.713627) (xy 275.127645 -381.786977) (xy 275.078517 -381.85597)
			(xy 275.023053 -381.91998) (xy 274.961756 -381.978429) (xy 274.895181 -382.030786) (xy 274.82393 -382.076578)
			(xy 274.74865 -382.11539) (xy 274.670021 -382.14687) (xy 274.588755 -382.170734) (xy 274.505589 -382.186766)
			(xy 274.421276 -382.194819) (xy 274.378928 -382.195324) (xy 274.338875 -382.194882) (xy 274.259094 -382.187673)
			(xy 274.180284 -382.173321) (xy 274.103083 -382.151941) (xy 274.028118 -382.123707) (xy 273.955994 -382.088848)
			(xy 273.887297 -382.047645) (xy 273.822582 -382.000433) (xy 273.792188 -381.974344) (xy 273.785058 -381.968672)
			(xy 273.768015 -381.96228) (xy 273.758914 -381.961898) (xy 273.728942 -381.961898) (xy 273.719844 -381.962314)
			(xy 273.702793 -381.968673) (xy 273.695668 -381.974344) (xy 273.665302 -382.000468) (xy 273.600585 -382.047682)
			(xy 273.531885 -382.088884) (xy 273.459757 -382.123742) (xy 273.384787 -382.151972) (xy 273.307582 -382.173345)
			(xy 273.228767 -382.187689) (xy 273.148983 -382.194887) (xy 273.108928 -382.195324) (xy 273.066579 -382.194805)
			(xy 272.982263 -382.186757) (xy 272.899095 -382.17073) (xy 272.817826 -382.146869) (xy 272.739194 -382.115392)
			(xy 272.66391 -382.076582) (xy 272.592656 -382.030792) (xy 272.526078 -381.978436) (xy 272.464777 -381.919988)
			(xy 272.409311 -381.855978) (xy 272.36018 -381.786985) (xy 272.31783 -381.713635) (xy 272.282644 -381.63659)
			(xy 272.254941 -381.55655) (xy 272.234972 -381.474239) (xy 272.222918 -381.390403) (xy 272.218888 -381.3058)
			(xy 269.334044 -381.3058) (xy 269.330014 -381.390406) (xy 269.317959 -381.474246) (xy 269.297989 -381.556561)
			(xy 269.270285 -381.636604) (xy 269.235098 -381.713651) (xy 269.192746 -381.787005) (xy 269.143612 -381.856001)
			(xy 269.088143 -381.920013) (xy 269.02684 -381.978463) (xy 268.960258 -382.030821) (xy 268.889001 -382.076613)
			(xy 268.813714 -382.115423) (xy 268.735078 -382.146902) (xy 268.653806 -382.170762) (xy 268.570634 -382.186789)
			(xy 268.486315 -382.194838) (xy 268.443964 -382.195324) (xy 268.403911 -382.19486) (xy 268.324131 -382.187654)
			(xy 268.245322 -382.173305) (xy 268.168121 -382.151929) (xy 268.093156 -382.123698) (xy 268.021032 -382.088841)
			(xy 267.952334 -382.047641) (xy 267.887619 -382.000432) (xy 267.857224 -381.974344) (xy 267.850113 -381.968645)
			(xy 267.833056 -381.962269) (xy 267.82395 -381.961898) (xy 267.793978 -381.961898) (xy 267.784876 -381.962283)
			(xy 267.767826 -381.968664) (xy 267.760704 -381.974344) (xy 267.730324 -382.00045) (xy 267.665609 -382.047666)
			(xy 267.596911 -382.08887) (xy 267.524786 -382.12373) (xy 267.449817 -382.151962) (xy 267.372614 -382.173338)
			(xy 267.293802 -382.187684) (xy 267.214018 -382.194885) (xy 267.173964 -382.195324) (xy 267.131617 -382.194787)
			(xy 267.047308 -382.186733) (xy 266.964146 -382.170702) (xy 266.882884 -382.146838) (xy 266.804258 -382.115358)
			(xy 266.728981 -382.076548) (xy 266.657734 -382.030757) (xy 266.591161 -381.978402) (xy 266.529867 -381.919955)
			(xy 266.474406 -381.855947) (xy 266.42528 -381.786957) (xy 266.382935 -381.71361) (xy 266.347753 -381.63657)
			(xy 266.320053 -381.556535) (xy 266.300086 -381.474229) (xy 266.288033 -381.390397) (xy 266.284003 -381.3058)
			(xy 263.399029 -381.3058) (xy 263.394998 -381.390403) (xy 263.382945 -381.474239) (xy 263.362976 -381.55655)
			(xy 263.335274 -381.63659) (xy 263.300089 -381.713635) (xy 263.25774 -381.786986) (xy 263.20861 -381.855979)
			(xy 263.153144 -381.91999) (xy 263.091845 -381.978439) (xy 263.025267 -382.030796) (xy 262.954014 -382.076587)
			(xy 262.878731 -382.115398) (xy 262.8001 -382.146878) (xy 262.718832 -382.17074) (xy 262.635664 -382.186769)
			(xy 262.551349 -382.19482) (xy 262.509 -382.195324) (xy 262.468947 -382.194899) (xy 262.389165 -382.187688)
			(xy 262.310355 -382.173333) (xy 262.233154 -382.151951) (xy 262.158188 -382.123715) (xy 262.086065 -382.088853)
			(xy 262.017368 -382.047648) (xy 261.952654 -382.000434) (xy 261.92226 -381.974344) (xy 261.915138 -381.96866)
			(xy 261.898089 -381.962275) (xy 261.888986 -381.961898) (xy 261.859014 -381.961898) (xy 261.849914 -381.962301)
			(xy 261.832864 -381.968669) (xy 261.82574 -381.974344) (xy 261.795345 -382.000433) (xy 261.730633 -382.04765)
			(xy 261.661937 -382.088856) (xy 261.589814 -382.123718) (xy 261.514848 -382.151952) (xy 261.437647 -382.173331)
			(xy 261.358836 -382.18768) (xy 261.279053 -382.194884) (xy 261.239 -382.195324) (xy 261.196652 -382.194788)
			(xy 261.11234 -382.186738) (xy 261.029175 -382.170709) (xy 260.947911 -382.146847) (xy 260.869282 -382.115369)
			(xy 260.794002 -382.07656) (xy 260.722751 -382.03077) (xy 260.656176 -381.978414) (xy 260.594879 -381.919968)
			(xy 260.539415 -381.855959) (xy 260.490287 -381.786968) (xy 260.44794 -381.71362) (xy 260.412756 -381.636578)
			(xy 260.385055 -381.556541) (xy 260.365087 -381.474233) (xy 260.353033 -381.3904) (xy 260.349004 -381.3058)
			(xy 257.464029 -381.3058) (xy 257.459999 -381.3904) (xy 257.447945 -381.474235) (xy 257.427978 -381.556544)
			(xy 257.400277 -381.636582) (xy 257.365094 -381.713625) (xy 257.322747 -381.786975) (xy 257.273619 -381.855967)
			(xy 257.218156 -381.919977) (xy 257.15686 -381.978426) (xy 257.090285 -382.030783) (xy 257.019035 -382.076575)
			(xy 256.943755 -382.115388) (xy 256.865127 -382.146868) (xy 256.783862 -382.170733) (xy 256.700697 -382.186765)
			(xy 256.616384 -382.194819) (xy 256.574036 -382.195324) (xy 256.533983 -382.194877) (xy 256.454202 -382.187669)
			(xy 256.375392 -382.173318) (xy 256.298192 -382.151939) (xy 256.223226 -382.123705) (xy 256.151103 -382.088846)
			(xy 256.082405 -382.047644) (xy 256.01769 -382.000433) (xy 255.987296 -381.974344) (xy 255.980193 -381.968633)
			(xy 255.963129 -381.962264) (xy 255.954022 -381.961898) (xy 255.92405 -381.961898) (xy 255.914952 -381.962318)
			(xy 255.897902 -381.968675) (xy 255.890776 -381.974344) (xy 255.860407 -382.000464) (xy 255.795691 -382.047678)
			(xy 255.726991 -382.088881) (xy 255.654863 -382.123739) (xy 255.579894 -382.15197) (xy 255.502689 -382.173344)
			(xy 255.423875 -382.187688) (xy 255.34409 -382.194886) (xy 255.304036 -382.195324) (xy 255.261686 -382.194806)
			(xy 255.17737 -382.186758) (xy 255.094201 -382.170731) (xy 255.012932 -382.146871) (xy 254.934299 -382.115394)
			(xy 254.859015 -382.076585) (xy 254.78776 -382.030795) (xy 254.721181 -381.978439) (xy 254.65988 -381.919991)
			(xy 254.604413 -381.855981) (xy 254.555281 -381.786988) (xy 254.512931 -381.713637) (xy 254.477745 -381.636592)
			(xy 254.450042 -381.556552) (xy 254.430073 -381.47424) (xy 254.418018 -381.390403) (xy 254.413988 -381.3058)
			(xy 251.529144 -381.3058) (xy 251.525114 -381.390406) (xy 251.513059 -381.474245) (xy 251.49309 -381.556559)
			(xy 251.465386 -381.636602) (xy 251.430199 -381.713649) (xy 251.387847 -381.787003) (xy 251.338714 -381.855998)
			(xy 251.283246 -381.920011) (xy 251.221943 -381.97846) (xy 251.155362 -382.030818) (xy 251.084106 -382.07661)
			(xy 251.008819 -382.115421) (xy 250.930184 -382.1469) (xy 250.848913 -382.170761) (xy 250.765741 -382.186788)
			(xy 250.681423 -382.194837) (xy 250.639072 -382.195324) (xy 250.59902 -382.194855) (xy 250.519239 -382.18765)
			(xy 250.44043 -382.173302) (xy 250.36323 -382.151926) (xy 250.288264 -382.123696) (xy 250.21614 -382.08884)
			(xy 250.147442 -382.04764) (xy 250.082727 -382.000431) (xy 250.052332 -381.974344) (xy 250.045219 -381.968649)
			(xy 250.028163 -381.962271) (xy 250.019058 -381.961898) (xy 249.989086 -381.961898) (xy 249.979985 -381.962287)
			(xy 249.962935 -381.968665) (xy 249.955812 -381.974344) (xy 249.925429 -382.000446) (xy 249.860715 -382.047662)
			(xy 249.792017 -382.088867) (xy 249.719892 -382.123727) (xy 249.644924 -382.15196) (xy 249.567721 -382.173336)
			(xy 249.488909 -382.187683) (xy 249.409126 -382.194885) (xy 249.369072 -382.195324) (xy 249.326725 -382.194787)
			(xy 249.242415 -382.186734) (xy 249.159252 -382.170703) (xy 249.07799 -382.14684) (xy 248.999364 -382.115361)
			(xy 248.924086 -382.07655) (xy 248.852838 -382.03076) (xy 248.786265 -381.978404) (xy 248.72497 -381.919958)
			(xy 248.669508 -381.85595) (xy 248.620382 -381.78696) (xy 248.578036 -381.713612) (xy 248.542853 -381.636572)
			(xy 248.515153 -381.556536) (xy 248.495186 -381.47423) (xy 248.483133 -381.390398) (xy 248.479103 -381.3058)
			(xy 245.594129 -381.3058) (xy 245.590098 -381.390402) (xy 245.578045 -381.474238) (xy 245.558077 -381.556549)
			(xy 245.530375 -381.636588) (xy 245.49519 -381.713633) (xy 245.452841 -381.786983) (xy 245.403712 -381.855976)
			(xy 245.348247 -381.919987) (xy 245.286948 -381.978436) (xy 245.220371 -382.030793) (xy 245.149119 -382.076585)
			(xy 245.073836 -382.115396) (xy 244.995206 -382.146876) (xy 244.913939 -382.170738) (xy 244.830771 -382.186768)
			(xy 244.746457 -382.19482) (xy 244.704108 -382.195324) (xy 244.664055 -382.194894) (xy 244.584273 -382.187684)
			(xy 244.505463 -382.17333) (xy 244.428262 -382.151948) (xy 244.353297 -382.123713) (xy 244.281173 -382.088852)
			(xy 244.212476 -382.047647) (xy 244.147762 -382.000434) (xy 244.117368 -381.974344) (xy 244.110244 -381.968664)
			(xy 244.093196 -381.962277) (xy 244.084094 -381.961898) (xy 244.054122 -381.961898) (xy 244.045023 -381.962304)
			(xy 244.027972 -381.968671) (xy 244.020848 -381.974344) (xy 243.99045 -382.000429) (xy 243.925739 -382.047646)
			(xy 243.857043 -382.088853) (xy 243.78492 -382.123715) (xy 243.709955 -382.15195) (xy 243.632754 -382.173329)
			(xy 243.553943 -382.187679) (xy 243.474161 -382.194883) (xy 243.434108 -382.195324) (xy 243.391759 -382.194804)
			(xy 243.307445 -382.186754) (xy 243.224278 -382.170726) (xy 243.143012 -382.146864) (xy 243.064381 -382.115386)
			(xy 242.989099 -382.076576) (xy 242.917846 -382.030785) (xy 242.851269 -381.978429) (xy 242.789971 -381.919981)
			(xy 242.734505 -381.855972) (xy 242.685376 -381.786979) (xy 242.643027 -381.713629) (xy 242.607842 -381.636586)
			(xy 242.58014 -381.556547) (xy 242.560172 -381.474237) (xy 242.548118 -381.390402) (xy 242.544088 -381.3058)
			(xy 211.42452 -381.3058) (xy 211.42452 -381.676402) (xy 211.424076 -381.713827) (xy 211.416739 -381.788317)
			(xy 211.402135 -381.861729) (xy 211.380406 -381.933356) (xy 211.351761 -382.002508) (xy 211.316476 -382.068519)
			(xy 211.274889 -382.130754) (xy 211.227403 -382.188612) (xy 211.201254 -382.21539) (xy 210.724242 -382.692402)
			(xy 210.695412 -382.720518) (xy 210.632805 -382.771173) (xy 210.565211 -382.814951) (xy 210.49338 -382.851364)
			(xy 210.418113 -382.880008) (xy 210.37931 -382.890776) (xy 210.370566 -382.893489) (xy 210.355669 -382.904107)
			(xy 210.345484 -382.919304) (xy 210.342988 -382.928114) (xy 210.333089 -382.967977) (xy 210.306882 -383.045826)
			(xy 210.290664 -383.083562) (xy 210.286853 -383.093502) (xy 210.286866 -383.114763) (xy 210.290664 -383.12471)
			(xy 210.308901 -383.167375) (xy 210.337437 -383.255669) (xy 210.35663 -383.346452) (xy 210.366272 -383.438741)
			(xy 210.366864 -383.485136) (xy 210.366399 -383.52639) (xy 210.358762 -383.608545) (xy 210.343548 -383.689638)
			(xy 210.320887 -383.768974) (xy 210.290975 -383.845869) (xy 210.254068 -383.919663) (xy 210.210484 -383.989721)
			(xy 210.160598 -384.05544) (xy 210.104839 -384.116256) (xy 210.043686 -384.171645) (xy 209.977665 -384.221132)
			(xy 209.907344 -384.26429) (xy 209.870548 -384.28295) (xy 209.862237 -384.28751) (xy 209.849486 -384.301519)
			(xy 209.842679 -384.319197) (xy 209.842354 -384.32867) (xy 209.842354 -384.419602) (xy 209.842685 -384.429079)
			(xy 209.849468 -384.446774) (xy 209.862218 -384.460793) (xy 209.870548 -384.465322) (xy 209.907343 -384.48398)
			(xy 209.97765 -384.527153) (xy 210.043658 -384.57665) (xy 210.104799 -384.632046) (xy 210.16055 -384.692865)
			(xy 210.210429 -384.758584) (xy 210.25401 -384.82864) (xy 210.290917 -384.902429) (xy 210.320833 -384.979319)
			(xy 210.343503 -385.058648) (xy 210.35873 -385.139735) (xy 210.366384 -385.221884) (xy 210.366864 -385.263136)
			(xy 210.366277 -385.309532) (xy 210.35664 -385.401821) (xy 210.337443 -385.492604) (xy 210.308894 -385.580894)
			(xy 210.290664 -385.623562) (xy 210.286853 -385.633502) (xy 210.286866 -385.654763) (xy 210.290664 -385.66471)
			(xy 210.308901 -385.707375) (xy 210.337437 -385.795669) (xy 210.35663 -385.886452) (xy 210.366272 -385.978741)
			(xy 210.366864 -386.025136) (xy 210.366399 -386.06639) (xy 210.358762 -386.148545) (xy 210.343548 -386.229638)
			(xy 210.320887 -386.308974) (xy 210.290975 -386.385869) (xy 210.254068 -386.459663) (xy 210.247232 -386.470652)
			(xy 212.630512 -386.470652) (xy 212.631082 -386.4416) (xy 212.639874 -386.384165) (xy 212.657276 -386.328728)
			(xy 212.682887 -386.276573) (xy 212.716113 -386.228907) (xy 212.756186 -386.186832) (xy 212.778848 -386.168646)
			(xy 212.788246 -386.16128) (xy 212.79866 -386.14096) (xy 212.79993 -386.037582) (xy 212.790278 -386.017008)
			(xy 212.781134 -386.009388) (xy 212.75957 -385.991198) (xy 212.721564 -385.949506) (xy 212.690115 -385.902669)
			(xy 212.66591 -385.85171) (xy 212.649478 -385.797741) (xy 212.641176 -385.74194) (xy 212.640672 -385.713732)
			(xy 212.641185 -385.686481) (xy 212.648937 -385.632533) (xy 212.664288 -385.580237) (xy 212.686925 -385.530658)
			(xy 212.716388 -385.484806) (xy 212.752077 -385.443614) (xy 212.793264 -385.407919) (xy 212.839113 -385.37845)
			(xy 212.888688 -385.355806) (xy 212.940982 -385.340448) (xy 212.994929 -385.332689) (xy 213.02218 -385.332224)
			(xy 213.052195 -385.332809) (xy 213.111482 -385.342219) (xy 213.168566 -385.360794) (xy 213.222038 -385.388076)
			(xy 213.270579 -385.423393) (xy 213.292182 -385.444238) (xy 213.299294 -385.45135) (xy 213.317074 -385.45897)
			(xy 213.407752 -385.460494) (xy 213.425786 -385.453636) (xy 213.433152 -385.446778) (xy 213.454444 -385.427736)
			(xy 213.501644 -385.395567) (xy 213.553112 -385.370791) (xy 213.607696 -385.353961) (xy 213.66418 -385.345455)
			(xy 213.69274 -385.344924) (xy 213.719815 -385.345382) (xy 213.77342 -385.353036) (xy 213.825402 -385.368199)
			(xy 213.874716 -385.390566) (xy 213.920368 -385.419687) (xy 213.96144 -385.454975) (xy 213.997104 -385.49572)
			(xy 214.012272 -385.518152) (xy 214.01913 -385.528312) (xy 214.039704 -385.54025) (xy 214.145876 -385.5466)
			(xy 214.16772 -385.536948) (xy 214.175594 -385.52755) (xy 214.193806 -385.50636) (xy 214.23537 -385.469019)
			(xy 214.281936 -385.438141) (xy 214.332508 -385.414386) (xy 214.386005 -385.398262) (xy 214.441281 -385.390115)
			(xy 214.469218 -385.389628) (xy 214.499234 -385.390188) (xy 214.558522 -385.399603) (xy 214.615606 -385.418184)
			(xy 214.669078 -385.445472) (xy 214.717618 -385.480794) (xy 214.73922 -385.501642) (xy 214.746332 -385.508754)
			(xy 214.764112 -385.516374) (xy 214.85479 -385.517898) (xy 214.872824 -385.51104) (xy 214.88019 -385.504182)
			(xy 214.901508 -385.48517) (xy 214.948701 -385.452996) (xy 215.000162 -385.428214) (xy 215.054741 -385.411378)
			(xy 215.11122 -385.402863) (xy 215.139778 -385.402328) (xy 215.168755 -385.402882) (xy 215.226044 -385.411639)
			(xy 215.281351 -385.428954) (xy 215.333406 -385.45443) (xy 215.381011 -385.487481) (xy 215.423074 -385.527349)
			(xy 215.441276 -385.549902) (xy 215.448896 -385.559808) (xy 215.471756 -385.570222) (xy 215.580976 -385.563364)
			(xy 215.602312 -385.550156) (xy 215.608916 -385.539488) (xy 215.623759 -385.515449) (xy 215.65937 -385.471594)
			(xy 215.701063 -385.433474) (xy 215.747926 -385.401925) (xy 215.798932 -385.377637) (xy 215.852963 -385.361143)
			(xy 215.908837 -385.352803) (xy 215.937084 -385.35229) (xy 215.96688 -385.352819) (xy 216.025747 -385.362083)
			(xy 216.082457 -385.380389) (xy 216.135631 -385.407291) (xy 216.183975 -385.442135) (xy 216.226312 -385.484072)
			(xy 216.244424 -385.507738) (xy 216.25179 -385.517644) (xy 216.273126 -385.528566) (xy 216.379552 -385.528312)
			(xy 216.401142 -385.517644) (xy 216.408254 -385.507738) (xy 216.426378 -385.48399) (xy 216.468729 -385.441863)
			(xy 216.517131 -385.406854) (xy 216.570398 -385.37982) (xy 216.62723 -385.361421) (xy 216.686234 -385.352108)
			(xy 216.716102 -385.351528) (xy 216.746117 -385.352098) (xy 216.805406 -385.361511) (xy 216.862489 -385.38009)
			(xy 216.915961 -385.407375) (xy 216.964502 -385.442695) (xy 216.986104 -385.463542) (xy 216.993216 -385.470654)
			(xy 217.010996 -385.478274) (xy 217.101674 -385.479798) (xy 217.119708 -385.47294) (xy 217.127074 -385.466082)
			(xy 217.148399 -385.447078) (xy 217.19559 -385.414903) (xy 217.247049 -385.39012) (xy 217.301627 -385.373281)
			(xy 217.358104 -385.364764) (xy 217.386662 -385.364228) (xy 217.415602 -385.36477) (xy 217.472819 -385.373499)
			(xy 217.528064 -385.390763) (xy 217.580071 -385.416167) (xy 217.627648 -385.449128) (xy 217.649044 -385.468622)
			(xy 217.65641 -385.475734) (xy 217.675714 -385.4831) (xy 217.769186 -385.479036) (xy 217.787728 -385.470146)
			(xy 217.794586 -385.462526) (xy 217.812785 -385.442813) (xy 217.853733 -385.408151) (xy 217.899131 -385.379564)
			(xy 217.948085 -385.357615) (xy 217.999629 -385.342736) (xy 218.052749 -385.335221) (xy 218.079574 -385.334764)
			(xy 218.106823 -385.335302) (xy 218.160768 -385.343055) (xy 218.21306 -385.358405) (xy 218.262635 -385.381041)
			(xy 218.308484 -385.410502) (xy 218.349674 -385.446188) (xy 218.385366 -385.487373) (xy 218.414833 -385.533218)
			(xy 218.437476 -385.58279) (xy 218.452834 -385.63508) (xy 218.460594 -385.689023) (xy 218.461082 -385.716272)
			(xy 218.460594 -385.743332) (xy 218.452933 -385.796908) (xy 218.437775 -385.848862) (xy 218.415424 -385.898151)
			(xy 218.386329 -385.943786) (xy 218.351075 -385.984849) (xy 218.331034 -386.003038) (xy 218.322906 -386.010404)
			(xy 218.313762 -386.030216) (xy 218.313254 -386.128006) (xy 218.322144 -386.148072) (xy 218.330272 -386.155184)
			(xy 218.349929 -386.173354) (xy 218.384451 -386.214263) (xy 218.412919 -386.259594) (xy 218.434775 -386.308458)
			(xy 218.449589 -386.359896) (xy 218.457073 -386.4129) (xy 218.457526 -386.439664) (xy 218.457011 -386.466915)
			(xy 218.44926 -386.520863) (xy 218.433909 -386.573159) (xy 218.411272 -386.622738) (xy 218.38181 -386.66859)
			(xy 218.346121 -386.709783) (xy 218.304934 -386.745477) (xy 218.259085 -386.774946) (xy 218.20951 -386.79759)
			(xy 218.157216 -386.812948) (xy 218.103269 -386.820707) (xy 218.076018 -386.821172) (xy 218.049468 -386.820714)
			(xy 217.996882 -386.813336) (xy 217.945828 -386.798735) (xy 217.897294 -386.777192) (xy 217.852218 -386.749124)
			(xy 217.811471 -386.715075) (xy 217.793316 -386.695696) (xy 217.786204 -386.688076) (xy 217.767916 -386.67944)
			(xy 217.674698 -386.67563) (xy 217.655902 -386.682742) (xy 217.648282 -386.689854) (xy 217.626916 -386.70924)
			(xy 217.57946 -386.742042) (xy 217.527606 -386.767324) (xy 217.472536 -386.78451) (xy 217.415506 -386.793206)
			(xy 217.386662 -386.79374) (xy 217.356645 -386.793202) (xy 217.297355 -386.783782) (xy 217.240271 -386.765197)
			(xy 217.1868 -386.737904) (xy 217.138261 -386.702576) (xy 217.11666 -386.681726) (xy 217.109548 -386.674614)
			(xy 217.091768 -386.666994) (xy 217.00109 -386.66547) (xy 216.983056 -386.672328) (xy 216.97569 -386.679186)
			(xy 216.95439 -386.698218) (xy 216.907191 -386.730387) (xy 216.855725 -386.755164) (xy 216.801143 -386.771995)
			(xy 216.744661 -386.780507) (xy 216.716102 -386.78104) (xy 216.686306 -386.780509) (xy 216.62744 -386.771244)
			(xy 216.57073 -386.752937) (xy 216.517557 -386.726035) (xy 216.469213 -386.691193) (xy 216.426875 -386.649257)
			(xy 216.408762 -386.625592) (xy 216.401396 -386.615686) (xy 216.38006 -386.604764) (xy 216.273634 -386.605018)
			(xy 216.252044 -386.615686) (xy 216.244932 -386.625592) (xy 216.226824 -386.649353) (xy 216.184469 -386.691478)
			(xy 216.136064 -386.726484) (xy 216.082793 -386.753516) (xy 216.025959 -386.771912) (xy 215.966952 -386.781223)
			(xy 215.937084 -386.781802) (xy 215.908105 -386.781302) (xy 215.850812 -386.772538) (xy 215.795503 -386.755214)
			(xy 215.743448 -386.729728) (xy 215.695844 -386.696665) (xy 215.653785 -386.656787) (xy 215.635586 -386.634228)
			(xy 215.627966 -386.624322) (xy 215.605106 -386.613908) (xy 215.495886 -386.620766) (xy 215.47455 -386.633974)
			(xy 215.467946 -386.644642) (xy 215.45314 -386.668704) (xy 215.417522 -386.712559) (xy 215.375822 -386.750676)
			(xy 215.328953 -386.782222) (xy 215.277941 -386.806506) (xy 215.223905 -386.822995) (xy 215.168026 -386.83133)
			(xy 215.139778 -386.83184) (xy 215.109762 -386.831292) (xy 215.050472 -386.821875) (xy 214.993388 -386.803292)
			(xy 214.939916 -386.776001) (xy 214.891377 -386.740675) (xy 214.869776 -386.719826) (xy 214.862664 -386.712714)
			(xy 214.844884 -386.705094) (xy 214.754206 -386.70357) (xy 214.736172 -386.710428) (xy 214.728806 -386.717286)
			(xy 214.707499 -386.736311) (xy 214.660302 -386.76848) (xy 214.608838 -386.793259) (xy 214.554257 -386.810092)
			(xy 214.497777 -386.818605) (xy 214.469218 -386.81914) (xy 214.440741 -386.818606) (xy 214.384418 -386.810148)
			(xy 214.329981 -386.793403) (xy 214.278642 -386.768743) (xy 214.231544 -386.736718) (xy 214.189737 -386.698041)
			(xy 214.17153 -386.676138) (xy 214.163656 -386.666232) (xy 214.141304 -386.656326) (xy 214.033608 -386.662676)
			(xy 214.012526 -386.675122) (xy 214.005922 -386.68579) (xy 213.990893 -386.708914) (xy 213.955204 -386.750959)
			(xy 213.913833 -386.787427) (xy 213.867642 -386.817557) (xy 213.817593 -386.840721) (xy 213.76473 -386.856436)
			(xy 213.710155 -386.864375) (xy 213.68258 -386.86486) (xy 213.652564 -386.864305) (xy 213.593275 -386.854889)
			(xy 213.536191 -386.836307) (xy 213.48272 -386.809018) (xy 213.43418 -386.773694) (xy 213.412578 -386.752846)
			(xy 213.405466 -386.745734) (xy 213.387686 -386.738114) (xy 213.297008 -386.73659) (xy 213.278974 -386.743448)
			(xy 213.271608 -386.750306) (xy 213.250289 -386.769317) (xy 213.203096 -386.801491) (xy 213.151636 -386.826274)
			(xy 213.097057 -386.84311) (xy 213.040578 -386.851625) (xy 213.01202 -386.85216) (xy 212.984765 -386.851726)
			(xy 212.930811 -386.84397) (xy 212.87851 -386.828615) (xy 212.828926 -386.805971) (xy 212.783071 -386.7765)
			(xy 212.741877 -386.740803) (xy 212.706183 -386.699607) (xy 212.676716 -386.653749) (xy 212.654076 -386.604164)
			(xy 212.638724 -386.551862) (xy 212.630972 -386.497907) (xy 212.630512 -386.470652) (xy 210.247232 -386.470652)
			(xy 210.210484 -386.529721) (xy 210.160598 -386.59544) (xy 210.104839 -386.656256) (xy 210.043686 -386.711645)
			(xy 209.977665 -386.761132) (xy 209.907344 -386.80429) (xy 209.870548 -386.82295) (xy 209.862237 -386.82751)
			(xy 209.849486 -386.841519) (xy 209.842679 -386.859197) (xy 209.842354 -386.86867) (xy 209.842354 -386.959602)
			(xy 209.842685 -386.969079) (xy 209.849468 -386.986774) (xy 209.862218 -387.000793) (xy 209.870548 -387.005322)
			(xy 209.907343 -387.02398) (xy 209.97765 -387.067153) (xy 210.043658 -387.11665) (xy 210.104799 -387.172046)
			(xy 210.16055 -387.232865) (xy 210.210429 -387.298584) (xy 210.25401 -387.36864) (xy 210.290917 -387.442429)
			(xy 210.320833 -387.519319) (xy 210.343503 -387.598648) (xy 210.35873 -387.679735) (xy 210.366384 -387.761884)
			(xy 210.366864 -387.803136) (xy 210.366277 -387.849532) (xy 210.35664 -387.941821) (xy 210.337443 -388.032604)
			(xy 210.308894 -388.120894) (xy 210.291966 -388.160514) (xy 221.30132 -388.160514) (xy 221.305305 -387.979173)
			(xy 221.317251 -387.798181) (xy 221.337135 -387.617889) (xy 221.364919 -387.438645) (xy 221.40055 -387.260793)
			(xy 221.443958 -387.084679) (xy 221.49506 -386.910641) (xy 221.553758 -386.739016) (xy 221.619937 -386.570135)
			(xy 221.69347 -386.404323) (xy 221.774215 -386.241902) (xy 221.862017 -386.083183) (xy 221.956706 -385.928475)
			(xy 222.058098 -385.778075) (xy 222.165999 -385.632274) (xy 222.2802 -385.491353) (xy 222.400481 -385.355584)
			(xy 222.526609 -385.22523) (xy 222.658341 -385.100541) (xy 222.795423 -384.981759) (xy 222.93759 -384.869113)
			(xy 223.084567 -384.76282) (xy 223.236072 -384.663086) (xy 223.391811 -384.570102) (xy 223.551484 -384.484049)
			(xy 223.714783 -384.405093) (xy 223.881392 -384.333385) (xy 224.05099 -384.269065) (xy 224.22325 -384.212257)
			(xy 224.397838 -384.163069) (xy 224.574419 -384.121598) (xy 224.752651 -384.087923) (xy 224.93219 -384.062109)
			(xy 225.112689 -384.044207) (xy 225.293801 -384.034249) (xy 225.475175 -384.032257) (xy 225.656462 -384.038233)
			(xy 225.837311 -384.052167) (xy 226.017374 -384.07403) (xy 226.196302 -384.103782) (xy 226.373751 -384.141364)
			(xy 226.549378 -384.186704) (xy 226.722844 -384.239715) (xy 226.893814 -384.300294) (xy 227.061959 -384.368324)
			(xy 227.226952 -384.443674) (xy 227.388477 -384.526199) (xy 227.546221 -384.615739) (xy 227.69988 -384.712121)
			(xy 227.849157 -384.815159) (xy 227.993764 -384.924655) (xy 228.133422 -385.040397) (xy 228.267862 -385.162162)
			(xy 228.396823 -385.289714) (xy 228.520057 -385.422808) (xy 228.637326 -385.561186) (xy 228.748404 -385.704582)
			(xy 228.853076 -385.852718) (xy 228.95114 -386.005309) (xy 229.042407 -386.16206) (xy 229.126701 -386.322669)
			(xy 229.203859 -386.486825) (xy 229.273732 -386.654212) (xy 229.336186 -386.824506) (xy 229.391098 -386.997379)
			(xy 229.438365 -387.172498) (xy 229.477894 -387.349523) (xy 229.509609 -387.528114) (xy 229.53345 -387.707926)
			(xy 229.549369 -387.888611) (xy 229.557336 -388.069821) (xy 229.557834 -388.160514) (xy 229.557336 -388.251207)
			(xy 229.549369 -388.432417) (xy 229.53345 -388.613102) (xy 229.509609 -388.792914) (xy 229.477894 -388.971505)
			(xy 229.438365 -389.14853) (xy 229.391098 -389.323649) (xy 229.336186 -389.496522) (xy 229.273732 -389.666816)
			(xy 229.203859 -389.834203) (xy 229.126701 -389.998359) (xy 229.042407 -390.158968) (xy 228.95114 -390.315719)
			(xy 228.853076 -390.46831) (xy 228.748404 -390.616446) (xy 228.637326 -390.759842) (xy 228.520057 -390.89822)
			(xy 228.396823 -391.031314) (xy 228.267862 -391.158866) (xy 228.133422 -391.280631) (xy 227.993764 -391.396373)
			(xy 227.849157 -391.505869) (xy 227.69988 -391.608907) (xy 227.546221 -391.705289) (xy 227.388477 -391.794829)
			(xy 227.226952 -391.877354) (xy 227.061959 -391.952704) (xy 226.893814 -392.020734) (xy 226.722844 -392.081313)
			(xy 226.549378 -392.134324) (xy 226.373751 -392.179664) (xy 226.196302 -392.217246) (xy 226.017374 -392.246998)
			(xy 225.837311 -392.268861) (xy 225.656462 -392.282795) (xy 225.475175 -392.288771) (xy 225.293801 -392.286779)
			(xy 225.112689 -392.276821) (xy 224.93219 -392.258919) (xy 224.752651 -392.233105) (xy 224.574419 -392.19943)
			(xy 224.397838 -392.157959) (xy 224.22325 -392.108771) (xy 224.05099 -392.051963) (xy 223.881392 -391.987643)
			(xy 223.714783 -391.915935) (xy 223.551484 -391.836979) (xy 223.391811 -391.750926) (xy 223.236072 -391.657942)
			(xy 223.084567 -391.558208) (xy 222.93759 -391.451915) (xy 222.795423 -391.339269) (xy 222.658341 -391.220487)
			(xy 222.526609 -391.095798) (xy 222.400481 -390.965444) (xy 222.2802 -390.829675) (xy 222.165999 -390.688754)
			(xy 222.058098 -390.542953) (xy 221.956706 -390.392553) (xy 221.862017 -390.237845) (xy 221.774215 -390.079126)
			(xy 221.69347 -389.916705) (xy 221.619937 -389.750893) (xy 221.553758 -389.582012) (xy 221.49506 -389.410387)
			(xy 221.443958 -389.236349) (xy 221.40055 -389.060235) (xy 221.364919 -388.882383) (xy 221.337135 -388.703139)
			(xy 221.317251 -388.522847) (xy 221.305305 -388.341855) (xy 221.30132 -388.160514) (xy 210.291966 -388.160514)
			(xy 210.290664 -388.163562) (xy 210.286853 -388.173502) (xy 210.286866 -388.194763) (xy 210.290664 -388.20471)
			(xy 210.308901 -388.247375) (xy 210.337437 -388.335669) (xy 210.35663 -388.426452) (xy 210.366272 -388.518741)
			(xy 210.366864 -388.565136) (xy 210.36636 -388.607484) (xy 210.358309 -388.691798) (xy 210.34228 -388.774964)
			(xy 210.318419 -388.856231) (xy 210.28694 -388.934861) (xy 210.248129 -389.010142) (xy 210.202339 -389.081394)
			(xy 210.149983 -389.14797) (xy 210.091535 -389.209268) (xy 210.027525 -389.264733) (xy 209.958533 -389.313862)
			(xy 209.885183 -389.356211) (xy 209.80814 -389.391395) (xy 209.728101 -389.419097) (xy 209.645792 -389.439065)
			(xy 209.561957 -389.451118) (xy 209.477356 -389.455149) (xy 209.392755 -389.451118) (xy 209.30892 -389.439065)
			(xy 209.226611 -389.419097) (xy 209.146572 -389.391395) (xy 209.069529 -389.356211) (xy 208.996179 -389.313862)
			(xy 208.927187 -389.264733) (xy 208.863177 -389.209268) (xy 208.804729 -389.14797) (xy 208.752373 -389.081394)
			(xy 208.706583 -389.010142) (xy 208.667772 -388.934861) (xy 208.636293 -388.856231) (xy 208.612432 -388.774964)
			(xy 208.596403 -388.691798) (xy 208.588352 -388.607484) (xy 208.587848 -388.565136) (xy 208.588431 -388.51874)
			(xy 208.598061 -388.426448) (xy 208.617252 -388.335662) (xy 208.645795 -388.247369) (xy 208.664048 -388.20471)
			(xy 208.667874 -388.19477) (xy 208.667888 -388.173496) (xy 208.664048 -388.163562) (xy 208.645812 -388.120897)
			(xy 208.617278 -388.032603) (xy 208.598088 -387.941819) (xy 208.588449 -387.849531) (xy 208.587848 -387.803136)
			(xy 208.588314 -387.761882) (xy 208.595954 -387.67973) (xy 208.61117 -387.598638) (xy 208.633833 -387.519305)
			(xy 208.663747 -387.442412) (xy 208.700655 -387.36862) (xy 208.74424 -387.298565) (xy 208.794127 -387.232848)
			(xy 208.849887 -387.172035) (xy 208.911041 -387.116648) (xy 208.977062 -387.067165) (xy 209.047382 -387.02401)
			(xy 209.084164 -387.005322) (xy 209.09247 -387.000759) (xy 209.10521 -386.986748) (xy 209.112006 -386.969072)
			(xy 209.112358 -386.959602) (xy 209.112358 -386.86867) (xy 209.112022 -386.859195) (xy 209.105234 -386.841507)
			(xy 209.092484 -386.827494) (xy 209.084164 -386.82295) (xy 209.04737 -386.804292) (xy 208.977063 -386.761119)
			(xy 208.911056 -386.711622) (xy 208.849915 -386.656226) (xy 208.794166 -386.595407) (xy 208.744288 -386.529687)
			(xy 208.700709 -386.459632) (xy 208.663804 -386.385842) (xy 208.633889 -386.308953) (xy 208.611222 -386.229623)
			(xy 208.595997 -386.148536) (xy 208.588346 -386.066388) (xy 208.587848 -386.025136) (xy 208.588431 -385.97874)
			(xy 208.598061 -385.886448) (xy 208.617252 -385.795662) (xy 208.645795 -385.707369) (xy 208.664048 -385.66471)
			(xy 208.667874 -385.65477) (xy 208.667888 -385.633496) (xy 208.664048 -385.623562) (xy 208.645812 -385.580897)
			(xy 208.617278 -385.492603) (xy 208.598088 -385.401819) (xy 208.588449 -385.309531) (xy 208.587848 -385.263136)
			(xy 208.588314 -385.221882) (xy 208.595954 -385.13973) (xy 208.61117 -385.058638) (xy 208.633833 -384.979305)
			(xy 208.663747 -384.902412) (xy 208.700655 -384.82862) (xy 208.74424 -384.758565) (xy 208.794127 -384.692848)
			(xy 208.849887 -384.632035) (xy 208.911041 -384.576648) (xy 208.977062 -384.527165) (xy 209.047382 -384.48401)
			(xy 209.084164 -384.465322) (xy 209.09247 -384.460759) (xy 209.10521 -384.446748) (xy 209.112006 -384.429072)
			(xy 209.112358 -384.419602) (xy 209.112358 -384.32867) (xy 209.112022 -384.319195) (xy 209.105234 -384.301507)
			(xy 209.092484 -384.287494) (xy 209.084164 -384.28295) (xy 209.04737 -384.264292) (xy 208.977063 -384.221119)
			(xy 208.911056 -384.171622) (xy 208.849915 -384.116226) (xy 208.794166 -384.055407) (xy 208.744288 -383.989687)
			(xy 208.700709 -383.919632) (xy 208.663804 -383.845842) (xy 208.633889 -383.768953) (xy 208.611222 -383.689623)
			(xy 208.595997 -383.608536) (xy 208.588346 -383.526388) (xy 208.587848 -383.485136) (xy 208.588431 -383.43874)
			(xy 208.598061 -383.346448) (xy 208.617252 -383.255662) (xy 208.645795 -383.167369) (xy 208.664048 -383.12471)
			(xy 208.667874 -383.11477) (xy 208.667888 -383.093496) (xy 208.664048 -383.083562) (xy 208.65035 -383.051871)
			(xy 208.627335 -382.986773) (xy 208.618074 -382.953514) (xy 208.613756 -382.93675) (xy 208.586578 -382.915668)
			(xy 208.3308 -382.915668) (xy 208.303622 -382.93675) (xy 208.299304 -382.953514) (xy 208.289946 -382.987102)
			(xy 208.26668 -383.052837) (xy 208.252822 -383.084832) (xy 208.249017 -383.094774) (xy 208.24902 -383.116037)
			(xy 208.252822 -383.12598) (xy 208.27126 -383.168824) (xy 208.300092 -383.257534) (xy 208.319481 -383.348775)
			(xy 208.329214 -383.441545) (xy 208.329784 -383.488184) (xy 208.329324 -383.529312) (xy 208.321731 -383.611218)
			(xy 208.30661 -383.692073) (xy 208.28409 -383.771186) (xy 208.254362 -383.847883) (xy 208.21768 -383.921508)
			(xy 208.174358 -383.991432) (xy 208.124767 -384.057058) (xy 208.069328 -384.117826) (xy 208.008517 -384.173216)
			(xy 207.942851 -384.222756) (xy 207.872893 -384.266022) (xy 207.836262 -384.284728) (xy 207.823054 -384.291332)
			(xy 207.808068 -384.315462) (xy 207.807814 -384.435858) (xy 207.823054 -384.460242) (xy 207.836008 -384.466592)
			(xy 207.872631 -384.485313) (xy 207.942591 -384.528573) (xy 208.008258 -384.578109) (xy 208.069071 -384.633496)
			(xy 208.12451 -384.694262) (xy 208.174101 -384.759887) (xy 208.217421 -384.829811) (xy 208.254099 -384.903437)
			(xy 208.283822 -384.980134) (xy 208.306336 -385.059248) (xy 208.321449 -385.140103) (xy 208.329032 -385.222008)
			(xy 208.32953 -385.263136) (xy 208.328909 -385.309639) (xy 208.319177 -385.402136) (xy 208.299854 -385.493114)
			(xy 208.271151 -385.581581) (xy 208.252822 -385.624324) (xy 208.248897 -385.634388) (xy 208.249017 -385.65597)
			(xy 208.253076 -385.66598) (xy 208.272159 -385.709456) (xy 208.302017 -385.799591) (xy 208.322114 -385.892392)
			(xy 208.33222 -385.986804) (xy 208.332832 -386.03428) (xy 208.332371 -386.075107) (xy 208.324887 -386.156419)
			(xy 208.309981 -386.236702) (xy 208.287779 -386.31528) (xy 208.258466 -386.391492) (xy 208.222291 -386.464696)
			(xy 208.179557 -386.534276) (xy 208.130625 -386.599646) (xy 208.075906 -386.660254) (xy 208.015862 -386.715591)
			(xy 207.950998 -386.765191) (xy 207.88186 -386.808636) (xy 207.84566 -386.827522) (xy 207.832706 -386.834126)
			(xy 207.81772 -386.85851) (xy 207.817974 -386.978144) (xy 207.83296 -387.002274) (xy 207.845914 -387.008878)
			(xy 207.882235 -387.027718) (xy 207.951602 -387.071122) (xy 208.01669 -387.120714) (xy 208.076947 -387.176075)
			(xy 208.131863 -387.236737) (xy 208.180976 -387.302186) (xy 208.223869 -387.371871) (xy 208.26018 -387.445201)
			(xy 208.289601 -387.521556) (xy 208.311884 -387.600291) (xy 208.326841 -387.68074) (xy 208.334345 -387.762222)
			(xy 208.334864 -387.803136) (xy 208.334277 -387.849532) (xy 208.32464 -387.941821) (xy 208.305443 -388.032604)
			(xy 208.276894 -388.120894) (xy 208.258664 -388.163562) (xy 208.254853 -388.173502) (xy 208.254866 -388.194763)
			(xy 208.258664 -388.20471) (xy 208.276901 -388.247375) (xy 208.305437 -388.335669) (xy 208.32463 -388.426452)
			(xy 208.334272 -388.518741) (xy 208.334864 -388.565136) (xy 208.33436 -388.607484) (xy 208.326309 -388.691798)
			(xy 208.31028 -388.774964) (xy 208.286419 -388.856231) (xy 208.25494 -388.934861) (xy 208.216129 -389.010142)
			(xy 208.170339 -389.081394) (xy 208.117983 -389.14797) (xy 208.059535 -389.209268) (xy 207.995525 -389.264733)
			(xy 207.926533 -389.313862) (xy 207.853183 -389.356211) (xy 207.77614 -389.391395) (xy 207.696101 -389.419097)
			(xy 207.613792 -389.439065) (xy 207.529957 -389.451118) (xy 207.445356 -389.455149) (xy 207.360755 -389.451118)
			(xy 207.27692 -389.439065) (xy 207.194611 -389.419097) (xy 207.114572 -389.391395) (xy 207.037529 -389.356211)
			(xy 206.964179 -389.313862) (xy 206.895187 -389.264733) (xy 206.831177 -389.209268) (xy 206.772729 -389.14797)
			(xy 206.720373 -389.081394) (xy 206.674583 -389.010142) (xy 206.635772 -388.934861) (xy 206.604293 -388.856231)
			(xy 206.580432 -388.774964) (xy 206.564403 -388.691798) (xy 206.556352 -388.607484) (xy 206.555848 -388.565136)
			(xy 206.556431 -388.51874) (xy 206.566061 -388.426448) (xy 206.585252 -388.335662) (xy 206.613795 -388.247369)
			(xy 206.632048 -388.20471) (xy 206.635874 -388.19477) (xy 206.635888 -388.173496) (xy 206.632048 -388.163562)
			(xy 206.613812 -388.120897) (xy 206.585278 -388.032603) (xy 206.566088 -387.941819) (xy 206.556449 -387.849531)
			(xy 206.555848 -387.803136) (xy 206.556309 -387.762309) (xy 206.563791 -387.680998) (xy 206.578697 -387.600716)
			(xy 206.600899 -387.522138) (xy 206.630213 -387.445927) (xy 206.666389 -387.372724) (xy 206.709124 -387.303146)
			(xy 206.758058 -387.237779) (xy 206.812779 -387.177173) (xy 206.872826 -387.121839) (xy 206.937692 -387.072243)
			(xy 207.006832 -387.028803) (xy 207.04302 -387.009894) (xy 207.055974 -387.00329) (xy 207.07096 -386.978906)
			(xy 207.070706 -386.859272) (xy 207.05572 -386.835142) (xy 207.042766 -386.828538) (xy 207.006442 -386.8097)
			(xy 206.937068 -386.766301) (xy 206.871975 -386.716712) (xy 206.811711 -386.661353) (xy 206.756788 -386.600692)
			(xy 206.70767 -386.535243) (xy 206.664772 -386.465558) (xy 206.628456 -386.392227) (xy 206.59903 -386.31587)
			(xy 206.576743 -386.237133) (xy 206.561784 -386.156681) (xy 206.554277 -386.075195) (xy 206.553816 -386.03428)
			(xy 206.554436 -385.987776) (xy 206.564166 -385.895279) (xy 206.583486 -385.8043) (xy 206.612186 -385.715832)
			(xy 206.630524 -385.673092) (xy 206.634456 -385.663028) (xy 206.634342 -385.641442) (xy 206.63027 -385.631436)
			(xy 206.611185 -385.58796) (xy 206.581324 -385.497826) (xy 206.561225 -385.405025) (xy 206.551116 -385.310612)
			(xy 206.550514 -385.263136) (xy 206.550978 -385.22201) (xy 206.558577 -385.140108) (xy 206.573704 -385.059258)
			(xy 206.59623 -384.98015) (xy 206.625962 -384.903459) (xy 206.662647 -384.82984) (xy 206.705971 -384.759922)
			(xy 206.755565 -384.694301) (xy 206.811004 -384.633539) (xy 206.871816 -384.578155) (xy 206.93748 -384.52862)
			(xy 207.007437 -384.485359) (xy 207.044036 -384.466592) (xy 207.057244 -384.459988) (xy 207.07223 -384.435858)
			(xy 207.072484 -384.315462) (xy 207.057244 -384.291078) (xy 207.04429 -384.284728) (xy 207.007667 -384.266007)
			(xy 206.937705 -384.222747) (xy 206.872037 -384.173212) (xy 206.811223 -384.117825) (xy 206.755783 -384.057059)
			(xy 206.706191 -383.991434) (xy 206.66287 -383.92151) (xy 206.62619 -383.847885) (xy 206.596466 -383.771188)
			(xy 206.57395 -383.692073) (xy 206.558835 -383.611218) (xy 206.55125 -383.529312) (xy 206.550768 -383.488184)
			(xy 206.551365 -383.441617) (xy 206.561069 -383.348989) (xy 206.580388 -383.25788) (xy 206.609114 -383.169286)
			(xy 206.627476 -383.126488) (xy 206.631285 -383.116546) (xy 206.631291 -383.09528) (xy 206.627476 -383.08534)
			(xy 206.61353 -383.053229) (xy 206.590131 -382.98724) (xy 206.58074 -382.953514) (xy 206.576422 -382.93675)
			(xy 206.549244 -382.915668) (xy 206.304134 -382.915668) (xy 206.276956 -382.93675) (xy 206.272638 -382.953514)
			(xy 206.263366 -382.98677) (xy 206.240355 -383.051868) (xy 206.226664 -383.083562) (xy 206.222853 -383.093502)
			(xy 206.222866 -383.114763) (xy 206.226664 -383.12471) (xy 206.244901 -383.167375) (xy 206.273437 -383.255669)
			(xy 206.29263 -383.346452) (xy 206.302272 -383.438741) (xy 206.302864 -383.485136) (xy 206.302399 -383.52639)
			(xy 206.294762 -383.608545) (xy 206.279548 -383.689638) (xy 206.256887 -383.768974) (xy 206.226975 -383.845869)
			(xy 206.190068 -383.919663) (xy 206.146484 -383.989721) (xy 206.096598 -384.05544) (xy 206.040839 -384.116256)
			(xy 205.979686 -384.171645) (xy 205.913665 -384.221132) (xy 205.843344 -384.26429) (xy 205.806548 -384.28295)
			(xy 205.798237 -384.28751) (xy 205.785486 -384.301519) (xy 205.778679 -384.319197) (xy 205.778354 -384.32867)
			(xy 205.778354 -384.419602) (xy 205.778685 -384.429079) (xy 205.785468 -384.446774) (xy 205.798218 -384.460793)
			(xy 205.806548 -384.465322) (xy 205.843343 -384.48398) (xy 205.91365 -384.527153) (xy 205.979658 -384.57665)
			(xy 206.040799 -384.632046) (xy 206.09655 -384.692865) (xy 206.146429 -384.758584) (xy 206.19001 -384.82864)
			(xy 206.226917 -384.902429) (xy 206.256833 -384.979319) (xy 206.279503 -385.058648) (xy 206.29473 -385.139735)
			(xy 206.302384 -385.221884) (xy 206.302864 -385.263136) (xy 206.302277 -385.309532) (xy 206.29264 -385.401821)
			(xy 206.273443 -385.492604) (xy 206.244894 -385.580894) (xy 206.226664 -385.623562) (xy 206.222853 -385.633502)
			(xy 206.222866 -385.654763) (xy 206.226664 -385.66471) (xy 206.244901 -385.707375) (xy 206.273437 -385.795669)
			(xy 206.29263 -385.886452) (xy 206.302272 -385.978741) (xy 206.302864 -386.025136) (xy 206.30236 -386.067484)
			(xy 206.294309 -386.151798) (xy 206.27828 -386.234964) (xy 206.254419 -386.316231) (xy 206.22294 -386.394861)
			(xy 206.184129 -386.470142) (xy 206.138339 -386.541394) (xy 206.085983 -386.60797) (xy 206.027535 -386.669268)
			(xy 205.963525 -386.724733) (xy 205.894533 -386.773862) (xy 205.821183 -386.816211) (xy 205.74414 -386.851395)
			(xy 205.664101 -386.879097) (xy 205.581792 -386.899065) (xy 205.497957 -386.911118) (xy 205.413356 -386.915149)
			(xy 205.328755 -386.911118) (xy 205.24492 -386.899065) (xy 205.162611 -386.879097) (xy 205.082572 -386.851395)
			(xy 205.005529 -386.816211) (xy 204.932179 -386.773862) (xy 204.863187 -386.724733) (xy 204.799177 -386.669268)
			(xy 204.740729 -386.60797) (xy 204.688373 -386.541394) (xy 204.642583 -386.470142) (xy 204.603772 -386.394861)
			(xy 204.572293 -386.316231) (xy 204.548432 -386.234964) (xy 204.532403 -386.151798) (xy 204.524352 -386.067484)
			(xy 204.523848 -386.025136) (xy 204.524431 -385.97874) (xy 204.534061 -385.886448) (xy 204.553252 -385.795662)
			(xy 204.581795 -385.707369) (xy 204.600048 -385.66471) (xy 204.603874 -385.65477) (xy 204.603888 -385.633496)
			(xy 204.600048 -385.623562) (xy 204.581812 -385.580897) (xy 204.553278 -385.492603) (xy 204.534088 -385.401819)
			(xy 204.524449 -385.309531) (xy 204.523848 -385.263136) (xy 204.524314 -385.221882) (xy 204.531954 -385.13973)
			(xy 204.54717 -385.058638) (xy 204.569833 -384.979305) (xy 204.599747 -384.902412) (xy 204.636655 -384.82862)
			(xy 204.68024 -384.758565) (xy 204.730127 -384.692848) (xy 204.785887 -384.632035) (xy 204.847041 -384.576648)
			(xy 204.913062 -384.527165) (xy 204.983382 -384.48401) (xy 205.020164 -384.465322) (xy 205.02847 -384.460759)
			(xy 205.04121 -384.446748) (xy 205.048006 -384.429072) (xy 205.048358 -384.419602) (xy 205.048358 -384.32867)
			(xy 205.048022 -384.319195) (xy 205.041234 -384.301507) (xy 205.028484 -384.287494) (xy 205.020164 -384.28295)
			(xy 204.9813 -384.2632) (xy 204.907247 -384.217188) (xy 204.83805 -384.164153) (xy 204.774373 -384.104604)
			(xy 204.716827 -384.039111) (xy 204.665963 -383.968303) (xy 204.622271 -383.892858) (xy 204.586168 -383.813502)
			(xy 204.558001 -383.730994) (xy 204.53804 -383.646127) (xy 204.531722 -383.602992) (xy 204.52969 -383.588514)
			(xy 204.511402 -383.566162) (xy 204.411326 -383.53238) (xy 204.402275 -383.529718) (xy 204.38344 -383.53056)
			(xy 204.366193 -383.538177) (xy 204.359256 -383.544572) (xy 203.513436 -384.390138) (xy 203.486648 -384.416276)
			(xy 203.42879 -384.46376) (xy 203.366556 -384.505345) (xy 203.300546 -384.54063) (xy 203.231395 -384.569275)
			(xy 203.15977 -384.591006) (xy 203.08636 -384.605611) (xy 203.011872 -384.612952) (xy 202.974448 -384.613404)
			(xy 200.533508 -384.613404) (xy 200.523486 -384.613822) (xy 200.504967 -384.621491) (xy 200.490793 -384.635664)
			(xy 200.483123 -384.654182) (xy 200.482708 -384.664204) (xy 200.482708 -386.6007) (xy 200.482285 -386.61077)
			(xy 200.474572 -386.629376) (xy 200.467722 -386.636768) (xy 200.421494 -386.682996) (xy 200.414648 -386.690395)
			(xy 200.406913 -386.708992) (xy 200.406508 -386.719064) (xy 200.406508 -387.960616) (xy 200.741024 -387.960616)
			(xy 200.745095 -387.904994) (xy 200.757221 -387.850557) (xy 200.777144 -387.798466) (xy 200.80444 -387.749831)
			(xy 200.838526 -387.705688) (xy 200.878675 -387.666979) (xy 200.924033 -387.634528) (xy 200.973633 -387.609027)
			(xy 201.026417 -387.59102) (xy 201.08126 -387.58089) (xy 201.136994 -387.578853) (xy 201.192431 -387.584953)
			(xy 201.246388 -387.599059) (xy 201.297717 -387.620871) (xy 201.345323 -387.649925) (xy 201.388191 -387.6856)
			(xy 201.425408 -387.727137) (xy 201.456181 -387.77365) (xy 201.479853 -387.824147) (xy 201.495921 -387.877554)
			(xy 201.504041 -387.93273) (xy 201.50455 -387.960616) (xy 201.504041 -387.988502) (xy 201.495921 -388.043678)
			(xy 201.479853 -388.097085) (xy 201.456181 -388.147582) (xy 201.425408 -388.194095) (xy 201.388191 -388.235632)
			(xy 201.345323 -388.271307) (xy 201.297717 -388.300361) (xy 201.246388 -388.322173) (xy 201.192431 -388.336279)
			(xy 201.136994 -388.342379) (xy 201.08126 -388.340342) (xy 201.026417 -388.330212) (xy 200.973633 -388.312205)
			(xy 200.924033 -388.286704) (xy 200.878675 -388.254253) (xy 200.838526 -388.215544) (xy 200.80444 -388.171401)
			(xy 200.777144 -388.122766) (xy 200.757221 -388.070675) (xy 200.745095 -388.016238) (xy 200.741024 -387.960616)
			(xy 200.406508 -387.960616) (xy 200.406508 -389.181594) (xy 200.406086 -389.191665) (xy 200.398374 -389.210272)
			(xy 200.391522 -389.217662) (xy 199.619362 -389.989822) (xy 199.611965 -389.996671) (xy 199.593366 -390.004404)
			(xy 199.583294 -390.004808) (xy 199.582278 -390.004808) (xy 199.557386 -390.021064) (xy 199.551036 -390.035034)
			(xy 199.539463 -390.060015) (xy 199.510192 -390.106643) (xy 199.47452 -390.148576) (xy 199.433187 -390.184944)
			(xy 199.387054 -390.214989) (xy 199.33708 -390.238087) (xy 199.284303 -390.253758) (xy 199.229821 -390.261675)
			(xy 199.174767 -390.261675) (xy 199.120285 -390.253758) (xy 199.067508 -390.238087) (xy 199.017534 -390.214989)
			(xy 198.971401 -390.184944) (xy 198.930068 -390.148576) (xy 198.894396 -390.106643) (xy 198.865125 -390.060015)
			(xy 198.853552 -390.035034) (xy 198.847202 -390.021064) (xy 198.82231 -390.004808) (xy 192.95745 -390.004808)
			(xy 192.932558 -390.021064) (xy 192.926208 -390.035034) (xy 192.914635 -390.060015) (xy 192.885364 -390.106643)
			(xy 192.849692 -390.148576) (xy 192.808359 -390.184944) (xy 192.762226 -390.214989) (xy 192.712252 -390.238087)
			(xy 192.659475 -390.253758) (xy 192.604993 -390.261675) (xy 192.549939 -390.261675) (xy 192.495457 -390.253758)
			(xy 192.44268 -390.238087) (xy 192.392706 -390.214989) (xy 192.346573 -390.184944) (xy 192.30524 -390.148576)
			(xy 192.269568 -390.106643) (xy 192.240297 -390.060015) (xy 192.228724 -390.035034) (xy 192.222374 -390.021064)
			(xy 192.197482 -390.004808) (xy 189.13094 -390.004808) (xy 189.120875 -390.005242) (xy 189.102287 -390.012973)
			(xy 189.094872 -390.019794) (xy 184.53481 -394.579856) (xy 184.527971 -394.587257) (xy 184.520255 -394.605855)
			(xy 184.519824 -394.615924) (xy 184.519824 -395.95552) (xy 184.520251 -395.965588) (xy 184.527974 -395.984185)
			(xy 184.53481 -395.991588) (xy 184.616344 -396.073122) (xy 184.623741 -396.07997) (xy 184.64234 -396.087701)
			(xy 184.652412 -396.088108) (xy 185.033412 -396.088108) (xy 185.043481 -396.088534) (xy 185.062082 -396.096252)
			(xy 185.06948 -396.103094) (xy 185.345832 -396.379446) (xy 185.352679 -396.386844) (xy 185.360407 -396.405443)
			(xy 185.360818 -396.415514) (xy 185.360818 -398.992852) (xy 185.361229 -399.002878) (xy 185.368891 -399.021409)
			(xy 185.383066 -399.035592) (xy 185.401592 -399.043265) (xy 185.411618 -399.043652) (xy 188.916056 -399.043652)
			(xy 188.926046 -399.043121) (xy 188.944485 -399.035414) (xy 188.95187 -399.028666) (xy 189.23762 -398.742916)
			(xy 189.265594 -398.715695) (xy 189.3265 -398.666875) (xy 189.392382 -398.625011) (xy 189.462447 -398.590605)
			(xy 189.535856 -398.56407) (xy 189.611727 -398.545724) (xy 189.65037 -398.540224) (xy 189.658752 -398.539208)
			(xy 189.673738 -398.531842) (xy 190.454026 -397.751554) (xy 190.461423 -397.744706) (xy 190.480022 -397.736972)
			(xy 190.490094 -397.736568) (xy 193.891408 -397.736568) (xy 193.902695 -397.735961) (xy 193.923117 -397.726338)
			(xy 193.930778 -397.718026) (xy 193.95739 -397.6864) (xy 194.015584 -397.627696) (xy 194.078973 -397.574644)
			(xy 194.147011 -397.527703) (xy 194.219111 -397.487276) (xy 194.294651 -397.453713) (xy 194.372978 -397.427304)
			(xy 194.453418 -397.408275) (xy 194.535277 -397.396792) (xy 194.617848 -397.392954) (xy 194.700419 -397.396792)
			(xy 194.782278 -397.408275) (xy 194.862718 -397.427304) (xy 194.941045 -397.453713) (xy 195.016585 -397.487276)
			(xy 195.088685 -397.527703) (xy 195.156723 -397.574644) (xy 195.220112 -397.627696) (xy 195.278306 -397.6864)
			(xy 195.304918 -397.718026) (xy 195.312536 -397.7264) (xy 195.332981 -397.736046) (xy 195.344288 -397.736568)
			(xy 196.068188 -397.736568) (xy 196.07826 -397.736988) (xy 196.09687 -397.744696) (xy 196.104256 -397.751554)
			(xy 197.656704 -399.304002) (xy 197.664103 -399.310848) (xy 197.682701 -399.31858) (xy 197.692772 -399.318988)
		)
		(stroke
			(width 0)
			(type solid)
		)
		(fill yes)
		(layer "In15.Cu")
		(net "P12V_AUX")
	)
	(gr_poly
		(pts
			(xy 21.555964 -43.038522) (xy 21.56603 -43.038088) (xy 21.584619 -43.03036) (xy 21.592032 -43.023536)
			(xy 23.69566 -40.919908) (xy 23.705471 -40.909424) (xy 23.719342 -40.884298) (xy 23.725673 -40.856305)
			(xy 23.723964 -40.827655) (xy 23.71435 -40.800613) (xy 23.69759 -40.777314) (xy 23.675009 -40.7596)
			(xy 23.661878 -40.753792) (xy 23.635726 -40.742737) (xy 23.586747 -40.714021) (xy 23.542564 -40.678366)
			(xy 23.50415 -40.636558) (xy 23.472354 -40.589521) (xy 23.447877 -40.538292) (xy 23.431259 -40.484003)
			(xy 23.422869 -40.42785) (xy 23.422356 -40.399462) (xy 23.422845 -40.372195) (xy 23.430611 -40.318216)
			(xy 23.44598 -40.265892) (xy 23.468639 -40.216288) (xy 23.498126 -40.170413) (xy 23.533841 -40.129202)
			(xy 23.575058 -40.093492) (xy 23.620937 -40.064012) (xy 23.670545 -40.04136) (xy 23.722871 -40.025999)
			(xy 23.776851 -40.018241) (xy 23.804118 -40.0177) (xy 23.832504 -40.018221) (xy 23.888651 -40.026628)
			(xy 23.942934 -40.043255) (xy 23.994157 -40.067734) (xy 24.041193 -40.099527) (xy 24.083003 -40.137932)
			(xy 24.118667 -40.182104) (xy 24.147399 -40.23107) (xy 24.158448 -40.257222) (xy 24.164256 -40.270356)
			(xy 24.181954 -40.292955) (xy 24.205248 -40.309727) (xy 24.232293 -40.319344) (xy 24.260947 -40.321044)
			(xy 24.288939 -40.314692) (xy 24.314053 -40.300792) (xy 24.324564 -40.291004) (xy 24.721566 -39.894002)
			(xy 24.728968 -39.887166) (xy 24.747566 -39.879455) (xy 24.757634 -39.879016) (xy 24.898604 -39.879016)
			(xy 24.913169 -39.878559) (xy 24.941119 -39.87036) (xy 24.965616 -39.854601) (xy 24.984666 -39.832565)
			(xy 24.996717 -39.806047) (xy 25.000789 -39.777205) (xy 24.99655 -39.748387) (xy 24.990806 -39.734998)
			(xy 24.979751 -39.709874) (xy 24.964149 -39.657248) (xy 24.95624 -39.60293) (xy 24.955754 -39.575486)
			(xy 24.955754 -39.574978) (xy 24.95624 -39.547709) (xy 24.964002 -39.493725) (xy 24.979367 -39.441395)
			(xy 25.002024 -39.391785) (xy 25.03151 -39.345904) (xy 25.067225 -39.304687) (xy 25.108442 -39.268972)
			(xy 25.154323 -39.239486) (xy 25.203933 -39.216829) (xy 25.256263 -39.201464) (xy 25.310247 -39.193702)
			(xy 25.364785 -39.193702) (xy 25.418769 -39.201464) (xy 25.471099 -39.216829) (xy 25.520709 -39.239486)
			(xy 25.56659 -39.268972) (xy 25.607807 -39.304687) (xy 25.643522 -39.345904) (xy 25.673008 -39.391785)
			(xy 25.695665 -39.441395) (xy 25.71103 -39.493725) (xy 25.718792 -39.547709) (xy 25.719278 -39.574978)
			(xy 25.719278 -39.575486) (xy 25.718787 -39.602931) (xy 25.710894 -39.657252) (xy 25.695296 -39.70988)
			(xy 25.684226 -39.734998) (xy 25.678581 -39.748415) (xy 25.674385 -39.777208) (xy 25.678472 -39.806016)
			(xy 25.690511 -39.832506) (xy 25.709526 -39.85453) (xy 25.733976 -39.870304) (xy 25.76188 -39.87855)
			(xy 25.776428 -39.879016) (xy 64.351154 -39.879016) (xy 64.36682 -39.878436) (xy 64.396678 -39.868941)
			(xy 64.422265 -39.850859) (xy 64.441184 -39.825884) (xy 64.45166 -39.796356) (xy 64.452754 -39.780718)
			(xy 64.454643 -39.737971) (xy 64.465602 -39.653105) (xy 64.484658 -39.569684) (xy 64.511636 -39.488477)
			(xy 64.546286 -39.410236) (xy 64.588287 -39.335682) (xy 64.637253 -39.265506) (xy 64.69273 -39.200355)
			(xy 64.754206 -39.140832) (xy 64.821112 -39.087485) (xy 64.892832 -39.040809) (xy 64.968701 -39.001234)
			(xy 65.04802 -38.969127) (xy 65.130054 -38.944783) (xy 65.214047 -38.928427) (xy 65.299223 -38.920212)
			(xy 65.384793 -38.920212) (xy 65.469969 -38.928427) (xy 65.553962 -38.944783) (xy 65.635996 -38.969127)
			(xy 65.715315 -39.001234) (xy 65.791184 -39.040809) (xy 65.862904 -39.087485) (xy 65.92981 -39.140832)
			(xy 65.991286 -39.200355) (xy 66.046763 -39.265506) (xy 66.095729 -39.335682) (xy 66.13773 -39.410236)
			(xy 66.17238 -39.488477) (xy 66.199358 -39.569684) (xy 66.218414 -39.653105) (xy 66.229373 -39.737971)
			(xy 66.231262 -39.780718) (xy 66.232335 -39.796369) (xy 66.24278 -39.825933) (xy 66.261695 -39.850939)
			(xy 66.287299 -39.869037) (xy 66.317184 -39.878522) (xy 66.332862 -39.879016) (xy 66.873882 -39.879016)
			(xy 66.887438 -39.878592) (xy 66.913595 -39.871461) (xy 66.936952 -39.857696) (xy 66.955863 -39.838269)
			(xy 66.968994 -39.81455) (xy 66.975419 -39.788211) (xy 66.974685 -39.761109) (xy 66.966844 -39.735157)
			(xy 66.952448 -39.712183) (xy 66.942716 -39.70274) (xy 66.923727 -39.684602) (xy 66.890405 -39.644018)
			(xy 66.862961 -39.599248) (xy 66.841914 -39.551138) (xy 66.827662 -39.500597) (xy 66.820473 -39.44858)
			(xy 66.820034 -39.422324) (xy 66.82052 -39.395055) (xy 66.828282 -39.341071) (xy 66.843647 -39.288741)
			(xy 66.866304 -39.239131) (xy 66.89579 -39.19325) (xy 66.931505 -39.152033) (xy 66.972722 -39.116318)
			(xy 67.018603 -39.086832) (xy 67.068213 -39.064175) (xy 67.120543 -39.04881) (xy 67.174527 -39.041048)
			(xy 67.229065 -39.041048) (xy 67.283049 -39.04881) (xy 67.335379 -39.064175) (xy 67.384989 -39.086832)
			(xy 67.43087 -39.116318) (xy 67.472087 -39.152033) (xy 67.507802 -39.19325) (xy 67.537288 -39.239131)
			(xy 67.559945 -39.288741) (xy 67.57531 -39.341071) (xy 67.583072 -39.395055) (xy 67.583558 -39.422324)
			(xy 67.58312 -39.448579) (xy 67.575921 -39.500594) (xy 67.561664 -39.551132) (xy 67.540616 -39.599239)
			(xy 67.513175 -39.644009) (xy 67.479859 -39.684596) (xy 67.460876 -39.70274) (xy 67.451205 -39.712234)
			(xy 67.436822 -39.73519) (xy 67.428987 -39.761123) (xy 67.428254 -39.788204) (xy 67.434674 -39.814522)
			(xy 67.447794 -39.838223) (xy 67.46669 -39.857636) (xy 67.490029 -39.871391) (xy 67.516165 -39.878518)
			(xy 67.52971 -39.879016) (xy 72.855582 -39.879016) (xy 72.867001 -39.878557) (xy 72.88763 -39.868775)
			(xy 72.895206 -39.86022) (xy 72.895206 -39.859966) (xy 72.899186 -39.854744) (xy 72.904587 -39.842782)
			(xy 72.905874 -39.836344) (xy 72.905874 -39.835836) (xy 72.905874 -39.835582) (xy 72.910512 -39.808941)
			(xy 72.926314 -39.757227) (xy 72.949256 -39.708259) (xy 72.978877 -39.66302) (xy 73.014587 -39.622412)
			(xy 73.055669 -39.58725) (xy 73.101301 -39.558237) (xy 73.150571 -39.535953) (xy 73.202493 -39.520845)
			(xy 73.256027 -39.513215) (xy 73.310101 -39.513215) (xy 73.363635 -39.520845) (xy 73.415557 -39.535953)
			(xy 73.464827 -39.558237) (xy 73.510459 -39.58725) (xy 73.551541 -39.622412) (xy 73.587251 -39.66302)
			(xy 73.616872 -39.708259) (xy 73.639814 -39.757227) (xy 73.655616 -39.808941) (xy 73.660254 -39.835582)
			(xy 73.660254 -39.835836) (xy 73.660254 -39.836344) (xy 73.661536 -39.842784) (xy 73.666931 -39.854752)
			(xy 73.670922 -39.859966) (xy 73.670922 -39.86022) (xy 73.678593 -39.86865) (xy 73.699164 -39.878398)
			(xy 73.710546 -39.879016) (xy 75.024996 -39.879016) (xy 75.027536 -39.878762) (xy 75.0316 -39.878254)
			(xy 75.036004 -39.877394) (xy 75.044433 -39.874321) (xy 75.048364 -39.872158) (xy 75.077652 -39.855659)
			(xy 75.139649 -39.829675) (xy 75.204531 -39.812095) (xy 75.271166 -39.803228) (xy 75.338388 -39.803228)
			(xy 75.405023 -39.812095) (xy 75.469905 -39.829675) (xy 75.531902 -39.855659) (xy 75.56119 -39.872158)
			(xy 75.567286 -39.87546) (xy 75.579986 -39.879016) (xy 75.593448 -39.879016) (xy 75.603515 -39.878585)
			(xy 75.622108 -39.87086) (xy 75.629516 -39.86403) (xy 76.55814 -38.935406) (xy 76.558648 -38.934898)
			(xy 76.565223 -38.927514) (xy 76.572657 -38.909215) (xy 76.573126 -38.899338) (xy 76.573126 -38.213284)
			(xy 76.572672 -38.199541) (xy 76.565337 -38.173053) (xy 76.551201 -38.149481) (xy 76.531291 -38.130534)
			(xy 76.507047 -38.117584) (xy 76.480228 -38.11157) (xy 76.452777 -38.112928) (xy 76.426682 -38.121559)
			(xy 76.403835 -38.136838) (xy 76.394564 -38.14699) (xy 76.376351 -38.167384) (xy 76.335093 -38.203263)
			(xy 76.289136 -38.232886) (xy 76.239423 -38.255648) (xy 76.18697 -38.271083) (xy 76.132851 -38.278873)
			(xy 76.105512 -38.279324) (xy 76.078243 -38.278861) (xy 76.02426 -38.271101) (xy 75.971931 -38.255738)
			(xy 75.922322 -38.233083) (xy 75.876441 -38.203599) (xy 75.835224 -38.167885) (xy 75.799508 -38.126669)
			(xy 75.770023 -38.080789) (xy 75.747366 -38.03118) (xy 75.732001 -37.978851) (xy 75.724239 -37.924869)
			(xy 75.724239 -37.870331) (xy 75.732001 -37.816349) (xy 75.747366 -37.76402) (xy 75.770023 -37.714411)
			(xy 75.799508 -37.668531) (xy 75.835224 -37.627315) (xy 75.876441 -37.591601) (xy 75.922322 -37.562117)
			(xy 75.971931 -37.539462) (xy 76.02426 -37.524099) (xy 76.078243 -37.516339) (xy 76.105512 -37.5158)
			(xy 76.132849 -37.516268) (xy 76.186964 -37.524067) (xy 76.239414 -37.539503) (xy 76.289127 -37.562261)
			(xy 76.335086 -37.591876) (xy 76.376352 -37.627742) (xy 76.394564 -37.648134) (xy 76.403874 -37.658242)
			(xy 76.42671 -37.673509) (xy 76.452791 -37.682132) (xy 76.480226 -37.683488) (xy 76.50703 -37.677478)
			(xy 76.53126 -37.664536) (xy 76.551161 -37.645602) (xy 76.565292 -37.622046) (xy 76.572628 -37.595574)
			(xy 76.573126 -37.58184) (xy 76.573126 -34.868866) (xy 76.572697 -34.858798) (xy 76.564977 -34.8402)
			(xy 76.55814 -34.832798) (xy 71.987664 -30.262322) (xy 71.983528 -30.258436) (xy 71.973914 -30.252411)
			(xy 71.968614 -30.250384) (xy 71.957692 -30.246574) (xy 71.946008 -30.247844) (xy 71.92076 -30.250576)
			(xy 71.870056 -30.253501) (xy 71.844662 -30.253686) (xy 71.803549 -30.253209) (xy 71.721673 -30.245619)
			(xy 71.640846 -30.230507) (xy 71.561759 -30.208002) (xy 71.485085 -30.178297) (xy 71.411479 -30.141643)
			(xy 71.341569 -30.098355) (xy 71.275951 -30.048801) (xy 71.215185 -29.993405) (xy 71.15979 -29.932638)
			(xy 71.110237 -29.867019) (xy 71.06695 -29.797108) (xy 71.030298 -29.723502) (xy 71.000593 -29.646828)
			(xy 70.978089 -29.56774) (xy 70.962979 -29.486914) (xy 70.95539 -29.405037) (xy 70.9549 -29.363924)
			(xy 70.955117 -29.339423) (xy 70.957913 -29.2905) (xy 70.960488 -29.266134) (xy 70.960488 -29.265626)
			(xy 70.960996 -29.261308) (xy 70.961328 -29.255888) (xy 70.959914 -29.245125) (xy 70.958202 -29.239972)
			(xy 70.954392 -29.22905) (xy 70.198488 -28.473146) (xy 70.187865 -28.463169) (xy 70.1623 -28.449198)
			(xy 70.133832 -28.443013) (xy 70.104775 -28.445115) (xy 70.077494 -28.455335) (xy 70.054207 -28.47284)
			(xy 70.036809 -28.496208) (xy 70.031356 -28.509722) (xy 70.016829 -28.547401) (xy 69.981716 -28.620127)
			(xy 69.939973 -28.689261) (xy 69.891964 -28.754201) (xy 69.838108 -28.81438) (xy 69.778874 -28.869274)
			(xy 69.714778 -28.918404) (xy 69.64638 -28.961342) (xy 69.574275 -28.997713) (xy 69.499092 -29.027201)
			(xy 69.421487 -29.049549) (xy 69.342135 -29.064561) (xy 69.261729 -29.072107) (xy 69.22135 -29.072586)
			(xy 69.221096 -29.072586) (xy 69.177331 -29.07202) (xy 69.090251 -29.063152) (xy 69.004511 -29.045537)
			(xy 68.920988 -29.019356) (xy 68.840535 -28.984876) (xy 68.801996 -28.964128) (xy 68.796154 -28.960826)
			(xy 68.783708 -28.957778) (xy 68.777558 -28.956419) (xy 68.764966 -28.956419) (xy 68.758816 -28.957778)
			(xy 68.74637 -28.960826) (xy 68.740528 -28.964128) (xy 68.701988 -28.984875) (xy 68.621543 -29.01938)
			(xy 68.538021 -29.045574) (xy 68.452278 -29.063188) (xy 68.365194 -29.072042) (xy 68.321428 -29.072586)
			(xy 68.321174 -29.072586) (xy 68.276738 -29.072003) (xy 68.188338 -29.062857) (xy 68.101341 -29.044697)
			(xy 68.016664 -29.017712) (xy 67.935201 -28.982188) (xy 67.896232 -28.960826) (xy 67.888437 -28.956862)
			(xy 67.871213 -28.953903) (xy 67.853989 -28.956862) (xy 67.846194 -28.960826) (xy 67.807226 -28.982191)
			(xy 67.72577 -29.017737) (xy 67.641094 -29.044728) (xy 67.554094 -29.062882) (xy 67.465689 -29.072004)
			(xy 67.421252 -29.072586) (xy 67.376816 -29.072001) (xy 67.288417 -29.062854) (xy 67.201421 -29.044691)
			(xy 67.116745 -29.017705) (xy 67.035283 -28.982179) (xy 66.99631 -28.960826) (xy 66.988515 -28.956862)
			(xy 66.971291 -28.953903) (xy 66.954067 -28.956862) (xy 66.946272 -28.960826) (xy 66.907305 -28.982195)
			(xy 66.82585 -29.017748) (xy 66.741174 -29.044747) (xy 66.654174 -29.062908) (xy 66.565768 -29.072038)
			(xy 66.52133 -29.072586) (xy 66.47889 -29.072084) (xy 66.394418 -29.063767) (xy 66.311169 -29.04721)
			(xy 66.229943 -29.022574) (xy 66.151523 -28.990094) (xy 66.076664 -28.950084) (xy 66.006088 -28.90293)
			(xy 65.940473 -28.849085) (xy 65.880452 -28.789067) (xy 65.826602 -28.723456) (xy 65.779443 -28.652882)
			(xy 65.739429 -28.578026) (xy 65.706944 -28.499608) (xy 65.682303 -28.418384) (xy 65.665741 -28.335135)
			(xy 65.657419 -28.250664) (xy 65.656968 -28.208224) (xy 65.656968 -28.207462) (xy 65.657395 -28.169834)
			(xy 65.663983 -28.094867) (xy 65.677069 -28.020757) (xy 65.696555 -27.948067) (xy 65.709038 -27.912568)
			(xy 65.709038 -27.912314) (xy 65.710562 -27.907996) (xy 65.712086 -27.899614) (xy 65.712778 -27.895195)
			(xy 65.712782 -27.886252) (xy 65.712086 -27.881834) (xy 65.710562 -27.873706) (xy 65.709038 -27.869642)
			(xy 65.70345 -27.853386) (xy 65.698116 -27.837892) (xy 65.6717 -27.818842) (xy 64.873124 -27.818842)
			(xy 64.859274 -27.819306) (xy 64.832594 -27.826749) (xy 64.808899 -27.841094) (xy 64.789935 -27.861283)
			(xy 64.7771 -27.885828) (xy 64.771339 -27.912921) (xy 64.773077 -27.940566) (xy 64.782186 -27.966724)
			(xy 64.797995 -27.989469) (xy 64.808354 -27.998674) (xy 64.832663 -28.019443) (xy 64.876424 -28.066059)
			(xy 64.914001 -28.117789) (xy 64.944801 -28.173819) (xy 64.96834 -28.233267) (xy 64.984246 -28.295195)
			(xy 64.992268 -28.358627) (xy 64.992758 -28.390596) (xy 64.992319 -28.420928) (xy 64.985107 -28.481162)
			(xy 64.970784 -28.540111) (xy 64.949554 -28.596939) (xy 64.921718 -28.65084) (xy 64.887671 -28.701049)
			(xy 64.847896 -28.746854) (xy 64.802957 -28.787605) (xy 64.753491 -28.822723) (xy 64.727074 -28.837636)
			(xy 64.714257 -28.845203) (xy 64.693336 -28.866355) (xy 64.679391 -28.892635) (xy 64.673603 -28.921818)
			(xy 64.676464 -28.95143) (xy 64.681608 -28.965398) (xy 64.693744 -28.996251) (xy 64.710825 -29.060313)
			(xy 64.719439 -29.12605) (xy 64.719962 -29.1592) (xy 64.71946 -29.191177) (xy 64.711445 -29.254627)
			(xy 64.69554 -29.316572) (xy 64.671997 -29.376034) (xy 64.641187 -29.432078) (xy 64.603595 -29.483818)
			(xy 64.559816 -29.530438) (xy 64.510538 -29.571204) (xy 64.45654 -29.605472) (xy 64.398673 -29.632703)
			(xy 64.337849 -29.652466) (xy 64.275028 -29.664449) (xy 64.2112 -29.668465) (xy 64.147372 -29.664449)
			(xy 64.084551 -29.652466) (xy 64.023727 -29.632703) (xy 63.96586 -29.605472) (xy 63.911862 -29.571204)
			(xy 63.862584 -29.530438) (xy 63.818805 -29.483818) (xy 63.781213 -29.432078) (xy 63.750403 -29.376034)
			(xy 63.72686 -29.316572) (xy 63.710955 -29.254627) (xy 63.70294 -29.191177) (xy 63.702438 -29.1592)
			(xy 63.702877 -29.128868) (xy 63.71009 -29.068634) (xy 63.724413 -29.009685) (xy 63.745643 -28.952857)
			(xy 63.773479 -28.898957) (xy 63.807526 -28.848748) (xy 63.847301 -28.802943) (xy 63.89224 -28.762193)
			(xy 63.941706 -28.727074) (xy 63.968122 -28.71216) (xy 63.980929 -28.704586) (xy 64.001829 -28.683429)
			(xy 64.015759 -28.657154) (xy 64.02154 -28.627981) (xy 64.018683 -28.598379) (xy 64.013588 -28.584398)
			(xy 64.001453 -28.553545) (xy 63.984372 -28.489483) (xy 63.975759 -28.423746) (xy 63.975234 -28.390596)
			(xy 63.975736 -28.358627) (xy 63.983749 -28.295193) (xy 63.99965 -28.233264) (xy 64.023186 -28.173816)
			(xy 64.053986 -28.117786) (xy 64.091566 -28.066058) (xy 64.135333 -28.019448) (xy 64.159638 -27.998674)
			(xy 64.170008 -27.989479) (xy 64.185808 -27.966723) (xy 64.194909 -27.940557) (xy 64.196643 -27.912908)
			(xy 64.190882 -27.88581) (xy 64.178049 -27.861258) (xy 64.15909 -27.841059) (xy 64.135398 -27.826699)
			(xy 64.108719 -27.819235) (xy 64.094868 -27.818842) (xy 61.354208 -27.818842) (xy 61.344138 -27.819265)
			(xy 61.325536 -27.826982) (xy 61.31814 -27.833828) (xy 60.169806 -28.982162) (xy 60.162991 -28.989489)
			(xy 60.155249 -29.007926) (xy 60.155178 -29.027922) (xy 60.162791 -29.046413) (xy 60.169552 -29.05379)
			(xy 60.192292 -29.077665) (xy 60.232056 -29.130259) (xy 60.264695 -29.187548) (xy 60.289664 -29.248572)
			(xy 60.306543 -29.312309) (xy 60.315049 -29.377693) (xy 60.315602 -29.41066) (xy 60.31514 -29.441409)
			(xy 60.307732 -29.502459) (xy 60.29302 -29.56217) (xy 60.271217 -29.619673) (xy 60.242642 -29.674129)
			(xy 60.207711 -29.724743) (xy 60.166934 -29.770778) (xy 60.120906 -29.811562) (xy 60.070297 -29.8465)
			(xy 60.015846 -29.875084) (xy 59.958347 -29.896896) (xy 59.898637 -29.911618) (xy 59.837589 -29.919035)
			(xy 59.80684 -29.919422) (xy 59.80684 -29.919676) (xy 59.774643 -29.919184) (xy 59.710763 -29.911065)
			(xy 59.648418 -29.894952) (xy 59.588603 -29.871103) (xy 59.560206 -29.855922) (xy 59.558936 -29.85516)
			(xy 59.552586 -29.852112) (xy 59.550808 -29.85135) (xy 59.518734 -29.838119) (xy 59.4582 -29.804217)
			(xy 59.430158 -29.783786) (xy 59.422654 -29.778573) (xy 59.40516 -29.773348) (xy 59.386944 -29.774598)
			(xy 59.370328 -29.782165) (xy 59.36361 -29.788358) (xy 57.950862 -31.201106) (xy 57.943461 -31.207946)
			(xy 57.924863 -31.215665) (xy 57.914794 -31.216092) (xy 55.397908 -31.216092) (xy 55.390958 -31.21585)
			(xy 55.377568 -31.21211) (xy 55.371492 -31.208726) (xy 55.36565 -31.20517) (xy 55.358284 -31.202884)
			(xy 55.344568 -31.201106) (xy 46.566328 -31.201106) (xy 46.556303 -31.201521) (xy 46.537778 -31.209186)
			(xy 46.523598 -31.223359) (xy 46.515925 -31.241882) (xy 46.515528 -31.251906) (xy 46.515528 -31.595953)
			(xy 59.218134 -31.595953) (xy 59.223349 -31.533052) (xy 59.236304 -31.47128) (xy 59.256801 -31.411585)
			(xy 59.284525 -31.354883) (xy 59.319049 -31.302047) (xy 59.359843 -31.253886) (xy 59.406282 -31.211141)
			(xy 59.457651 -31.174469) (xy 59.513162 -31.144433) (xy 59.571962 -31.121494) (xy 59.633148 -31.106004)
			(xy 59.69578 -31.098201) (xy 59.727338 -31.097728) (xy 59.757256 -31.09814) (xy 59.816681 -31.105137)
			(xy 59.874876 -31.119053) (xy 59.903106 -31.12897) (xy 59.916309 -31.13334) (xy 59.944021 -31.13555)
			(xy 59.971301 -31.130197) (xy 59.996122 -31.117678) (xy 60.016643 -31.098923) (xy 60.031338 -31.075325)
			(xy 60.039117 -31.048636) (xy 60.039402 -31.020837) (xy 60.036202 -31.007304) (xy 60.028005 -30.974836)
			(xy 60.019209 -30.908452) (xy 60.018676 -30.87497) (xy 60.019145 -30.843416) (xy 60.026955 -30.780793)
			(xy 60.04245 -30.719617) (xy 60.065393 -30.660827) (xy 60.095432 -30.605326) (xy 60.132105 -30.553967)
			(xy 60.174848 -30.507539) (xy 60.223007 -30.466754) (xy 60.27584 -30.432239) (xy 60.332536 -30.404523)
			(xy 60.392225 -30.384033) (xy 60.453991 -30.371084) (xy 60.516883 -30.365874) (xy 60.579937 -30.368482)
			(xy 60.642185 -30.37887) (xy 60.702669 -30.396878) (xy 60.760462 -30.422228) (xy 60.814675 -30.454532)
			(xy 60.864477 -30.493294) (xy 60.909101 -30.537917) (xy 60.947863 -30.587718) (xy 60.980168 -30.641931)
			(xy 61.00552 -30.699723) (xy 61.023128 -30.758865) (xy 66.622162 -30.758865) (xy 66.622162 -30.694911)
			(xy 66.630177 -30.631461) (xy 66.646082 -30.569516) (xy 66.669625 -30.510054) (xy 66.700435 -30.45401)
			(xy 66.738027 -30.40227) (xy 66.781806 -30.35565) (xy 66.831084 -30.314884) (xy 66.885082 -30.280616)
			(xy 66.942949 -30.253385) (xy 67.003773 -30.233622) (xy 67.066594 -30.221639) (xy 67.130422 -30.217623)
			(xy 67.19425 -30.221639) (xy 67.257071 -30.233622) (xy 67.317895 -30.253385) (xy 67.375762 -30.280616)
			(xy 67.42976 -30.314884) (xy 67.479038 -30.35565) (xy 67.522817 -30.40227) (xy 67.560409 -30.45401)
			(xy 67.591219 -30.510054) (xy 67.614762 -30.569516) (xy 67.630667 -30.631461) (xy 67.638682 -30.694911)
			(xy 67.639184 -30.726888) (xy 67.638694 -30.75813) (xy 67.940936 -30.75813) (xy 67.94152 -30.725393)
			(xy 67.949923 -30.660461) (xy 67.966581 -30.597142) (xy 67.99122 -30.536481) (xy 68.023433 -30.47948)
			(xy 68.062687 -30.427079) (xy 68.108336 -30.380143) (xy 68.159626 -30.339446) (xy 68.215709 -30.305662)
			(xy 68.245482 -30.29204) (xy 68.258437 -30.285809) (xy 68.280486 -30.267383) (xy 68.296521 -30.24354)
			(xy 68.305272 -30.216171) (xy 68.306042 -30.187447) (xy 68.302886 -30.173422) (xy 68.297199 -30.149956)
			(xy 68.291082 -30.10206) (xy 68.290694 -30.077918) (xy 68.290694 -30.07741) (xy 68.291234 -30.050143)
			(xy 68.298993 -29.996163) (xy 68.314355 -29.943838) (xy 68.337006 -29.89423) (xy 68.366487 -29.848352)
			(xy 68.402197 -29.807135) (xy 68.443408 -29.77142) (xy 68.489283 -29.741932) (xy 68.538887 -29.719273)
			(xy 68.591211 -29.703904) (xy 68.645189 -29.696137) (xy 68.672456 -29.695648) (xy 68.699067 -29.69612)
			(xy 68.751774 -29.703507) (xy 68.802944 -29.718145) (xy 68.851585 -29.739748) (xy 68.896753 -29.767899)
			(xy 68.937572 -29.802052) (xy 68.973252 -29.841543) (xy 69.0031 -29.885608) (xy 69.026537 -29.933393)
			(xy 69.043109 -29.983969) (xy 69.052494 -30.036357) (xy 69.053964 -30.062932) (xy 69.054945 -30.076319)
			(xy 69.06297 -30.101923) (xy 69.077378 -30.124559) (xy 69.097178 -30.142667) (xy 69.121007 -30.155002)
			(xy 69.147224 -30.160715) (xy 69.160644 -30.160468) (xy 69.179694 -30.15996) (xy 69.206113 -30.160387)
			(xy 69.258446 -30.167679) (xy 69.309272 -30.182124) (xy 69.357617 -30.203445) (xy 69.402558 -30.231234)
			(xy 69.443233 -30.26496) (xy 69.46138 -30.284166) (xy 69.470649 -30.293782) (xy 69.493168 -30.308132)
			(xy 69.518639 -30.316152) (xy 69.545317 -30.317292) (xy 69.571379 -30.311475) (xy 69.595041 -30.299099)
			(xy 69.614684 -30.28101) (xy 69.622162 -30.269942) (xy 69.63973 -30.243259) (xy 69.680493 -30.194066)
			(xy 69.727095 -30.150365) (xy 69.778803 -30.112844) (xy 69.834802 -30.082094) (xy 69.894211 -30.058598)
			(xy 69.956095 -30.042726) (xy 70.019479 -30.034729) (xy 70.051422 -30.03423) (xy 70.083398 -30.034749)
			(xy 70.146844 -30.042767) (xy 70.208786 -30.058673) (xy 70.268245 -30.082217) (xy 70.324285 -30.113028)
			(xy 70.376022 -30.150619) (xy 70.42264 -30.194397) (xy 70.463403 -30.243673) (xy 70.497669 -30.29767)
			(xy 70.524897 -30.355535) (xy 70.544659 -30.416356) (xy 70.556642 -30.479175) (xy 70.560657 -30.543)
			(xy 70.556642 -30.606825) (xy 70.544659 -30.669644) (xy 70.524897 -30.730465) (xy 70.497669 -30.78833)
			(xy 70.463403 -30.842327) (xy 70.42264 -30.891603) (xy 70.376022 -30.935381) (xy 70.324285 -30.972972)
			(xy 70.268245 -31.003783) (xy 70.208786 -31.027327) (xy 70.146844 -31.043233) (xy 70.083398 -31.051251)
			(xy 70.051422 -31.051754) (xy 70.019388 -31.051265) (xy 69.955828 -31.043202) (xy 69.893783 -31.027226)
			(xy 69.834233 -31.003589) (xy 69.778121 -30.972665) (xy 69.726334 -30.934943) (xy 69.67969 -30.89102)
			(xy 69.638927 -30.841591) (xy 69.6214 -30.814772) (xy 69.613954 -30.803672) (xy 69.594354 -30.785514)
			(xy 69.570707 -30.773075) (xy 69.54464 -30.76721) (xy 69.517944 -30.768323) (xy 69.492455 -30.776338)
			(xy 69.469926 -30.790702) (xy 69.460618 -30.800294) (xy 69.442445 -30.819333) (xy 69.40182 -30.852792)
			(xy 69.356983 -30.880353) (xy 69.308785 -30.901494) (xy 69.258141 -30.915815) (xy 69.206009 -30.923044)
			(xy 69.179694 -30.923484) (xy 69.17944 -30.923484) (xy 69.145696 -30.922762) (xy 69.079262 -30.910884)
			(xy 69.04736 -30.899862) (xy 69.032599 -30.894964) (xy 69.001551 -30.89343) (xy 68.971482 -30.901317)
			(xy 68.945185 -30.917894) (xy 68.925101 -30.941621) (xy 68.918582 -30.955742) (xy 68.9052 -30.986061)
			(xy 68.871734 -31.043263) (xy 68.831127 -31.095637) (xy 68.784065 -31.142298) (xy 68.731346 -31.182457)
			(xy 68.67386 -31.215433) (xy 68.612581 -31.240669) (xy 68.548544 -31.257739) (xy 68.482834 -31.266353)
			(xy 68.449698 -31.266892) (xy 68.418953 -31.2664) (xy 68.357911 -31.258988) (xy 68.298207 -31.244273)
			(xy 68.240712 -31.222469) (xy 68.186264 -31.193893) (xy 68.135658 -31.158964) (xy 68.089631 -31.118189)
			(xy 68.048854 -31.072164) (xy 68.013921 -31.02156) (xy 67.985343 -30.967114) (xy 67.963536 -30.90962)
			(xy 67.948817 -30.849917) (xy 67.941402 -30.788875) (xy 67.940936 -30.75813) (xy 67.638694 -30.75813)
			(xy 67.638682 -30.758865) (xy 67.630667 -30.822315) (xy 67.614762 -30.88426) (xy 67.591219 -30.943722)
			(xy 67.560409 -30.999766) (xy 67.522817 -31.051506) (xy 67.479038 -31.098126) (xy 67.42976 -31.138892)
			(xy 67.375762 -31.17316) (xy 67.317895 -31.200391) (xy 67.257071 -31.220154) (xy 67.19425 -31.232137)
			(xy 67.130422 -31.236153) (xy 67.066594 -31.232137) (xy 67.003773 -31.220154) (xy 66.942949 -31.200391)
			(xy 66.885082 -31.17316) (xy 66.831084 -31.138892) (xy 66.781806 -31.098126) (xy 66.738027 -31.051506)
			(xy 66.700435 -30.999766) (xy 66.669625 -30.943722) (xy 66.646082 -30.88426) (xy 66.630177 -30.822315)
			(xy 66.622162 -30.758865) (xy 61.023128 -30.758865) (xy 61.023528 -30.760207) (xy 61.033917 -30.822455)
			(xy 61.036527 -30.885509) (xy 61.031317 -30.948401) (xy 61.018369 -31.010167) (xy 60.99788 -31.069856)
			(xy 60.970165 -31.126553) (xy 60.935651 -31.179387) (xy 60.894867 -31.227546) (xy 60.848439 -31.27029)
			(xy 60.79708 -31.306964) (xy 60.74158 -31.337003) (xy 60.682791 -31.359947) (xy 60.621615 -31.375444)
			(xy 60.558992 -31.383254) (xy 60.527438 -31.383732) (xy 60.49752 -31.383324) (xy 60.438095 -31.376325)
			(xy 60.3799 -31.362408) (xy 60.35167 -31.35249) (xy 60.338494 -31.348021) (xy 60.310765 -31.345812)
			(xy 60.28347 -31.351172) (xy 60.258636 -31.363703) (xy 60.238108 -31.382475) (xy 60.223412 -31.406092)
			(xy 60.215638 -31.432801) (xy 60.215365 -31.460616) (xy 60.218574 -31.474156) (xy 60.226784 -31.506621)
			(xy 60.235571 -31.573007) (xy 60.2361 -31.60649) (xy 60.235597 -31.638048) (xy 60.227791 -31.70068)
			(xy 60.212298 -31.761865) (xy 60.189355 -31.820663) (xy 60.159316 -31.876173) (xy 60.122641 -31.92754)
			(xy 60.079894 -31.973976) (xy 60.066669 -31.985177) (xy 67.05574 -31.985177) (xy 67.05574 -31.921223)
			(xy 67.063755 -31.857773) (xy 67.07966 -31.795828) (xy 67.103203 -31.736366) (xy 67.134013 -31.680322)
			(xy 67.171605 -31.628582) (xy 67.215384 -31.581962) (xy 67.264662 -31.541196) (xy 67.31866 -31.506928)
			(xy 67.376527 -31.479697) (xy 67.437351 -31.459934) (xy 67.500172 -31.447951) (xy 67.564 -31.443935)
			(xy 67.627828 -31.447951) (xy 67.690649 -31.459934) (xy 67.751473 -31.479697) (xy 67.80934 -31.506928)
			(xy 67.863338 -31.541196) (xy 67.912616 -31.581962) (xy 67.956395 -31.628582) (xy 67.993987 -31.680322)
			(xy 68.024797 -31.736366) (xy 68.04834 -31.795828) (xy 68.064245 -31.857773) (xy 68.07226 -31.921223)
			(xy 68.072762 -31.9532) (xy 68.07226 -31.985177) (xy 68.064245 -32.048627) (xy 68.04834 -32.110572)
			(xy 68.024797 -32.170034) (xy 67.993987 -32.226078) (xy 67.956395 -32.277818) (xy 67.912616 -32.324438)
			(xy 67.863338 -32.365204) (xy 67.80934 -32.399472) (xy 67.751473 -32.426703) (xy 67.690649 -32.446466)
			(xy 67.627828 -32.458449) (xy 67.564 -32.462465) (xy 67.500172 -32.458449) (xy 67.437351 -32.446466)
			(xy 67.376527 -32.426703) (xy 67.31866 -32.399472) (xy 67.264662 -32.365204) (xy 67.215384 -32.324438)
			(xy 67.171605 -32.277818) (xy 67.134013 -32.226078) (xy 67.103203 -32.170034) (xy 67.07966 -32.110572)
			(xy 67.063755 -32.048627) (xy 67.05574 -31.985177) (xy 60.066669 -31.985177) (xy 60.031731 -32.014768)
			(xy 59.978892 -32.049289) (xy 59.922189 -32.07701) (xy 59.862493 -32.097503) (xy 59.80072 -32.110455)
			(xy 59.737819 -32.115666) (xy 59.674757 -32.113057) (xy 59.612502 -32.102668) (xy 59.55201 -32.084657)
			(xy 59.494211 -32.059303) (xy 59.439991 -32.026993) (xy 59.390185 -31.988225) (xy 59.345556 -31.943594)
			(xy 59.306791 -31.893786) (xy 59.274484 -31.839564) (xy 59.249133 -31.781764) (xy 59.231126 -31.721271)
			(xy 59.22074 -31.659015) (xy 59.218134 -31.595953) (xy 46.515528 -31.595953) (xy 46.515528 -32.295084)
			(xy 56.527698 -32.295084) (xy 56.531771 -32.239425) (xy 56.543906 -32.184952) (xy 56.563842 -32.132826)
			(xy 56.591156 -32.084158) (xy 56.625264 -32.039986) (xy 56.665441 -32.001251) (xy 56.710829 -31.968779)
			(xy 56.760461 -31.943261) (xy 56.813281 -31.925242) (xy 56.86816 -31.915105) (xy 56.923931 -31.913067)
			(xy 56.979405 -31.91917) (xy 57.033398 -31.933286) (xy 57.084761 -31.955113) (xy 57.132399 -31.984186)
			(xy 57.175295 -32.019885) (xy 57.212537 -32.061449) (xy 57.243331 -32.107993) (xy 57.267019 -32.158524)
			(xy 57.283097 -32.211966) (xy 57.291223 -32.26718) (xy 57.291732 -32.295084) (xy 57.291223 -32.322988)
			(xy 57.283097 -32.378202) (xy 57.267019 -32.431644) (xy 57.243331 -32.482175) (xy 57.212537 -32.528719)
			(xy 57.175295 -32.570283) (xy 57.132399 -32.605982) (xy 57.084761 -32.635055) (xy 57.033398 -32.656882)
			(xy 56.979405 -32.670998) (xy 56.923931 -32.677101) (xy 56.86816 -32.675063) (xy 56.813281 -32.664926)
			(xy 56.760461 -32.646907) (xy 56.710829 -32.621389) (xy 56.665441 -32.588917) (xy 56.625264 -32.550182)
			(xy 56.591156 -32.50601) (xy 56.563842 -32.457342) (xy 56.543906 -32.405216) (xy 56.531771 -32.350743)
			(xy 56.527698 -32.295084) (xy 46.515528 -32.295084) (xy 46.515528 -32.937196) (xy 47.179228 -32.937196)
			(xy 47.183301 -32.881537) (xy 47.195436 -32.827064) (xy 47.215372 -32.774938) (xy 47.242686 -32.72627)
			(xy 47.276794 -32.682098) (xy 47.316971 -32.643363) (xy 47.362359 -32.610891) (xy 47.411991 -32.585373)
			(xy 47.464811 -32.567354) (xy 47.51969 -32.557217) (xy 47.575461 -32.555179) (xy 47.630935 -32.561282)
			(xy 47.684928 -32.575398) (xy 47.736291 -32.597225) (xy 47.783929 -32.626298) (xy 47.826825 -32.661997)
			(xy 47.864067 -32.703561) (xy 47.894861 -32.750105) (xy 47.918549 -32.800636) (xy 47.934627 -32.854078)
			(xy 47.942753 -32.909292) (xy 47.943262 -32.937196) (xy 47.942753 -32.9651) (xy 47.934627 -33.020314)
			(xy 47.918549 -33.073756) (xy 47.894861 -33.124287) (xy 47.864067 -33.170831) (xy 47.826825 -33.212395)
			(xy 47.783929 -33.248094) (xy 47.736291 -33.277167) (xy 47.684928 -33.298994) (xy 47.630935 -33.31311)
			(xy 47.621645 -33.314132) (xy 51.195222 -33.314132) (xy 51.199295 -33.258473) (xy 51.21143 -33.204)
			(xy 51.231366 -33.151874) (xy 51.25868 -33.103206) (xy 51.292788 -33.059034) (xy 51.332965 -33.020299)
			(xy 51.378353 -32.987827) (xy 51.427985 -32.962309) (xy 51.480805 -32.94429) (xy 51.535684 -32.934153)
			(xy 51.591455 -32.932115) (xy 51.646929 -32.938218) (xy 51.700922 -32.952334) (xy 51.752285 -32.974161)
			(xy 51.799923 -33.003234) (xy 51.842819 -33.038933) (xy 51.880061 -33.080497) (xy 51.907255 -33.1216)
			(xy 60.095638 -33.1216) (xy 60.096102 -33.090854) (xy 60.103514 -33.029809) (xy 60.11823 -32.970103)
			(xy 60.140036 -32.912607) (xy 60.168613 -32.858158) (xy 60.203545 -32.80755) (xy 60.244322 -32.761522)
			(xy 60.29035 -32.720745) (xy 60.340958 -32.685813) (xy 60.395407 -32.657236) (xy 60.452903 -32.63543)
			(xy 60.512609 -32.620714) (xy 60.573654 -32.613302) (xy 60.6044 -32.612838) (xy 60.637289 -32.613359)
			(xy 60.702516 -32.621851) (xy 60.766104 -32.63868) (xy 60.826992 -32.663566) (xy 60.884165 -32.696093)
			(xy 60.936667 -32.735718) (xy 60.960508 -32.75838) (xy 60.968885 -32.765846) (xy 60.990026 -32.77329)
			(xy 61.012324 -32.77102) (xy 61.02223 -32.765746) (xy 61.051888 -32.748669) (xy 61.114821 -32.72178)
			(xy 61.180795 -32.703585) (xy 61.248615 -32.694414) (xy 61.282834 -32.693864) (xy 61.313845 -32.694302)
			(xy 61.375404 -32.701856) (xy 61.435589 -32.716836) (xy 61.493507 -32.73902) (xy 61.5483 -32.768079)
			(xy 61.599154 -32.803582) (xy 61.645317 -32.845003) (xy 61.686103 -32.891727) (xy 61.720908 -32.943061)
			(xy 61.724009 -32.949107) (xy 69.543162 -32.949107) (xy 69.543162 -32.885153) (xy 69.551177 -32.821703)
			(xy 69.567082 -32.759758) (xy 69.590625 -32.700296) (xy 69.621435 -32.644252) (xy 69.659027 -32.592512)
			(xy 69.702806 -32.545892) (xy 69.752084 -32.505126) (xy 69.806082 -32.470858) (xy 69.863949 -32.443627)
			(xy 69.924773 -32.423864) (xy 69.987594 -32.411881) (xy 70.051422 -32.407865) (xy 70.11525 -32.411881)
			(xy 70.178071 -32.423864) (xy 70.238895 -32.443627) (xy 70.296762 -32.470858) (xy 70.35076 -32.505126)
			(xy 70.400038 -32.545892) (xy 70.443817 -32.592512) (xy 70.481409 -32.644252) (xy 70.512219 -32.700296)
			(xy 70.535762 -32.759758) (xy 70.551667 -32.821703) (xy 70.559682 -32.885153) (xy 70.560184 -32.91713)
			(xy 70.559682 -32.949107) (xy 70.551667 -33.012557) (xy 70.535762 -33.074502) (xy 70.512219 -33.133964)
			(xy 70.481409 -33.190008) (xy 70.443817 -33.241748) (xy 70.400038 -33.288368) (xy 70.35076 -33.329134)
			(xy 70.296762 -33.363402) (xy 70.238895 -33.390633) (xy 70.178071 -33.410396) (xy 70.11525 -33.422379)
			(xy 70.051422 -33.426395) (xy 69.987594 -33.422379) (xy 69.924773 -33.410396) (xy 69.863949 -33.390633)
			(xy 69.806082 -33.363402) (xy 69.752084 -33.329134) (xy 69.702806 -33.288368) (xy 69.659027 -33.241748)
			(xy 69.621435 -33.190008) (xy 69.590625 -33.133964) (xy 69.567082 -33.074502) (xy 69.551177 -33.012557)
			(xy 69.543162 -32.949107) (xy 61.724009 -32.949107) (xy 61.749216 -32.998246) (xy 61.770606 -33.056461)
			(xy 61.778134 -33.086548) (xy 61.780799 -33.095883) (xy 61.791945 -33.111757) (xy 61.808179 -33.122373)
			(xy 61.82719 -33.12622) (xy 61.836808 -33.124902) (xy 61.859529 -33.120984) (xy 61.905447 -33.116788)
			(xy 61.928502 -33.11652) (xy 61.959248 -33.117) (xy 62.020291 -33.124412) (xy 62.079995 -33.139128)
			(xy 62.137491 -33.160933) (xy 62.191939 -33.189509) (xy 62.242546 -33.224439) (xy 62.288574 -33.265215)
			(xy 62.329351 -33.311241) (xy 62.364283 -33.361847) (xy 62.392861 -33.416294) (xy 62.414667 -33.473789)
			(xy 62.429385 -33.533493) (xy 62.436799 -33.594536) (xy 62.437264 -33.625282) (xy 62.436799 -33.656029)
			(xy 62.429389 -33.717075) (xy 62.414675 -33.776782) (xy 62.39287 -33.834281) (xy 62.364294 -33.888732)
			(xy 62.329362 -33.939341) (xy 62.288585 -33.985371) (xy 62.262067 -34.008865) (xy 65.215068 -34.008865)
			(xy 65.215068 -33.954336) (xy 65.222828 -33.900361) (xy 65.23819 -33.848041) (xy 65.26084 -33.798439)
			(xy 65.290319 -33.752565) (xy 65.326026 -33.711353) (xy 65.367235 -33.675642) (xy 65.413106 -33.646159)
			(xy 65.462705 -33.623503) (xy 65.515024 -33.608136) (xy 65.568998 -33.600371) (xy 65.596262 -33.599882)
			(xy 65.622604 -33.600326) (xy 65.674785 -33.607578) (xy 65.725474 -33.621935) (xy 65.773709 -33.643124)
			(xy 65.818571 -33.670744) (xy 65.859211 -33.704269) (xy 65.894856 -33.743063) (xy 65.910206 -33.764474)
			(xy 65.91857 -33.77576) (xy 65.940243 -33.793615) (xy 65.965957 -33.804898) (xy 65.993772 -33.808756)
			(xy 66.021587 -33.804898) (xy 66.047301 -33.793615) (xy 66.068974 -33.77576) (xy 66.077338 -33.764474)
			(xy 66.092724 -33.743088) (xy 66.128355 -33.704285) (xy 66.168986 -33.670751) (xy 66.213843 -33.643126)
			(xy 66.262074 -33.621933) (xy 66.312761 -33.607575) (xy 66.364941 -33.600326) (xy 66.391282 -33.599882)
			(xy 66.418557 -33.600256) (xy 66.472552 -33.608017) (xy 66.524893 -33.623384) (xy 66.574514 -33.646043)
			(xy 66.620405 -33.675533) (xy 66.661632 -33.711255) (xy 66.697356 -33.75248) (xy 66.726848 -33.79837)
			(xy 66.74951 -33.84799) (xy 66.764879 -33.90033) (xy 66.772642 -33.954325) (xy 66.772642 -34.008875)
			(xy 66.764879 -34.06287) (xy 66.74951 -34.11521) (xy 66.726848 -34.16483) (xy 66.697356 -34.21072)
			(xy 66.661632 -34.251945) (xy 66.620405 -34.287667) (xy 66.574514 -34.317157) (xy 66.524893 -34.339816)
			(xy 66.472552 -34.355183) (xy 66.418557 -34.362944) (xy 66.391282 -34.363406) (xy 66.364939 -34.363009)
			(xy 66.312755 -34.35575) (xy 66.262064 -34.341385) (xy 66.21383 -34.320188) (xy 66.168968 -34.292561)
			(xy 66.128329 -34.259029) (xy 66.092687 -34.220228) (xy 66.077338 -34.198814) (xy 66.068974 -34.187528)
			(xy 66.047301 -34.169673) (xy 66.021587 -34.15839) (xy 65.993772 -34.154532) (xy 65.965957 -34.15839)
			(xy 65.940243 -34.169673) (xy 65.91857 -34.187528) (xy 65.910206 -34.198814) (xy 65.894882 -34.220246)
			(xy 65.859237 -34.259044) (xy 65.818594 -34.292571) (xy 65.773727 -34.32019) (xy 65.725487 -34.341375)
			(xy 65.674792 -34.355725) (xy 65.622605 -34.362966) (xy 65.596262 -34.363406) (xy 65.568998 -34.362829)
			(xy 65.515024 -34.355064) (xy 65.462705 -34.339697) (xy 65.413106 -34.317041) (xy 65.367235 -34.287558)
			(xy 65.326026 -34.251847) (xy 65.290319 -34.210635) (xy 65.26084 -34.164761) (xy 65.23819 -34.115159)
			(xy 65.222828 -34.062839) (xy 65.215068 -34.008865) (xy 62.262067 -34.008865) (xy 62.242557 -34.02615)
			(xy 62.191949 -34.061083) (xy 62.137499 -34.089662) (xy 62.080002 -34.111469) (xy 62.020295 -34.126186)
			(xy 61.959249 -34.133598) (xy 61.928502 -34.134044) (xy 61.897493 -34.133567) (xy 61.835935 -34.126017)
			(xy 61.775751 -34.111041) (xy 61.717834 -34.088862) (xy 61.663041 -34.059807) (xy 61.612187 -34.024308)
			(xy 61.566024 -33.982891) (xy 61.525237 -33.936171) (xy 61.490431 -33.88484) (xy 61.462122 -33.829658)
			(xy 61.44073 -33.771445) (xy 61.433202 -33.74136) (xy 61.430599 -33.732002) (xy 61.419437 -33.71612)
			(xy 61.403182 -33.705507) (xy 61.384152 -33.701676) (xy 61.374528 -33.703006) (xy 61.351806 -33.70692)
			(xy 61.305889 -33.711118) (xy 61.282834 -33.711388) (xy 61.249945 -33.710866) (xy 61.184717 -33.702377)
			(xy 61.121128 -33.68555) (xy 61.060239 -33.660664) (xy 61.003067 -33.628136) (xy 60.950566 -33.588509)
			(xy 60.926726 -33.565846) (xy 60.918326 -33.558409) (xy 60.897198 -33.550954) (xy 60.874908 -33.553212)
			(xy 60.865004 -33.55848) (xy 60.83534 -33.575546) (xy 60.772409 -33.602437) (xy 60.706436 -33.620635)
			(xy 60.638618 -33.62981) (xy 60.6044 -33.630362) (xy 60.573654 -33.629898) (xy 60.512609 -33.622486)
			(xy 60.452903 -33.60777) (xy 60.395407 -33.585964) (xy 60.340958 -33.557387) (xy 60.29035 -33.522455)
			(xy 60.244322 -33.481678) (xy 60.203545 -33.43565) (xy 60.168613 -33.385042) (xy 60.140036 -33.330593)
			(xy 60.11823 -33.273097) (xy 60.103514 -33.213391) (xy 60.096102 -33.152346) (xy 60.095638 -33.1216)
			(xy 51.907255 -33.1216) (xy 51.910855 -33.127041) (xy 51.934543 -33.177572) (xy 51.950621 -33.231014)
			(xy 51.958747 -33.286228) (xy 51.959256 -33.314132) (xy 51.958747 -33.342036) (xy 51.950621 -33.39725)
			(xy 51.934543 -33.450692) (xy 51.910855 -33.501223) (xy 51.880061 -33.547767) (xy 51.842819 -33.589331)
			(xy 51.799923 -33.62503) (xy 51.752285 -33.654103) (xy 51.700922 -33.67593) (xy 51.646929 -33.690046)
			(xy 51.591455 -33.696149) (xy 51.535684 -33.694111) (xy 51.480805 -33.683974) (xy 51.427985 -33.665955)
			(xy 51.378353 -33.640437) (xy 51.332965 -33.607965) (xy 51.292788 -33.56923) (xy 51.25868 -33.525058)
			(xy 51.231366 -33.47639) (xy 51.21143 -33.424264) (xy 51.199295 -33.369791) (xy 51.195222 -33.314132)
			(xy 47.621645 -33.314132) (xy 47.575461 -33.319213) (xy 47.51969 -33.317175) (xy 47.464811 -33.307038)
			(xy 47.411991 -33.289019) (xy 47.362359 -33.263501) (xy 47.316971 -33.231029) (xy 47.276794 -33.192294)
			(xy 47.242686 -33.148122) (xy 47.215372 -33.099454) (xy 47.195436 -33.047328) (xy 47.183301 -32.992855)
			(xy 47.179228 -32.937196) (xy 46.515528 -32.937196) (xy 46.515528 -33.749488) (xy 46.515108 -33.75956)
			(xy 46.5074 -33.77817) (xy 46.500542 -33.785556) (xy 45.561504 -34.724594) (xy 45.554106 -34.731442)
			(xy 45.535508 -34.739179) (xy 45.525436 -34.73958) (xy 20.980908 -34.73958) (xy 20.970919 -34.740115)
			(xy 20.952483 -34.747824) (xy 20.945094 -34.754566) (xy 20.383968 -35.315625) (xy 51.330092 -35.315625)
			(xy 51.330092 -35.251671) (xy 51.338107 -35.188221) (xy 51.354012 -35.126276) (xy 51.377555 -35.066814)
			(xy 51.408365 -35.01077) (xy 51.445957 -34.95903) (xy 51.489736 -34.91241) (xy 51.539014 -34.871644)
			(xy 51.593012 -34.837376) (xy 51.650879 -34.810145) (xy 51.711703 -34.790382) (xy 51.774524 -34.778399)
			(xy 51.838352 -34.774383) (xy 51.90218 -34.778399) (xy 51.965001 -34.790382) (xy 52.025825 -34.810145)
			(xy 52.083692 -34.837376) (xy 52.13769 -34.871644) (xy 52.147195 -34.879507) (xy 58.745876 -34.879507)
			(xy 58.745876 -34.815553) (xy 58.753891 -34.752103) (xy 58.769796 -34.690158) (xy 58.793339 -34.630696)
			(xy 58.824149 -34.574652) (xy 58.861741 -34.522912) (xy 58.90552 -34.476292) (xy 58.954798 -34.435526)
			(xy 59.008796 -34.401258) (xy 59.066663 -34.374027) (xy 59.127487 -34.354264) (xy 59.190308 -34.342281)
			(xy 59.254136 -34.338265) (xy 59.317964 -34.342281) (xy 59.380785 -34.354264) (xy 59.441609 -34.374027)
			(xy 59.499476 -34.401258) (xy 59.553474 -34.435526) (xy 59.602752 -34.476292) (xy 59.646531 -34.522912)
			(xy 59.684123 -34.574652) (xy 59.714933 -34.630696) (xy 59.738476 -34.690158) (xy 59.754381 -34.752103)
			(xy 59.762396 -34.815553) (xy 59.762898 -34.84753) (xy 59.762396 -34.879507) (xy 59.754381 -34.942957)
			(xy 59.738476 -35.004902) (xy 59.714933 -35.064364) (xy 59.684123 -35.120408) (xy 59.646531 -35.172148)
			(xy 59.602752 -35.218768) (xy 59.553474 -35.259534) (xy 59.499476 -35.293802) (xy 59.441609 -35.321033)
			(xy 59.380785 -35.340796) (xy 59.317964 -35.352779) (xy 59.254136 -35.356795) (xy 59.190308 -35.352779)
			(xy 59.127487 -35.340796) (xy 59.066663 -35.321033) (xy 59.008796 -35.293802) (xy 58.954798 -35.259534)
			(xy 58.90552 -35.218768) (xy 58.861741 -35.172148) (xy 58.824149 -35.120408) (xy 58.793339 -35.064364)
			(xy 58.769796 -35.004902) (xy 58.753891 -34.942957) (xy 58.745876 -34.879507) (xy 52.147195 -34.879507)
			(xy 52.186968 -34.91241) (xy 52.230747 -34.95903) (xy 52.268339 -35.01077) (xy 52.299149 -35.066814)
			(xy 52.322692 -35.126276) (xy 52.338597 -35.188221) (xy 52.346612 -35.251671) (xy 52.347114 -35.283648)
			(xy 52.346612 -35.315625) (xy 52.338597 -35.379075) (xy 52.322692 -35.44102) (xy 52.299149 -35.500482)
			(xy 52.268339 -35.556526) (xy 52.230747 -35.608266) (xy 52.186968 -35.654886) (xy 52.13769 -35.695652)
			(xy 52.083692 -35.72992) (xy 52.025825 -35.757151) (xy 51.965001 -35.776914) (xy 51.90218 -35.788897)
			(xy 51.838352 -35.792913) (xy 51.774524 -35.788897) (xy 51.711703 -35.776914) (xy 51.650879 -35.757151)
			(xy 51.593012 -35.72992) (xy 51.539014 -35.695652) (xy 51.489736 -35.654886) (xy 51.445957 -35.608266)
			(xy 51.408365 -35.556526) (xy 51.377555 -35.500482) (xy 51.354012 -35.44102) (xy 51.338107 -35.379075)
			(xy 51.330092 -35.315625) (xy 20.383968 -35.315625) (xy 19.220762 -36.478691) (xy 20.326344 -36.478691)
			(xy 20.326344 -36.414737) (xy 20.334359 -36.351287) (xy 20.350264 -36.289342) (xy 20.373807 -36.22988)
			(xy 20.404617 -36.173836) (xy 20.442209 -36.122096) (xy 20.485988 -36.075476) (xy 20.535266 -36.03471)
			(xy 20.589264 -36.000442) (xy 20.647131 -35.973211) (xy 20.707955 -35.953448) (xy 20.770776 -35.941465)
			(xy 20.834604 -35.937449) (xy 20.898432 -35.941465) (xy 20.961253 -35.953448) (xy 21.022077 -35.973211)
			(xy 21.079944 -36.000442) (xy 21.133942 -36.03471) (xy 21.18322 -36.075476) (xy 21.226999 -36.122096)
			(xy 21.264591 -36.173836) (xy 21.295401 -36.22988) (xy 21.318944 -36.289342) (xy 21.334849 -36.351287)
			(xy 21.342864 -36.414737) (xy 21.343366 -36.446714) (xy 21.342864 -36.478691) (xy 21.337345 -36.522379)
			(xy 21.624538 -36.522379) (xy 21.624538 -36.458425) (xy 21.632553 -36.394975) (xy 21.648458 -36.33303)
			(xy 21.672001 -36.273568) (xy 21.702811 -36.217524) (xy 21.740403 -36.165784) (xy 21.784182 -36.119164)
			(xy 21.83346 -36.078398) (xy 21.887458 -36.04413) (xy 21.945325 -36.016899) (xy 22.006149 -35.997136)
			(xy 22.06897 -35.985153) (xy 22.132798 -35.981137) (xy 22.196626 -35.985153) (xy 22.259447 -35.997136)
			(xy 22.320271 -36.016899) (xy 22.378138 -36.04413) (xy 22.432136 -36.078398) (xy 22.481414 -36.119164)
			(xy 22.525193 -36.165784) (xy 22.562785 -36.217524) (xy 22.593595 -36.273568) (xy 22.617138 -36.33303)
			(xy 22.633043 -36.394975) (xy 22.641058 -36.458425) (xy 22.64156 -36.490402) (xy 22.641058 -36.522379)
			(xy 22.634962 -36.570639) (xy 22.909778 -36.570639) (xy 22.909778 -36.506685) (xy 22.917793 -36.443235)
			(xy 22.933698 -36.38129) (xy 22.957241 -36.321828) (xy 22.988051 -36.265784) (xy 23.025643 -36.214044)
			(xy 23.069422 -36.167424) (xy 23.1187 -36.126658) (xy 23.172698 -36.09239) (xy 23.230565 -36.065159)
			(xy 23.291389 -36.045396) (xy 23.35421 -36.033413) (xy 23.418038 -36.029397) (xy 23.481866 -36.033413)
			(xy 23.544687 -36.045396) (xy 23.605511 -36.065159) (xy 23.663378 -36.09239) (xy 23.717376 -36.126658)
			(xy 23.766654 -36.167424) (xy 23.810433 -36.214044) (xy 23.848025 -36.265784) (xy 23.878835 -36.321828)
			(xy 23.891564 -36.353977) (xy 47.75174 -36.353977) (xy 47.75174 -36.290023) (xy 47.759755 -36.226573)
			(xy 47.77566 -36.164628) (xy 47.799203 -36.105166) (xy 47.830013 -36.049122) (xy 47.867605 -35.997382)
			(xy 47.911384 -35.950762) (xy 47.960662 -35.909996) (xy 48.01466 -35.875728) (xy 48.072527 -35.848497)
			(xy 48.133351 -35.828734) (xy 48.196172 -35.816751) (xy 48.26 -35.812735) (xy 48.323828 -35.816751)
			(xy 48.386649 -35.828734) (xy 48.447473 -35.848497) (xy 48.50534 -35.875728) (xy 48.559338 -35.909996)
			(xy 48.608616 -35.950762) (xy 48.652395 -35.997382) (xy 48.689987 -36.049122) (xy 48.720797 -36.105166)
			(xy 48.74434 -36.164628) (xy 48.760245 -36.226573) (xy 48.765561 -36.26866) (xy 51.811934 -36.26866)
			(xy 51.816007 -36.213001) (xy 51.828142 -36.158528) (xy 51.848078 -36.106402) (xy 51.875392 -36.057734)
			(xy 51.9095 -36.013562) (xy 51.949677 -35.974827) (xy 51.995065 -35.942355) (xy 52.044697 -35.916837)
			(xy 52.097517 -35.898818) (xy 52.152396 -35.888681) (xy 52.208167 -35.886643) (xy 52.263641 -35.892746)
			(xy 52.317634 -35.906862) (xy 52.368997 -35.928689) (xy 52.416635 -35.957762) (xy 52.459531 -35.993461)
			(xy 52.496773 -36.035025) (xy 52.527567 -36.081569) (xy 52.539397 -36.106805) (xy 60.067694 -36.106805)
			(xy 60.067694 -36.022083) (xy 60.075747 -35.937746) (xy 60.091781 -35.854556) (xy 60.115649 -35.773266)
			(xy 60.147137 -35.694614) (xy 60.185959 -35.619311) (xy 60.231762 -35.548039) (xy 60.284133 -35.481443)
			(xy 60.342598 -35.420128) (xy 60.406626 -35.364647) (xy 60.475638 -35.315504) (xy 60.549008 -35.273144)
			(xy 60.626073 -35.237949) (xy 60.706135 -35.21024) (xy 60.788468 -35.190266) (xy 60.872327 -35.178209)
			(xy 60.956952 -35.174178) (xy 61.041577 -35.178209) (xy 61.045124 -35.178719) (xy 64.664584 -35.178719)
			(xy 64.664584 -35.114765) (xy 64.672599 -35.051315) (xy 64.688504 -34.98937) (xy 64.712047 -34.929908)
			(xy 64.742857 -34.873864) (xy 64.780449 -34.822124) (xy 64.824228 -34.775504) (xy 64.873506 -34.734738)
			(xy 64.927504 -34.70047) (xy 64.985371 -34.673239) (xy 65.046195 -34.653476) (xy 65.109016 -34.641493)
			(xy 65.172844 -34.637477) (xy 65.236672 -34.641493) (xy 65.299493 -34.653476) (xy 65.360317 -34.673239)
			(xy 65.418184 -34.70047) (xy 65.472182 -34.734738) (xy 65.52146 -34.775504) (xy 65.565239 -34.822124)
			(xy 65.602831 -34.873864) (xy 65.633641 -34.929908) (xy 65.657184 -34.98937) (xy 65.673089 -35.051315)
			(xy 65.681104 -35.114765) (xy 65.681606 -35.146742) (xy 65.681104 -35.178719) (xy 65.673089 -35.242169)
			(xy 65.657184 -35.304114) (xy 65.633641 -35.363576) (xy 65.602831 -35.41962) (xy 65.565239 -35.47136)
			(xy 65.52146 -35.51798) (xy 65.472182 -35.558746) (xy 65.418184 -35.593014) (xy 65.360317 -35.620245)
			(xy 65.299493 -35.640008) (xy 65.236672 -35.651991) (xy 65.172844 -35.656007) (xy 65.109016 -35.651991)
			(xy 65.046195 -35.640008) (xy 64.985371 -35.620245) (xy 64.927504 -35.593014) (xy 64.873506 -35.558746)
			(xy 64.824228 -35.51798) (xy 64.780449 -35.47136) (xy 64.742857 -35.41962) (xy 64.712047 -35.363576)
			(xy 64.688504 -35.304114) (xy 64.672599 -35.242169) (xy 64.664584 -35.178719) (xy 61.045124 -35.178719)
			(xy 61.125436 -35.190266) (xy 61.207769 -35.21024) (xy 61.287831 -35.237949) (xy 61.364896 -35.273144)
			(xy 61.438266 -35.315504) (xy 61.507278 -35.364647) (xy 61.571306 -35.420128) (xy 61.629771 -35.481443)
			(xy 61.682142 -35.548039) (xy 61.727945 -35.619311) (xy 61.756018 -35.673765) (xy 68.116952 -35.673765)
			(xy 68.116952 -35.609811) (xy 68.124967 -35.546361) (xy 68.140872 -35.484416) (xy 68.164415 -35.424954)
			(xy 68.195225 -35.36891) (xy 68.232817 -35.31717) (xy 68.276596 -35.27055) (xy 68.325874 -35.229784)
			(xy 68.379872 -35.195516) (xy 68.437739 -35.168285) (xy 68.498563 -35.148522) (xy 68.561384 -35.136539)
			(xy 68.625212 -35.132523) (xy 68.68904 -35.136539) (xy 68.751861 -35.148522) (xy 68.812685 -35.168285)
			(xy 68.870552 -35.195516) (xy 68.92455 -35.229784) (xy 68.973828 -35.27055) (xy 69.017607 -35.31717)
			(xy 69.055199 -35.36891) (xy 69.086009 -35.424954) (xy 69.109552 -35.484416) (xy 69.125457 -35.546361)
			(xy 69.133472 -35.609811) (xy 69.133974 -35.641788) (xy 69.133472 -35.673765) (xy 69.128884 -35.710087)
			(xy 69.804274 -35.710087) (xy 69.804274 -35.646133) (xy 69.812289 -35.582683) (xy 69.828194 -35.520738)
			(xy 69.851737 -35.461276) (xy 69.882547 -35.405232) (xy 69.920139 -35.353492) (xy 69.963918 -35.306872)
			(xy 70.013196 -35.266106) (xy 70.067194 -35.231838) (xy 70.125061 -35.204607) (xy 70.185885 -35.184844)
			(xy 70.248706 -35.172861) (xy 70.312534 -35.168845) (xy 70.376362 -35.172861) (xy 70.439183 -35.184844)
			(xy 70.500007 -35.204607) (xy 70.557874 -35.231838) (xy 70.611872 -35.266106) (xy 70.66115 -35.306872)
			(xy 70.704929 -35.353492) (xy 70.742521 -35.405232) (xy 70.773331 -35.461276) (xy 70.785377 -35.4917)
			(xy 71.385088 -35.4917) (xy 71.389105 -35.427863) (xy 71.401091 -35.365032) (xy 71.420858 -35.304199)
			(xy 71.448094 -35.246324) (xy 71.482369 -35.192319) (xy 71.523143 -35.143036) (xy 71.569772 -35.099252)
			(xy 71.621522 -35.061658) (xy 71.677575 -35.030847) (xy 71.737049 -35.007304) (xy 71.799004 -34.991402)
			(xy 71.862464 -34.98339) (xy 71.894446 -34.982912) (xy 71.926204 -34.983413) (xy 71.989226 -34.991331)
			(xy 72.050773 -35.007026) (xy 72.109891 -35.030254) (xy 72.16566 -35.060655) (xy 72.217215 -35.097756)
			(xy 72.263755 -35.140982) (xy 72.304557 -35.18966) (xy 72.322182 -35.216084) (xy 72.330211 -35.227589)
			(xy 72.351245 -35.246131) (xy 72.376531 -35.258251) (xy 72.40416 -35.263036) (xy 72.432048 -35.260123)
			(xy 72.458093 -35.249733) (xy 72.480328 -35.23265) (xy 72.48906 -35.221672) (xy 72.509729 -35.194898)
			(xy 72.556978 -35.146499) (xy 72.610224 -35.104787) (xy 72.668527 -35.070498) (xy 72.73086 -35.044238)
			(xy 72.796123 -35.026468) (xy 72.863165 -35.017504) (xy 72.896984 -35.016948) (xy 72.928964 -35.017409)
			(xy 72.992419 -35.025423) (xy 73.054369 -35.041327) (xy 73.113837 -35.064871) (xy 73.169886 -35.095682)
			(xy 73.22163 -35.133275) (xy 73.268255 -35.177058) (xy 73.309025 -35.226338) (xy 73.343297 -35.280341)
			(xy 73.37053 -35.338212) (xy 73.390294 -35.399041) (xy 73.402279 -35.461867) (xy 73.406296 -35.5257)
			(xy 73.402279 -35.589533) (xy 73.390294 -35.652359) (xy 73.37053 -35.713188) (xy 73.343297 -35.771059)
			(xy 73.309025 -35.825062) (xy 73.268255 -35.874342) (xy 73.22163 -35.918125) (xy 73.169886 -35.955718)
			(xy 73.113837 -35.986529) (xy 73.054369 -36.010073) (xy 72.992419 -36.025977) (xy 72.928964 -36.033991)
			(xy 72.896984 -36.034472) (xy 72.865226 -36.033955) (xy 72.802205 -36.026041) (xy 72.740658 -36.010349)
			(xy 72.68154 -35.987123) (xy 72.625771 -35.956724) (xy 72.574215 -35.919625) (xy 72.527675 -35.8764)
			(xy 72.486873 -35.827723) (xy 72.469248 -35.8013) (xy 72.461307 -35.78973) (xy 72.440252 -35.771188)
			(xy 72.414948 -35.759072) (xy 72.387302 -35.754297) (xy 72.3594 -35.757221) (xy 72.333345 -35.767626)
			(xy 72.311103 -35.784725) (xy 72.30237 -35.795712) (xy 72.281678 -35.822468) (xy 72.234434 -35.870869)
			(xy 72.181192 -35.912583) (xy 72.122893 -35.946874) (xy 72.060563 -35.973137) (xy 71.995304 -35.99091)
			(xy 71.928264 -35.999878) (xy 71.894446 -36.000436) (xy 71.862464 -36.00001) (xy 71.799004 -35.991998)
			(xy 71.737049 -35.976096) (xy 71.677575 -35.952553) (xy 71.621522 -35.921742) (xy 71.569772 -35.884148)
			(xy 71.523143 -35.840364) (xy 71.482369 -35.791081) (xy 71.448094 -35.737076) (xy 71.420858 -35.679201)
			(xy 71.401091 -35.618368) (xy 71.389105 -35.555537) (xy 71.385088 -35.4917) (xy 70.785377 -35.4917)
			(xy 70.796874 -35.520738) (xy 70.812779 -35.582683) (xy 70.820794 -35.646133) (xy 70.821296 -35.67811)
			(xy 70.820794 -35.710087) (xy 70.812779 -35.773537) (xy 70.796874 -35.835482) (xy 70.773331 -35.894944)
			(xy 70.742521 -35.950988) (xy 70.704929 -36.002728) (xy 70.66115 -36.049348) (xy 70.611872 -36.090114)
			(xy 70.557874 -36.124382) (xy 70.500007 -36.151613) (xy 70.439183 -36.171376) (xy 70.376362 -36.183359)
			(xy 70.312534 -36.187375) (xy 70.248706 -36.183359) (xy 70.185885 -36.171376) (xy 70.125061 -36.151613)
			(xy 70.067194 -36.124382) (xy 70.013196 -36.090114) (xy 69.963918 -36.049348) (xy 69.920139 -36.002728)
			(xy 69.882547 -35.950988) (xy 69.851737 -35.894944) (xy 69.828194 -35.835482) (xy 69.812289 -35.773537)
			(xy 69.804274 -35.710087) (xy 69.128884 -35.710087) (xy 69.125457 -35.737215) (xy 69.109552 -35.79916)
			(xy 69.086009 -35.858622) (xy 69.055199 -35.914666) (xy 69.017607 -35.966406) (xy 68.973828 -36.013026)
			(xy 68.92455 -36.053792) (xy 68.870552 -36.08806) (xy 68.812685 -36.115291) (xy 68.751861 -36.135054)
			(xy 68.68904 -36.147037) (xy 68.625212 -36.151053) (xy 68.561384 -36.147037) (xy 68.498563 -36.135054)
			(xy 68.437739 -36.115291) (xy 68.379872 -36.08806) (xy 68.325874 -36.053792) (xy 68.276596 -36.013026)
			(xy 68.232817 -35.966406) (xy 68.195225 -35.914666) (xy 68.164415 -35.858622) (xy 68.140872 -35.79916)
			(xy 68.124967 -35.737215) (xy 68.116952 -35.673765) (xy 61.756018 -35.673765) (xy 61.766767 -35.694614)
			(xy 61.798255 -35.773266) (xy 61.822123 -35.854556) (xy 61.838157 -35.937746) (xy 61.84621 -36.022083)
			(xy 61.846714 -36.064444) (xy 61.84621 -36.106805) (xy 61.838157 -36.191142) (xy 61.822123 -36.274332)
			(xy 61.798255 -36.355622) (xy 61.766767 -36.434274) (xy 61.727945 -36.509577) (xy 61.682142 -36.580849)
			(xy 61.629771 -36.647445) (xy 61.620393 -36.65728) (xy 63.675258 -36.65728) (xy 63.679331 -36.601621)
			(xy 63.691466 -36.547148) (xy 63.711402 -36.495022) (xy 63.738716 -36.446354) (xy 63.772824 -36.402182)
			(xy 63.813001 -36.363447) (xy 63.858389 -36.330975) (xy 63.908021 -36.305457) (xy 63.960841 -36.287438)
			(xy 64.01572 -36.277301) (xy 64.071491 -36.275263) (xy 64.126965 -36.281366) (xy 64.180958 -36.295482)
			(xy 64.232321 -36.317309) (xy 64.279959 -36.346382) (xy 64.322855 -36.382081) (xy 64.360097 -36.423645)
			(xy 64.390891 -36.470189) (xy 64.414579 -36.52072) (xy 64.430657 -36.574162) (xy 64.438783 -36.629376)
			(xy 64.439292 -36.65728) (xy 64.438783 -36.685184) (xy 64.430657 -36.740398) (xy 64.414579 -36.79384)
			(xy 64.390891 -36.844371) (xy 64.360097 -36.890915) (xy 64.322855 -36.932479) (xy 64.279959 -36.968178)
			(xy 64.232321 -36.997251) (xy 64.180958 -37.019078) (xy 64.126965 -37.033194) (xy 64.071491 -37.039297)
			(xy 64.01572 -37.037259) (xy 63.960841 -37.027122) (xy 63.908021 -37.009103) (xy 63.858389 -36.983585)
			(xy 63.813001 -36.951113) (xy 63.772824 -36.912378) (xy 63.738716 -36.868206) (xy 63.711402 -36.819538)
			(xy 63.691466 -36.767412) (xy 63.679331 -36.712939) (xy 63.675258 -36.65728) (xy 61.620393 -36.65728)
			(xy 61.571306 -36.70876) (xy 61.507278 -36.764241) (xy 61.438266 -36.813384) (xy 61.364896 -36.855744)
			(xy 61.287831 -36.890939) (xy 61.207769 -36.918648) (xy 61.125436 -36.938622) (xy 61.041577 -36.950679)
			(xy 60.956952 -36.954711) (xy 60.872327 -36.950679) (xy 60.788468 -36.938622) (xy 60.706135 -36.918648)
			(xy 60.626073 -36.890939) (xy 60.549008 -36.855744) (xy 60.475638 -36.813384) (xy 60.406626 -36.764241)
			(xy 60.342598 -36.70876) (xy 60.284133 -36.647445) (xy 60.231762 -36.580849) (xy 60.185959 -36.509577)
			(xy 60.147137 -36.434274) (xy 60.115649 -36.355622) (xy 60.091781 -36.274332) (xy 60.075747 -36.191142)
			(xy 60.067694 -36.106805) (xy 52.539397 -36.106805) (xy 52.551255 -36.1321) (xy 52.567333 -36.185542)
			(xy 52.575459 -36.240756) (xy 52.575968 -36.26866) (xy 52.575459 -36.296564) (xy 52.567333 -36.351778)
			(xy 52.551255 -36.40522) (xy 52.527567 -36.455751) (xy 52.496773 -36.502295) (xy 52.459531 -36.543859)
			(xy 52.416635 -36.579558) (xy 52.368997 -36.608631) (xy 52.317634 -36.630458) (xy 52.263641 -36.644574)
			(xy 52.208167 -36.650677) (xy 52.152396 -36.648639) (xy 52.097517 -36.638502) (xy 52.044697 -36.620483)
			(xy 51.995065 -36.594965) (xy 51.949677 -36.562493) (xy 51.9095 -36.523758) (xy 51.875392 -36.479586)
			(xy 51.848078 -36.430918) (xy 51.828142 -36.378792) (xy 51.816007 -36.324319) (xy 51.811934 -36.26866)
			(xy 48.765561 -36.26866) (xy 48.76826 -36.290023) (xy 48.768762 -36.322) (xy 48.76826 -36.353977)
			(xy 48.760245 -36.417427) (xy 48.74434 -36.479372) (xy 48.720797 -36.538834) (xy 48.689987 -36.594878)
			(xy 48.652395 -36.646618) (xy 48.608616 -36.693238) (xy 48.559338 -36.734004) (xy 48.50534 -36.768272)
			(xy 48.447473 -36.795503) (xy 48.386649 -36.815266) (xy 48.323828 -36.827249) (xy 48.26 -36.831265)
			(xy 48.196172 -36.827249) (xy 48.133351 -36.815266) (xy 48.072527 -36.795503) (xy 48.01466 -36.768272)
			(xy 47.960662 -36.734004) (xy 47.911384 -36.693238) (xy 47.867605 -36.646618) (xy 47.830013 -36.594878)
			(xy 47.799203 -36.538834) (xy 47.77566 -36.479372) (xy 47.759755 -36.417427) (xy 47.75174 -36.353977)
			(xy 23.891564 -36.353977) (xy 23.902378 -36.38129) (xy 23.918283 -36.443235) (xy 23.926298 -36.506685)
			(xy 23.9268 -36.538662) (xy 23.926298 -36.570639) (xy 23.918283 -36.634089) (xy 23.902378 -36.696034)
			(xy 23.878835 -36.755496) (xy 23.848025 -36.81154) (xy 23.810433 -36.86328) (xy 23.766654 -36.9099)
			(xy 23.717376 -36.950666) (xy 23.663378 -36.984934) (xy 23.605511 -37.012165) (xy 23.544687 -37.031928)
			(xy 23.481866 -37.043911) (xy 23.418038 -37.047927) (xy 23.35421 -37.043911) (xy 23.291389 -37.031928)
			(xy 23.230565 -37.012165) (xy 23.172698 -36.984934) (xy 23.1187 -36.950666) (xy 23.069422 -36.9099)
			(xy 23.025643 -36.86328) (xy 22.988051 -36.81154) (xy 22.957241 -36.755496) (xy 22.933698 -36.696034)
			(xy 22.917793 -36.634089) (xy 22.909778 -36.570639) (xy 22.634962 -36.570639) (xy 22.633043 -36.585829)
			(xy 22.617138 -36.647774) (xy 22.593595 -36.707236) (xy 22.562785 -36.76328) (xy 22.525193 -36.81502)
			(xy 22.481414 -36.86164) (xy 22.432136 -36.902406) (xy 22.378138 -36.936674) (xy 22.320271 -36.963905)
			(xy 22.259447 -36.983668) (xy 22.196626 -36.995651) (xy 22.132798 -36.999667) (xy 22.06897 -36.995651)
			(xy 22.006149 -36.983668) (xy 21.945325 -36.963905) (xy 21.887458 -36.936674) (xy 21.83346 -36.902406)
			(xy 21.784182 -36.86164) (xy 21.740403 -36.81502) (xy 21.702811 -36.76328) (xy 21.672001 -36.707236)
			(xy 21.648458 -36.647774) (xy 21.632553 -36.585829) (xy 21.624538 -36.522379) (xy 21.337345 -36.522379)
			(xy 21.334849 -36.542141) (xy 21.318944 -36.604086) (xy 21.295401 -36.663548) (xy 21.264591 -36.719592)
			(xy 21.226999 -36.771332) (xy 21.18322 -36.817952) (xy 21.133942 -36.858718) (xy 21.079944 -36.892986)
			(xy 21.022077 -36.920217) (xy 20.961253 -36.93998) (xy 20.898432 -36.951963) (xy 20.834604 -36.955979)
			(xy 20.770776 -36.951963) (xy 20.707955 -36.93998) (xy 20.647131 -36.920217) (xy 20.589264 -36.892986)
			(xy 20.535266 -36.858718) (xy 20.485988 -36.817952) (xy 20.442209 -36.771332) (xy 20.404617 -36.719592)
			(xy 20.373807 -36.663548) (xy 20.350264 -36.604086) (xy 20.334359 -36.542141) (xy 20.326344 -36.478691)
			(xy 19.220762 -36.478691) (xy 18.824702 -36.874704) (xy 18.396712 -37.302694) (xy 18.389092 -37.321236)
			(xy 18.389092 -37.331142) (xy 18.386359 -37.343854) (xy 18.386705 -37.369844) (xy 18.393602 -37.394905)
			(xy 18.398879 -37.40404) (xy 45.98492 -37.40404) (xy 45.988993 -37.348381) (xy 46.001128 -37.293908)
			(xy 46.021064 -37.241782) (xy 46.048378 -37.193114) (xy 46.082486 -37.148942) (xy 46.122663 -37.110207)
			(xy 46.168051 -37.077735) (xy 46.217683 -37.052217) (xy 46.270503 -37.034198) (xy 46.325382 -37.024061)
			(xy 46.381153 -37.022023) (xy 46.436627 -37.028126) (xy 46.49062 -37.042242) (xy 46.541983 -37.064069)
			(xy 46.589621 -37.093142) (xy 46.632517 -37.128841) (xy 46.669759 -37.170405) (xy 46.700553 -37.216949)
			(xy 46.724241 -37.26748) (xy 46.740319 -37.320922) (xy 46.748445 -37.376136) (xy 46.748954 -37.40404)
			(xy 46.748445 -37.431944) (xy 46.740319 -37.487158) (xy 46.724241 -37.5406) (xy 46.700553 -37.591131)
			(xy 46.669759 -37.637675) (xy 46.632517 -37.679239) (xy 46.589621 -37.714938) (xy 46.541983 -37.744011)
			(xy 46.49062 -37.765838) (xy 46.436627 -37.779954) (xy 46.390397 -37.78504) (xy 52.134768 -37.78504)
			(xy 52.138841 -37.729381) (xy 52.150976 -37.674908) (xy 52.170912 -37.622782) (xy 52.198226 -37.574114)
			(xy 52.232334 -37.529942) (xy 52.272511 -37.491207) (xy 52.317899 -37.458735) (xy 52.367531 -37.433217)
			(xy 52.420351 -37.415198) (xy 52.47523 -37.405061) (xy 52.531001 -37.403023) (xy 52.586475 -37.409126)
			(xy 52.640468 -37.423242) (xy 52.691831 -37.445069) (xy 52.739469 -37.474142) (xy 52.782365 -37.509841)
			(xy 52.819607 -37.551405) (xy 52.850401 -37.597949) (xy 52.862602 -37.623977) (xy 58.92774 -37.623977)
			(xy 58.92774 -37.560023) (xy 58.935755 -37.496573) (xy 58.95166 -37.434628) (xy 58.975203 -37.375166)
			(xy 59.006013 -37.319122) (xy 59.043605 -37.267382) (xy 59.087384 -37.220762) (xy 59.136662 -37.179996)
			(xy 59.19066 -37.145728) (xy 59.248527 -37.118497) (xy 59.309351 -37.098734) (xy 59.372172 -37.086751)
			(xy 59.436 -37.082735) (xy 59.499828 -37.086751) (xy 59.562649 -37.098734) (xy 59.623473 -37.118497)
			(xy 59.68134 -37.145728) (xy 59.735338 -37.179996) (xy 59.784616 -37.220762) (xy 59.828395 -37.267382)
			(xy 59.865987 -37.319122) (xy 59.896797 -37.375166) (xy 59.92034 -37.434628) (xy 59.92103 -37.437314)
			(xy 66.390772 -37.437314) (xy 66.394845 -37.381655) (xy 66.40698 -37.327182) (xy 66.426916 -37.275056)
			(xy 66.45423 -37.226388) (xy 66.488338 -37.182216) (xy 66.528515 -37.143481) (xy 66.573903 -37.111009)
			(xy 66.623535 -37.085491) (xy 66.676355 -37.067472) (xy 66.731234 -37.057335) (xy 66.787005 -37.055297)
			(xy 66.842479 -37.0614) (xy 66.896472 -37.075516) (xy 66.947835 -37.097343) (xy 66.995473 -37.126416)
			(xy 67.038369 -37.162115) (xy 67.075611 -37.203679) (xy 67.106405 -37.250223) (xy 67.130093 -37.300754)
			(xy 67.146171 -37.354196) (xy 67.154297 -37.40941) (xy 67.154806 -37.437314) (xy 67.154297 -37.465218)
			(xy 67.146171 -37.520432) (xy 67.130093 -37.573874) (xy 67.106405 -37.624405) (xy 67.075611 -37.670949)
			(xy 67.038369 -37.712513) (xy 66.995473 -37.748212) (xy 66.947835 -37.777285) (xy 66.896472 -37.799112)
			(xy 66.842479 -37.813228) (xy 66.787005 -37.819331) (xy 66.731234 -37.817293) (xy 66.676355 -37.807156)
			(xy 66.623535 -37.789137) (xy 66.573903 -37.763619) (xy 66.528515 -37.731147) (xy 66.488338 -37.692412)
			(xy 66.45423 -37.64824) (xy 66.426916 -37.599572) (xy 66.40698 -37.547446) (xy 66.394845 -37.492973)
			(xy 66.390772 -37.437314) (xy 59.92103 -37.437314) (xy 59.936245 -37.496573) (xy 59.94426 -37.560023)
			(xy 59.944762 -37.592) (xy 59.94426 -37.623977) (xy 59.936245 -37.687427) (xy 59.92034 -37.749372)
			(xy 59.896797 -37.808834) (xy 59.865987 -37.864878) (xy 59.828395 -37.916618) (xy 59.784616 -37.963238)
			(xy 59.735338 -38.004004) (xy 59.68134 -38.038272) (xy 59.623473 -38.065503) (xy 59.562649 -38.085266)
			(xy 59.499828 -38.097249) (xy 59.436 -38.101265) (xy 59.372172 -38.097249) (xy 59.309351 -38.085266)
			(xy 59.248527 -38.065503) (xy 59.19066 -38.038272) (xy 59.136662 -38.004004) (xy 59.087384 -37.963238)
			(xy 59.043605 -37.916618) (xy 59.006013 -37.864878) (xy 58.975203 -37.808834) (xy 58.95166 -37.749372)
			(xy 58.935755 -37.687427) (xy 58.92774 -37.623977) (xy 52.862602 -37.623977) (xy 52.874089 -37.64848)
			(xy 52.890167 -37.701922) (xy 52.898293 -37.757136) (xy 52.898802 -37.78504) (xy 52.898293 -37.812944)
			(xy 52.890167 -37.868158) (xy 52.874089 -37.9216) (xy 52.850401 -37.972131) (xy 52.819607 -38.018675)
			(xy 52.782365 -38.060239) (xy 52.739469 -38.095938) (xy 52.691831 -38.125011) (xy 52.640468 -38.146838)
			(xy 52.586475 -38.160954) (xy 52.531001 -38.167057) (xy 52.47523 -38.165019) (xy 52.420351 -38.154882)
			(xy 52.367531 -38.136863) (xy 52.317899 -38.111345) (xy 52.272511 -38.078873) (xy 52.232334 -38.040138)
			(xy 52.198226 -37.995966) (xy 52.170912 -37.947298) (xy 52.150976 -37.895172) (xy 52.138841 -37.840699)
			(xy 52.134768 -37.78504) (xy 46.390397 -37.78504) (xy 46.381153 -37.786057) (xy 46.325382 -37.784019)
			(xy 46.270503 -37.773882) (xy 46.217683 -37.755863) (xy 46.168051 -37.730345) (xy 46.122663 -37.697873)
			(xy 46.082486 -37.659138) (xy 46.048378 -37.614966) (xy 46.021064 -37.566298) (xy 46.001128 -37.514172)
			(xy 45.988993 -37.459699) (xy 45.98492 -37.40404) (xy 18.398879 -37.40404) (xy 18.406604 -37.417412)
			(xy 18.424867 -37.435907) (xy 18.435828 -37.442902) (xy 18.437352 -37.443664) (xy 18.438114 -37.444172)
			(xy 18.4404 -37.445442) (xy 18.467181 -37.460212) (xy 18.517335 -37.495216) (xy 18.562931 -37.53598)
			(xy 18.603312 -37.581916) (xy 18.637895 -37.63236) (xy 18.666183 -37.686587) (xy 18.687765 -37.743814)
			(xy 18.702333 -37.803215) (xy 18.709675 -37.863933) (xy 18.710148 -37.894514) (xy 18.709695 -37.925034)
			(xy 18.702384 -37.985636) (xy 18.687868 -38.044926) (xy 18.666357 -38.102051) (xy 18.638159 -38.156189)
			(xy 18.603681 -38.20656) (xy 18.56342 -38.25244) (xy 18.517954 -38.293169) (xy 18.493232 -38.311074)
			(xy 18.492216 -38.311836) (xy 18.488914 -38.314376) (xy 18.478722 -38.323321) (xy 18.46306 -38.345447)
			(xy 18.453756 -38.370909) (xy 18.451462 -38.39792) (xy 18.452302 -38.402514) (xy 26.244294 -38.402514)
			(xy 26.248367 -38.346855) (xy 26.260502 -38.292382) (xy 26.280438 -38.240256) (xy 26.307752 -38.191588)
			(xy 26.34186 -38.147416) (xy 26.382037 -38.108681) (xy 26.427425 -38.076209) (xy 26.477057 -38.050691)
			(xy 26.529877 -38.032672) (xy 26.584756 -38.022535) (xy 26.640527 -38.020497) (xy 26.696001 -38.0266)
			(xy 26.749994 -38.040716) (xy 26.801357 -38.062543) (xy 26.848995 -38.091616) (xy 26.891891 -38.127315)
			(xy 26.929133 -38.168879) (xy 26.959927 -38.215423) (xy 26.983615 -38.265954) (xy 26.999693 -38.319396)
			(xy 27.007819 -38.37461) (xy 27.008328 -38.402514) (xy 27.007819 -38.430418) (xy 26.999693 -38.485632)
			(xy 26.983615 -38.539074) (xy 26.959927 -38.589605) (xy 26.929133 -38.636149) (xy 26.926613 -38.638961)
			(xy 59.462156 -38.638961) (xy 59.462156 -38.575007) (xy 59.470171 -38.511557) (xy 59.486076 -38.449612)
			(xy 59.509619 -38.39015) (xy 59.540429 -38.334106) (xy 59.578021 -38.282366) (xy 59.6218 -38.235746)
			(xy 59.671078 -38.19498) (xy 59.725076 -38.160712) (xy 59.782943 -38.133481) (xy 59.843767 -38.113718)
			(xy 59.906588 -38.101735) (xy 59.970416 -38.097719) (xy 60.034244 -38.101735) (xy 60.097065 -38.113718)
			(xy 60.157889 -38.133481) (xy 60.215756 -38.160712) (xy 60.269754 -38.19498) (xy 60.319032 -38.235746)
			(xy 60.362811 -38.282366) (xy 60.400403 -38.334106) (xy 60.431213 -38.39015) (xy 60.454756 -38.449612)
			(xy 60.470661 -38.511557) (xy 60.476042 -38.554152) (xy 61.140338 -38.554152) (xy 61.144411 -38.498493)
			(xy 61.156546 -38.44402) (xy 61.176482 -38.391894) (xy 61.203796 -38.343226) (xy 61.237904 -38.299054)
			(xy 61.278081 -38.260319) (xy 61.323469 -38.227847) (xy 61.373101 -38.202329) (xy 61.425921 -38.18431)
			(xy 61.4808 -38.174173) (xy 61.536571 -38.172135) (xy 61.592045 -38.178238) (xy 61.646038 -38.192354)
			(xy 61.697401 -38.214181) (xy 61.745039 -38.243254) (xy 61.787935 -38.278953) (xy 61.825177 -38.320517)
			(xy 61.855971 -38.367061) (xy 61.857583 -38.3705) (xy 65.682145 -38.3705) (xy 65.68616 -38.306675)
			(xy 65.698144 -38.243856) (xy 65.717905 -38.183034) (xy 65.745134 -38.125169) (xy 65.7794 -38.071173)
			(xy 65.820164 -38.021897) (xy 65.866782 -37.978118) (xy 65.918519 -37.940527) (xy 65.974559 -37.909717)
			(xy 66.034019 -37.886174) (xy 66.095961 -37.870268) (xy 66.159408 -37.862251) (xy 66.191384 -37.861748)
			(xy 66.223557 -37.862284) (xy 66.287388 -37.870402) (xy 66.349687 -37.886499) (xy 66.409462 -37.910318)
			(xy 66.465759 -37.941478) (xy 66.517681 -37.979484) (xy 66.5644 -38.02373) (xy 66.605172 -38.073509)
			(xy 66.622676 -38.100508) (xy 66.630577 -38.112305) (xy 66.651662 -38.131305) (xy 66.677162 -38.143766)
			(xy 66.705108 -38.148725) (xy 66.733338 -38.145799) (xy 66.759673 -38.135214) (xy 66.782076 -38.117788)
			(xy 66.790824 -38.106604) (xy 66.808785 -38.082673) (xy 66.849457 -38.038784) (xy 66.894999 -37.999972)
			(xy 66.944782 -37.966773) (xy 66.998116 -37.939646) (xy 67.054266 -37.918966) (xy 67.112454 -37.905018)
			(xy 67.171878 -37.897995) (xy 67.201796 -37.897562) (xy 67.233776 -37.897995) (xy 67.297232 -37.906011)
			(xy 67.359182 -37.921916) (xy 67.418651 -37.945461) (xy 67.4747 -37.976274) (xy 67.526445 -38.013868)
			(xy 67.57307 -38.057652) (xy 67.61384 -38.106934) (xy 67.648111 -38.160937) (xy 67.675344 -38.21881)
			(xy 67.695109 -38.279639) (xy 67.707094 -38.342466) (xy 67.71111 -38.4063) (xy 67.707094 -38.470134)
			(xy 67.695109 -38.532961) (xy 67.675344 -38.59379) (xy 67.648111 -38.651663) (xy 67.61384 -38.705666)
			(xy 67.588312 -38.736524) (xy 71.740774 -38.736524) (xy 71.744847 -38.680865) (xy 71.756982 -38.626392)
			(xy 71.776918 -38.574266) (xy 71.804232 -38.525598) (xy 71.83834 -38.481426) (xy 71.878517 -38.442691)
			(xy 71.923905 -38.410219) (xy 71.973537 -38.384701) (xy 72.026357 -38.366682) (xy 72.081236 -38.356545)
			(xy 72.137007 -38.354507) (xy 72.192481 -38.36061) (xy 72.246474 -38.374726) (xy 72.297837 -38.396553)
			(xy 72.345475 -38.425626) (xy 72.388371 -38.461325) (xy 72.425613 -38.502889) (xy 72.456407 -38.549433)
			(xy 72.480095 -38.599964) (xy 72.496173 -38.653406) (xy 72.504299 -38.70862) (xy 72.504808 -38.736524)
			(xy 72.504299 -38.764428) (xy 72.496173 -38.819642) (xy 72.480095 -38.873084) (xy 72.456407 -38.923615)
			(xy 72.425613 -38.970159) (xy 72.388371 -39.011723) (xy 72.345475 -39.047422) (xy 72.308437 -39.070026)
			(xy 74.43419 -39.070026) (xy 74.438263 -39.014367) (xy 74.450398 -38.959894) (xy 74.470334 -38.907768)
			(xy 74.497648 -38.8591) (xy 74.531756 -38.814928) (xy 74.571933 -38.776193) (xy 74.617321 -38.743721)
			(xy 74.666953 -38.718203) (xy 74.719773 -38.700184) (xy 74.774652 -38.690047) (xy 74.830423 -38.688009)
			(xy 74.885897 -38.694112) (xy 74.93989 -38.708228) (xy 74.991253 -38.730055) (xy 75.038891 -38.759128)
			(xy 75.081787 -38.794827) (xy 75.119029 -38.836391) (xy 75.149823 -38.882935) (xy 75.173511 -38.933466)
			(xy 75.189589 -38.986908) (xy 75.197715 -39.042122) (xy 75.198224 -39.070026) (xy 75.197715 -39.09793)
			(xy 75.189589 -39.153144) (xy 75.173511 -39.206586) (xy 75.149823 -39.257117) (xy 75.119029 -39.303661)
			(xy 75.081787 -39.345225) (xy 75.038891 -39.380924) (xy 74.991253 -39.409997) (xy 74.93989 -39.431824)
			(xy 74.885897 -39.44594) (xy 74.830423 -39.452043) (xy 74.774652 -39.450005) (xy 74.719773 -39.439868)
			(xy 74.666953 -39.421849) (xy 74.617321 -39.396331) (xy 74.571933 -39.363859) (xy 74.531756 -39.325124)
			(xy 74.497648 -39.280952) (xy 74.470334 -39.232284) (xy 74.450398 -39.180158) (xy 74.438263 -39.125685)
			(xy 74.43419 -39.070026) (xy 72.308437 -39.070026) (xy 72.297837 -39.076495) (xy 72.246474 -39.098322)
			(xy 72.192481 -39.112438) (xy 72.137007 -39.118541) (xy 72.081236 -39.116503) (xy 72.026357 -39.106366)
			(xy 71.973537 -39.088347) (xy 71.923905 -39.062829) (xy 71.878517 -39.030357) (xy 71.83834 -38.991622)
			(xy 71.804232 -38.94745) (xy 71.776918 -38.898782) (xy 71.756982 -38.846656) (xy 71.744847 -38.792183)
			(xy 71.740774 -38.736524) (xy 67.588312 -38.736524) (xy 67.57307 -38.754948) (xy 67.526445 -38.798732)
			(xy 67.4747 -38.836326) (xy 67.418651 -38.867139) (xy 67.359182 -38.890684) (xy 67.297232 -38.906589)
			(xy 67.233776 -38.914605) (xy 67.201796 -38.915086) (xy 67.169624 -38.91455) (xy 67.105793 -38.90643)
			(xy 67.043494 -38.890332) (xy 66.98372 -38.866513) (xy 66.927423 -38.835352) (xy 66.875501 -38.797347)
			(xy 66.828782 -38.753102) (xy 66.788009 -38.703324) (xy 66.770504 -38.676326) (xy 66.762629 -38.664509)
			(xy 66.741541 -38.645502) (xy 66.716035 -38.633037) (xy 66.688082 -38.628078) (xy 66.659844 -38.631009)
			(xy 66.633506 -38.641603) (xy 66.611103 -38.659041) (xy 66.602356 -38.67023) (xy 66.584388 -38.694156)
			(xy 66.543719 -38.738047) (xy 66.498179 -38.776861) (xy 66.448398 -38.810062) (xy 66.395064 -38.837191)
			(xy 66.338914 -38.857871) (xy 66.280726 -38.871819) (xy 66.221302 -38.87884) (xy 66.191384 -38.879272)
			(xy 66.159408 -38.878749) (xy 66.095961 -38.870732) (xy 66.034019 -38.854826) (xy 65.974559 -38.831283)
			(xy 65.918519 -38.800473) (xy 65.866782 -38.762882) (xy 65.820164 -38.719103) (xy 65.7794 -38.669827)
			(xy 65.745134 -38.615831) (xy 65.717905 -38.557966) (xy 65.698144 -38.497144) (xy 65.68616 -38.434325)
			(xy 65.682145 -38.3705) (xy 61.857583 -38.3705) (xy 61.879659 -38.417592) (xy 61.895737 -38.471034)
			(xy 61.903863 -38.526248) (xy 61.904372 -38.554152) (xy 61.903863 -38.582056) (xy 61.895737 -38.63727)
			(xy 61.879659 -38.690712) (xy 61.855971 -38.741243) (xy 61.8275 -38.784276) (xy 63.050418 -38.784276)
			(xy 63.054491 -38.728617) (xy 63.066626 -38.674144) (xy 63.086562 -38.622018) (xy 63.113876 -38.57335)
			(xy 63.147984 -38.529178) (xy 63.188161 -38.490443) (xy 63.233549 -38.457971) (xy 63.283181 -38.432453)
			(xy 63.336001 -38.414434) (xy 63.39088 -38.404297) (xy 63.446651 -38.402259) (xy 63.502125 -38.408362)
			(xy 63.556118 -38.422478) (xy 63.607481 -38.444305) (xy 63.655119 -38.473378) (xy 63.698015 -38.509077)
			(xy 63.735257 -38.550641) (xy 63.766051 -38.597185) (xy 63.789739 -38.647716) (xy 63.805817 -38.701158)
			(xy 63.813943 -38.756372) (xy 63.814452 -38.784276) (xy 63.813943 -38.81218) (xy 63.805817 -38.867394)
			(xy 63.789739 -38.920836) (xy 63.766051 -38.971367) (xy 63.735257 -39.017911) (xy 63.698015 -39.059475)
			(xy 63.655119 -39.095174) (xy 63.607481 -39.124247) (xy 63.556118 -39.146074) (xy 63.502125 -39.16019)
			(xy 63.446651 -39.166293) (xy 63.39088 -39.164255) (xy 63.336001 -39.154118) (xy 63.283181 -39.136099)
			(xy 63.233549 -39.110581) (xy 63.188161 -39.078109) (xy 63.147984 -39.039374) (xy 63.113876 -38.995202)
			(xy 63.086562 -38.946534) (xy 63.066626 -38.894408) (xy 63.054491 -38.839935) (xy 63.050418 -38.784276)
			(xy 61.8275 -38.784276) (xy 61.825177 -38.787787) (xy 61.787935 -38.829351) (xy 61.745039 -38.86505)
			(xy 61.697401 -38.894123) (xy 61.646038 -38.91595) (xy 61.592045 -38.930066) (xy 61.536571 -38.936169)
			(xy 61.4808 -38.934131) (xy 61.425921 -38.923994) (xy 61.373101 -38.905975) (xy 61.323469 -38.880457)
			(xy 61.278081 -38.847985) (xy 61.237904 -38.80925) (xy 61.203796 -38.765078) (xy 61.176482 -38.71641)
			(xy 61.156546 -38.664284) (xy 61.144411 -38.609811) (xy 61.140338 -38.554152) (xy 60.476042 -38.554152)
			(xy 60.478676 -38.575007) (xy 60.479178 -38.606984) (xy 60.478676 -38.638961) (xy 60.470661 -38.702411)
			(xy 60.454756 -38.764356) (xy 60.431213 -38.823818) (xy 60.400403 -38.879862) (xy 60.362811 -38.931602)
			(xy 60.319032 -38.978222) (xy 60.269754 -39.018988) (xy 60.215756 -39.053256) (xy 60.157889 -39.080487)
			(xy 60.097065 -39.10025) (xy 60.034244 -39.112233) (xy 59.970416 -39.116249) (xy 59.906588 -39.112233)
			(xy 59.843767 -39.10025) (xy 59.782943 -39.080487) (xy 59.725076 -39.053256) (xy 59.671078 -39.018988)
			(xy 59.6218 -38.978222) (xy 59.578021 -38.931602) (xy 59.540429 -38.879862) (xy 59.509619 -38.823818)
			(xy 59.486076 -38.764356) (xy 59.470171 -38.702411) (xy 59.462156 -38.638961) (xy 26.926613 -38.638961)
			(xy 26.891891 -38.677713) (xy 26.848995 -38.713412) (xy 26.801357 -38.742485) (xy 26.749994 -38.764312)
			(xy 26.696001 -38.778428) (xy 26.640527 -38.784531) (xy 26.584756 -38.782493) (xy 26.529877 -38.772356)
			(xy 26.477057 -38.754337) (xy 26.427425 -38.728819) (xy 26.382037 -38.696347) (xy 26.34186 -38.657612)
			(xy 26.307752 -38.61344) (xy 26.280438 -38.564772) (xy 26.260502 -38.512646) (xy 26.248367 -38.458173)
			(xy 26.244294 -38.402514) (xy 18.452302 -38.402514) (xy 18.456339 -38.424586) (xy 18.468045 -38.449036)
			(xy 18.485759 -38.469556) (xy 18.496788 -38.477444) (xy 18.499836 -38.479476) (xy 18.500344 -38.479984)
			(xy 18.527405 -38.497441) (xy 18.577309 -38.538142) (xy 18.621672 -38.584822) (xy 18.659781 -38.636734)
			(xy 18.691026 -38.693044) (xy 18.714906 -38.75285) (xy 18.731039 -38.815194) (xy 18.739165 -38.879077)
			(xy 18.739612 -38.911276) (xy 18.73911 -38.943253) (xy 18.731095 -39.006703) (xy 18.71519 -39.068648)
			(xy 18.691647 -39.12811) (xy 18.660837 -39.184154) (xy 18.623245 -39.235894) (xy 18.618003 -39.241476)
			(xy 22.261828 -39.241476) (xy 22.265901 -39.185817) (xy 22.278036 -39.131344) (xy 22.297972 -39.079218)
			(xy 22.325286 -39.03055) (xy 22.359394 -38.986378) (xy 22.399571 -38.947643) (xy 22.444959 -38.915171)
			(xy 22.494591 -38.889653) (xy 22.547411 -38.871634) (xy 22.60229 -38.861497) (xy 22.658061 -38.859459)
			(xy 22.713535 -38.865562) (xy 22.767528 -38.879678) (xy 22.818891 -38.901505) (xy 22.866529 -38.930578)
			(xy 22.909425 -38.966277) (xy 22.946667 -39.007841) (xy 22.977461 -39.054385) (xy 23.001149 -39.104916)
			(xy 23.017227 -39.158358) (xy 23.025353 -39.213572) (xy 23.025862 -39.241476) (xy 23.025353 -39.26938)
			(xy 23.017227 -39.324594) (xy 23.001149 -39.378036) (xy 22.977461 -39.428567) (xy 22.946667 -39.475111)
			(xy 22.909425 -39.516675) (xy 22.866529 -39.552374) (xy 22.818891 -39.581447) (xy 22.767528 -39.603274)
			(xy 22.713535 -39.61739) (xy 22.658061 -39.623493) (xy 22.60229 -39.621455) (xy 22.547411 -39.611318)
			(xy 22.494591 -39.593299) (xy 22.444959 -39.567781) (xy 22.399571 -39.535309) (xy 22.359394 -39.496574)
			(xy 22.325286 -39.452402) (xy 22.297972 -39.403734) (xy 22.278036 -39.351608) (xy 22.265901 -39.297135)
			(xy 22.261828 -39.241476) (xy 18.618003 -39.241476) (xy 18.579466 -39.282514) (xy 18.530188 -39.32328)
			(xy 18.47619 -39.357548) (xy 18.418323 -39.384779) (xy 18.357499 -39.404542) (xy 18.294678 -39.416525)
			(xy 18.23085 -39.420541) (xy 18.167022 -39.416525) (xy 18.104201 -39.404542) (xy 18.043377 -39.384779)
			(xy 17.98551 -39.357548) (xy 17.931512 -39.32328) (xy 17.882234 -39.282514) (xy 17.838455 -39.235894)
			(xy 17.800863 -39.184154) (xy 17.770053 -39.12811) (xy 17.74651 -39.068648) (xy 17.730605 -39.006703)
			(xy 17.72259 -38.943253) (xy 17.722088 -38.911276) (xy 17.722535 -38.880752) (xy 17.729836 -38.820144)
			(xy 17.744343 -38.760846) (xy 17.765846 -38.703711) (xy 17.794036 -38.649563) (xy 17.828507 -38.59918)
			(xy 17.868763 -38.553287) (xy 17.914226 -38.512545) (xy 17.939004 -38.494716) (xy 17.94002 -38.493954)
			(xy 17.943322 -38.491414) (xy 17.953342 -38.482656) (xy 17.968876 -38.46106) (xy 17.978297 -38.436182)
			(xy 17.980966 -38.409714) (xy 17.976702 -38.383456) (xy 17.965793 -38.359194) (xy 17.948982 -38.338576)
			(xy 17.938496 -38.330378) (xy 17.935194 -38.328346) (xy 17.906686 -38.310162) (xy 17.85429 -38.26742)
			(xy 17.808016 -38.218116) (xy 17.76868 -38.163118) (xy 17.752314 -38.133528) (xy 17.751044 -38.131242)
			(xy 17.750536 -38.13048) (xy 17.749774 -38.128956) (xy 17.742804 -38.117975) (xy 17.724315 -38.099693)
			(xy 17.701801 -38.086686) (xy 17.676729 -38.079801) (xy 17.65073 -38.079484) (xy 17.638014 -38.08222)
			(xy 17.628108 -38.08222) (xy 17.609566 -38.08984) (xy 17.535906 -38.1635) (xy 17.253204 -38.446456)
			(xy 17.246402 -38.453804) (xy 17.238689 -38.472267) (xy 17.238218 -38.48227) (xy 17.238218 -39.927276)
			(xy 17.849594 -39.927276) (xy 17.853667 -39.871617) (xy 17.865802 -39.817144) (xy 17.885738 -39.765018)
			(xy 17.913052 -39.71635) (xy 17.94716 -39.672178) (xy 17.987337 -39.633443) (xy 18.032725 -39.600971)
			(xy 18.082357 -39.575453) (xy 18.135177 -39.557434) (xy 18.190056 -39.547297) (xy 18.245827 -39.545259)
			(xy 18.301301 -39.551362) (xy 18.355294 -39.565478) (xy 18.406657 -39.587305) (xy 18.454295 -39.616378)
			(xy 18.497191 -39.652077) (xy 18.534433 -39.693641) (xy 18.565227 -39.740185) (xy 18.588915 -39.790716)
			(xy 18.604993 -39.844158) (xy 18.613119 -39.899372) (xy 18.613628 -39.927276) (xy 18.613119 -39.95518)
			(xy 18.604993 -40.010394) (xy 18.588915 -40.063836) (xy 18.565227 -40.114367) (xy 18.534433 -40.160911)
			(xy 18.497191 -40.202475) (xy 18.454295 -40.238174) (xy 18.406657 -40.267247) (xy 18.355294 -40.289074)
			(xy 18.301301 -40.30319) (xy 18.245827 -40.309293) (xy 18.190056 -40.307255) (xy 18.135177 -40.297118)
			(xy 18.082357 -40.279099) (xy 18.032725 -40.253581) (xy 17.987337 -40.221109) (xy 17.94716 -40.182374)
			(xy 17.913052 -40.138202) (xy 17.885738 -40.089534) (xy 17.865802 -40.037408) (xy 17.853667 -39.982935)
			(xy 17.849594 -39.927276) (xy 17.238218 -39.927276) (xy 17.238218 -40.943276) (xy 17.849594 -40.943276)
			(xy 17.853667 -40.887617) (xy 17.865802 -40.833144) (xy 17.885738 -40.781018) (xy 17.913052 -40.73235)
			(xy 17.94716 -40.688178) (xy 17.987337 -40.649443) (xy 18.032725 -40.616971) (xy 18.082357 -40.591453)
			(xy 18.135177 -40.573434) (xy 18.190056 -40.563297) (xy 18.245827 -40.561259) (xy 18.301301 -40.567362)
			(xy 18.355294 -40.581478) (xy 18.406657 -40.603305) (xy 18.454295 -40.632378) (xy 18.497191 -40.668077)
			(xy 18.534433 -40.709641) (xy 18.565227 -40.756185) (xy 18.588915 -40.806716) (xy 18.604993 -40.860158)
			(xy 18.613119 -40.915372) (xy 18.613628 -40.943276) (xy 18.613119 -40.97118) (xy 18.604993 -41.026394)
			(xy 18.588915 -41.079836) (xy 18.565227 -41.130367) (xy 18.534433 -41.176911) (xy 18.497191 -41.218475)
			(xy 18.454295 -41.254174) (xy 18.406657 -41.283247) (xy 18.355294 -41.305074) (xy 18.301301 -41.31919)
			(xy 18.245827 -41.325293) (xy 18.190056 -41.323255) (xy 18.135177 -41.313118) (xy 18.082357 -41.295099)
			(xy 18.032725 -41.269581) (xy 17.987337 -41.237109) (xy 17.94716 -41.198374) (xy 17.913052 -41.154202)
			(xy 17.885738 -41.105534) (xy 17.865802 -41.053408) (xy 17.853667 -40.998935) (xy 17.849594 -40.943276)
			(xy 17.238218 -40.943276) (xy 17.238218 -41.711372) (xy 17.238655 -41.721436) (xy 17.24639 -41.74002)
			(xy 17.253204 -41.74744) (xy 18.5293 -43.023536) (xy 18.529808 -43.024044) (xy 18.537187 -43.030634)
			(xy 18.555485 -43.038102) (xy 18.565368 -43.038522)
		)
		(stroke
			(width 0)
			(type solid)
		)
		(fill yes)
		(layer "In15.Cu")
		(net "P3V3_AUX")
	)
	(gr_poly
		(pts
			(xy 461.144366 -83.548728) (xy 461.154418 -83.548225) (xy 461.172982 -83.540507) (xy 461.180434 -83.533742)
			(xy 469.488012 -75.226164) (xy 469.494862 -75.218768) (xy 469.502598 -75.200169) (xy 469.502998 -75.190096)
			(xy 469.502998 -47.356776) (xy 469.50257 -47.346708) (xy 469.49485 -47.32811) (xy 469.488012 -47.320708)
			(xy 467.244176 -45.076872) (xy 467.23678 -45.070022) (xy 467.218181 -45.062284) (xy 467.208108 -45.061886)
			(xy 457.79436 -45.061886) (xy 457.784357 -45.06238) (xy 457.765876 -45.070047) (xy 457.751732 -45.084198)
			(xy 457.744075 -45.102682) (xy 457.74356 -45.112686) (xy 457.74356 -45.697902) (xy 457.743985 -45.707971)
			(xy 457.751707 -45.726569) (xy 457.758546 -45.73397) (xy 457.897738 -45.873162) (xy 457.902132 -45.877226)
			(xy 461.205832 -45.877226) (xy 461.209903 -45.821604) (xy 461.222029 -45.767167) (xy 461.241952 -45.715076)
			(xy 461.269248 -45.666441) (xy 461.303334 -45.622298) (xy 461.343483 -45.583589) (xy 461.388841 -45.551138)
			(xy 461.438441 -45.525637) (xy 461.491225 -45.50763) (xy 461.546068 -45.4975) (xy 461.601802 -45.495463)
			(xy 461.657239 -45.501563) (xy 461.711196 -45.515669) (xy 461.762525 -45.537481) (xy 461.810131 -45.566535)
			(xy 461.852999 -45.60221) (xy 461.890216 -45.643747) (xy 461.920989 -45.69026) (xy 461.944661 -45.740757)
			(xy 461.960729 -45.794164) (xy 461.968849 -45.84934) (xy 461.969358 -45.877226) (xy 461.968849 -45.905112)
			(xy 461.960729 -45.960288) (xy 461.944661 -46.013695) (xy 461.920989 -46.064192) (xy 461.890216 -46.110705)
			(xy 461.852999 -46.152242) (xy 461.810131 -46.187917) (xy 461.762525 -46.216971) (xy 461.711196 -46.238783)
			(xy 461.657239 -46.252889) (xy 461.601802 -46.258989) (xy 461.546068 -46.256952) (xy 461.491225 -46.246822)
			(xy 461.438441 -46.228815) (xy 461.388841 -46.203314) (xy 461.343483 -46.170863) (xy 461.303334 -46.132154)
			(xy 461.269248 -46.088011) (xy 461.241952 -46.039376) (xy 461.222029 -45.987285) (xy 461.209903 -45.932848)
			(xy 461.205832 -45.877226) (xy 457.902132 -45.877226) (xy 457.905137 -45.880006) (xy 457.923735 -45.887733)
			(xy 457.933806 -45.888148) (xy 459.820518 -45.888148) (xy 459.848494 -45.88872) (xy 459.903752 -45.897512)
			(xy 459.956958 -45.91483) (xy 460.006804 -45.940248) (xy 460.052067 -45.973143) (xy 460.072232 -45.992542)
			(xy 460.81061 -46.73092) (xy 460.830042 -46.75106) (xy 460.862965 -46.796314) (xy 460.888397 -46.846165)
			(xy 460.905712 -46.899381) (xy 460.914483 -46.954653) (xy 460.915004 -46.982634) (xy 460.915004 -49.316132)
			(xy 460.917798 -49.324514) (xy 460.928309 -49.355734) (xy 460.939681 -49.420613) (xy 460.940404 -49.453546)
			(xy 460.939918 -49.480797) (xy 460.932162 -49.534745) (xy 460.916807 -49.58704) (xy 460.894165 -49.636617)
			(xy 460.864699 -49.682467) (xy 460.829008 -49.723658) (xy 460.787817 -49.759349) (xy 460.741967 -49.788815)
			(xy 460.69239 -49.811457) (xy 460.640095 -49.826812) (xy 460.586147 -49.834568) (xy 460.531645 -49.834568)
			(xy 460.477697 -49.826812) (xy 460.425402 -49.811457) (xy 460.375825 -49.788815) (xy 460.329975 -49.759349)
			(xy 460.288784 -49.723658) (xy 460.253093 -49.682467) (xy 460.223627 -49.636617) (xy 460.200985 -49.58704)
			(xy 460.18563 -49.534745) (xy 460.177874 -49.480797) (xy 460.177388 -49.453546) (xy 460.1781 -49.420611)
			(xy 460.189465 -49.355729) (xy 460.199994 -49.324514) (xy 460.202788 -49.316132) (xy 460.202788 -47.15129)
			(xy 460.202363 -47.141221) (xy 460.194644 -47.12262) (xy 460.187802 -47.115222) (xy 459.68793 -46.61535)
			(xy 459.68053 -46.608509) (xy 459.661931 -46.600792) (xy 459.651862 -46.600364) (xy 457.76515 -46.600364)
			(xy 457.737175 -46.59979) (xy 457.681919 -46.590994) (xy 457.628716 -46.573673) (xy 457.578873 -46.548252)
			(xy 457.533613 -46.515356) (xy 457.513436 -46.49597) (xy 457.135738 -46.118272) (xy 457.116309 -46.09813)
			(xy 457.083392 -46.052874) (xy 457.057965 -46.003024) (xy 457.040654 -45.949808) (xy 457.031885 -45.894538)
			(xy 457.031344 -45.866558) (xy 457.031344 -45.255434) (xy 457.031094 -45.24802) (xy 457.026841 -45.233816)
			(xy 457.022962 -45.227494) (xy 457.01052 -45.20812) (xy 456.989866 -45.166967) (xy 456.974323 -45.123624)
			(xy 456.96886 -45.101256) (xy 456.964796 -45.083984) (xy 456.93711 -45.061886) (xy 456.012804 -45.061886)
			(xy 456.001876 -45.062409) (xy 455.981999 -45.071493) (xy 455.97445 -45.079412) (xy 455.924158 -45.137578)
			(xy 455.9174 -45.14616) (xy 455.911213 -45.167087) (xy 455.91222 -45.177964) (xy 455.91222 -45.178218)
			(xy 455.914108 -45.191856) (xy 455.916143 -45.219315) (xy 455.916284 -45.233082) (xy 455.915798 -45.260333)
			(xy 455.908042 -45.314281) (xy 455.892687 -45.366576) (xy 455.870045 -45.416153) (xy 455.840579 -45.462003)
			(xy 455.804888 -45.503194) (xy 455.763697 -45.538885) (xy 455.717847 -45.568351) (xy 455.66827 -45.590993)
			(xy 455.615975 -45.606348) (xy 455.562027 -45.614104) (xy 455.507525 -45.614104) (xy 455.453577 -45.606348)
			(xy 455.401282 -45.590993) (xy 455.351705 -45.568351) (xy 455.305855 -45.538885) (xy 455.264664 -45.503194)
			(xy 455.228973 -45.462003) (xy 455.199507 -45.416153) (xy 455.176865 -45.366576) (xy 455.16151 -45.314281)
			(xy 455.153754 -45.260333) (xy 455.153268 -45.233082) (xy 455.153419 -45.219315) (xy 455.15545 -45.191856)
			(xy 455.157332 -45.178218) (xy 455.157332 -45.177964) (xy 455.158358 -45.167082) (xy 455.152188 -45.146137)
			(xy 455.145394 -45.137578) (xy 455.095102 -45.079412) (xy 455.087546 -45.071508) (xy 455.06767 -45.06244)
			(xy 455.056748 -45.061886) (xy 451.70598 -45.061886) (xy 451.696307 -45.06235) (xy 451.678365 -45.069593)
			(xy 451.664381 -45.082966) (xy 451.660006 -45.091604) (xy 451.615302 -45.18914) (xy 451.619366 -45.21835)
			(xy 451.629272 -45.22978) (xy 451.646613 -45.250653) (xy 451.675838 -45.296375) (xy 451.698295 -45.345774)
			(xy 451.713532 -45.397855) (xy 451.721243 -45.451568) (xy 451.721728 -45.4787) (xy 451.721728 -45.478954)
			(xy 451.721242 -45.506205) (xy 451.713486 -45.560153) (xy 451.710703 -45.569632) (xy 451.973948 -45.569632)
			(xy 451.978019 -45.51401) (xy 451.990145 -45.459573) (xy 452.010068 -45.407482) (xy 452.037364 -45.358847)
			(xy 452.07145 -45.314704) (xy 452.111599 -45.275995) (xy 452.156957 -45.243544) (xy 452.206557 -45.218043)
			(xy 452.259341 -45.200036) (xy 452.314184 -45.189906) (xy 452.369918 -45.187869) (xy 452.425355 -45.193969)
			(xy 452.479312 -45.208075) (xy 452.530641 -45.229887) (xy 452.578247 -45.258941) (xy 452.621115 -45.294616)
			(xy 452.658332 -45.336153) (xy 452.689105 -45.382666) (xy 452.712777 -45.433163) (xy 452.728845 -45.48657)
			(xy 452.736965 -45.541746) (xy 452.737474 -45.569632) (xy 452.736965 -45.597518) (xy 452.728845 -45.652694)
			(xy 452.712777 -45.706101) (xy 452.689105 -45.756598) (xy 452.658332 -45.803111) (xy 452.621115 -45.844648)
			(xy 452.578247 -45.880323) (xy 452.530641 -45.909377) (xy 452.479312 -45.931189) (xy 452.425355 -45.945295)
			(xy 452.369918 -45.951395) (xy 452.314184 -45.949358) (xy 452.259341 -45.939228) (xy 452.206557 -45.921221)
			(xy 452.156957 -45.89572) (xy 452.111599 -45.863269) (xy 452.07145 -45.82456) (xy 452.037364 -45.780417)
			(xy 452.010068 -45.731782) (xy 451.990145 -45.679691) (xy 451.978019 -45.625254) (xy 451.973948 -45.569632)
			(xy 451.710703 -45.569632) (xy 451.698131 -45.612448) (xy 451.675489 -45.662025) (xy 451.646023 -45.707875)
			(xy 451.610332 -45.749066) (xy 451.569141 -45.784757) (xy 451.523291 -45.814223) (xy 451.473714 -45.836865)
			(xy 451.421419 -45.85222) (xy 451.367471 -45.859976) (xy 451.312969 -45.859976) (xy 451.259021 -45.85222)
			(xy 451.206726 -45.836865) (xy 451.157149 -45.814223) (xy 451.111299 -45.784757) (xy 451.070108 -45.749066)
			(xy 451.034417 -45.707875) (xy 451.004951 -45.662025) (xy 450.982309 -45.612448) (xy 450.966954 -45.560153)
			(xy 450.959198 -45.506205) (xy 450.958712 -45.478954) (xy 450.958712 -45.4787) (xy 450.959184 -45.451565)
			(xy 450.966869 -45.397843) (xy 450.982097 -45.345755) (xy 451.004561 -45.296353) (xy 451.033806 -45.250638)
			(xy 451.051168 -45.22978) (xy 451.061074 -45.21835) (xy 451.065138 -45.18914) (xy 451.020434 -45.091604)
			(xy 451.016036 -45.08298) (xy 451.002062 -45.069605) (xy 450.984129 -45.062352) (xy 450.97446 -45.061886)
			(xy 432.384962 -45.061886) (xy 432.374895 -45.062316) (xy 432.356299 -45.070038) (xy 432.348894 -45.076872)
			(xy 430.189132 -47.236634) (xy 430.182287 -47.244033) (xy 430.176708 -47.257462) (xy 452.986392 -47.257462)
			(xy 452.990463 -47.20184) (xy 453.002589 -47.147403) (xy 453.022512 -47.095312) (xy 453.049808 -47.046677)
			(xy 453.083894 -47.002534) (xy 453.124043 -46.963825) (xy 453.169401 -46.931374) (xy 453.219001 -46.905873)
			(xy 453.271785 -46.887866) (xy 453.326628 -46.877736) (xy 453.382362 -46.875699) (xy 453.437799 -46.881799)
			(xy 453.491756 -46.895905) (xy 453.543085 -46.917717) (xy 453.590691 -46.946771) (xy 453.633559 -46.982446)
			(xy 453.670776 -47.023983) (xy 453.701549 -47.070496) (xy 453.725221 -47.120993) (xy 453.741289 -47.1744)
			(xy 453.749409 -47.229576) (xy 453.749918 -47.257462) (xy 453.749409 -47.285348) (xy 453.741289 -47.340524)
			(xy 453.725221 -47.393931) (xy 453.701549 -47.444428) (xy 453.680726 -47.475902) (xy 457.470762 -47.475902)
			(xy 457.474833 -47.42028) (xy 457.486959 -47.365843) (xy 457.506882 -47.313752) (xy 457.534178 -47.265117)
			(xy 457.568264 -47.220974) (xy 457.608413 -47.182265) (xy 457.653771 -47.149814) (xy 457.703371 -47.124313)
			(xy 457.756155 -47.106306) (xy 457.810998 -47.096176) (xy 457.866732 -47.094139) (xy 457.922169 -47.100239)
			(xy 457.976126 -47.114345) (xy 458.027455 -47.136157) (xy 458.075061 -47.165211) (xy 458.117929 -47.200886)
			(xy 458.155146 -47.242423) (xy 458.185919 -47.288936) (xy 458.209591 -47.339433) (xy 458.225659 -47.39284)
			(xy 458.233779 -47.448016) (xy 458.23407 -47.463964) (xy 458.461362 -47.463964) (xy 458.465433 -47.408342)
			(xy 458.477559 -47.353905) (xy 458.497482 -47.301814) (xy 458.524778 -47.253179) (xy 458.558864 -47.209036)
			(xy 458.599013 -47.170327) (xy 458.644371 -47.137876) (xy 458.693971 -47.112375) (xy 458.746755 -47.094368)
			(xy 458.801598 -47.084238) (xy 458.857332 -47.082201) (xy 458.912769 -47.088301) (xy 458.966726 -47.102407)
			(xy 459.018055 -47.124219) (xy 459.065661 -47.153273) (xy 459.108529 -47.188948) (xy 459.145746 -47.230485)
			(xy 459.176519 -47.276998) (xy 459.200191 -47.327495) (xy 459.216259 -47.380902) (xy 459.224379 -47.436078)
			(xy 459.224888 -47.463964) (xy 459.224379 -47.49185) (xy 459.216259 -47.547026) (xy 459.200191 -47.600433)
			(xy 459.176519 -47.65093) (xy 459.145746 -47.697443) (xy 459.108529 -47.73898) (xy 459.065661 -47.774655)
			(xy 459.018055 -47.803709) (xy 458.966726 -47.825521) (xy 458.912769 -47.839627) (xy 458.857332 -47.845727)
			(xy 458.801598 -47.84369) (xy 458.746755 -47.83356) (xy 458.693971 -47.815553) (xy 458.644371 -47.790052)
			(xy 458.599013 -47.757601) (xy 458.558864 -47.718892) (xy 458.524778 -47.674749) (xy 458.497482 -47.626114)
			(xy 458.477559 -47.574023) (xy 458.465433 -47.519586) (xy 458.461362 -47.463964) (xy 458.23407 -47.463964)
			(xy 458.234288 -47.475902) (xy 458.233779 -47.503788) (xy 458.225659 -47.558964) (xy 458.209591 -47.612371)
			(xy 458.185919 -47.662868) (xy 458.155146 -47.709381) (xy 458.117929 -47.750918) (xy 458.075061 -47.786593)
			(xy 458.027455 -47.815647) (xy 457.976126 -47.837459) (xy 457.922169 -47.851565) (xy 457.866732 -47.857665)
			(xy 457.810998 -47.855628) (xy 457.756155 -47.845498) (xy 457.703371 -47.827491) (xy 457.653771 -47.80199)
			(xy 457.608413 -47.769539) (xy 457.568264 -47.73083) (xy 457.534178 -47.686687) (xy 457.506882 -47.638052)
			(xy 457.486959 -47.585961) (xy 457.474833 -47.531524) (xy 457.470762 -47.475902) (xy 453.680726 -47.475902)
			(xy 453.670776 -47.490941) (xy 453.633559 -47.532478) (xy 453.590691 -47.568153) (xy 453.543085 -47.597207)
			(xy 453.491756 -47.619019) (xy 453.437799 -47.633125) (xy 453.382362 -47.639225) (xy 453.326628 -47.637188)
			(xy 453.271785 -47.627058) (xy 453.219001 -47.609051) (xy 453.169401 -47.58355) (xy 453.124043 -47.551099)
			(xy 453.083894 -47.51239) (xy 453.049808 -47.468247) (xy 453.022512 -47.419612) (xy 453.002589 -47.367521)
			(xy 452.990463 -47.313084) (xy 452.986392 -47.257462) (xy 430.176708 -47.257462) (xy 430.17456 -47.262631)
			(xy 430.174146 -47.272702) (xy 430.174146 -49.333751) (xy 449.466958 -49.333751) (xy 449.466958 -49.279249)
			(xy 449.474714 -49.225301) (xy 449.490068 -49.173006) (xy 449.512708 -49.123428) (xy 449.542173 -49.077576)
			(xy 449.577864 -49.036385) (xy 449.619052 -49.000691) (xy 449.664901 -48.971223) (xy 449.714478 -48.948579)
			(xy 449.766771 -48.93322) (xy 449.820719 -48.92546) (xy 449.84797 -48.924972) (xy 449.87568 -48.925455)
			(xy 449.930515 -48.933487) (xy 449.983609 -48.949372) (xy 450.033845 -48.972775) (xy 450.080164 -49.003203)
			(xy 450.101208 -49.021238) (xy 450.10836 -49.027025) (xy 450.125545 -49.033545) (xy 450.134736 -49.033938)
			(xy 450.212206 -49.033938) (xy 450.229224 -49.027588) (xy 450.236336 -49.021238) (xy 450.257401 -49.003229)
			(xy 450.303712 -48.972794) (xy 450.353943 -48.949387) (xy 450.407034 -48.933501) (xy 450.461866 -48.925472)
			(xy 450.489574 -48.924972) (xy 450.516827 -48.925474) (xy 450.570778 -48.933227) (xy 450.623076 -48.94858)
			(xy 450.672657 -48.97122) (xy 450.718511 -49.000686) (xy 450.759704 -49.036377) (xy 450.763093 -49.040288)
			(xy 453.089262 -49.040288) (xy 453.093333 -48.984666) (xy 453.105459 -48.930229) (xy 453.125382 -48.878138)
			(xy 453.152678 -48.829503) (xy 453.186764 -48.78536) (xy 453.226913 -48.746651) (xy 453.272271 -48.7142)
			(xy 453.321871 -48.688699) (xy 453.374655 -48.670692) (xy 453.429498 -48.660562) (xy 453.485232 -48.658525)
			(xy 453.540669 -48.664625) (xy 453.594626 -48.678731) (xy 453.645955 -48.700543) (xy 453.693561 -48.729597)
			(xy 453.736429 -48.765272) (xy 453.773646 -48.806809) (xy 453.804419 -48.853322) (xy 453.828091 -48.903819)
			(xy 453.844159 -48.957226) (xy 453.852279 -49.012402) (xy 453.852788 -49.040288) (xy 453.852279 -49.068174)
			(xy 453.844159 -49.12335) (xy 453.828091 -49.176757) (xy 453.804419 -49.227254) (xy 453.773646 -49.273767)
			(xy 453.736429 -49.315304) (xy 453.693561 -49.350979) (xy 453.645955 -49.380033) (xy 453.594626 -49.401845)
			(xy 453.540669 -49.415951) (xy 453.485232 -49.422051) (xy 453.429498 -49.420014) (xy 453.374655 -49.409884)
			(xy 453.321871 -49.391877) (xy 453.272271 -49.366376) (xy 453.226913 -49.333925) (xy 453.186764 -49.295216)
			(xy 453.152678 -49.251073) (xy 453.125382 -49.202438) (xy 453.105459 -49.150347) (xy 453.093333 -49.09591)
			(xy 453.089262 -49.040288) (xy 450.763093 -49.040288) (xy 450.795399 -49.077569) (xy 450.824868 -49.123421)
			(xy 450.847511 -49.173) (xy 450.862867 -49.225297) (xy 450.870625 -49.279247) (xy 450.870625 -49.333753)
			(xy 450.862867 -49.387703) (xy 450.847511 -49.44) (xy 450.824868 -49.489579) (xy 450.795399 -49.535431)
			(xy 450.759704 -49.576623) (xy 450.718511 -49.612314) (xy 450.672657 -49.64178) (xy 450.623076 -49.66442)
			(xy 450.570778 -49.679773) (xy 450.516827 -49.687526) (xy 450.489574 -49.687988) (xy 450.461865 -49.687489)
			(xy 450.40703 -49.679462) (xy 450.353935 -49.663582) (xy 450.303699 -49.640182) (xy 450.257379 -49.609756)
			(xy 450.236336 -49.591722) (xy 450.229196 -49.585918) (xy 450.212002 -49.579407) (xy 450.202808 -49.579022)
			(xy 450.125338 -49.579022) (xy 450.10832 -49.585372) (xy 450.101208 -49.591722) (xy 450.080173 -49.609767)
			(xy 450.033853 -49.640195) (xy 449.983614 -49.663594) (xy 449.930517 -49.679472) (xy 449.87568 -49.687493)
			(xy 449.84797 -49.687988) (xy 449.820719 -49.68754) (xy 449.766771 -49.67978) (xy 449.714478 -49.664421)
			(xy 449.664901 -49.641777) (xy 449.619052 -49.612309) (xy 449.577864 -49.576615) (xy 449.542173 -49.535424)
			(xy 449.512708 -49.489572) (xy 449.490068 -49.439994) (xy 449.474714 -49.387699) (xy 449.466958 -49.333751)
			(xy 430.174146 -49.333751) (xy 430.174146 -50.489796) (xy 431.237386 -50.489796) (xy 431.237386 -50.4051)
			(xy 431.245437 -50.320786) (xy 431.261466 -50.23762) (xy 431.285327 -50.156353) (xy 431.316806 -50.077723)
			(xy 431.355617 -50.002442) (xy 431.401407 -49.93119) (xy 431.453763 -49.864614) (xy 431.512211 -49.803316)
			(xy 431.576221 -49.747851) (xy 431.645213 -49.698722) (xy 431.718563 -49.656373) (xy 431.795606 -49.621189)
			(xy 431.875645 -49.593487) (xy 431.957954 -49.573519) (xy 432.041789 -49.561466) (xy 432.12639 -49.557436)
			(xy 432.210991 -49.561466) (xy 432.294826 -49.573519) (xy 432.377135 -49.593487) (xy 432.457174 -49.621189)
			(xy 432.534217 -49.656373) (xy 432.607567 -49.698722) (xy 432.676559 -49.747851) (xy 432.740569 -49.803316)
			(xy 432.799017 -49.864614) (xy 432.851373 -49.93119) (xy 432.897163 -50.002442) (xy 432.935974 -50.077723)
			(xy 432.967453 -50.156353) (xy 432.991314 -50.23762) (xy 433.007343 -50.320786) (xy 433.015394 -50.4051)
			(xy 433.015898 -50.447448) (xy 433.015394 -50.489796) (xy 438.952636 -50.489796) (xy 438.952636 -50.4051)
			(xy 438.960687 -50.320786) (xy 438.976716 -50.23762) (xy 439.000577 -50.156353) (xy 439.032056 -50.077723)
			(xy 439.070867 -50.002442) (xy 439.116657 -49.93119) (xy 439.169013 -49.864614) (xy 439.227461 -49.803316)
			(xy 439.291471 -49.747851) (xy 439.360463 -49.698722) (xy 439.433813 -49.656373) (xy 439.510856 -49.621189)
			(xy 439.590895 -49.593487) (xy 439.673204 -49.573519) (xy 439.757039 -49.561466) (xy 439.84164 -49.557436)
			(xy 439.926241 -49.561466) (xy 440.010076 -49.573519) (xy 440.092385 -49.593487) (xy 440.172424 -49.621189)
			(xy 440.249467 -49.656373) (xy 440.322817 -49.698722) (xy 440.391809 -49.747851) (xy 440.455819 -49.803316)
			(xy 440.514267 -49.864614) (xy 440.566623 -49.93119) (xy 440.612413 -50.002442) (xy 440.651224 -50.077723)
			(xy 440.682703 -50.156353) (xy 440.706564 -50.23762) (xy 440.721842 -50.316892) (xy 459.681578 -50.316892)
			(xy 459.685649 -50.26127) (xy 459.697775 -50.206833) (xy 459.717698 -50.154742) (xy 459.744994 -50.106107)
			(xy 459.77908 -50.061964) (xy 459.819229 -50.023255) (xy 459.864587 -49.990804) (xy 459.914187 -49.965303)
			(xy 459.966971 -49.947296) (xy 460.021814 -49.937166) (xy 460.077548 -49.935129) (xy 460.132985 -49.941229)
			(xy 460.186942 -49.955335) (xy 460.238271 -49.977147) (xy 460.285877 -50.006201) (xy 460.328745 -50.041876)
			(xy 460.365962 -50.083413) (xy 460.396735 -50.129926) (xy 460.420407 -50.180423) (xy 460.436475 -50.23383)
			(xy 460.444595 -50.289006) (xy 460.445104 -50.316892) (xy 460.444595 -50.344778) (xy 460.436475 -50.399954)
			(xy 460.420407 -50.453361) (xy 460.396735 -50.503858) (xy 460.365962 -50.550371) (xy 460.328745 -50.591908)
			(xy 460.285877 -50.627583) (xy 460.238271 -50.656637) (xy 460.186942 -50.678449) (xy 460.132985 -50.692555)
			(xy 460.077548 -50.698655) (xy 460.021814 -50.696618) (xy 459.966971 -50.686488) (xy 459.914187 -50.668481)
			(xy 459.864587 -50.64298) (xy 459.819229 -50.610529) (xy 459.77908 -50.57182) (xy 459.744994 -50.527677)
			(xy 459.717698 -50.479042) (xy 459.697775 -50.426951) (xy 459.685649 -50.372514) (xy 459.681578 -50.316892)
			(xy 440.721842 -50.316892) (xy 440.722593 -50.320786) (xy 440.730644 -50.4051) (xy 440.731148 -50.447448)
			(xy 440.730644 -50.489796) (xy 440.722593 -50.57411) (xy 440.706564 -50.657276) (xy 440.682703 -50.738543)
			(xy 440.651224 -50.817173) (xy 440.612413 -50.892454) (xy 440.566623 -50.963706) (xy 440.514267 -51.030282)
			(xy 440.455819 -51.09158) (xy 440.391809 -51.147045) (xy 440.322817 -51.196174) (xy 440.249467 -51.238523)
			(xy 440.172424 -51.273707) (xy 440.092385 -51.301409) (xy 440.010076 -51.321377) (xy 439.926241 -51.33343)
			(xy 439.84164 -51.337461) (xy 439.757039 -51.33343) (xy 439.673204 -51.321377) (xy 439.590895 -51.301409)
			(xy 439.510856 -51.273707) (xy 439.433813 -51.238523) (xy 439.360463 -51.196174) (xy 439.291471 -51.147045)
			(xy 439.227461 -51.09158) (xy 439.169013 -51.030282) (xy 439.116657 -50.963706) (xy 439.070867 -50.892454)
			(xy 439.032056 -50.817173) (xy 439.000577 -50.738543) (xy 438.976716 -50.657276) (xy 438.960687 -50.57411)
			(xy 438.952636 -50.489796) (xy 433.015394 -50.489796) (xy 433.007343 -50.57411) (xy 432.991314 -50.657276)
			(xy 432.967453 -50.738543) (xy 432.935974 -50.817173) (xy 432.897163 -50.892454) (xy 432.851373 -50.963706)
			(xy 432.799017 -51.030282) (xy 432.740569 -51.09158) (xy 432.676559 -51.147045) (xy 432.607567 -51.196174)
			(xy 432.534217 -51.238523) (xy 432.457174 -51.273707) (xy 432.377135 -51.301409) (xy 432.294826 -51.321377)
			(xy 432.210991 -51.33343) (xy 432.12639 -51.337461) (xy 432.041789 -51.33343) (xy 431.957954 -51.321377)
			(xy 431.875645 -51.301409) (xy 431.795606 -51.273707) (xy 431.718563 -51.238523) (xy 431.645213 -51.196174)
			(xy 431.576221 -51.147045) (xy 431.512211 -51.09158) (xy 431.453763 -51.030282) (xy 431.401407 -50.963706)
			(xy 431.355617 -50.892454) (xy 431.316806 -50.817173) (xy 431.285327 -50.738543) (xy 431.261466 -50.657276)
			(xy 431.245437 -50.57411) (xy 431.237386 -50.489796) (xy 430.174146 -50.489796) (xy 430.174146 -51.402053)
			(xy 445.516957 -51.402053) (xy 445.516957 -51.347547) (xy 445.524715 -51.293595) (xy 445.540071 -51.241296)
			(xy 445.562715 -51.191715) (xy 445.592184 -51.145861) (xy 445.62788 -51.104668) (xy 445.669074 -51.068975)
			(xy 445.714929 -51.039507) (xy 445.764511 -51.016866) (xy 445.81681 -51.001511) (xy 445.870763 -50.993756)
			(xy 445.898016 -50.993294) (xy 445.925725 -50.993804) (xy 445.980559 -51.001828) (xy 446.033653 -51.017707)
			(xy 446.08389 -51.041104) (xy 446.13021 -51.071527) (xy 446.151254 -51.08956) (xy 446.15839 -51.095369)
			(xy 446.175588 -51.101875) (xy 446.184782 -51.10226) (xy 446.262252 -51.10226) (xy 446.27927 -51.09591)
			(xy 446.286382 -51.08956) (xy 446.307418 -51.071517) (xy 446.353739 -51.041089) (xy 446.403977 -51.01769)
			(xy 446.457073 -51.001812) (xy 446.51191 -50.99379) (xy 446.53962 -50.993294) (xy 446.56687 -50.993777)
			(xy 446.620816 -51.001536) (xy 446.673109 -51.016893) (xy 446.722684 -51.039535) (xy 446.768532 -51.069002)
			(xy 446.80972 -51.104694) (xy 446.84541 -51.145884) (xy 446.874874 -51.191734) (xy 446.897514 -51.24131)
			(xy 446.912868 -51.293603) (xy 446.920624 -51.34755) (xy 446.920624 -51.40205) (xy 446.918324 -51.418049)
			(xy 447.310282 -51.418049) (xy 447.310282 -51.363551) (xy 447.318037 -51.309608) (xy 447.33339 -51.257317)
			(xy 447.356027 -51.207743) (xy 447.385489 -51.161895) (xy 447.421176 -51.120707) (xy 447.46236 -51.085016)
			(xy 447.508205 -51.055548) (xy 447.557776 -51.032905) (xy 447.610065 -51.017546) (xy 447.664007 -51.009785)
			(xy 447.691256 -51.009296) (xy 447.718966 -51.009781) (xy 447.773801 -51.017812) (xy 447.826895 -51.033696)
			(xy 447.877132 -51.057099) (xy 447.923451 -51.087527) (xy 447.944494 -51.105562) (xy 447.951648 -51.111346)
			(xy 447.968832 -51.117867) (xy 447.978022 -51.118262) (xy 448.055492 -51.118262) (xy 448.07251 -51.111912)
			(xy 448.079622 -51.105562) (xy 448.100643 -51.0875) (xy 448.146968 -51.057076) (xy 448.197209 -51.03368)
			(xy 448.25031 -51.017806) (xy 448.305149 -51.009789) (xy 448.33286 -51.009296) (xy 448.360115 -51.009749)
			(xy 448.414071 -51.017501) (xy 448.466374 -51.032854) (xy 448.51596 -51.055494) (xy 448.524452 -51.060951)
			(xy 449.047858 -51.060951) (xy 449.047858 -51.006449) (xy 449.055614 -50.952501) (xy 449.070968 -50.900206)
			(xy 449.093608 -50.850628) (xy 449.123073 -50.804776) (xy 449.158764 -50.763585) (xy 449.199952 -50.727891)
			(xy 449.245801 -50.698423) (xy 449.295378 -50.675779) (xy 449.347671 -50.66042) (xy 449.401619 -50.65266)
			(xy 449.42887 -50.652172) (xy 449.45658 -50.652655) (xy 449.511415 -50.660687) (xy 449.564509 -50.676572)
			(xy 449.614745 -50.699975) (xy 449.661064 -50.730403) (xy 449.682108 -50.748438) (xy 449.68926 -50.754225)
			(xy 449.706445 -50.760745) (xy 449.715636 -50.761138) (xy 449.793106 -50.761138) (xy 449.810124 -50.754788)
			(xy 449.817236 -50.748438) (xy 449.838301 -50.730429) (xy 449.884612 -50.699994) (xy 449.934843 -50.676587)
			(xy 449.987934 -50.660701) (xy 450.042766 -50.652672) (xy 450.070474 -50.652172) (xy 450.096709 -50.652656)
			(xy 450.148683 -50.659847) (xy 450.199181 -50.674097) (xy 450.247247 -50.695137) (xy 450.291975 -50.722569)
			(xy 450.332518 -50.755875) (xy 450.350636 -50.774854) (xy 450.357801 -50.781955) (xy 450.376138 -50.79033)
			(xy 450.386196 -50.79111) (xy 450.459094 -50.793142) (xy 450.469199 -50.793029) (xy 450.488061 -50.785822)
			(xy 450.49567 -50.779172) (xy 450.517104 -50.759388) (xy 450.564862 -50.725905) (xy 450.617157 -50.700074)
			(xy 450.672772 -50.682494) (xy 450.730413 -50.673576) (xy 450.759576 -50.673) (xy 450.787286 -50.673473)
			(xy 450.842122 -50.681506) (xy 450.895217 -50.697393) (xy 450.945453 -50.720799) (xy 450.991771 -50.75123)
			(xy 451.012814 -50.769266) (xy 451.019961 -50.775059) (xy 451.03715 -50.781574) (xy 451.046342 -50.781966)
			(xy 451.123812 -50.781966) (xy 451.14083 -50.775616) (xy 451.147942 -50.769266) (xy 451.168995 -50.751243)
			(xy 451.21531 -50.720812) (xy 451.265544 -50.697409) (xy 451.318637 -50.681526) (xy 451.373471 -50.673499)
			(xy 451.40118 -50.673) (xy 451.428434 -50.673446) (xy 451.482389 -50.681201) (xy 451.53469 -50.696555)
			(xy 451.584274 -50.719197) (xy 451.63013 -50.748665) (xy 451.671326 -50.78436) (xy 451.707023 -50.825554)
			(xy 451.736493 -50.871409) (xy 451.759138 -50.920991) (xy 451.774495 -50.973292) (xy 451.782253 -51.027246)
			(xy 451.782253 -51.081754) (xy 451.774495 -51.135708) (xy 451.759138 -51.188009) (xy 451.736493 -51.237591)
			(xy 451.707023 -51.283446) (xy 451.671326 -51.32464) (xy 451.63013 -51.360335) (xy 451.584274 -51.389803)
			(xy 451.53469 -51.412445) (xy 451.482389 -51.427799) (xy 451.428434 -51.435554) (xy 451.40118 -51.436016)
			(xy 451.373471 -51.435506) (xy 451.318637 -51.427481) (xy 451.265543 -51.411603) (xy 451.215307 -51.388206)
			(xy 451.168986 -51.357783) (xy 451.147942 -51.33975) (xy 451.140806 -51.33394) (xy 451.123608 -51.327435)
			(xy 451.114414 -51.32705) (xy 451.036944 -51.32705) (xy 451.019926 -51.3334) (xy 451.012814 -51.33975)
			(xy 450.99178 -51.357797) (xy 450.945459 -51.388223) (xy 450.895221 -51.411622) (xy 450.842123 -51.427499)
			(xy 450.787286 -51.435521) (xy 450.759576 -51.436016) (xy 450.73334 -51.435569) (xy 450.681364 -51.428371)
			(xy 450.630865 -51.414114) (xy 450.582799 -51.393067) (xy 450.538072 -51.365628) (xy 450.497531 -51.332316)
			(xy 450.479414 -51.313334) (xy 450.472233 -51.306252) (xy 450.453908 -51.297866) (xy 450.443854 -51.297078)
			(xy 450.370956 -51.295046) (xy 450.360849 -51.295135) (xy 450.341987 -51.302359) (xy 450.33438 -51.309016)
			(xy 450.312924 -51.328774) (xy 450.265171 -51.362261) (xy 450.212882 -51.388098) (xy 450.157272 -51.405683)
			(xy 450.099635 -51.414608) (xy 450.070474 -51.415188) (xy 450.042765 -51.414689) (xy 449.98793 -51.406662)
			(xy 449.934835 -51.390782) (xy 449.884599 -51.367382) (xy 449.838279 -51.336956) (xy 449.817236 -51.318922)
			(xy 449.810096 -51.313118) (xy 449.792902 -51.306607) (xy 449.783708 -51.306222) (xy 449.706238 -51.306222)
			(xy 449.68922 -51.312572) (xy 449.682108 -51.318922) (xy 449.661073 -51.336967) (xy 449.614753 -51.367395)
			(xy 449.564514 -51.390794) (xy 449.511417 -51.406672) (xy 449.45658 -51.414693) (xy 449.42887 -51.415188)
			(xy 449.401619 -51.41474) (xy 449.347671 -51.40698) (xy 449.295378 -51.391621) (xy 449.245801 -51.368977)
			(xy 449.199952 -51.339509) (xy 449.158764 -51.303815) (xy 449.123073 -51.262624) (xy 449.093608 -51.216772)
			(xy 449.070968 -51.167194) (xy 449.055614 -51.114899) (xy 449.047858 -51.060951) (xy 448.524452 -51.060951)
			(xy 448.561818 -51.084961) (xy 448.603016 -51.120655) (xy 448.638715 -51.16185) (xy 448.668187 -51.207705)
			(xy 448.690832 -51.257288) (xy 448.70619 -51.30959) (xy 448.713949 -51.363545) (xy 448.713949 -51.418055)
			(xy 448.70619 -51.47201) (xy 448.690832 -51.524312) (xy 448.668187 -51.573895) (xy 448.638715 -51.61975)
			(xy 448.603016 -51.660945) (xy 448.561818 -51.696639) (xy 448.51596 -51.726106) (xy 448.466374 -51.748746)
			(xy 448.414071 -51.764099) (xy 448.360115 -51.771851) (xy 448.33286 -51.772312) (xy 448.305151 -51.771815)
			(xy 448.250316 -51.763787) (xy 448.197222 -51.747906) (xy 448.146986 -51.724506) (xy 448.100666 -51.69408)
			(xy 448.079622 -51.676046) (xy 448.072493 -51.670227) (xy 448.05529 -51.663727) (xy 448.046094 -51.663346)
			(xy 447.968624 -51.663346) (xy 447.951606 -51.669696) (xy 447.944494 -51.676046) (xy 447.923468 -51.694101)
			(xy 447.877145 -51.724527) (xy 447.826904 -51.747924) (xy 447.773805 -51.763799) (xy 447.718967 -51.771818)
			(xy 447.691256 -51.772312) (xy 447.664007 -51.771815) (xy 447.610065 -51.764054) (xy 447.557776 -51.748695)
			(xy 447.508205 -51.726052) (xy 447.46236 -51.696584) (xy 447.421176 -51.660893) (xy 447.385489 -51.619705)
			(xy 447.356027 -51.573857) (xy 447.33339 -51.524283) (xy 447.318037 -51.471992) (xy 447.310282 -51.418049)
			(xy 446.918324 -51.418049) (xy 446.912868 -51.455997) (xy 446.897514 -51.50829) (xy 446.874874 -51.557866)
			(xy 446.84541 -51.603716) (xy 446.80972 -51.644906) (xy 446.768532 -51.680598) (xy 446.722684 -51.710065)
			(xy 446.673109 -51.732707) (xy 446.620816 -51.748064) (xy 446.56687 -51.755823) (xy 446.53962 -51.75631)
			(xy 446.51191 -51.755837) (xy 446.457074 -51.747803) (xy 446.40398 -51.731916) (xy 446.353744 -51.708511)
			(xy 446.307425 -51.67808) (xy 446.286382 -51.660044) (xy 446.279235 -51.65425) (xy 446.262046 -51.647735)
			(xy 446.252854 -51.647344) (xy 446.175384 -51.647344) (xy 446.158366 -51.653694) (xy 446.151254 -51.660044)
			(xy 446.130204 -51.678071) (xy 446.083888 -51.708501) (xy 446.033653 -51.731903) (xy 445.980559 -51.747785)
			(xy 445.925725 -51.755812) (xy 445.898016 -51.75631) (xy 445.870763 -51.755844) (xy 445.81681 -51.748089)
			(xy 445.764511 -51.732734) (xy 445.714929 -51.710093) (xy 445.669074 -51.680625) (xy 445.62788 -51.644932)
			(xy 445.592184 -51.603739) (xy 445.562715 -51.557885) (xy 445.540071 -51.508304) (xy 445.524715 -51.456005)
			(xy 445.516957 -51.402053) (xy 430.174146 -51.402053) (xy 430.174146 -53.055266) (xy 460.930242 -53.055266)
			(xy 460.934313 -52.999644) (xy 460.946439 -52.945207) (xy 460.966362 -52.893116) (xy 460.993658 -52.844481)
			(xy 461.027744 -52.800338) (xy 461.067893 -52.761629) (xy 461.113251 -52.729178) (xy 461.162851 -52.703677)
			(xy 461.215635 -52.68567) (xy 461.270478 -52.67554) (xy 461.326212 -52.673503) (xy 461.381649 -52.679603)
			(xy 461.435606 -52.693709) (xy 461.486935 -52.715521) (xy 461.534541 -52.744575) (xy 461.577409 -52.78025)
			(xy 461.614626 -52.821787) (xy 461.645399 -52.8683) (xy 461.669071 -52.918797) (xy 461.685139 -52.972204)
			(xy 461.693259 -53.02738) (xy 461.693768 -53.055266) (xy 461.693259 -53.083152) (xy 461.685139 -53.138328)
			(xy 461.669071 -53.191735) (xy 461.645399 -53.242232) (xy 461.614626 -53.288745) (xy 461.577409 -53.330282)
			(xy 461.534541 -53.365957) (xy 461.486935 -53.395011) (xy 461.435606 -53.416823) (xy 461.381649 -53.430929)
			(xy 461.326212 -53.437029) (xy 461.270478 -53.434992) (xy 461.215635 -53.424862) (xy 461.162851 -53.406855)
			(xy 461.113251 -53.381354) (xy 461.067893 -53.348903) (xy 461.027744 -53.310194) (xy 460.993658 -53.266051)
			(xy 460.966362 -53.217416) (xy 460.946439 -53.165325) (xy 460.934313 -53.110888) (xy 460.930242 -53.055266)
			(xy 430.174146 -53.055266) (xy 430.174146 -54.09438) (xy 430.174585 -54.104443) (xy 430.182325 -54.123022)
			(xy 430.189132 -54.130448) (xy 437.064912 -61.006228) (xy 437.071764 -61.013624) (xy 437.079502 -61.032223)
			(xy 437.079898 -61.042296) (xy 437.079898 -68.527676) (xy 444.63208 -68.527676) (xy 444.632623 -68.49876)
			(xy 444.641342 -68.441588) (xy 444.658594 -68.386389) (xy 444.68398 -68.334426) (xy 444.716921 -68.286892)
			(xy 444.756661 -68.244876) (xy 444.779146 -68.226686) (xy 444.787957 -68.219083) (xy 444.798137 -68.198179)
			(xy 444.798704 -68.186554) (xy 444.798704 -68.106798) (xy 444.79815 -68.095168) (xy 444.787972 -68.074258)
			(xy 444.779146 -68.066666) (xy 444.756635 -68.048508) (xy 444.716904 -68.00648) (xy 444.68397 -67.958937)
			(xy 444.658587 -67.90697) (xy 444.641336 -67.851767) (xy 444.632612 -67.794594) (xy 444.63208 -67.765676)
			(xy 444.632555 -67.738425) (xy 444.640315 -67.684477) (xy 444.655672 -67.632183) (xy 444.678316 -67.582607)
			(xy 444.707783 -67.536757) (xy 444.743476 -67.495567) (xy 444.784666 -67.459876) (xy 444.830517 -67.43041)
			(xy 444.880094 -67.407768) (xy 444.932389 -67.392412) (xy 444.986337 -67.384655) (xy 445.013588 -67.384168)
			(xy 445.042506 -67.384669) (xy 445.099679 -67.393398) (xy 445.154879 -67.410658) (xy 445.206842 -67.436052)
			(xy 445.254375 -67.469) (xy 445.29639 -67.508746) (xy 445.314578 -67.531234) (xy 445.322199 -67.540027)
			(xy 445.343089 -67.550217) (xy 445.35471 -67.550792) (xy 445.434466 -67.550792) (xy 445.446094 -67.550222)
			(xy 445.467004 -67.540055) (xy 445.474598 -67.531234) (xy 445.491351 -67.510451) (xy 445.529705 -67.473321)
			(xy 445.572859 -67.441899) (xy 445.619973 -67.4168) (xy 445.670125 -67.398514) (xy 445.722336 -67.387397)
			(xy 445.775588 -67.383667) (xy 445.82884 -67.387397) (xy 445.881051 -67.398514) (xy 445.931203 -67.4168)
			(xy 445.978317 -67.441899) (xy 446.021471 -67.473321) (xy 446.059825 -67.510451) (xy 446.076578 -67.531234)
			(xy 446.084199 -67.540027) (xy 446.105089 -67.550217) (xy 446.11671 -67.550792) (xy 446.196466 -67.550792)
			(xy 446.208094 -67.550222) (xy 446.229004 -67.540055) (xy 446.236598 -67.531234) (xy 446.254799 -67.508759)
			(xy 446.296815 -67.469021) (xy 446.344348 -67.43608) (xy 446.396308 -67.41069) (xy 446.451504 -67.393433)
			(xy 446.508672 -67.384703) (xy 446.537588 -67.384168) (xy 446.564838 -67.384689) (xy 446.618783 -67.392444)
			(xy 446.671076 -67.407796) (xy 446.720651 -67.430434) (xy 446.7665 -67.459897) (xy 446.80769 -67.495584)
			(xy 446.843382 -67.536771) (xy 446.872849 -67.582617) (xy 446.895491 -67.632191) (xy 446.910849 -67.684482)
			(xy 446.918608 -67.738426) (xy 446.919096 -67.765676) (xy 446.918562 -67.794592) (xy 446.909836 -67.851763)
			(xy 446.892582 -67.906961) (xy 446.867193 -67.958923) (xy 446.834252 -68.006458) (xy 446.794514 -68.048475)
			(xy 446.77203 -68.066666) (xy 446.763237 -68.074286) (xy 446.753048 -68.095177) (xy 446.752472 -68.106798)
			(xy 446.752472 -68.186554) (xy 446.752969 -68.198192) (xy 446.763185 -68.219103) (xy 446.77203 -68.226686)
			(xy 446.794513 -68.244877) (xy 446.834247 -68.286898) (xy 446.867185 -68.334433) (xy 446.892573 -68.386394)
			(xy 446.90983 -68.441591) (xy 446.917662 -68.492878) (xy 447.058034 -68.492878) (xy 447.058596 -68.463963)
			(xy 447.067314 -68.406793) (xy 447.084562 -68.351594) (xy 447.109946 -68.299632) (xy 447.142883 -68.252097)
			(xy 447.182617 -68.210079) (xy 447.2051 -68.191888) (xy 447.213903 -68.184276) (xy 447.224089 -68.163379)
			(xy 447.224658 -68.151756) (xy 447.224658 -68.072) (xy 447.224119 -68.060368) (xy 447.213932 -68.039457)
			(xy 447.2051 -68.031868) (xy 447.182601 -68.013695) (xy 447.142867 -67.971672) (xy 447.10993 -67.924133)
			(xy 447.084544 -67.872168) (xy 447.067291 -67.816967) (xy 447.058567 -67.759795) (xy 447.058034 -67.730878)
			(xy 447.058435 -67.703623) (xy 447.066196 -67.649667) (xy 447.081557 -67.597366) (xy 447.104205 -67.547783)
			(xy 447.133679 -67.501927) (xy 447.169379 -67.460734) (xy 447.210579 -67.425041) (xy 447.256439 -67.395574)
			(xy 447.306026 -67.372934) (xy 447.35833 -67.357582) (xy 447.412287 -67.34983) (xy 447.439542 -67.34937)
			(xy 447.468459 -67.349904) (xy 447.52563 -67.358626) (xy 447.58083 -67.375879) (xy 447.632792 -67.401268)
			(xy 447.680326 -67.43421) (xy 447.722342 -67.473951) (xy 447.740532 -67.496436) (xy 447.748129 -67.505254)
			(xy 447.769038 -67.51543) (xy 447.780664 -67.515994) (xy 447.86042 -67.515994) (xy 447.872052 -67.515454)
			(xy 447.892961 -67.505266) (xy 447.900552 -67.496436) (xy 447.917305 -67.475653) (xy 447.955659 -67.438523)
			(xy 447.998813 -67.407101) (xy 448.045927 -67.382002) (xy 448.096079 -67.363716) (xy 448.14829 -67.352599)
			(xy 448.201542 -67.348869) (xy 448.254794 -67.352599) (xy 448.307005 -67.363716) (xy 448.357157 -67.382002)
			(xy 448.404271 -67.407101) (xy 448.447425 -67.438523) (xy 448.485779 -67.475653) (xy 448.502532 -67.496436)
			(xy 448.510129 -67.505254) (xy 448.531038 -67.51543) (xy 448.542664 -67.515994) (xy 448.62242 -67.515994)
			(xy 448.634052 -67.515454) (xy 448.654961 -67.505266) (xy 448.662552 -67.496436) (xy 448.680779 -67.473983)
			(xy 448.72279 -67.434244) (xy 448.770317 -67.401301) (xy 448.822272 -67.375907) (xy 448.877463 -67.358644)
			(xy 448.934628 -67.349908) (xy 448.963542 -67.34937) (xy 448.990793 -67.349839) (xy 449.04474 -67.3576)
			(xy 449.097034 -67.37296) (xy 449.14661 -67.395604) (xy 449.192459 -67.425073) (xy 449.233648 -67.460766)
			(xy 449.269339 -67.501957) (xy 449.298806 -67.547807) (xy 449.321447 -67.597385) (xy 449.336804 -67.649679)
			(xy 449.344563 -67.703627) (xy 449.34505 -67.730878) (xy 449.344535 -67.759795) (xy 449.335808 -67.816967)
			(xy 449.318551 -67.872167) (xy 449.293158 -67.924129) (xy 449.260213 -67.971663) (xy 449.220471 -68.013679)
			(xy 449.197984 -68.031868) (xy 449.189198 -68.039496) (xy 449.179003 -68.060381) (xy 449.178426 -68.072)
			(xy 449.178426 -68.151756) (xy 449.178938 -68.163392) (xy 449.189145 -68.184301) (xy 449.197984 -68.191888)
			(xy 449.220458 -68.21009) (xy 449.260195 -68.252107) (xy 449.293135 -68.299639) (xy 449.318526 -68.351599)
			(xy 449.335784 -68.406794) (xy 449.344514 -68.463963) (xy 449.34505 -68.492878) (xy 449.344501 -68.520127)
			(xy 449.336749 -68.57407) (xy 449.321399 -68.626361) (xy 449.298763 -68.675935) (xy 449.269303 -68.721784)
			(xy 449.233618 -68.762973) (xy 449.192435 -68.798665) (xy 449.146591 -68.828133) (xy 449.097021 -68.850776)
			(xy 449.044733 -68.866135) (xy 448.990791 -68.873897) (xy 448.963542 -68.874386) (xy 448.934626 -68.873843)
			(xy 448.877456 -68.86512) (xy 448.822257 -68.847867) (xy 448.770295 -68.82248) (xy 448.722761 -68.789541)
			(xy 448.680743 -68.749804) (xy 448.662552 -68.72732) (xy 448.65497 -68.718488) (xy 448.63405 -68.708321)
			(xy 448.62242 -68.707762) (xy 448.542664 -68.707762) (xy 448.531028 -68.708273) (xy 448.510118 -68.71848)
			(xy 448.502532 -68.72732) (xy 448.485779 -68.748103) (xy 448.447425 -68.785233) (xy 448.404271 -68.816655)
			(xy 448.357157 -68.841754) (xy 448.307005 -68.86004) (xy 448.254794 -68.871157) (xy 448.201542 -68.874887)
			(xy 448.14829 -68.871157) (xy 448.096079 -68.86004) (xy 448.045927 -68.841754) (xy 447.998813 -68.816655)
			(xy 447.955659 -68.785233) (xy 447.917305 -68.748103) (xy 447.900552 -68.72732) (xy 447.89297 -68.718488)
			(xy 447.87205 -68.708321) (xy 447.86042 -68.707762) (xy 447.780664 -68.707762) (xy 447.769028 -68.708273)
			(xy 447.748118 -68.71848) (xy 447.740532 -68.72732) (xy 447.722328 -68.749792) (xy 447.68031 -68.789527)
			(xy 447.632778 -68.822467) (xy 447.580819 -68.847857) (xy 447.525624 -68.865116) (xy 447.468457 -68.873849)
			(xy 447.439542 -68.874386) (xy 447.412289 -68.873906) (xy 447.358338 -68.866154) (xy 447.306039 -68.850802)
			(xy 447.256457 -68.828163) (xy 447.210603 -68.798697) (xy 447.169409 -68.763005) (xy 447.133715 -68.721813)
			(xy 447.104247 -68.67596) (xy 447.081605 -68.62638) (xy 447.066251 -68.574082) (xy 447.058496 -68.520131)
			(xy 447.058034 -68.492878) (xy 446.917662 -68.492878) (xy 446.91856 -68.49876) (xy 446.919096 -68.527676)
			(xy 446.918622 -68.554929) (xy 446.910868 -68.60888) (xy 446.895515 -68.661178) (xy 446.872874 -68.710759)
			(xy 446.843408 -68.756613) (xy 446.807715 -68.797806) (xy 446.766523 -68.8335) (xy 446.72067 -68.862968)
			(xy 446.67109 -68.885611) (xy 446.618792 -68.900966) (xy 446.564841 -68.908721) (xy 446.537588 -68.909184)
			(xy 446.508673 -68.908609) (xy 446.451504 -68.899892) (xy 446.396306 -68.882646) (xy 446.344344 -68.857265)
			(xy 446.296809 -68.824331) (xy 446.25479 -68.784599) (xy 446.236598 -68.762118) (xy 446.228996 -68.753306)
			(xy 446.208091 -68.743128) (xy 446.196466 -68.74256) (xy 446.11671 -68.74256) (xy 446.105077 -68.743098)
			(xy 446.084167 -68.753286) (xy 446.076578 -68.762118) (xy 446.059825 -68.782901) (xy 446.021471 -68.820031)
			(xy 445.978317 -68.851453) (xy 445.931203 -68.876552) (xy 445.881051 -68.894838) (xy 445.82884 -68.905955)
			(xy 445.775588 -68.909685) (xy 445.722336 -68.905955) (xy 445.670125 -68.894838) (xy 445.619973 -68.876552)
			(xy 445.572859 -68.851453) (xy 445.529705 -68.820031) (xy 445.491351 -68.782901) (xy 445.474598 -68.762118)
			(xy 445.466996 -68.753306) (xy 445.446091 -68.743128) (xy 445.434466 -68.74256) (xy 445.35471 -68.74256)
			(xy 445.343077 -68.743098) (xy 445.322167 -68.753286) (xy 445.314578 -68.762118) (xy 445.296404 -68.784616)
			(xy 445.25438 -68.824349) (xy 445.206842 -68.857286) (xy 445.154877 -68.882672) (xy 445.099677 -68.899925)
			(xy 445.042505 -68.908651) (xy 445.013588 -68.909184) (xy 444.986334 -68.908756) (xy 444.93238 -68.900997)
			(xy 444.88008 -68.885638) (xy 444.830498 -68.862993) (xy 444.784644 -68.833521) (xy 444.743451 -68.797824)
			(xy 444.707757 -68.756627) (xy 444.67829 -68.71077) (xy 444.655649 -68.661186) (xy 444.640295 -68.608885)
			(xy 444.632541 -68.55493) (xy 444.63208 -68.527676) (xy 437.079898 -68.527676) (xy 437.079898 -69.003164)
			(xy 450.629274 -69.003164) (xy 450.629701 -68.975792) (xy 450.637525 -68.921611) (xy 450.653023 -68.869106)
			(xy 450.675874 -68.81936) (xy 450.705608 -68.773396) (xy 450.723254 -68.752466) (xy 450.723508 -68.752212)
			(xy 450.729097 -68.745127) (xy 450.735342 -68.728209) (xy 450.7357 -68.719192) (xy 450.7357 -68.652136)
			(xy 450.735326 -68.643121) (xy 450.72909 -68.626204) (xy 450.723508 -68.619116) (xy 450.723254 -68.619116)
			(xy 450.723254 -68.618862) (xy 450.705577 -68.597958) (xy 450.675852 -68.551986) (xy 450.653007 -68.502235)
			(xy 450.637512 -68.449729) (xy 450.629686 -68.395546) (xy 450.62969 -68.3408) (xy 450.637524 -68.286618)
			(xy 450.653026 -68.234114) (xy 450.675878 -68.184366) (xy 450.70561 -68.138398) (xy 450.723254 -68.117466)
			(xy 450.723508 -68.117212) (xy 450.729097 -68.110127) (xy 450.735342 -68.093209) (xy 450.7357 -68.084192)
			(xy 450.7357 -68.017136) (xy 450.735326 -68.008121) (xy 450.72909 -67.991204) (xy 450.723508 -67.984116)
			(xy 450.723254 -67.984116) (xy 450.723254 -67.983862) (xy 450.705577 -67.962958) (xy 450.675852 -67.916986)
			(xy 450.653007 -67.867235) (xy 450.637512 -67.814729) (xy 450.629686 -67.760546) (xy 450.62969 -67.7058)
			(xy 450.637524 -67.651618) (xy 450.653026 -67.599114) (xy 450.675878 -67.549366) (xy 450.70561 -67.503398)
			(xy 450.723254 -67.482466) (xy 450.723508 -67.482212) (xy 450.729097 -67.475127) (xy 450.735342 -67.458209)
			(xy 450.7357 -67.449192) (xy 450.7357 -67.382136) (xy 450.735326 -67.373121) (xy 450.72909 -67.356204)
			(xy 450.723508 -67.349116) (xy 450.723254 -67.349116) (xy 450.723254 -67.348862) (xy 450.705577 -67.327958)
			(xy 450.675852 -67.281986) (xy 450.653007 -67.232235) (xy 450.637512 -67.179729) (xy 450.629686 -67.125546)
			(xy 450.62969 -67.0708) (xy 450.637524 -67.016618) (xy 450.653026 -66.964114) (xy 450.675878 -66.914366)
			(xy 450.70561 -66.868398) (xy 450.723254 -66.847466) (xy 450.723508 -66.847212) (xy 450.729097 -66.840127)
			(xy 450.735342 -66.823209) (xy 450.7357 -66.814192) (xy 450.7357 -66.747136) (xy 450.735326 -66.738121)
			(xy 450.72909 -66.721204) (xy 450.723508 -66.714116) (xy 450.723254 -66.714116) (xy 450.723254 -66.713862)
			(xy 450.705639 -66.69291) (xy 450.675922 -66.646944) (xy 450.65308 -66.597201) (xy 450.637584 -66.544705)
			(xy 450.62975 -66.490532) (xy 450.629274 -66.463164) (xy 450.629744 -66.435913) (xy 450.637505 -66.381965)
			(xy 450.652864 -66.329671) (xy 450.675508 -66.280095) (xy 450.704976 -66.234246) (xy 450.740669 -66.193057)
			(xy 450.78186 -66.157366) (xy 450.827711 -66.127899) (xy 450.877288 -66.105258) (xy 450.929583 -66.089901)
			(xy 450.983531 -66.082143) (xy 451.010782 -66.081656) (xy 451.037266 -66.082125) (xy 451.089726 -66.089444)
			(xy 451.140667 -66.103956) (xy 451.189108 -66.125383) (xy 451.234115 -66.153311) (xy 451.274821 -66.187202)
			(xy 451.310442 -66.226404) (xy 451.325742 -66.248026) (xy 451.325996 -66.24828) (xy 451.333593 -66.258166)
			(xy 451.355703 -66.269623) (xy 451.36816 -66.270124) (xy 451.465696 -66.269108) (xy 451.487794 -66.256916)
			(xy 451.494652 -66.246248) (xy 451.509819 -66.223831) (xy 451.545524 -66.183154) (xy 451.586616 -66.147929)
			(xy 451.632272 -66.118861) (xy 451.681577 -66.096533) (xy 451.733541 -66.081394) (xy 451.787122 -66.073747)
			(xy 451.814184 -66.073274) (xy 451.841434 -66.073793) (xy 451.89538 -66.081547) (xy 451.947673 -66.096899)
			(xy 451.997248 -66.119537) (xy 452.043098 -66.149) (xy 452.084288 -66.184688) (xy 452.11998 -66.225875)
			(xy 452.149447 -66.271722) (xy 452.172089 -66.321296) (xy 452.187446 -66.373587) (xy 452.195204 -66.427532)
			(xy 452.195692 -66.454782) (xy 452.195217 -66.482152) (xy 452.187402 -66.536331) (xy 452.171915 -66.588834)
			(xy 452.149075 -66.638581) (xy 452.119352 -66.684548) (xy 452.101712 -66.70548) (xy 452.101458 -66.705734)
			(xy 452.095888 -66.712832) (xy 452.089632 -66.72974) (xy 452.089266 -66.738754) (xy 452.089266 -66.80581)
			(xy 452.089625 -66.814826) (xy 452.095872 -66.831743) (xy 452.101458 -66.83883) (xy 452.101712 -66.83883)
			(xy 452.101712 -66.839084) (xy 452.119333 -66.860032) (xy 452.149056 -66.905998) (xy 452.1719 -66.955742)
			(xy 452.187396 -67.008241) (xy 452.195225 -67.062417) (xy 452.195227 -67.117156) (xy 452.187402 -67.171332)
			(xy 452.17191 -67.223833) (xy 452.149069 -67.273578) (xy 452.11935 -67.319547) (xy 452.101712 -67.34048)
			(xy 452.101458 -67.340734) (xy 452.095888 -67.347832) (xy 452.089632 -67.36474) (xy 452.089266 -67.373754)
			(xy 452.089266 -67.44081) (xy 452.089625 -67.449826) (xy 452.095872 -67.466743) (xy 452.101458 -67.47383)
			(xy 452.101712 -67.47383) (xy 452.101712 -67.474084) (xy 452.119333 -67.495032) (xy 452.149056 -67.540998)
			(xy 452.1719 -67.590742) (xy 452.187396 -67.643241) (xy 452.195225 -67.697417) (xy 452.195227 -67.752156)
			(xy 452.187402 -67.806332) (xy 452.17191 -67.858833) (xy 452.149069 -67.908578) (xy 452.11935 -67.954547)
			(xy 452.101712 -67.97548) (xy 452.101458 -67.975734) (xy 452.095888 -67.982832) (xy 452.089632 -67.99974)
			(xy 452.089266 -68.008754) (xy 452.089266 -68.07581) (xy 452.089625 -68.084826) (xy 452.095872 -68.101743)
			(xy 452.101458 -68.10883) (xy 452.101712 -68.10883) (xy 452.101712 -68.109084) (xy 452.119333 -68.130032)
			(xy 452.149056 -68.175998) (xy 452.1719 -68.225742) (xy 452.187396 -68.278241) (xy 452.195225 -68.332417)
			(xy 452.195227 -68.387156) (xy 452.187402 -68.441332) (xy 452.17191 -68.493833) (xy 452.149069 -68.543578)
			(xy 452.11935 -68.589547) (xy 452.101712 -68.61048) (xy 452.101458 -68.610734) (xy 452.095888 -68.617832)
			(xy 452.089632 -68.63474) (xy 452.089266 -68.643754) (xy 452.089266 -68.71081) (xy 452.089625 -68.719826)
			(xy 452.095872 -68.736743) (xy 452.101458 -68.74383) (xy 452.101712 -68.74383) (xy 452.101712 -68.744084)
			(xy 452.119359 -68.76501) (xy 452.149069 -68.810984) (xy 452.171903 -68.860734) (xy 452.187393 -68.913236)
			(xy 452.195219 -68.967412) (xy 452.195692 -68.994782) (xy 452.728076 -68.994782) (xy 452.728513 -68.967411)
			(xy 452.736335 -68.913229) (xy 452.75183 -68.860725) (xy 452.774679 -68.810979) (xy 452.804411 -68.765014)
			(xy 452.822056 -68.744084) (xy 452.82231 -68.74383) (xy 452.827891 -68.73674) (xy 452.834141 -68.719826)
			(xy 452.834502 -68.71081) (xy 452.834502 -68.643754) (xy 452.834118 -68.63474) (xy 452.827889 -68.617823)
			(xy 452.82231 -68.610734) (xy 452.822056 -68.610734) (xy 452.822056 -68.61048) (xy 452.804396 -68.589562)
			(xy 452.77467 -68.543592) (xy 452.751824 -68.493844) (xy 452.736328 -68.441339) (xy 452.7285 -68.387158)
			(xy 452.728502 -68.332415) (xy 452.736334 -68.278234) (xy 452.751834 -68.225731) (xy 452.774683 -68.175984)
			(xy 452.804413 -68.130016) (xy 452.822056 -68.109084) (xy 452.82231 -68.10883) (xy 452.827891 -68.10174)
			(xy 452.834141 -68.084826) (xy 452.834502 -68.07581) (xy 452.834502 -68.008754) (xy 452.834118 -67.99974)
			(xy 452.827889 -67.982823) (xy 452.82231 -67.975734) (xy 452.822056 -67.975734) (xy 452.822056 -67.97548)
			(xy 452.804434 -67.954535) (xy 452.774721 -67.908565) (xy 452.751882 -67.858821) (xy 452.736387 -67.806323)
			(xy 452.728553 -67.75215) (xy 452.728076 -67.724782) (xy 452.728562 -67.697531) (xy 452.736318 -67.643583)
			(xy 452.751673 -67.591288) (xy 452.774315 -67.541711) (xy 452.803781 -67.495861) (xy 452.839472 -67.45467)
			(xy 452.880663 -67.418979) (xy 452.926513 -67.389513) (xy 452.97609 -67.366871) (xy 453.028385 -67.351516)
			(xy 453.082333 -67.34376) (xy 453.136835 -67.34376) (xy 453.190783 -67.351516) (xy 453.243078 -67.366871)
			(xy 453.292655 -67.389513) (xy 453.338505 -67.418979) (xy 453.379696 -67.45467) (xy 453.415387 -67.495861)
			(xy 453.444853 -67.541711) (xy 453.467495 -67.591288) (xy 453.48285 -67.643583) (xy 453.490606 -67.697531)
			(xy 453.491092 -67.724782) (xy 453.490617 -67.752152) (xy 453.482802 -67.806331) (xy 453.467315 -67.858834)
			(xy 453.444475 -67.908581) (xy 453.414752 -67.954548) (xy 453.397112 -67.97548) (xy 453.396858 -67.975734)
			(xy 453.391288 -67.982832) (xy 453.385032 -67.99974) (xy 453.384666 -68.008754) (xy 453.384666 -68.07581)
			(xy 453.385025 -68.084826) (xy 453.391272 -68.101743) (xy 453.396858 -68.10883) (xy 453.397112 -68.10883)
			(xy 453.397112 -68.109084) (xy 453.414733 -68.130032) (xy 453.444456 -68.175998) (xy 453.4673 -68.225742)
			(xy 453.482796 -68.278241) (xy 453.490625 -68.332417) (xy 453.490627 -68.387156) (xy 453.482802 -68.441332)
			(xy 453.46731 -68.493833) (xy 453.444469 -68.543578) (xy 453.41475 -68.589547) (xy 453.397112 -68.61048)
			(xy 453.396858 -68.610734) (xy 453.391288 -68.617832) (xy 453.385032 -68.63474) (xy 453.384666 -68.643754)
			(xy 453.384666 -68.71081) (xy 453.385025 -68.719826) (xy 453.391272 -68.736743) (xy 453.396858 -68.74383)
			(xy 453.397112 -68.74383) (xy 453.397112 -68.744084) (xy 453.414759 -68.76501) (xy 453.444469 -68.810984)
			(xy 453.467303 -68.860734) (xy 453.482793 -68.913236) (xy 453.490619 -68.967412) (xy 453.491092 -68.994782)
			(xy 458.747876 -68.994782) (xy 458.748313 -68.967411) (xy 458.756135 -68.913229) (xy 458.77163 -68.860725)
			(xy 458.794479 -68.810979) (xy 458.824211 -68.765014) (xy 458.841856 -68.744084) (xy 458.84211 -68.74383)
			(xy 458.847691 -68.73674) (xy 458.853941 -68.719826) (xy 458.854302 -68.71081) (xy 458.854302 -68.643754)
			(xy 458.853918 -68.63474) (xy 458.847689 -68.617823) (xy 458.84211 -68.610734) (xy 458.841856 -68.610734)
			(xy 458.841856 -68.61048) (xy 458.824196 -68.589562) (xy 458.79447 -68.543592) (xy 458.771624 -68.493844)
			(xy 458.756128 -68.441339) (xy 458.7483 -68.387158) (xy 458.748302 -68.332415) (xy 458.756134 -68.278234)
			(xy 458.771634 -68.225731) (xy 458.794483 -68.175984) (xy 458.824213 -68.130016) (xy 458.841856 -68.109084)
			(xy 458.84211 -68.10883) (xy 458.847691 -68.10174) (xy 458.853941 -68.084826) (xy 458.854302 -68.07581)
			(xy 458.854302 -68.008754) (xy 458.853918 -67.99974) (xy 458.847689 -67.982823) (xy 458.84211 -67.975734)
			(xy 458.841856 -67.975734) (xy 458.841856 -67.97548) (xy 458.824196 -67.954562) (xy 458.79447 -67.908592)
			(xy 458.771624 -67.858844) (xy 458.756128 -67.806339) (xy 458.7483 -67.752158) (xy 458.748302 -67.697415)
			(xy 458.756134 -67.643234) (xy 458.771634 -67.590731) (xy 458.794483 -67.540984) (xy 458.824213 -67.495016)
			(xy 458.841856 -67.474084) (xy 458.84211 -67.47383) (xy 458.847691 -67.46674) (xy 458.853941 -67.449826)
			(xy 458.854302 -67.44081) (xy 458.854302 -67.373754) (xy 458.853918 -67.36474) (xy 458.847689 -67.347823)
			(xy 458.84211 -67.340734) (xy 458.841856 -67.340734) (xy 458.841856 -67.34048) (xy 458.824234 -67.319535)
			(xy 458.794521 -67.273565) (xy 458.771682 -67.223821) (xy 458.756187 -67.171323) (xy 458.748353 -67.11715)
			(xy 458.747876 -67.089782) (xy 458.748362 -67.062531) (xy 458.756118 -67.008583) (xy 458.771473 -66.956288)
			(xy 458.794115 -66.906711) (xy 458.823581 -66.860861) (xy 458.859272 -66.81967) (xy 458.900463 -66.783979)
			(xy 458.946313 -66.754513) (xy 458.99589 -66.731871) (xy 459.048185 -66.716516) (xy 459.102133 -66.70876)
			(xy 459.156635 -66.70876) (xy 459.210583 -66.716516) (xy 459.262878 -66.731871) (xy 459.312455 -66.754513)
			(xy 459.358305 -66.783979) (xy 459.399496 -66.81967) (xy 459.435187 -66.860861) (xy 459.464653 -66.906711)
			(xy 459.487295 -66.956288) (xy 459.50265 -67.008583) (xy 459.510406 -67.062531) (xy 459.510892 -67.089782)
			(xy 459.510417 -67.117152) (xy 459.502602 -67.171331) (xy 459.487115 -67.223834) (xy 459.464275 -67.273581)
			(xy 459.434552 -67.319548) (xy 459.416912 -67.34048) (xy 459.416658 -67.340734) (xy 459.411088 -67.347832)
			(xy 459.404832 -67.36474) (xy 459.404466 -67.373754) (xy 459.404466 -67.44081) (xy 459.404825 -67.449826)
			(xy 459.411072 -67.466743) (xy 459.416658 -67.47383) (xy 459.416912 -67.47383) (xy 459.416912 -67.474084)
			(xy 459.434533 -67.495032) (xy 459.464256 -67.540998) (xy 459.4871 -67.590742) (xy 459.502596 -67.643241)
			(xy 459.510425 -67.697417) (xy 459.510427 -67.752156) (xy 459.502602 -67.806332) (xy 459.48711 -67.858833)
			(xy 459.464269 -67.908578) (xy 459.43455 -67.954547) (xy 459.416912 -67.97548) (xy 459.416658 -67.975734)
			(xy 459.411088 -67.982832) (xy 459.404832 -67.99974) (xy 459.404466 -68.008754) (xy 459.404466 -68.07581)
			(xy 459.404825 -68.084826) (xy 459.411072 -68.101743) (xy 459.416658 -68.10883) (xy 459.416912 -68.10883)
			(xy 459.416912 -68.109084) (xy 459.434533 -68.130032) (xy 459.464256 -68.175998) (xy 459.4871 -68.225742)
			(xy 459.502596 -68.278241) (xy 459.510425 -68.332417) (xy 459.510427 -68.387156) (xy 459.502602 -68.441332)
			(xy 459.48711 -68.493833) (xy 459.464269 -68.543578) (xy 459.43455 -68.589547) (xy 459.416912 -68.61048)
			(xy 459.416658 -68.610734) (xy 459.411088 -68.617832) (xy 459.404832 -68.63474) (xy 459.404466 -68.643754)
			(xy 459.404466 -68.71081) (xy 459.404825 -68.719826) (xy 459.411072 -68.736743) (xy 459.416658 -68.74383)
			(xy 459.416912 -68.74383) (xy 459.416912 -68.744084) (xy 459.434559 -68.76501) (xy 459.464269 -68.810984)
			(xy 459.487103 -68.860734) (xy 459.502593 -68.913236) (xy 459.510419 -68.967412) (xy 459.510892 -68.994782)
			(xy 459.510406 -69.022033) (xy 459.50265 -69.075981) (xy 459.487295 -69.128276) (xy 459.464653 -69.177853)
			(xy 459.435187 -69.223703) (xy 459.399496 -69.264894) (xy 459.358305 -69.300585) (xy 459.312455 -69.330051)
			(xy 459.262878 -69.352693) (xy 459.210583 -69.368048) (xy 459.156635 -69.375804) (xy 459.102133 -69.375804)
			(xy 459.048185 -69.368048) (xy 458.99589 -69.352693) (xy 458.946313 -69.330051) (xy 458.900463 -69.300585)
			(xy 458.859272 -69.264894) (xy 458.823581 -69.223703) (xy 458.794115 -69.177853) (xy 458.771473 -69.128276)
			(xy 458.756118 -69.075981) (xy 458.748362 -69.022033) (xy 458.747876 -68.994782) (xy 453.491092 -68.994782)
			(xy 453.490606 -69.022033) (xy 453.48285 -69.075981) (xy 453.467495 -69.128276) (xy 453.444853 -69.177853)
			(xy 453.415387 -69.223703) (xy 453.379696 -69.264894) (xy 453.338505 -69.300585) (xy 453.292655 -69.330051)
			(xy 453.243078 -69.352693) (xy 453.190783 -69.368048) (xy 453.136835 -69.375804) (xy 453.082333 -69.375804)
			(xy 453.028385 -69.368048) (xy 452.97609 -69.352693) (xy 452.926513 -69.330051) (xy 452.880663 -69.300585)
			(xy 452.839472 -69.264894) (xy 452.803781 -69.223703) (xy 452.774315 -69.177853) (xy 452.751673 -69.128276)
			(xy 452.736318 -69.075981) (xy 452.728562 -69.022033) (xy 452.728076 -68.994782) (xy 452.195692 -68.994782)
			(xy 452.195228 -69.022035) (xy 452.187473 -69.075987) (xy 452.172118 -69.128286) (xy 452.149477 -69.177867)
			(xy 452.120009 -69.223721) (xy 452.084315 -69.264914) (xy 452.043122 -69.300608) (xy 451.997269 -69.330076)
			(xy 451.947688 -69.352718) (xy 451.895389 -69.368073) (xy 451.841437 -69.375828) (xy 451.814184 -69.37629)
			(xy 451.7877 -69.375826) (xy 451.735241 -69.368504) (xy 451.6843 -69.353989) (xy 451.63586 -69.332561)
			(xy 451.590853 -69.304633) (xy 451.550147 -69.270742) (xy 451.514525 -69.231541) (xy 451.499224 -69.20992)
			(xy 451.49897 -69.209666) (xy 451.491381 -69.199772) (xy 451.469266 -69.188317) (xy 451.456806 -69.187822)
			(xy 451.35927 -69.188838) (xy 451.337172 -69.20103) (xy 451.330314 -69.211698) (xy 451.315087 -69.234072)
			(xy 451.279394 -69.274752) (xy 451.238313 -69.309983) (xy 451.192667 -69.339057) (xy 451.143372 -69.361391)
			(xy 451.091416 -69.376538) (xy 451.037841 -69.384194) (xy 451.010782 -69.384672) (xy 450.983527 -69.384262)
			(xy 450.929572 -69.376501) (xy 450.877271 -69.361141) (xy 450.827689 -69.338494) (xy 450.781834 -69.309021)
			(xy 450.74064 -69.273321) (xy 450.704947 -69.232123) (xy 450.67548 -69.186264) (xy 450.65284 -69.136678)
			(xy 450.637487 -69.084375) (xy 450.629734 -69.030419) (xy 450.629274 -69.003164) (xy 437.079898 -69.003164)
			(xy 437.079898 -69.722746) (xy 454.449178 -69.722746) (xy 454.453249 -69.667124) (xy 454.465375 -69.612687)
			(xy 454.485298 -69.560596) (xy 454.512594 -69.511961) (xy 454.54668 -69.467818) (xy 454.586829 -69.429109)
			(xy 454.632187 -69.396658) (xy 454.681787 -69.371157) (xy 454.734571 -69.35315) (xy 454.789414 -69.34302)
			(xy 454.845148 -69.340983) (xy 454.900585 -69.347083) (xy 454.954542 -69.361189) (xy 455.005871 -69.383001)
			(xy 455.053477 -69.412055) (xy 455.096345 -69.44773) (xy 455.133562 -69.489267) (xy 455.164335 -69.53578)
			(xy 455.188007 -69.586277) (xy 455.204075 -69.639684) (xy 455.212195 -69.69486) (xy 455.212704 -69.722746)
			(xy 455.338178 -69.722746) (xy 455.342249 -69.667124) (xy 455.354375 -69.612687) (xy 455.374298 -69.560596)
			(xy 455.401594 -69.511961) (xy 455.43568 -69.467818) (xy 455.475829 -69.429109) (xy 455.521187 -69.396658)
			(xy 455.570787 -69.371157) (xy 455.623571 -69.35315) (xy 455.678414 -69.34302) (xy 455.734148 -69.340983)
			(xy 455.789585 -69.347083) (xy 455.843542 -69.361189) (xy 455.894871 -69.383001) (xy 455.942477 -69.412055)
			(xy 455.985345 -69.44773) (xy 456.022562 -69.489267) (xy 456.053335 -69.53578) (xy 456.077007 -69.586277)
			(xy 456.093075 -69.639684) (xy 456.101195 -69.69486) (xy 456.101704 -69.722746) (xy 456.227178 -69.722746)
			(xy 456.231249 -69.667124) (xy 456.243375 -69.612687) (xy 456.263298 -69.560596) (xy 456.290594 -69.511961)
			(xy 456.32468 -69.467818) (xy 456.364829 -69.429109) (xy 456.410187 -69.396658) (xy 456.459787 -69.371157)
			(xy 456.512571 -69.35315) (xy 456.567414 -69.34302) (xy 456.623148 -69.340983) (xy 456.678585 -69.347083)
			(xy 456.732542 -69.361189) (xy 456.783871 -69.383001) (xy 456.831477 -69.412055) (xy 456.874345 -69.44773)
			(xy 456.911562 -69.489267) (xy 456.942335 -69.53578) (xy 456.966007 -69.586277) (xy 456.982075 -69.639684)
			(xy 456.990195 -69.69486) (xy 456.990704 -69.722746) (xy 457.116178 -69.722746) (xy 457.120249 -69.667124)
			(xy 457.132375 -69.612687) (xy 457.152298 -69.560596) (xy 457.179594 -69.511961) (xy 457.21368 -69.467818)
			(xy 457.253829 -69.429109) (xy 457.299187 -69.396658) (xy 457.348787 -69.371157) (xy 457.401571 -69.35315)
			(xy 457.456414 -69.34302) (xy 457.512148 -69.340983) (xy 457.567585 -69.347083) (xy 457.621542 -69.361189)
			(xy 457.672871 -69.383001) (xy 457.720477 -69.412055) (xy 457.763345 -69.44773) (xy 457.800562 -69.489267)
			(xy 457.831335 -69.53578) (xy 457.855007 -69.586277) (xy 457.871075 -69.639684) (xy 457.879195 -69.69486)
			(xy 457.879704 -69.722746) (xy 457.879195 -69.750632) (xy 457.871075 -69.805808) (xy 457.855007 -69.859215)
			(xy 457.831335 -69.909712) (xy 457.800562 -69.956225) (xy 457.763345 -69.997762) (xy 457.720477 -70.033437)
			(xy 457.672871 -70.062491) (xy 457.621542 -70.084303) (xy 457.567585 -70.098409) (xy 457.512148 -70.104509)
			(xy 457.456414 -70.102472) (xy 457.401571 -70.092342) (xy 457.348787 -70.074335) (xy 457.299187 -70.048834)
			(xy 457.253829 -70.016383) (xy 457.21368 -69.977674) (xy 457.179594 -69.933531) (xy 457.152298 -69.884896)
			(xy 457.132375 -69.832805) (xy 457.120249 -69.778368) (xy 457.116178 -69.722746) (xy 456.990704 -69.722746)
			(xy 456.990195 -69.750632) (xy 456.982075 -69.805808) (xy 456.966007 -69.859215) (xy 456.942335 -69.909712)
			(xy 456.911562 -69.956225) (xy 456.874345 -69.997762) (xy 456.831477 -70.033437) (xy 456.783871 -70.062491)
			(xy 456.732542 -70.084303) (xy 456.678585 -70.098409) (xy 456.623148 -70.104509) (xy 456.567414 -70.102472)
			(xy 456.512571 -70.092342) (xy 456.459787 -70.074335) (xy 456.410187 -70.048834) (xy 456.364829 -70.016383)
			(xy 456.32468 -69.977674) (xy 456.290594 -69.933531) (xy 456.263298 -69.884896) (xy 456.243375 -69.832805)
			(xy 456.231249 -69.778368) (xy 456.227178 -69.722746) (xy 456.101704 -69.722746) (xy 456.101195 -69.750632)
			(xy 456.093075 -69.805808) (xy 456.077007 -69.859215) (xy 456.053335 -69.909712) (xy 456.022562 -69.956225)
			(xy 455.985345 -69.997762) (xy 455.942477 -70.033437) (xy 455.894871 -70.062491) (xy 455.843542 -70.084303)
			(xy 455.789585 -70.098409) (xy 455.734148 -70.104509) (xy 455.678414 -70.102472) (xy 455.623571 -70.092342)
			(xy 455.570787 -70.074335) (xy 455.521187 -70.048834) (xy 455.475829 -70.016383) (xy 455.43568 -69.977674)
			(xy 455.401594 -69.933531) (xy 455.374298 -69.884896) (xy 455.354375 -69.832805) (xy 455.342249 -69.778368)
			(xy 455.338178 -69.722746) (xy 455.212704 -69.722746) (xy 455.212195 -69.750632) (xy 455.204075 -69.805808)
			(xy 455.188007 -69.859215) (xy 455.164335 -69.909712) (xy 455.133562 -69.956225) (xy 455.096345 -69.997762)
			(xy 455.053477 -70.033437) (xy 455.005871 -70.062491) (xy 454.954542 -70.084303) (xy 454.900585 -70.098409)
			(xy 454.845148 -70.104509) (xy 454.789414 -70.102472) (xy 454.734571 -70.092342) (xy 454.681787 -70.074335)
			(xy 454.632187 -70.048834) (xy 454.586829 -70.016383) (xy 454.54668 -69.977674) (xy 454.512594 -69.933531)
			(xy 454.485298 -69.884896) (xy 454.465375 -69.832805) (xy 454.453249 -69.778368) (xy 454.449178 -69.722746)
			(xy 437.079898 -69.722746) (xy 437.079898 -71.592186) (xy 444.82258 -71.592186) (xy 444.82313 -71.56327)
			(xy 444.831848 -71.506099) (xy 444.849098 -71.450899) (xy 444.874483 -71.398937) (xy 444.907423 -71.351402)
			(xy 444.947162 -71.309386) (xy 444.969646 -71.291196) (xy 444.978453 -71.283589) (xy 444.988635 -71.262688)
			(xy 444.989204 -71.251064) (xy 444.989204 -71.171308) (xy 444.988645 -71.159679) (xy 444.97847 -71.138769)
			(xy 444.969646 -71.131176) (xy 444.94714 -71.113012) (xy 444.907408 -71.070985) (xy 444.874474 -71.023444)
			(xy 444.84909 -70.971478) (xy 444.831838 -70.916276) (xy 444.823113 -70.859103) (xy 444.82258 -70.830186)
			(xy 444.823065 -70.802935) (xy 444.830823 -70.748988) (xy 444.846179 -70.696694) (xy 444.868821 -70.647117)
			(xy 444.898288 -70.601268) (xy 444.933979 -70.560078) (xy 444.975169 -70.524386) (xy 445.021019 -70.49492)
			(xy 445.070596 -70.472278) (xy 445.12289 -70.456922) (xy 445.176837 -70.449165) (xy 445.204088 -70.448678)
			(xy 445.233006 -70.449175) (xy 445.29018 -70.457904) (xy 445.34538 -70.475165) (xy 445.397342 -70.50056)
			(xy 445.444876 -70.533509) (xy 445.48689 -70.573256) (xy 445.505078 -70.595744) (xy 445.512697 -70.604538)
			(xy 445.533589 -70.614727) (xy 445.54521 -70.615302) (xy 445.624966 -70.615302) (xy 445.636594 -70.614728)
			(xy 445.657503 -70.604564) (xy 445.665098 -70.595744) (xy 445.681851 -70.574961) (xy 445.720205 -70.537831)
			(xy 445.763359 -70.506409) (xy 445.810473 -70.48131) (xy 445.860625 -70.463024) (xy 445.912836 -70.451907)
			(xy 445.966088 -70.448177) (xy 446.01934 -70.451907) (xy 446.071551 -70.463024) (xy 446.121703 -70.48131)
			(xy 446.168817 -70.506409) (xy 446.211971 -70.537831) (xy 446.250325 -70.574961) (xy 446.267078 -70.595744)
			(xy 446.274697 -70.604538) (xy 446.295589 -70.614727) (xy 446.30721 -70.615302) (xy 446.386966 -70.615302)
			(xy 446.398594 -70.614728) (xy 446.419503 -70.604564) (xy 446.427098 -70.595744) (xy 446.443851 -70.574961)
			(xy 446.482205 -70.537831) (xy 446.525359 -70.506409) (xy 446.572473 -70.48131) (xy 446.622625 -70.463024)
			(xy 446.674836 -70.451907) (xy 446.728088 -70.448177) (xy 446.78134 -70.451907) (xy 446.833551 -70.463024)
			(xy 446.883703 -70.48131) (xy 446.930817 -70.506409) (xy 446.973971 -70.537831) (xy 447.012325 -70.574961)
			(xy 447.029078 -70.595744) (xy 447.036697 -70.604538) (xy 447.057589 -70.614727) (xy 447.06921 -70.615302)
			(xy 447.148966 -70.615302) (xy 447.160594 -70.614728) (xy 447.181503 -70.604564) (xy 447.189098 -70.595744)
			(xy 447.207301 -70.573271) (xy 447.249317 -70.533533) (xy 447.296849 -70.500591) (xy 447.348808 -70.475201)
			(xy 447.404004 -70.457943) (xy 447.461173 -70.449213) (xy 447.490088 -70.448678) (xy 447.517338 -70.449189)
			(xy 447.571284 -70.456944) (xy 447.623578 -70.472297) (xy 447.673154 -70.494935) (xy 447.719004 -70.524399)
			(xy 447.760194 -70.560088) (xy 447.795885 -70.601276) (xy 447.825352 -70.647123) (xy 447.847994 -70.696698)
			(xy 447.863351 -70.74899) (xy 447.871109 -70.802936) (xy 447.871596 -70.830186) (xy 447.871069 -70.859103)
			(xy 447.862342 -70.916273) (xy 447.845086 -70.971472) (xy 447.819696 -71.023434) (xy 447.786754 -71.070968)
			(xy 447.747015 -71.112985) (xy 447.72453 -71.131176) (xy 447.715732 -71.138791) (xy 447.705546 -71.159686)
			(xy 447.704972 -71.171308) (xy 447.704972 -71.251064) (xy 447.705463 -71.262703) (xy 447.715683 -71.283613)
			(xy 447.72453 -71.291196) (xy 447.747018 -71.309382) (xy 447.786751 -71.351403) (xy 447.819689 -71.39894)
			(xy 447.845076 -71.450902) (xy 447.862332 -71.5061) (xy 447.871061 -71.56327) (xy 447.871596 -71.592186)
			(xy 447.871132 -71.619439) (xy 447.863376 -71.673391) (xy 447.848021 -71.725689) (xy 447.82538 -71.77527)
			(xy 447.795912 -71.821124) (xy 447.760218 -71.862317) (xy 447.719025 -71.898011) (xy 447.673172 -71.927479)
			(xy 447.623591 -71.950121) (xy 447.571293 -71.965476) (xy 447.517341 -71.973231) (xy 447.490088 -71.973694)
			(xy 447.461173 -71.973115) (xy 447.404005 -71.964399) (xy 447.348807 -71.947153) (xy 447.296845 -71.921773)
			(xy 447.24931 -71.88884) (xy 447.20729 -71.849109) (xy 447.189098 -71.826628) (xy 447.181494 -71.817818)
			(xy 447.16059 -71.807639) (xy 447.148966 -71.80707) (xy 447.06921 -71.80707) (xy 447.057577 -71.807605)
			(xy 447.036666 -71.817794) (xy 447.029078 -71.826628) (xy 447.012325 -71.847411) (xy 446.973971 -71.884541)
			(xy 446.930817 -71.915963) (xy 446.883703 -71.941062) (xy 446.833551 -71.959348) (xy 446.78134 -71.970465)
			(xy 446.728088 -71.974195) (xy 446.674836 -71.970465) (xy 446.622625 -71.959348) (xy 446.572473 -71.941062)
			(xy 446.525359 -71.915963) (xy 446.482205 -71.884541) (xy 446.443851 -71.847411) (xy 446.427098 -71.826628)
			(xy 446.419494 -71.817818) (xy 446.39859 -71.807639) (xy 446.386966 -71.80707) (xy 446.30721 -71.80707)
			(xy 446.295577 -71.807605) (xy 446.274666 -71.817794) (xy 446.267078 -71.826628) (xy 446.250325 -71.847411)
			(xy 446.211971 -71.884541) (xy 446.168817 -71.915963) (xy 446.121703 -71.941062) (xy 446.071551 -71.959348)
			(xy 446.01934 -71.970465) (xy 445.966088 -71.974195) (xy 445.912836 -71.970465) (xy 445.860625 -71.959348)
			(xy 445.810473 -71.941062) (xy 445.763359 -71.915963) (xy 445.720205 -71.884541) (xy 445.681851 -71.847411)
			(xy 445.665098 -71.826628) (xy 445.657494 -71.817818) (xy 445.63659 -71.807639) (xy 445.624966 -71.80707)
			(xy 445.54521 -71.80707) (xy 445.533577 -71.807605) (xy 445.512666 -71.817794) (xy 445.505078 -71.826628)
			(xy 445.486906 -71.849128) (xy 445.444882 -71.888861) (xy 445.397343 -71.921797) (xy 445.345378 -71.947182)
			(xy 445.290177 -71.964435) (xy 445.233005 -71.973161) (xy 445.204088 -71.973694) (xy 445.176834 -71.973256)
			(xy 445.122882 -71.965497) (xy 445.070582 -71.950139) (xy 445.021001 -71.927494) (xy 444.975147 -71.898023)
			(xy 444.933954 -71.862327) (xy 444.898261 -71.821132) (xy 444.868793 -71.775276) (xy 444.846152 -71.725693)
			(xy 444.830797 -71.673393) (xy 444.823042 -71.61944) (xy 444.82258 -71.592186) (xy 437.079898 -71.592186)
			(xy 437.079898 -72.415584) (xy 448.803264 -72.415584) (xy 448.803264 -72.330888) (xy 448.811315 -72.246574)
			(xy 448.827344 -72.163408) (xy 448.851205 -72.082141) (xy 448.882684 -72.003511) (xy 448.921495 -71.92823)
			(xy 448.967285 -71.856978) (xy 449.019641 -71.790402) (xy 449.078089 -71.729104) (xy 449.142099 -71.673639)
			(xy 449.211091 -71.62451) (xy 449.284441 -71.582161) (xy 449.361484 -71.546977) (xy 449.441523 -71.519275)
			(xy 449.523832 -71.499307) (xy 449.607667 -71.487254) (xy 449.692268 -71.483224) (xy 449.776869 -71.487254)
			(xy 449.860704 -71.499307) (xy 449.943013 -71.519275) (xy 450.023052 -71.546977) (xy 450.100095 -71.582161)
			(xy 450.173445 -71.62451) (xy 450.242437 -71.673639) (xy 450.306447 -71.729104) (xy 450.364895 -71.790402)
			(xy 450.417251 -71.856978) (xy 450.463041 -71.92823) (xy 450.501852 -72.003511) (xy 450.533331 -72.082141)
			(xy 450.557192 -72.163408) (xy 450.573221 -72.246574) (xy 450.581272 -72.330888) (xy 450.581776 -72.373236)
			(xy 450.581272 -72.415584) (xy 456.311504 -72.415584) (xy 456.311504 -72.330888) (xy 456.319555 -72.246574)
			(xy 456.335584 -72.163408) (xy 456.359445 -72.082141) (xy 456.390924 -72.003511) (xy 456.429735 -71.92823)
			(xy 456.475525 -71.856978) (xy 456.527881 -71.790402) (xy 456.586329 -71.729104) (xy 456.650339 -71.673639)
			(xy 456.719331 -71.62451) (xy 456.792681 -71.582161) (xy 456.869724 -71.546977) (xy 456.949763 -71.519275)
			(xy 457.032072 -71.499307) (xy 457.115907 -71.487254) (xy 457.200508 -71.483224) (xy 457.285109 -71.487254)
			(xy 457.368944 -71.499307) (xy 457.451253 -71.519275) (xy 457.531292 -71.546977) (xy 457.608335 -71.582161)
			(xy 457.681685 -71.62451) (xy 457.750677 -71.673639) (xy 457.814687 -71.729104) (xy 457.873135 -71.790402)
			(xy 457.925491 -71.856978) (xy 457.971281 -71.92823) (xy 458.010092 -72.003511) (xy 458.041571 -72.082141)
			(xy 458.065432 -72.163408) (xy 458.081461 -72.246574) (xy 458.089512 -72.330888) (xy 458.090016 -72.373236)
			(xy 458.089512 -72.415584) (xy 458.081461 -72.499898) (xy 458.065432 -72.583064) (xy 458.041571 -72.664331)
			(xy 458.010092 -72.742961) (xy 457.971281 -72.818242) (xy 457.925491 -72.889494) (xy 457.873135 -72.95607)
			(xy 457.814687 -73.017368) (xy 457.750677 -73.072833) (xy 457.681685 -73.121962) (xy 457.608335 -73.164311)
			(xy 457.531292 -73.199495) (xy 457.451253 -73.227197) (xy 457.368944 -73.247165) (xy 457.285109 -73.259218)
			(xy 457.200508 -73.263249) (xy 457.115907 -73.259218) (xy 457.032072 -73.247165) (xy 456.949763 -73.227197)
			(xy 456.869724 -73.199495) (xy 456.792681 -73.164311) (xy 456.719331 -73.121962) (xy 456.650339 -73.072833)
			(xy 456.586329 -73.017368) (xy 456.527881 -72.95607) (xy 456.475525 -72.889494) (xy 456.429735 -72.818242)
			(xy 456.390924 -72.742961) (xy 456.359445 -72.664331) (xy 456.335584 -72.583064) (xy 456.319555 -72.499898)
			(xy 456.311504 -72.415584) (xy 450.581272 -72.415584) (xy 450.573221 -72.499898) (xy 450.557192 -72.583064)
			(xy 450.533331 -72.664331) (xy 450.501852 -72.742961) (xy 450.463041 -72.818242) (xy 450.417251 -72.889494)
			(xy 450.364895 -72.95607) (xy 450.306447 -73.017368) (xy 450.242437 -73.072833) (xy 450.173445 -73.121962)
			(xy 450.100095 -73.164311) (xy 450.023052 -73.199495) (xy 449.943013 -73.227197) (xy 449.860704 -73.247165)
			(xy 449.776869 -73.259218) (xy 449.692268 -73.263249) (xy 449.607667 -73.259218) (xy 449.523832 -73.247165)
			(xy 449.441523 -73.227197) (xy 449.361484 -73.199495) (xy 449.284441 -73.164311) (xy 449.211091 -73.121962)
			(xy 449.142099 -73.072833) (xy 449.078089 -73.017368) (xy 449.019641 -72.95607) (xy 448.967285 -72.889494)
			(xy 448.921495 -72.818242) (xy 448.882684 -72.742961) (xy 448.851205 -72.664331) (xy 448.827344 -72.583064)
			(xy 448.811315 -72.499898) (xy 448.803264 -72.415584) (xy 437.079898 -72.415584) (xy 437.079898 -74.439272)
			(xy 437.38495 -74.439272) (xy 437.389021 -74.38365) (xy 437.401147 -74.329213) (xy 437.42107 -74.277122)
			(xy 437.448366 -74.228487) (xy 437.482452 -74.184344) (xy 437.522601 -74.145635) (xy 437.567959 -74.113184)
			(xy 437.617559 -74.087683) (xy 437.670343 -74.069676) (xy 437.725186 -74.059546) (xy 437.78092 -74.057509)
			(xy 437.836357 -74.063609) (xy 437.890314 -74.077715) (xy 437.941643 -74.099527) (xy 437.989249 -74.128581)
			(xy 438.032117 -74.164256) (xy 438.069334 -74.205793) (xy 438.100107 -74.252306) (xy 438.123779 -74.302803)
			(xy 438.139847 -74.35621) (xy 438.147967 -74.411386) (xy 438.148476 -74.439272) (xy 438.147967 -74.467158)
			(xy 438.139847 -74.522334) (xy 438.123779 -74.575741) (xy 438.100107 -74.626238) (xy 438.069334 -74.672751)
			(xy 438.032117 -74.714288) (xy 437.989249 -74.749963) (xy 437.941643 -74.779017) (xy 437.890314 -74.800829)
			(xy 437.836357 -74.814935) (xy 437.78092 -74.821035) (xy 437.725186 -74.818998) (xy 437.670343 -74.808868)
			(xy 437.617559 -74.790861) (xy 437.567959 -74.76536) (xy 437.522601 -74.732909) (xy 437.482452 -74.6942)
			(xy 437.448366 -74.650057) (xy 437.42107 -74.601422) (xy 437.401147 -74.549331) (xy 437.389021 -74.494894)
			(xy 437.38495 -74.439272) (xy 437.079898 -74.439272) (xy 437.079898 -77.655928) (xy 439.102246 -77.655928)
			(xy 439.102767 -77.627011) (xy 439.111493 -77.569839) (xy 439.128749 -77.51464) (xy 439.15414 -77.462677)
			(xy 439.187084 -77.415144) (xy 439.226826 -77.373127) (xy 439.249312 -77.354938) (xy 439.258094 -77.347306)
			(xy 439.268291 -77.326424) (xy 439.26887 -77.314806) (xy 439.26887 -77.23505) (xy 439.268356 -77.223415)
			(xy 439.25815 -77.202505) (xy 439.249312 -77.194918) (xy 439.22684 -77.176714) (xy 439.187103 -77.134697)
			(xy 439.154163 -77.087165) (xy 439.128772 -77.035206) (xy 439.111514 -76.980011) (xy 439.102782 -76.922843)
			(xy 439.102246 -76.893928) (xy 439.102828 -76.864027) (xy 439.112143 -76.804956) (xy 439.130564 -76.748063)
			(xy 439.15764 -76.694743) (xy 439.192707 -76.646303) (xy 439.234906 -76.60393) (xy 439.25871 -76.585826)
			(xy 439.267783 -76.578485) (xy 439.278618 -76.557838) (xy 439.279538 -76.546202) (xy 439.282078 -76.453746)
			(xy 439.272172 -76.432664) (xy 439.263028 -76.425044) (xy 439.24149 -76.406825) (xy 439.203482 -76.365138)
			(xy 439.17203 -76.318308) (xy 439.147821 -76.267355) (xy 439.131383 -76.213391) (xy 439.123074 -76.157594)
			(xy 439.122566 -76.129388) (xy 439.123123 -76.100472) (xy 439.13184 -76.043302) (xy 439.149089 -75.988103)
			(xy 439.174473 -75.93614) (xy 439.207411 -75.888605) (xy 439.247148 -75.846588) (xy 439.269632 -75.828398)
			(xy 439.278436 -75.820787) (xy 439.28862 -75.799889) (xy 439.28919 -75.788266) (xy 439.28919 -75.70851)
			(xy 439.288634 -75.69688) (xy 439.278457 -75.67597) (xy 439.269632 -75.668378) (xy 439.248838 -75.651638)
			(xy 439.21171 -75.613282) (xy 439.180291 -75.570125) (xy 439.155194 -75.52301) (xy 439.13691 -75.472857)
			(xy 439.125795 -75.420645) (xy 439.122066 -75.367393) (xy 439.125797 -75.314141) (xy 439.136914 -75.261929)
			(xy 439.1552 -75.211776) (xy 439.180299 -75.164662) (xy 439.21172 -75.121507) (xy 439.248849 -75.083152)
			(xy 439.269632 -75.066398) (xy 439.278436 -75.058787) (xy 439.28862 -75.037889) (xy 439.28919 -75.026266)
			(xy 439.28919 -74.94651) (xy 439.288634 -74.93488) (xy 439.278457 -74.91397) (xy 439.269632 -74.906378)
			(xy 439.247145 -74.888191) (xy 439.207408 -74.846172) (xy 439.174469 -74.798636) (xy 439.149081 -74.746674)
			(xy 439.131826 -74.691475) (xy 439.123099 -74.634304) (xy 439.122566 -74.605388) (xy 439.123067 -74.578138)
			(xy 439.130824 -74.524192) (xy 439.146179 -74.471899) (xy 439.16882 -74.422323) (xy 439.198285 -74.376474)
			(xy 439.233975 -74.335285) (xy 439.275163 -74.299594) (xy 439.321011 -74.270127) (xy 439.370586 -74.247484)
			(xy 439.422878 -74.232127) (xy 439.476824 -74.224368) (xy 439.504074 -74.22388) (xy 439.531445 -74.224342)
			(xy 439.585625 -74.232158) (xy 439.638129 -74.247647) (xy 439.687875 -74.27049) (xy 439.733841 -74.300217)
			(xy 439.754772 -74.31786) (xy 439.755026 -74.318114) (xy 439.762128 -74.323677) (xy 439.779033 -74.329938)
			(xy 439.788046 -74.330306) (xy 439.855102 -74.330306) (xy 439.864119 -74.329949) (xy 439.881036 -74.323701)
			(xy 439.888122 -74.318114) (xy 439.888122 -74.31786) (xy 439.888376 -74.31786) (xy 439.909301 -74.300212)
			(xy 439.955276 -74.270503) (xy 440.005026 -74.247669) (xy 440.057528 -74.23218) (xy 440.111704 -74.224353)
			(xy 440.139074 -74.22388) (xy 440.167778 -74.224384) (xy 440.224539 -74.232984) (xy 440.27937 -74.249992)
			(xy 440.331033 -74.275026) (xy 440.378361 -74.307519) (xy 440.399678 -74.32675) (xy 440.407079 -74.333093)
			(xy 440.425241 -74.340133) (xy 440.434984 -74.340466) (xy 440.515502 -74.33945) (xy 440.53379 -74.331576)
			(xy 440.540648 -74.324718) (xy 440.548874 -74.316646) (xy 440.566159 -74.301397) (xy 440.575192 -74.294238)
			(xy 440.583971 -74.286603) (xy 440.59417 -74.265724) (xy 440.59475 -74.254106) (xy 440.59475 -74.17435)
			(xy 440.594243 -74.162714) (xy 440.584033 -74.141803) (xy 440.575192 -74.134218) (xy 440.552715 -74.116019)
			(xy 440.51298 -74.074001) (xy 440.480041 -74.026467) (xy 440.454651 -73.974508) (xy 440.437393 -73.919312)
			(xy 440.428662 -73.862143) (xy 440.428126 -73.833228) (xy 440.428581 -73.805974) (xy 440.436336 -73.752021)
			(xy 440.45169 -73.699721) (xy 440.474331 -73.650139) (xy 440.5038 -73.604284) (xy 440.539494 -73.56309)
			(xy 440.580689 -73.527396) (xy 440.626544 -73.497929) (xy 440.676127 -73.475288) (xy 440.728427 -73.459934)
			(xy 440.78238 -73.452181) (xy 440.809634 -73.45172) (xy 440.837005 -73.452161) (xy 440.891186 -73.459984)
			(xy 440.943689 -73.475479) (xy 440.993436 -73.498326) (xy 441.039401 -73.528056) (xy 441.060332 -73.5457)
			(xy 441.060586 -73.545954) (xy 441.067668 -73.551547) (xy 441.084588 -73.557789) (xy 441.093606 -73.558146)
			(xy 441.160662 -73.558146) (xy 441.169678 -73.557783) (xy 441.186596 -73.551541) (xy 441.193682 -73.545954)
			(xy 441.193682 -73.5457) (xy 441.193936 -73.5457) (xy 441.214869 -73.528059) (xy 441.260837 -73.498335)
			(xy 441.310583 -73.475489) (xy 441.363085 -73.459993) (xy 441.417263 -73.452164) (xy 441.472005 -73.452164)
			(xy 441.526183 -73.459993) (xy 441.578685 -73.475489) (xy 441.628431 -73.498335) (xy 441.674399 -73.528059)
			(xy 441.695332 -73.5457) (xy 441.695586 -73.545954) (xy 441.702668 -73.551547) (xy 441.719588 -73.557789)
			(xy 441.728606 -73.558146) (xy 441.795662 -73.558146) (xy 441.804678 -73.557783) (xy 441.821596 -73.551541)
			(xy 441.828682 -73.545954) (xy 441.828682 -73.5457) (xy 441.828936 -73.5457) (xy 441.849869 -73.528059)
			(xy 441.895837 -73.498335) (xy 441.945583 -73.475489) (xy 441.998085 -73.459993) (xy 442.052263 -73.452164)
			(xy 442.107005 -73.452164) (xy 442.161183 -73.459993) (xy 442.213685 -73.475489) (xy 442.263431 -73.498335)
			(xy 442.309399 -73.528059) (xy 442.330332 -73.5457) (xy 442.330586 -73.545954) (xy 442.337668 -73.551547)
			(xy 442.354588 -73.557789) (xy 442.363606 -73.558146) (xy 442.430662 -73.558146) (xy 442.439678 -73.557783)
			(xy 442.456596 -73.551541) (xy 442.463682 -73.545954) (xy 442.463682 -73.5457) (xy 442.463936 -73.5457)
			(xy 442.484881 -73.528077) (xy 442.530851 -73.498363) (xy 442.580595 -73.475524) (xy 442.633092 -73.460029)
			(xy 442.687266 -73.452196) (xy 442.714634 -73.45172) (xy 442.744758 -73.452278) (xy 442.804254 -73.461763)
			(xy 442.861522 -73.480478) (xy 442.915139 -73.507956) (xy 442.963773 -73.543516) (xy 442.985398 -73.564496)
			(xy 442.992805 -73.571327) (xy 443.011399 -73.579052) (xy 443.021466 -73.579482) (xy 443.093602 -73.579482)
			(xy 443.103672 -73.579062) (xy 443.12227 -73.571338) (xy 443.12967 -73.564496) (xy 443.151284 -73.543504)
			(xy 443.199916 -73.507938) (xy 443.253535 -73.48046) (xy 443.310808 -73.461754) (xy 443.370309 -73.452287)
			(xy 443.400434 -73.45172) (xy 443.427687 -73.452146) (xy 443.481639 -73.459908) (xy 443.533936 -73.475269)
			(xy 443.583515 -73.497916) (xy 443.629367 -73.527389) (xy 443.670558 -73.563086) (xy 443.706249 -73.604283)
			(xy 443.735714 -73.650139) (xy 443.758353 -73.699722) (xy 443.773705 -73.752022) (xy 443.781458 -73.805975)
			(xy 443.781942 -73.833228) (xy 443.781394 -73.862144) (xy 443.772674 -73.919315) (xy 443.755423 -73.974514)
			(xy 443.730037 -74.026476) (xy 443.697098 -74.074011) (xy 443.65736 -74.116028) (xy 443.634876 -74.134218)
			(xy 443.626066 -74.141823) (xy 443.615885 -74.162725) (xy 443.615318 -74.17435) (xy 443.615318 -74.254106)
			(xy 443.615861 -74.265738) (xy 443.626046 -74.286648) (xy 443.634876 -74.294238) (xy 443.657373 -74.312414)
			(xy 443.697108 -74.354436) (xy 443.730046 -74.401974) (xy 443.755433 -74.453938) (xy 443.772686 -74.509139)
			(xy 443.77435 -74.520044) (xy 444.46139 -74.520044) (xy 444.465461 -74.464422) (xy 444.477587 -74.409985)
			(xy 444.49751 -74.357894) (xy 444.524806 -74.309259) (xy 444.558892 -74.265116) (xy 444.599041 -74.226407)
			(xy 444.644399 -74.193956) (xy 444.693999 -74.168455) (xy 444.746783 -74.150448) (xy 444.801626 -74.140318)
			(xy 444.85736 -74.138281) (xy 444.912797 -74.144381) (xy 444.966754 -74.158487) (xy 445.018083 -74.180299)
			(xy 445.065689 -74.209353) (xy 445.108557 -74.245028) (xy 445.145774 -74.286565) (xy 445.176547 -74.333078)
			(xy 445.200219 -74.383575) (xy 445.216287 -74.436982) (xy 445.224407 -74.492158) (xy 445.224916 -74.520044)
			(xy 445.224407 -74.54793) (xy 445.216287 -74.603106) (xy 445.200219 -74.656513) (xy 445.176547 -74.70701)
			(xy 445.145774 -74.753523) (xy 445.108557 -74.79506) (xy 445.065689 -74.830735) (xy 445.018083 -74.859789)
			(xy 444.966754 -74.881601) (xy 444.912797 -74.895707) (xy 444.85736 -74.901807) (xy 444.801626 -74.89977)
			(xy 444.746783 -74.88964) (xy 444.693999 -74.871633) (xy 444.644399 -74.846132) (xy 444.599041 -74.813681)
			(xy 444.558892 -74.774972) (xy 444.524806 -74.730829) (xy 444.49751 -74.682194) (xy 444.477587 -74.630103)
			(xy 444.465461 -74.575666) (xy 444.46139 -74.520044) (xy 443.77435 -74.520044) (xy 443.78141 -74.566311)
			(xy 443.781942 -74.595228) (xy 443.781448 -74.622478) (xy 443.773689 -74.676424) (xy 443.758332 -74.728717)
			(xy 443.73569 -74.778292) (xy 443.706224 -74.82414) (xy 443.670534 -74.865329) (xy 443.629345 -74.90102)
			(xy 443.606495 -74.915706) (xy 448.803264 -74.915706) (xy 448.803264 -74.83101) (xy 448.811315 -74.746696)
			(xy 448.827344 -74.66353) (xy 448.851205 -74.582263) (xy 448.882684 -74.503633) (xy 448.921495 -74.428352)
			(xy 448.967285 -74.3571) (xy 449.019641 -74.290524) (xy 449.078089 -74.229226) (xy 449.142099 -74.173761)
			(xy 449.211091 -74.124632) (xy 449.284441 -74.082283) (xy 449.361484 -74.047099) (xy 449.441523 -74.019397)
			(xy 449.523832 -73.999429) (xy 449.607667 -73.987376) (xy 449.692268 -73.983346) (xy 449.776869 -73.987376)
			(xy 449.860704 -73.999429) (xy 449.943013 -74.019397) (xy 450.023052 -74.047099) (xy 450.100095 -74.082283)
			(xy 450.173445 -74.124632) (xy 450.242437 -74.173761) (xy 450.306447 -74.229226) (xy 450.364895 -74.290524)
			(xy 450.417251 -74.3571) (xy 450.463041 -74.428352) (xy 450.501852 -74.503633) (xy 450.533331 -74.582263)
			(xy 450.557192 -74.66353) (xy 450.573221 -74.746696) (xy 450.581272 -74.83101) (xy 450.581776 -74.873358)
			(xy 450.581272 -74.915706) (xy 456.311504 -74.915706) (xy 456.311504 -74.83101) (xy 456.319555 -74.746696)
			(xy 456.335584 -74.66353) (xy 456.359445 -74.582263) (xy 456.390924 -74.503633) (xy 456.429735 -74.428352)
			(xy 456.475525 -74.3571) (xy 456.527881 -74.290524) (xy 456.586329 -74.229226) (xy 456.650339 -74.173761)
			(xy 456.719331 -74.124632) (xy 456.792681 -74.082283) (xy 456.869724 -74.047099) (xy 456.949763 -74.019397)
			(xy 457.032072 -73.999429) (xy 457.115907 -73.987376) (xy 457.200508 -73.983346) (xy 457.285109 -73.987376)
			(xy 457.368944 -73.999429) (xy 457.451253 -74.019397) (xy 457.531292 -74.047099) (xy 457.608335 -74.082283)
			(xy 457.681685 -74.124632) (xy 457.750677 -74.173761) (xy 457.814687 -74.229226) (xy 457.873135 -74.290524)
			(xy 457.925491 -74.3571) (xy 457.971281 -74.428352) (xy 458.010092 -74.503633) (xy 458.041571 -74.582263)
			(xy 458.065432 -74.66353) (xy 458.081461 -74.746696) (xy 458.089512 -74.83101) (xy 458.090016 -74.873358)
			(xy 458.089512 -74.915706) (xy 458.081461 -75.00002) (xy 458.065432 -75.083186) (xy 458.041571 -75.164453)
			(xy 458.010092 -75.243083) (xy 457.971281 -75.318364) (xy 457.925491 -75.389616) (xy 457.873135 -75.456192)
			(xy 457.814687 -75.51749) (xy 457.750677 -75.572955) (xy 457.681685 -75.622084) (xy 457.608335 -75.664433)
			(xy 457.531292 -75.699617) (xy 457.451253 -75.727319) (xy 457.368944 -75.747287) (xy 457.285109 -75.75934)
			(xy 457.200508 -75.763371) (xy 457.115907 -75.75934) (xy 457.032072 -75.747287) (xy 456.949763 -75.727319)
			(xy 456.869724 -75.699617) (xy 456.792681 -75.664433) (xy 456.719331 -75.622084) (xy 456.650339 -75.572955)
			(xy 456.586329 -75.51749) (xy 456.527881 -75.456192) (xy 456.475525 -75.389616) (xy 456.429735 -75.318364)
			(xy 456.390924 -75.243083) (xy 456.359445 -75.164453) (xy 456.335584 -75.083186) (xy 456.319555 -75.00002)
			(xy 456.311504 -74.915706) (xy 450.581272 -74.915706) (xy 450.573221 -75.00002) (xy 450.557192 -75.083186)
			(xy 450.533331 -75.164453) (xy 450.501852 -75.243083) (xy 450.463041 -75.318364) (xy 450.417251 -75.389616)
			(xy 450.364895 -75.456192) (xy 450.306447 -75.51749) (xy 450.242437 -75.572955) (xy 450.173445 -75.622084)
			(xy 450.100095 -75.664433) (xy 450.023052 -75.699617) (xy 449.943013 -75.727319) (xy 449.860704 -75.747287)
			(xy 449.776869 -75.75934) (xy 449.692268 -75.763371) (xy 449.607667 -75.75934) (xy 449.523832 -75.747287)
			(xy 449.441523 -75.727319) (xy 449.361484 -75.699617) (xy 449.284441 -75.664433) (xy 449.211091 -75.622084)
			(xy 449.142099 -75.572955) (xy 449.078089 -75.51749) (xy 449.019641 -75.456192) (xy 448.967285 -75.389616)
			(xy 448.921495 -75.318364) (xy 448.882684 -75.243083) (xy 448.851205 -75.164453) (xy 448.827344 -75.083186)
			(xy 448.811315 -75.00002) (xy 448.803264 -74.915706) (xy 443.606495 -74.915706) (xy 443.583497 -74.930487)
			(xy 443.533922 -74.95313) (xy 443.48163 -74.968488) (xy 443.427684 -74.976248) (xy 443.400434 -74.976736)
			(xy 443.370311 -74.976148) (xy 443.310815 -74.966672) (xy 443.253548 -74.947965) (xy 443.19993 -74.920493)
			(xy 443.151295 -74.884938) (xy 443.12967 -74.86396) (xy 443.122279 -74.857109) (xy 443.103673 -74.849397)
			(xy 443.093602 -74.848974) (xy 443.021466 -74.848974) (xy 443.011392 -74.849362) (xy 442.992793 -74.857107)
			(xy 442.985398 -74.86396) (xy 442.963791 -74.884959) (xy 442.915158 -74.920527) (xy 442.861537 -74.948004)
			(xy 442.804263 -74.966708) (xy 442.74476 -74.976172) (xy 442.714634 -74.976736) (xy 442.687264 -74.976266)
			(xy 442.633084 -74.968451) (xy 442.580581 -74.952964) (xy 442.530834 -74.930123) (xy 442.484867 -74.900398)
			(xy 442.463936 -74.882756) (xy 442.463682 -74.882502) (xy 442.456605 -74.876902) (xy 442.439681 -74.870663)
			(xy 442.430662 -74.87031) (xy 442.363606 -74.87031) (xy 442.354589 -74.870668) (xy 442.337672 -74.876914)
			(xy 442.330586 -74.882502) (xy 442.330586 -74.882756) (xy 442.330078 -74.882756) (xy 442.314076 -74.896218)
			(xy 442.305266 -74.903823) (xy 442.295085 -74.924725) (xy 442.294518 -74.93635) (xy 442.294518 -75.016106)
			(xy 442.295061 -75.027738) (xy 442.305246 -75.048648) (xy 442.314076 -75.056238) (xy 442.334885 -75.072959)
			(xy 442.372013 -75.111318) (xy 442.403431 -75.154477) (xy 442.428527 -75.201594) (xy 442.44681 -75.25175)
			(xy 442.457924 -75.303964) (xy 442.461651 -75.357217) (xy 442.457919 -75.41047) (xy 442.446801 -75.462684)
			(xy 442.428513 -75.512837) (xy 442.403413 -75.559952) (xy 442.37199 -75.603108) (xy 442.334859 -75.641464)
			(xy 442.314076 -75.658218) (xy 442.305266 -75.665823) (xy 442.295085 -75.686725) (xy 442.294518 -75.69835)
			(xy 442.294518 -75.778106) (xy 442.295061 -75.789738) (xy 442.305246 -75.810648) (xy 442.314076 -75.818238)
			(xy 442.336573 -75.836414) (xy 442.376308 -75.878436) (xy 442.409246 -75.925974) (xy 442.434633 -75.977938)
			(xy 442.451886 -76.033139) (xy 442.46061 -76.090311) (xy 442.461142 -76.119228) (xy 442.460565 -76.149128)
			(xy 442.451244 -76.208198) (xy 442.432819 -76.26509) (xy 442.405742 -76.318409) (xy 442.370676 -76.366849)
			(xy 442.32848 -76.409224) (xy 442.304678 -76.42733) (xy 442.295622 -76.434688) (xy 442.284778 -76.455323)
			(xy 442.28385 -76.466954) (xy 442.28131 -76.55941) (xy 442.291216 -76.580492) (xy 442.30036 -76.588112)
			(xy 442.321923 -76.606304) (xy 442.359929 -76.647995) (xy 442.391378 -76.694832) (xy 442.415583 -76.74579)
			(xy 442.432016 -76.799759) (xy 442.440318 -76.85556) (xy 442.440822 -76.883768) (xy 442.44031 -76.912686)
			(xy 442.431584 -76.969858) (xy 442.414327 -77.025059) (xy 442.388934 -77.077021) (xy 442.355988 -77.124555)
			(xy 442.316243 -77.166569) (xy 442.293756 -77.184758) (xy 442.284971 -77.192386) (xy 442.274777 -77.213271)
			(xy 442.274198 -77.22489) (xy 442.274198 -77.304646) (xy 442.274726 -77.316279) (xy 442.284923 -77.337189)
			(xy 442.293756 -77.344778) (xy 442.31622 -77.362993) (xy 442.355958 -77.405006) (xy 442.388901 -77.452536)
			(xy 442.414293 -77.504493) (xy 442.431553 -77.559687) (xy 442.440285 -77.616853) (xy 442.440822 -77.645768)
			(xy 442.440315 -77.673019) (xy 442.432563 -77.726968) (xy 442.417211 -77.779264) (xy 442.394574 -77.828843)
			(xy 442.36511 -77.874696) (xy 442.329421 -77.915889) (xy 442.288233 -77.951583) (xy 442.242384 -77.981052)
			(xy 442.192807 -78.003695) (xy 442.140513 -78.019053) (xy 442.086565 -78.026812) (xy 442.059314 -78.027276)
			(xy 442.031944 -78.026808) (xy 441.977765 -78.018991) (xy 441.925261 -78.003503) (xy 441.875514 -77.980662)
			(xy 441.829548 -77.950937) (xy 441.808616 -77.933296) (xy 441.808362 -77.933042) (xy 441.801267 -77.927468)
			(xy 441.784356 -77.921215) (xy 441.775342 -77.92085) (xy 441.708286 -77.92085) (xy 441.699267 -77.92119)
			(xy 441.68235 -77.927448) (xy 441.675266 -77.933042) (xy 441.675266 -77.933296) (xy 441.675012 -77.933296)
			(xy 441.654079 -77.950937) (xy 441.608111 -77.980661) (xy 441.558365 -78.003507) (xy 441.505863 -78.019003)
			(xy 441.451685 -78.026832) (xy 441.396943 -78.026832) (xy 441.342765 -78.019003) (xy 441.290263 -78.003507)
			(xy 441.240517 -77.980661) (xy 441.194549 -77.950937) (xy 441.173616 -77.933296) (xy 441.173362 -77.933042)
			(xy 441.166267 -77.927468) (xy 441.149356 -77.921215) (xy 441.140342 -77.92085) (xy 441.073286 -77.92085)
			(xy 441.064267 -77.92119) (xy 441.04735 -77.927448) (xy 441.040266 -77.933042) (xy 441.040266 -77.933296)
			(xy 441.040012 -77.933296) (xy 441.019086 -77.950942) (xy 440.973111 -77.980653) (xy 440.923362 -78.003488)
			(xy 440.87086 -78.018977) (xy 440.816684 -78.026803) (xy 440.789314 -78.027276) (xy 440.76061 -78.026765)
			(xy 440.70385 -78.018165) (xy 440.649019 -78.001157) (xy 440.597356 -77.976125) (xy 440.550027 -77.943635)
			(xy 440.52871 -77.924406) (xy 440.521285 -77.918096) (xy 440.503141 -77.911038) (xy 440.493404 -77.91069)
			(xy 440.412886 -77.911706) (xy 440.394598 -77.91958) (xy 440.38774 -77.926438) (xy 440.366159 -77.947099)
			(xy 440.317752 -77.982114) (xy 440.264478 -78.009151) (xy 440.207639 -78.02755) (xy 440.148625 -78.036859)
			(xy 440.118754 -78.037436) (xy 440.091384 -78.036954) (xy 440.037205 -78.029142) (xy 439.984702 -78.013658)
			(xy 439.934954 -77.990819) (xy 439.888988 -77.961097) (xy 439.868056 -77.943456) (xy 439.867802 -77.943202)
			(xy 439.860719 -77.93761) (xy 439.843799 -77.931367) (xy 439.834782 -77.93101) (xy 439.767726 -77.93101)
			(xy 439.75871 -77.931377) (xy 439.741793 -77.937617) (xy 439.734706 -77.943202) (xy 439.734706 -77.943456)
			(xy 439.734452 -77.943456) (xy 439.713505 -77.961077) (xy 439.667537 -77.990793) (xy 439.617794 -78.013633)
			(xy 439.565296 -78.029128) (xy 439.511122 -78.03696) (xy 439.483754 -78.037436) (xy 439.456503 -78.036965)
			(xy 439.402556 -78.029203) (xy 439.350263 -78.013843) (xy 439.300687 -77.991199) (xy 439.254838 -77.961731)
			(xy 439.213649 -77.926038) (xy 439.177959 -77.884847) (xy 439.148492 -77.838997) (xy 439.12585 -77.78942)
			(xy 439.110493 -77.737126) (xy 439.102734 -77.683179) (xy 439.102246 -77.655928) (xy 437.079898 -77.655928)
			(xy 437.079898 -80.87487) (xy 437.080334 -80.884935) (xy 437.088066 -80.903521) (xy 437.094884 -80.910938)
			(xy 439.717688 -83.533742) (xy 439.725083 -83.540597) (xy 439.743682 -83.548345) (xy 439.753756 -83.548728)
		)
		(stroke
			(width 0)
			(type solid)
		)
		(fill yes)
		(layer "In15.Cu")
		(net "GND")
	)
	(gr_poly
		(pts
			(xy 321.34683 -204.530452) (xy 321.357228 -204.529948) (xy 321.376313 -204.521684) (xy 321.39055 -204.506524)
			(xy 321.394582 -204.496924) (xy 321.432428 -204.391768) (xy 321.424046 -204.36078) (xy 321.4116 -204.35062)
			(xy 321.387316 -204.329861) (xy 321.343604 -204.283271) (xy 321.306074 -204.23157) (xy 321.275318 -204.175574)
			(xy 321.251822 -204.116165) (xy 321.235955 -204.054281) (xy 321.227968 -203.990895) (xy 321.22745 -203.958952)
			(xy 321.227916 -203.928222) (xy 321.235329 -203.86721) (xy 321.250042 -203.807537) (xy 321.271839 -203.750072)
			(xy 321.300403 -203.695653) (xy 321.335318 -203.645073) (xy 321.376074 -203.59907) (xy 321.422078 -203.558314)
			(xy 321.472658 -203.5234) (xy 321.527078 -203.494837) (xy 321.584543 -203.47304) (xy 321.644216 -203.458328)
			(xy 321.705228 -203.450916) (xy 321.735958 -203.450444) (xy 321.75831 -203.450952) (xy 321.768724 -203.45146)
			(xy 321.788028 -203.444094) (xy 321.84848 -203.386182) (xy 321.855634 -203.378704) (xy 321.863759 -203.359691)
			(xy 321.864228 -203.349352) (xy 321.864228 -202.823064) (xy 321.863799 -202.812996) (xy 321.856079 -202.794398)
			(xy 321.849242 -202.786996) (xy 320.195702 -201.133456) (xy 320.192146 -201.130154) (xy 319.592452 -200.63841)
			(xy 319.585431 -200.633183) (xy 319.56894 -200.627352) (xy 319.560194 -200.62698) (xy 317.403226 -200.62698)
			(xy 317.393162 -200.626543) (xy 317.374579 -200.618807) (xy 317.367158 -200.611994) (xy 316.887352 -200.132188)
			(xy 316.880849 -200.126101) (xy 316.86474 -200.118526) (xy 316.847007 -200.11697) (xy 316.83833 -200.11898)
			(xy 316.740032 -200.145142) (xy 316.720982 -200.164192) (xy 316.717426 -200.1774) (xy 316.708238 -200.209357)
			(xy 316.682687 -200.270745) (xy 316.649351 -200.328278) (xy 316.608798 -200.380974) (xy 316.561722 -200.427933)
			(xy 316.508925 -200.468355) (xy 316.451309 -200.501548) (xy 316.389858 -200.526946) (xy 316.325619 -200.544116)
			(xy 316.259691 -200.552765) (xy 316.226444 -200.55332) (xy 316.19571 -200.552877) (xy 316.134689 -200.545473)
			(xy 316.075006 -200.530767) (xy 316.017531 -200.508974) (xy 315.963102 -200.480412) (xy 315.912512 -200.445498)
			(xy 315.8665 -200.404739) (xy 315.825737 -200.358732) (xy 315.790817 -200.308146) (xy 315.762249 -200.25372)
			(xy 315.74045 -200.196247) (xy 315.725737 -200.136566) (xy 315.718326 -200.075546) (xy 315.717936 -200.044812)
			(xy 315.718358 -200.015417) (xy 315.725136 -199.957019) (xy 315.738593 -199.89979) (xy 315.758549 -199.84449)
			(xy 315.771276 -199.81799) (xy 315.775129 -199.80931) (xy 315.776937 -199.790422) (xy 315.774832 -199.78116)
			(xy 315.766196 -199.751442) (xy 315.763131 -199.74251) (xy 315.751661 -199.727531) (xy 315.743844 -199.722232)
			(xy 315.71631 -199.70486) (xy 315.665478 -199.664181) (xy 315.620255 -199.617347) (xy 315.581379 -199.565123)
			(xy 315.549487 -199.508365) (xy 315.5251 -199.448) (xy 315.508618 -199.385017) (xy 315.500309 -199.320444)
			(xy 315.49975 -199.287892) (xy 315.49975 -199.272906) (xy 315.489336 -199.251824) (xy 315.405008 -199.187816)
			(xy 315.38164 -199.183752) (xy 315.369956 -199.187054) (xy 315.335341 -199.196435) (xy 315.264336 -199.206504)
			(xy 315.228478 -199.20712) (xy 315.197748 -199.206655) (xy 315.136735 -199.199244) (xy 315.077061 -199.184534)
			(xy 315.019595 -199.162738) (xy 314.965174 -199.134174) (xy 314.914594 -199.099259) (xy 314.86859 -199.058503)
			(xy 314.827834 -199.012498) (xy 314.792921 -198.961917) (xy 314.764358 -198.907496) (xy 314.742564 -198.85003)
			(xy 314.727854 -198.790355) (xy 314.720445 -198.729342) (xy 314.71997 -198.698612) (xy 314.721494 -198.660004)
			(xy 314.722256 -198.648066) (xy 314.71362 -198.626476) (xy 314.636912 -198.556626) (xy 314.61456 -198.550022)
			(xy 314.60313 -198.552054) (xy 314.581834 -198.555501) (xy 314.538849 -198.559192) (xy 314.517278 -198.55942)
			(xy 314.486548 -198.558955) (xy 314.425535 -198.551544) (xy 314.365861 -198.536834) (xy 314.308395 -198.515038)
			(xy 314.253974 -198.486474) (xy 314.203394 -198.451559) (xy 314.15739 -198.410803) (xy 314.116634 -198.364798)
			(xy 314.081721 -198.314217) (xy 314.053158 -198.259796) (xy 314.031364 -198.20233) (xy 314.016654 -198.142655)
			(xy 314.009245 -198.081642) (xy 314.00877 -198.050912) (xy 314.010548 -198.007986) (xy 314.011564 -197.99554)
			(xy 314.002166 -197.97268) (xy 313.918346 -197.903338) (xy 313.893962 -197.898258) (xy 313.882024 -197.901814)
			(xy 313.848353 -197.910608) (xy 313.779405 -197.92004) (xy 313.74461 -197.92061) (xy 313.713877 -197.920165)
			(xy 313.65286 -197.912757) (xy 313.593181 -197.898049) (xy 313.53571 -197.876254) (xy 313.481285 -197.84769)
			(xy 313.4307 -197.812775) (xy 313.384692 -197.772017) (xy 313.343932 -197.72601) (xy 313.309016 -197.675425)
			(xy 313.280451 -197.621001) (xy 313.258655 -197.56353) (xy 313.243945 -197.503851) (xy 313.236536 -197.442835)
			(xy 313.236102 -197.412102) (xy 313.236533 -197.381927) (xy 313.243677 -197.322001) (xy 313.257866 -197.263342)
			(xy 313.2789 -197.206776) (xy 313.306483 -197.153098) (xy 313.340227 -197.103062) (xy 313.379657 -197.057374)
			(xy 313.424219 -197.016675) (xy 313.473285 -196.981538) (xy 313.4995 -196.966586) (xy 313.508898 -196.961506)
			(xy 313.521598 -196.94525) (xy 313.545728 -196.853302) (xy 313.54268 -196.832982) (xy 313.537092 -196.824092)
			(xy 313.526223 -196.806139) (xy 313.507152 -196.768751) (xy 313.498992 -196.749416) (xy 313.494928 -196.739764)
			(xy 313.45505 -196.699886) (xy 313.424062 -196.694044) (xy 313.409838 -196.700648) (xy 313.377185 -196.714466)
			(xy 313.309009 -196.733941) (xy 313.238788 -196.743748) (xy 313.203336 -196.744336) (xy 313.172602 -196.743892)
			(xy 313.111581 -196.736488) (xy 313.051898 -196.721781) (xy 312.994423 -196.699988) (xy 312.939994 -196.671426)
			(xy 312.889404 -196.636511) (xy 312.843392 -196.595753) (xy 312.802628 -196.549746) (xy 312.767707 -196.499161)
			(xy 312.739138 -196.444735) (xy 312.717338 -196.387263) (xy 312.702624 -196.327582) (xy 312.695211 -196.266562)
			(xy 312.694828 -196.235828) (xy 312.695287 -196.20373) (xy 312.703319 -196.140039) (xy 312.71083 -196.108828)
			(xy 312.71337 -196.099176) (xy 312.71083 -196.079618) (xy 312.664856 -196.00037) (xy 312.649362 -195.988178)
			(xy 312.639456 -195.985638) (xy 312.609338 -195.976845) (xy 312.55137 -195.952839) (xy 312.496798 -195.921878)
			(xy 312.446454 -195.884434) (xy 312.401102 -195.841076) (xy 312.361434 -195.792465) (xy 312.328052 -195.739339)
			(xy 312.301465 -195.682508) (xy 312.282078 -195.622836) (xy 312.270185 -195.56123) (xy 312.2676 -195.529962)
			(xy 312.266838 -195.520564) (xy 312.259472 -195.504308) (xy 310.835802 -194.080638) (xy 310.829198 -194.07505)
			(xy 309.805578 -193.360294) (xy 309.799021 -193.356083) (xy 309.784156 -193.35143) (xy 309.776368 -193.35115)
			(xy 309.306214 -193.35115) (xy 309.297423 -193.351517) (xy 309.280879 -193.357467) (xy 309.267327 -193.368668)
			(xy 309.262526 -193.376042) (xy 309.241062 -193.4113) (xy 309.192462 -193.478029) (xy 309.137805 -193.539894)
			(xy 309.077576 -193.596347) (xy 309.012307 -193.64689) (xy 308.942576 -193.691074) (xy 308.869001 -193.728508)
			(xy 308.792233 -193.758861) (xy 308.712952 -193.781865) (xy 308.63186 -193.797314) (xy 308.549675 -193.805073)
			(xy 308.467125 -193.805073) (xy 308.38494 -193.797314) (xy 308.303848 -193.781865) (xy 308.224567 -193.758861)
			(xy 308.147799 -193.728508) (xy 308.074224 -193.691074) (xy 308.004493 -193.64689) (xy 307.939224 -193.596347)
			(xy 307.878995 -193.539894) (xy 307.824338 -193.478029) (xy 307.775738 -193.4113) (xy 307.754274 -193.376042)
			(xy 307.749469 -193.368677) (xy 307.735912 -193.357497) (xy 307.719372 -193.351559) (xy 307.710586 -193.35115)
			(xy 304.72253 -193.35115) (xy 304.712438 -193.351633) (xy 304.693841 -193.359489) (xy 304.686462 -193.36639)
			(xy 304.678606 -193.374252) (xy 304.662083 -193.389119) (xy 304.653442 -193.396108) (xy 304.643282 -193.403982)
			(xy 304.633376 -193.427096) (xy 304.642012 -193.53657) (xy 304.655474 -193.557906) (xy 304.66665 -193.564002)
			(xy 304.693357 -193.579547) (xy 304.743054 -193.616273) (xy 304.787803 -193.65889) (xy 304.82691 -193.706738)
			(xy 304.859767 -193.759074) (xy 304.885867 -193.815087) (xy 304.904804 -193.87391) (xy 304.916284 -193.934629)
			(xy 304.92013 -193.996305) (xy 304.916283 -194.05798) (xy 304.904801 -194.1187) (xy 304.885863 -194.177522)
			(xy 304.859763 -194.233535) (xy 304.826904 -194.28587) (xy 304.787797 -194.333717) (xy 304.743047 -194.376333)
			(xy 304.693348 -194.413058) (xy 304.66665 -194.428618) (xy 304.655474 -194.434714) (xy 304.642012 -194.45605)
			(xy 304.633376 -194.565524) (xy 304.643282 -194.588638) (xy 304.653442 -194.596512) (xy 304.674767 -194.61412)
			(xy 304.712406 -194.654635) (xy 304.743578 -194.700314) (xy 304.767585 -194.750132) (xy 304.783889 -194.802975)
			(xy 304.792125 -194.857659) (xy 304.792634 -194.88531) (xy 304.792118 -194.91291) (xy 304.783891 -194.967493)
			(xy 304.767621 -195.02024) (xy 304.743671 -195.069973) (xy 304.712576 -195.11558) (xy 304.675031 -195.156044)
			(xy 304.631874 -195.190461) (xy 304.58407 -195.21806) (xy 304.532686 -195.238227) (xy 304.478871 -195.25051)
			(xy 304.423826 -195.254635) (xy 304.368781 -195.25051) (xy 304.314966 -195.238227) (xy 304.263582 -195.21806)
			(xy 304.215778 -195.190461) (xy 304.172621 -195.156044) (xy 304.135076 -195.11558) (xy 304.103981 -195.069973)
			(xy 304.080031 -195.02024) (xy 304.063761 -194.967493) (xy 304.055534 -194.91291) (xy 304.055018 -194.88531)
			(xy 304.05549 -194.857655) (xy 304.063708 -194.802961) (xy 304.080005 -194.750108) (xy 304.104017 -194.700284)
			(xy 304.135204 -194.654607) (xy 304.172866 -194.614102) (xy 304.19421 -194.596512) (xy 304.20437 -194.588638)
			(xy 304.214276 -194.565524) (xy 304.20564 -194.45605) (xy 304.192178 -194.434714) (xy 304.181002 -194.428618)
			(xy 304.154292 -194.413075) (xy 304.104587 -194.376351) (xy 304.059831 -194.333735) (xy 304.020718 -194.285887)
			(xy 303.987855 -194.23355) (xy 303.96175 -194.177534) (xy 303.942809 -194.118708) (xy 303.931326 -194.057985)
			(xy 303.927478 -193.996305) (xy 303.931325 -193.934625) (xy 303.942807 -193.873901) (xy 303.961747 -193.815075)
			(xy 303.98785 -193.759059) (xy 304.020712 -193.706721) (xy 304.059824 -193.658872) (xy 304.104579 -193.616255)
			(xy 304.154284 -193.579531) (xy 304.181002 -193.564002) (xy 304.192178 -193.557906) (xy 304.20564 -193.53657)
			(xy 304.214276 -193.427096) (xy 304.20437 -193.403982) (xy 304.19421 -193.396108) (xy 304.185571 -193.389117)
			(xy 304.169051 -193.374246) (xy 304.16119 -193.36639) (xy 304.153816 -193.359482) (xy 304.135215 -193.351632)
			(xy 304.125122 -193.35115) (xy 302.996854 -193.35115) (xy 302.986446 -193.351638) (xy 302.967334 -193.359886)
			(xy 302.95307 -193.375046) (xy 302.949102 -193.384678) (xy 302.933122 -193.426908) (xy 302.893697 -193.508145)
			(xy 302.846133 -193.584901) (xy 302.790936 -193.656364) (xy 302.728689 -193.721778) (xy 302.66005 -193.780451)
			(xy 302.62322 -193.806572) (xy 302.615583 -193.81233) (xy 302.604919 -193.828191) (xy 302.600796 -193.846853)
			(xy 302.601884 -193.856356) (xy 302.604838 -193.875907) (xy 302.608019 -193.915324) (xy 302.608234 -193.935096)
			(xy 302.607774 -193.965786) (xy 302.600198 -194.026698) (xy 302.585162 -194.086209) (xy 302.562894 -194.143408)
			(xy 302.533737 -194.197422) (xy 302.498135 -194.247423) (xy 302.456634 -194.292648) (xy 302.409868 -194.332404)
			(xy 302.38446 -194.349624) (xy 302.37557 -194.355466) (xy 302.364394 -194.372484) (xy 302.347376 -194.465448)
			(xy 302.351694 -194.485514) (xy 302.358044 -194.49415) (xy 302.375887 -194.519613) (xy 302.405774 -194.574135)
			(xy 302.428607 -194.631968) (xy 302.444028 -194.692202) (xy 302.451794 -194.753892) (xy 302.452278 -194.78498)
			(xy 302.451771 -194.817444) (xy 302.443299 -194.881816) (xy 302.426496 -194.944532) (xy 302.40165 -195.004518)
			(xy 302.369187 -195.060747) (xy 302.329661 -195.112257) (xy 302.28375 -195.158168) (xy 302.232238 -195.197692)
			(xy 302.176009 -195.230154) (xy 302.116022 -195.254999) (xy 302.053306 -195.271801) (xy 301.988934 -195.280272)
			(xy 301.95647 -195.280788) (xy 301.923364 -195.280236) (xy 301.85774 -195.271421) (xy 301.793874 -195.253951)
			(xy 301.7329 -195.228137) (xy 301.675904 -195.194439) (xy 301.6239 -195.153455) (xy 301.577812 -195.105915)
			(xy 301.55769 -195.07962) (xy 301.550324 -195.069714) (xy 301.528988 -195.059046) (xy 301.4218 -195.059808)
			(xy 301.400718 -195.07073) (xy 301.393352 -195.08089) (xy 301.380571 -195.098366) (xy 301.352467 -195.131306)
			(xy 301.337218 -195.146676) (xy 301.329852 -195.154042) (xy 301.322232 -195.172076) (xy 301.321216 -195.264024)
			(xy 301.328582 -195.282566) (xy 301.335694 -195.289932) (xy 301.357518 -195.313114) (xy 301.395651 -195.3641)
			(xy 301.426938 -195.419552) (xy 301.450862 -195.478555) (xy 301.467029 -195.540137) (xy 301.469352 -195.558156)
			(xy 305.687984 -195.558156) (xy 305.688555 -195.524392) (xy 305.697736 -195.457489) (xy 305.715909 -195.392451)
			(xy 305.742737 -195.33048) (xy 305.777725 -195.272721) (xy 305.820225 -195.220243) (xy 305.844448 -195.196714)
			(xy 305.85156 -195.189856) (xy 305.859942 -195.171822) (xy 305.864006 -195.081144) (xy 305.857402 -195.062348)
			(xy 305.850544 -195.054982) (xy 305.830338 -195.031623) (xy 305.795112 -194.980888) (xy 305.766289 -194.926261)
			(xy 305.744291 -194.868546) (xy 305.729444 -194.808593) (xy 305.721966 -194.747282) (xy 305.721512 -194.7164)
			(xy 305.721967 -194.685796) (xy 305.729321 -194.625032) (xy 305.74391 -194.565589) (xy 305.765524 -194.508325)
			(xy 305.79385 -194.454067) (xy 305.828481 -194.403598) (xy 305.868914 -194.357648) (xy 305.891438 -194.336924)
			(xy 305.89855 -194.330828) (xy 305.906932 -194.314826) (xy 305.917346 -194.229482) (xy 305.913028 -194.211956)
			(xy 305.907694 -194.204082) (xy 305.892591 -194.180979) (xy 305.868679 -194.131233) (xy 305.85243 -194.078485)
			(xy 305.844206 -194.023907) (xy 305.843686 -193.99631) (xy 305.844202 -193.96871) (xy 305.852429 -193.914127)
			(xy 305.868699 -193.86138) (xy 305.892649 -193.811648) (xy 305.923744 -193.76604) (xy 305.961289 -193.725576)
			(xy 306.004446 -193.691159) (xy 306.05225 -193.66356) (xy 306.103634 -193.643393) (xy 306.157449 -193.63111)
			(xy 306.212494 -193.626985) (xy 306.267539 -193.63111) (xy 306.321354 -193.643393) (xy 306.372738 -193.66356)
			(xy 306.420542 -193.691159) (xy 306.463699 -193.725576) (xy 306.501244 -193.76604) (xy 306.532339 -193.811648)
			(xy 306.556289 -193.86138) (xy 306.572559 -193.914127) (xy 306.580786 -193.96871) (xy 306.581302 -193.99631)
			(xy 306.580849 -194.021645) (xy 306.573903 -194.071837) (xy 306.560143 -194.120603) (xy 306.539829 -194.167023)
			(xy 306.526946 -194.188842) (xy 306.52212 -194.19697) (xy 306.518564 -194.21475) (xy 306.533296 -194.299332)
			(xy 306.54244 -194.31508) (xy 306.549806 -194.320922) (xy 306.57465 -194.341679) (xy 306.619404 -194.388458)
			(xy 306.657862 -194.440538) (xy 306.689402 -194.497075) (xy 306.713514 -194.557157) (xy 306.729808 -194.619813)
			(xy 306.738022 -194.68403) (xy 306.738528 -194.7164) (xy 306.738104 -194.746865) (xy 306.73352 -194.78498)
			(xy 308.027576 -194.78498) (xy 308.03165 -194.721512) (xy 308.043808 -194.659087) (xy 308.063848 -194.598728)
			(xy 308.091442 -194.541428) (xy 308.126138 -194.488127) (xy 308.167364 -194.4397) (xy 308.214444 -194.396943)
			(xy 308.266606 -194.360557) (xy 308.322993 -194.33114) (xy 308.382678 -194.309175) (xy 308.444682 -194.295023)
			(xy 308.507986 -194.288917) (xy 308.571552 -194.290955) (xy 308.634335 -194.301105) (xy 308.695305 -194.319201)
			(xy 308.75346 -194.344944) (xy 308.807846 -194.377913) (xy 308.857569 -194.417566) (xy 308.901814 -194.463252)
			(xy 308.939853 -194.514221) (xy 308.971062 -194.569635) (xy 308.994928 -194.628586) (xy 309.01106 -194.690104)
			(xy 309.019193 -194.753181) (xy 309.019702 -194.78498) (xy 309.019193 -194.816779) (xy 309.01106 -194.879856)
			(xy 308.994928 -194.941374) (xy 308.971062 -195.000325) (xy 308.939853 -195.055739) (xy 308.901814 -195.106708)
			(xy 308.857569 -195.152394) (xy 308.807846 -195.192047) (xy 308.75346 -195.225016) (xy 308.695305 -195.250759)
			(xy 308.634335 -195.268855) (xy 308.571552 -195.279005) (xy 308.507986 -195.281043) (xy 308.444682 -195.274937)
			(xy 308.382678 -195.260785) (xy 308.322993 -195.23882) (xy 308.266606 -195.209403) (xy 308.214444 -195.173017)
			(xy 308.167364 -195.13026) (xy 308.126138 -195.081833) (xy 308.091442 -195.028532) (xy 308.063848 -194.971232)
			(xy 308.043808 -194.910873) (xy 308.03165 -194.848448) (xy 308.027576 -194.78498) (xy 306.73352 -194.78498)
			(xy 306.730828 -194.80736) (xy 306.71638 -194.866552) (xy 306.694967 -194.923596) (xy 306.666894 -194.977674)
			(xy 306.632565 -195.028013) (xy 306.59247 -195.073892) (xy 306.570126 -195.094606) (xy 306.562506 -195.10121)
			(xy 306.55387 -195.11899) (xy 306.548028 -195.209668) (xy 306.554124 -195.228464) (xy 306.560728 -195.236084)
			(xy 306.579409 -195.258561) (xy 306.61189 -195.307151) (xy 306.638432 -195.359224) (xy 306.658666 -195.414058)
			(xy 306.672311 -195.47089) (xy 306.679178 -195.528932) (xy 306.6796 -195.558156) (xy 306.679111 -195.589319)
			(xy 306.671299 -195.651153) (xy 306.655799 -195.711521) (xy 306.632856 -195.769469) (xy 306.60283 -195.824086)
			(xy 306.566196 -195.874508) (xy 306.523531 -195.919942) (xy 306.475509 -195.95967) (xy 306.422885 -195.993065)
			(xy 306.366491 -196.019602) (xy 306.307216 -196.038862) (xy 306.245995 -196.050541) (xy 306.183792 -196.054454)
			(xy 306.121589 -196.050541) (xy 306.060368 -196.038862) (xy 306.001093 -196.019602) (xy 305.944699 -195.993065)
			(xy 305.892075 -195.95967) (xy 305.844053 -195.919942) (xy 305.801388 -195.874508) (xy 305.764754 -195.824086)
			(xy 305.734728 -195.769469) (xy 305.711785 -195.711521) (xy 305.696285 -195.651153) (xy 305.688473 -195.589319)
			(xy 305.687984 -195.558156) (xy 301.469352 -195.558156) (xy 301.475171 -195.603283) (xy 301.475648 -195.635118)
			(xy 301.475159 -195.666281) (xy 301.467347 -195.728115) (xy 301.451847 -195.788483) (xy 301.428904 -195.846431)
			(xy 301.398878 -195.901048) (xy 301.362244 -195.95147) (xy 301.319579 -195.996904) (xy 301.271557 -196.036632)
			(xy 301.218933 -196.070027) (xy 301.162539 -196.096564) (xy 301.103264 -196.115824) (xy 301.042043 -196.127503)
			(xy 300.97984 -196.131416) (xy 300.917637 -196.127503) (xy 300.856416 -196.115824) (xy 300.797141 -196.096564)
			(xy 300.740747 -196.070027) (xy 300.688123 -196.036632) (xy 300.640101 -195.996904) (xy 300.597436 -195.95147)
			(xy 300.560802 -195.901048) (xy 300.530776 -195.846431) (xy 300.507833 -195.788483) (xy 300.492333 -195.728115)
			(xy 300.484521 -195.666281) (xy 300.484032 -195.635118) (xy 300.484527 -195.603286) (xy 300.492687 -195.540147)
			(xy 300.508863 -195.478573) (xy 300.532788 -195.419575) (xy 300.564069 -195.364126) (xy 300.60219 -195.313137)
			(xy 300.623986 -195.289932) (xy 300.631098 -195.282566) (xy 300.638464 -195.264024) (xy 300.637448 -195.172076)
			(xy 300.629828 -195.154042) (xy 300.622462 -195.146676) (xy 300.598974 -195.122715) (xy 300.557857 -195.069691)
			(xy 300.524068 -195.011722) (xy 300.498193 -194.949814) (xy 300.480681 -194.885041) (xy 300.471837 -194.818529)
			(xy 300.471332 -194.78498) (xy 300.471779 -194.75425) (xy 300.47919 -194.693237) (xy 300.493901 -194.633563)
			(xy 300.515698 -194.576097) (xy 300.544263 -194.521677) (xy 300.57918 -194.471098) (xy 300.619939 -194.425096)
			(xy 300.665945 -194.384343) (xy 300.716529 -194.349432) (xy 300.770952 -194.320873) (xy 300.82842 -194.299083)
			(xy 300.888096 -194.284379) (xy 300.949109 -194.276975) (xy 300.97984 -194.276472) (xy 301.010033 -194.2769)
			(xy 301.069995 -194.284046) (xy 301.128688 -194.298244) (xy 301.185286 -194.319295) (xy 301.238993 -194.346902)
			(xy 301.289051 -194.380676) (xy 301.334756 -194.420141) (xy 301.375464 -194.464743) (xy 301.393352 -194.48907)
			(xy 301.400718 -194.49923) (xy 301.4218 -194.510152) (xy 301.528988 -194.510914) (xy 301.550324 -194.500246)
			(xy 301.55769 -194.49034) (xy 301.57541 -194.46708) (xy 301.615455 -194.424468) (xy 301.660235 -194.386863)
			(xy 301.684436 -194.370452) (xy 301.693326 -194.36461) (xy 301.704502 -194.347592) (xy 301.72152 -194.254628)
			(xy 301.717202 -194.234562) (xy 301.710852 -194.225926) (xy 301.69301 -194.200463) (xy 301.663126 -194.14594)
			(xy 301.640296 -194.088107) (xy 301.624878 -194.027873) (xy 301.617115 -193.966184) (xy 301.616618 -193.935096)
			(xy 301.616906 -193.911647) (xy 301.621362 -193.86496) (xy 301.625508 -193.841878) (xy 301.626937 -193.832389)
			(xy 301.623412 -193.813543) (xy 301.613194 -193.797319) (xy 301.605696 -193.791332) (xy 301.574096 -193.767555)
			(xy 301.514859 -193.715156) (xy 301.460584 -193.657632) (xy 301.411713 -193.595451) (xy 301.368645 -193.52912)
			(xy 301.331728 -193.459177) (xy 301.301265 -193.386192) (xy 301.288958 -193.34861) (xy 301.283878 -193.332608)
			(xy 301.257208 -193.31305) (xy 297.21175 -193.31305) (xy 297.200079 -193.313612) (xy 297.179144 -193.323926)
			(xy 297.171618 -193.332862) (xy 297.157769 -193.35027) (xy 297.12657 -193.38198) (xy 297.109388 -193.396108)
			(xy 297.099228 -193.403982) (xy 297.089322 -193.427096) (xy 297.097958 -193.53657) (xy 297.11142 -193.557906)
			(xy 297.122596 -193.564002) (xy 297.149305 -193.579545) (xy 297.199008 -193.616268) (xy 297.243761 -193.658884)
			(xy 297.282872 -193.706731) (xy 297.315734 -193.759067) (xy 297.341836 -193.815081) (xy 297.360775 -193.873905)
			(xy 297.372257 -193.934627) (xy 297.376104 -193.996305) (xy 297.372256 -194.057983) (xy 297.360773 -194.118704)
			(xy 297.341833 -194.177528) (xy 297.315729 -194.233542) (xy 297.282866 -194.285877) (xy 297.243755 -194.333723)
			(xy 297.199 -194.376338) (xy 297.149297 -194.41306) (xy 297.122596 -194.428618) (xy 297.11142 -194.434714)
			(xy 297.097958 -194.45605) (xy 297.089322 -194.565524) (xy 297.099228 -194.588638) (xy 297.109388 -194.596512)
			(xy 297.130716 -194.614118) (xy 297.16836 -194.654631) (xy 297.199537 -194.700309) (xy 297.223547 -194.750128)
			(xy 297.239854 -194.802972) (xy 297.248091 -194.857658) (xy 297.24858 -194.88531) (xy 297.248064 -194.91291)
			(xy 297.239837 -194.967493) (xy 297.223567 -195.02024) (xy 297.199617 -195.069973) (xy 297.168522 -195.11558)
			(xy 297.130977 -195.156044) (xy 297.08782 -195.190461) (xy 297.040016 -195.21806) (xy 296.988632 -195.238227)
			(xy 296.934817 -195.25051) (xy 296.879772 -195.254635) (xy 296.824727 -195.25051) (xy 296.770912 -195.238227)
			(xy 296.719528 -195.21806) (xy 296.671724 -195.190461) (xy 296.628567 -195.156044) (xy 296.591022 -195.11558)
			(xy 296.559927 -195.069973) (xy 296.535977 -195.02024) (xy 296.519707 -194.967493) (xy 296.51148 -194.91291)
			(xy 296.510964 -194.88531) (xy 296.511436 -194.857656) (xy 296.519654 -194.802962) (xy 296.535954 -194.750111)
			(xy 296.559968 -194.700289) (xy 296.591157 -194.654615) (xy 296.628822 -194.614114) (xy 296.650156 -194.596512)
			(xy 296.660316 -194.588638) (xy 296.670222 -194.565524) (xy 296.661586 -194.45605) (xy 296.648124 -194.434714)
			(xy 296.636948 -194.428618) (xy 296.61024 -194.413073) (xy 296.56054 -194.376346) (xy 296.515789 -194.333729)
			(xy 296.47668 -194.28588) (xy 296.443821 -194.233543) (xy 296.417719 -194.177528) (xy 296.398781 -194.118704)
			(xy 296.387299 -194.057983) (xy 296.383451 -193.996305) (xy 296.387298 -193.934627) (xy 296.398778 -193.873905)
			(xy 296.417716 -193.815081) (xy 296.443816 -193.759066) (xy 296.476675 -193.706728) (xy 296.515782 -193.658879)
			(xy 296.560533 -193.61626) (xy 296.610232 -193.579532) (xy 296.636948 -193.564002) (xy 296.648124 -193.557906)
			(xy 296.661586 -193.53657) (xy 296.670222 -193.427096) (xy 296.660316 -193.403982) (xy 296.650156 -193.396108)
			(xy 296.632957 -193.381999) (xy 296.601755 -193.350288) (xy 296.587926 -193.332862) (xy 296.580344 -193.323994)
			(xy 296.559444 -193.313677) (xy 296.547794 -193.31305) (xy 295.44899 -193.31305) (xy 295.42232 -193.332608)
			(xy 295.41724 -193.34861) (xy 295.404322 -193.387963) (xy 295.372067 -193.464257) (xy 295.332766 -193.537173)
			(xy 295.286768 -193.60606) (xy 295.234483 -193.670306) (xy 295.176377 -193.729338) (xy 295.112966 -193.782632)
			(xy 295.079166 -193.806572) (xy 295.071524 -193.812327) (xy 295.060849 -193.828187) (xy 295.056722 -193.846854)
			(xy 295.05783 -193.856356) (xy 295.060784 -193.875907) (xy 295.063964 -193.915324) (xy 295.06418 -193.935096)
			(xy 295.06369 -193.96693) (xy 295.05554 -194.030074) (xy 295.039373 -194.091656) (xy 295.015456 -194.150661)
			(xy 294.984182 -194.206119) (xy 294.946065 -194.257116) (xy 294.924226 -194.280282) (xy 294.917114 -194.287648)
			(xy 294.909748 -194.305936) (xy 294.910764 -194.397884) (xy 294.918638 -194.416172) (xy 294.92575 -194.423284)
			(xy 294.949234 -194.447247) (xy 294.990344 -194.500272) (xy 295.024125 -194.558243) (xy 295.049992 -194.620151)
			(xy 295.067496 -194.684922) (xy 295.076332 -194.751433) (xy 295.07688 -194.78498) (xy 295.076378 -194.816941)
			(xy 295.068367 -194.880359) (xy 295.05247 -194.942273) (xy 295.028938 -195.001706) (xy 294.998144 -195.057721)
			(xy 294.960571 -195.109436) (xy 294.916814 -195.156033) (xy 294.867561 -195.196778) (xy 294.81359 -195.231029)
			(xy 294.755751 -195.258246) (xy 294.694958 -195.277999) (xy 294.632168 -195.289977) (xy 294.568372 -195.293991)
			(xy 294.504576 -195.289977) (xy 294.441786 -195.277999) (xy 294.380993 -195.258246) (xy 294.323154 -195.231029)
			(xy 294.269183 -195.196778) (xy 294.21993 -195.156033) (xy 294.176173 -195.109436) (xy 294.1386 -195.057721)
			(xy 294.107806 -195.001706) (xy 294.084274 -194.942273) (xy 294.068377 -194.880359) (xy 294.060366 -194.816941)
			(xy 294.059864 -194.78498) (xy 294.060398 -194.75143) (xy 294.069217 -194.684913) (xy 294.086712 -194.620135)
			(xy 294.112579 -194.558223) (xy 294.146368 -194.500252) (xy 294.187492 -194.447232) (xy 294.210994 -194.423284)
			(xy 294.218106 -194.416172) (xy 294.22598 -194.397884) (xy 294.226996 -194.305936) (xy 294.21963 -194.287648)
			(xy 294.212518 -194.280282) (xy 294.190693 -194.2571) (xy 294.152557 -194.206115) (xy 294.121268 -194.150664)
			(xy 294.097342 -194.091661) (xy 294.081173 -194.030078) (xy 294.073028 -193.966931) (xy 294.072564 -193.935096)
			(xy 294.072852 -193.911647) (xy 294.077308 -193.86496) (xy 294.081454 -193.841878) (xy 294.082883 -193.832389)
			(xy 294.07936 -193.813539) (xy 294.069148 -193.79731) (xy 294.061642 -193.791332) (xy 294.030041 -193.767556)
			(xy 293.970801 -193.715159) (xy 293.916523 -193.657636) (xy 293.86765 -193.595456) (xy 293.824579 -193.529125)
			(xy 293.787661 -193.459182) (xy 293.757195 -193.386198) (xy 293.744904 -193.34861) (xy 293.739824 -193.332608)
			(xy 293.713154 -193.31305) (xy 289.667696 -193.31305) (xy 289.656031 -193.313623) (xy 289.635114 -193.323951)
			(xy 289.627564 -193.332862) (xy 289.613716 -193.350271) (xy 289.582519 -193.381984) (xy 289.565334 -193.396108)
			(xy 289.555174 -193.403982) (xy 289.545268 -193.427096) (xy 289.553904 -193.53657) (xy 289.567366 -193.557906)
			(xy 289.578542 -193.564002) (xy 289.605249 -193.579547) (xy 289.654948 -193.616272) (xy 289.699697 -193.658889)
			(xy 289.738804 -193.706737) (xy 289.771662 -193.759073) (xy 289.797762 -193.815086) (xy 289.816699 -193.873909)
			(xy 289.82818 -193.934629) (xy 289.832026 -193.996305) (xy 289.828179 -194.057981) (xy 289.816697 -194.118701)
			(xy 289.797759 -194.177523) (xy 289.771658 -194.233536) (xy 289.738798 -194.285871) (xy 289.699691 -194.333718)
			(xy 289.65494 -194.376334) (xy 289.605241 -194.413059) (xy 289.578542 -194.428618) (xy 289.567366 -194.434714)
			(xy 289.553904 -194.45605) (xy 289.545268 -194.565524) (xy 289.555174 -194.588638) (xy 289.565334 -194.596512)
			(xy 289.586659 -194.61412) (xy 289.624299 -194.654635) (xy 289.655472 -194.700313) (xy 289.67948 -194.750131)
			(xy 289.695784 -194.802975) (xy 289.70402 -194.857659) (xy 289.704526 -194.88531) (xy 289.70401 -194.91291)
			(xy 289.695783 -194.967493) (xy 289.679513 -195.02024) (xy 289.655563 -195.069973) (xy 289.624468 -195.11558)
			(xy 289.586923 -195.156044) (xy 289.543766 -195.190461) (xy 289.495962 -195.21806) (xy 289.444578 -195.238227)
			(xy 289.390763 -195.25051) (xy 289.335718 -195.254635) (xy 289.280673 -195.25051) (xy 289.226858 -195.238227)
			(xy 289.175474 -195.21806) (xy 289.12767 -195.190461) (xy 289.084513 -195.156044) (xy 289.046968 -195.11558)
			(xy 289.015873 -195.069973) (xy 288.991923 -195.02024) (xy 288.975653 -194.967493) (xy 288.967426 -194.91291)
			(xy 288.96691 -194.88531) (xy 288.967382 -194.857655) (xy 288.975599 -194.802961) (xy 288.991897 -194.750108)
			(xy 289.015909 -194.700283) (xy 289.047095 -194.654606) (xy 289.084756 -194.614101) (xy 289.106102 -194.596512)
			(xy 289.116262 -194.588638) (xy 289.126168 -194.565524) (xy 289.117532 -194.45605) (xy 289.10407 -194.434714)
			(xy 289.092894 -194.428618) (xy 289.066184 -194.413074) (xy 289.01648 -194.37635) (xy 288.971725 -194.333734)
			(xy 288.932612 -194.285886) (xy 288.89975 -194.233549) (xy 288.873646 -194.177533) (xy 288.854705 -194.118708)
			(xy 288.843222 -194.057984) (xy 288.839374 -193.996305) (xy 288.843221 -193.934625) (xy 288.854703 -193.873902)
			(xy 288.873642 -193.815076) (xy 288.899745 -193.75906) (xy 288.932607 -193.706722) (xy 288.971718 -193.658873)
			(xy 289.016472 -193.616256) (xy 289.066176 -193.579531) (xy 289.092894 -193.564002) (xy 289.10407 -193.557906)
			(xy 289.117532 -193.53657) (xy 289.126168 -193.427096) (xy 289.116262 -193.403982) (xy 289.106102 -193.396108)
			(xy 289.088901 -193.382) (xy 289.057696 -193.350292) (xy 289.043872 -193.332862) (xy 289.036293 -193.323987)
			(xy 289.015394 -193.313651) (xy 289.00374 -193.31305) (xy 287.904936 -193.31305) (xy 287.878266 -193.332608)
			(xy 287.873186 -193.34861) (xy 287.860267 -193.387962) (xy 287.828011 -193.464255) (xy 287.788708 -193.537169)
			(xy 287.742708 -193.606053) (xy 287.690422 -193.670297) (xy 287.632314 -193.729327) (xy 287.568901 -193.782617)
			(xy 287.535112 -193.806572) (xy 287.527476 -193.812331) (xy 287.516813 -193.828191) (xy 287.512691 -193.846853)
			(xy 287.513776 -193.856356) (xy 287.51673 -193.875907) (xy 287.519911 -193.915324) (xy 287.520126 -193.935096)
			(xy 287.519636 -193.96693) (xy 287.511485 -194.030073) (xy 287.495317 -194.091654) (xy 287.471398 -194.150657)
			(xy 287.440121 -194.206113) (xy 287.402002 -194.257107) (xy 287.380172 -194.280282) (xy 287.37306 -194.287648)
			(xy 287.365694 -194.305936) (xy 287.36671 -194.397884) (xy 287.374584 -194.416172) (xy 287.381696 -194.423284)
			(xy 287.405179 -194.447247) (xy 287.446285 -194.500274) (xy 287.480063 -194.558245) (xy 287.505928 -194.620153)
			(xy 287.52343 -194.684924) (xy 287.532265 -194.751433) (xy 287.532826 -194.78498) (xy 287.532324 -194.816941)
			(xy 287.524313 -194.880359) (xy 287.508416 -194.942273) (xy 287.484884 -195.001706) (xy 287.45409 -195.057721)
			(xy 287.416517 -195.109436) (xy 287.37276 -195.156033) (xy 287.323507 -195.196778) (xy 287.269536 -195.231029)
			(xy 287.211697 -195.258246) (xy 287.150904 -195.277999) (xy 287.088114 -195.289977) (xy 287.024318 -195.293991)
			(xy 286.960522 -195.289977) (xy 286.897732 -195.277999) (xy 286.836939 -195.258246) (xy 286.7791 -195.231029)
			(xy 286.725129 -195.196778) (xy 286.675876 -195.156033) (xy 286.632119 -195.109436) (xy 286.594546 -195.057721)
			(xy 286.563752 -195.001706) (xy 286.54022 -194.942273) (xy 286.524323 -194.880359) (xy 286.516312 -194.816941)
			(xy 286.51581 -194.78498) (xy 286.516343 -194.75143) (xy 286.525161 -194.684912) (xy 286.542655 -194.620133)
			(xy 286.56852 -194.558218) (xy 286.602307 -194.500246) (xy 286.643428 -194.447222) (xy 286.66694 -194.423284)
			(xy 286.674052 -194.416172) (xy 286.681926 -194.397884) (xy 286.682942 -194.305936) (xy 286.675576 -194.287648)
			(xy 286.668464 -194.280282) (xy 286.646641 -194.257099) (xy 286.608509 -194.206113) (xy 286.577224 -194.150661)
			(xy 286.5533 -194.091658) (xy 286.537133 -194.030076) (xy 286.528989 -193.96693) (xy 286.52851 -193.935096)
			(xy 286.528798 -193.911647) (xy 286.533253 -193.86496) (xy 286.5374 -193.841878) (xy 286.538829 -193.83239)
			(xy 286.535304 -193.813543) (xy 286.525085 -193.79732) (xy 286.517588 -193.791332) (xy 286.485988 -193.767555)
			(xy 286.426751 -193.715155) (xy 286.372477 -193.657631) (xy 286.323607 -193.59545) (xy 286.280538 -193.529119)
			(xy 286.243622 -193.459176) (xy 286.213159 -193.386192) (xy 286.20085 -193.34861) (xy 286.19577 -193.332608)
			(xy 286.1691 -193.31305) (xy 282.123642 -193.31305) (xy 282.111972 -193.313614) (xy 282.091039 -193.32393)
			(xy 282.08351 -193.332862) (xy 282.069661 -193.35027) (xy 282.038461 -193.381979) (xy 282.02128 -193.396108)
			(xy 282.01112 -193.403982) (xy 282.001214 -193.427096) (xy 282.00985 -193.53657) (xy 282.023312 -193.557906)
			(xy 282.034488 -193.564002) (xy 282.061197 -193.579545) (xy 282.110901 -193.616268) (xy 282.155655 -193.658883)
			(xy 282.194767 -193.70673) (xy 282.227629 -193.759066) (xy 282.253732 -193.81508) (xy 282.272671 -193.873905)
			(xy 282.284153 -193.934627) (xy 282.288 -193.996305) (xy 282.284152 -194.057983) (xy 282.272669 -194.118705)
			(xy 282.253728 -194.177529) (xy 282.227624 -194.233543) (xy 282.194761 -194.285878) (xy 282.155649 -194.333724)
			(xy 282.110893 -194.376339) (xy 282.061189 -194.41306) (xy 282.034488 -194.428618) (xy 282.023312 -194.434714)
			(xy 282.00985 -194.45605) (xy 282.001214 -194.565524) (xy 282.01112 -194.588638) (xy 282.02128 -194.596512)
			(xy 282.042608 -194.614118) (xy 282.080253 -194.654631) (xy 282.111431 -194.700308) (xy 282.135442 -194.750127)
			(xy 282.151749 -194.802972) (xy 282.159986 -194.857658) (xy 282.160472 -194.88531) (xy 282.159956 -194.91291)
			(xy 282.151729 -194.967493) (xy 282.135459 -195.02024) (xy 282.111509 -195.069973) (xy 282.080414 -195.11558)
			(xy 282.042869 -195.156044) (xy 281.999712 -195.190461) (xy 281.951908 -195.21806) (xy 281.900524 -195.238227)
			(xy 281.846709 -195.25051) (xy 281.791664 -195.254635) (xy 281.736619 -195.25051) (xy 281.682804 -195.238227)
			(xy 281.63142 -195.21806) (xy 281.583616 -195.190461) (xy 281.540459 -195.156044) (xy 281.502914 -195.11558)
			(xy 281.471819 -195.069973) (xy 281.447869 -195.02024) (xy 281.431599 -194.967493) (xy 281.423372 -194.91291)
			(xy 281.422856 -194.88531) (xy 281.423328 -194.857656) (xy 281.431546 -194.802962) (xy 281.447845 -194.750111)
			(xy 281.471859 -194.700288) (xy 281.503048 -194.654613) (xy 281.540712 -194.614112) (xy 281.562048 -194.596512)
			(xy 281.572208 -194.588638) (xy 281.582114 -194.565524) (xy 281.573478 -194.45605) (xy 281.560016 -194.434714)
			(xy 281.54884 -194.428618) (xy 281.522133 -194.413073) (xy 281.472433 -194.376346) (xy 281.427683 -194.333728)
			(xy 281.388575 -194.285879) (xy 281.355716 -194.233542) (xy 281.329615 -194.177527) (xy 281.310677 -194.118703)
			(xy 281.299195 -194.057982) (xy 281.295347 -193.996305) (xy 281.299194 -193.934627) (xy 281.310674 -193.873906)
			(xy 281.329611 -193.815082) (xy 281.355711 -193.759067) (xy 281.388569 -193.706729) (xy 281.427676 -193.65888)
			(xy 281.472426 -193.616261) (xy 281.522124 -193.579533) (xy 281.54884 -193.564002) (xy 281.560016 -193.557906)
			(xy 281.573478 -193.53657) (xy 281.582114 -193.427096) (xy 281.572208 -193.403982) (xy 281.562048 -193.396108)
			(xy 281.544849 -193.381998) (xy 281.513648 -193.350287) (xy 281.499818 -193.332862) (xy 281.492236 -193.323996)
			(xy 281.471336 -193.313682) (xy 281.459686 -193.31305) (xy 280.360882 -193.31305) (xy 280.334212 -193.332608)
			(xy 280.329132 -193.34861) (xy 280.316213 -193.387963) (xy 280.283958 -193.464257) (xy 280.244657 -193.537172)
			(xy 280.198659 -193.606059) (xy 280.146374 -193.670304) (xy 280.088268 -193.729337) (xy 280.024856 -193.78263)
			(xy 279.991058 -193.806572) (xy 279.983417 -193.812328) (xy 279.972744 -193.828188) (xy 279.968618 -193.846853)
			(xy 279.969722 -193.856356) (xy 279.972676 -193.875907) (xy 279.975857 -193.915324) (xy 279.976072 -193.935096)
			(xy 279.975582 -193.96693) (xy 279.967432 -194.030074) (xy 279.951265 -194.091655) (xy 279.927347 -194.15066)
			(xy 279.896073 -194.206118) (xy 279.857956 -194.257115) (xy 279.836118 -194.280282) (xy 279.829006 -194.287648)
			(xy 279.82164 -194.305936) (xy 279.822656 -194.397884) (xy 279.83053 -194.416172) (xy 279.837642 -194.423284)
			(xy 279.861127 -194.447246) (xy 279.902237 -194.500272) (xy 279.936019 -194.558242) (xy 279.961886 -194.62015)
			(xy 279.97939 -194.684922) (xy 279.988227 -194.751433) (xy 279.988772 -194.78498) (xy 279.98827 -194.816941)
			(xy 279.980259 -194.880359) (xy 279.964362 -194.942273) (xy 279.94083 -195.001706) (xy 279.910036 -195.057721)
			(xy 279.872463 -195.109436) (xy 279.828706 -195.156033) (xy 279.779453 -195.196778) (xy 279.725482 -195.231029)
			(xy 279.667643 -195.258246) (xy 279.60685 -195.277999) (xy 279.54406 -195.289977) (xy 279.480264 -195.293991)
			(xy 279.416468 -195.289977) (xy 279.353678 -195.277999) (xy 279.292885 -195.258246) (xy 279.235046 -195.231029)
			(xy 279.181075 -195.196778) (xy 279.131822 -195.156033) (xy 279.088065 -195.109436) (xy 279.050492 -195.057721)
			(xy 279.019698 -195.001706) (xy 278.996166 -194.942273) (xy 278.980269 -194.880359) (xy 278.972258 -194.816941)
			(xy 278.971756 -194.78498) (xy 278.972289 -194.75143) (xy 278.981108 -194.684913) (xy 278.998603 -194.620135)
			(xy 279.02447 -194.558222) (xy 279.058259 -194.500251) (xy 279.099382 -194.44723) (xy 279.122886 -194.423284)
			(xy 279.129998 -194.416172) (xy 279.137872 -194.397884) (xy 279.138888 -194.305936) (xy 279.131522 -194.287648)
			(xy 279.12441 -194.280282) (xy 279.102586 -194.2571) (xy 279.06445 -194.206115) (xy 279.033161 -194.150663)
			(xy 279.009236 -194.09166) (xy 278.993067 -194.030078) (xy 278.984923 -193.966931) (xy 278.984456 -193.935096)
			(xy 278.984744 -193.911647) (xy 278.9892 -193.86496) (xy 278.993346 -193.841878) (xy 278.994775 -193.832389)
			(xy 278.991252 -193.81354) (xy 278.981039 -193.797311) (xy 278.973534 -193.791332) (xy 278.941933 -193.767556)
			(xy 278.882693 -193.715158) (xy 278.828416 -193.657635) (xy 278.779544 -193.595455) (xy 278.736473 -193.529124)
			(xy 278.699555 -193.459181) (xy 278.66909 -193.386197) (xy 278.656796 -193.34861) (xy 278.651716 -193.332608)
			(xy 278.625046 -193.31305) (xy 274.579842 -193.31305) (xy 274.568172 -193.313614) (xy 274.547239 -193.32393)
			(xy 274.53971 -193.332862) (xy 274.525861 -193.35027) (xy 274.494661 -193.381979) (xy 274.47748 -193.396108)
			(xy 274.46732 -193.403982) (xy 274.457414 -193.427096) (xy 274.46605 -193.53657) (xy 274.479512 -193.557906)
			(xy 274.490688 -193.564002) (xy 274.517397 -193.579545) (xy 274.567101 -193.616268) (xy 274.611855 -193.658883)
			(xy 274.650967 -193.70673) (xy 274.683829 -193.759066) (xy 274.709932 -193.81508) (xy 274.728871 -193.873905)
			(xy 274.740353 -193.934627) (xy 274.7442 -193.996305) (xy 274.740352 -194.057983) (xy 274.728869 -194.118705)
			(xy 274.709928 -194.177529) (xy 274.683824 -194.233543) (xy 274.650961 -194.285878) (xy 274.611849 -194.333724)
			(xy 274.567093 -194.376339) (xy 274.517389 -194.41306) (xy 274.490688 -194.428618) (xy 274.479512 -194.434714)
			(xy 274.46605 -194.45605) (xy 274.457414 -194.565524) (xy 274.46732 -194.588638) (xy 274.47748 -194.596512)
			(xy 274.498808 -194.614118) (xy 274.536453 -194.654631) (xy 274.567631 -194.700308) (xy 274.591642 -194.750127)
			(xy 274.607949 -194.802972) (xy 274.616186 -194.857658) (xy 274.616672 -194.88531) (xy 274.616156 -194.91291)
			(xy 274.607929 -194.967493) (xy 274.591659 -195.02024) (xy 274.567709 -195.069973) (xy 274.536614 -195.11558)
			(xy 274.499069 -195.156044) (xy 274.455912 -195.190461) (xy 274.408108 -195.21806) (xy 274.356724 -195.238227)
			(xy 274.302909 -195.25051) (xy 274.247864 -195.254635) (xy 274.192819 -195.25051) (xy 274.139004 -195.238227)
			(xy 274.08762 -195.21806) (xy 274.039816 -195.190461) (xy 273.996659 -195.156044) (xy 273.959114 -195.11558)
			(xy 273.928019 -195.069973) (xy 273.904069 -195.02024) (xy 273.887799 -194.967493) (xy 273.879572 -194.91291)
			(xy 273.879056 -194.88531) (xy 273.879528 -194.857656) (xy 273.887746 -194.802962) (xy 273.904045 -194.750111)
			(xy 273.928059 -194.700288) (xy 273.959248 -194.654613) (xy 273.996912 -194.614112) (xy 274.018248 -194.596512)
			(xy 274.028408 -194.588638) (xy 274.038314 -194.565524) (xy 274.029678 -194.45605) (xy 274.016216 -194.434714)
			(xy 274.00504 -194.428618) (xy 273.978333 -194.413073) (xy 273.928633 -194.376346) (xy 273.883883 -194.333728)
			(xy 273.844775 -194.285879) (xy 273.811916 -194.233542) (xy 273.785815 -194.177527) (xy 273.766877 -194.118703)
			(xy 273.755395 -194.057982) (xy 273.751547 -193.996305) (xy 273.755394 -193.934627) (xy 273.766874 -193.873906)
			(xy 273.785811 -193.815082) (xy 273.811911 -193.759067) (xy 273.844769 -193.706729) (xy 273.883876 -193.65888)
			(xy 273.928626 -193.616261) (xy 273.978324 -193.579533) (xy 274.00504 -193.564002) (xy 274.016216 -193.557906)
			(xy 274.029678 -193.53657) (xy 274.038314 -193.427096) (xy 274.028408 -193.403982) (xy 274.018248 -193.396108)
			(xy 274.001049 -193.381998) (xy 273.969848 -193.350287) (xy 273.956018 -193.332862) (xy 273.948436 -193.323996)
			(xy 273.927536 -193.313682) (xy 273.915886 -193.31305) (xy 272.817082 -193.31305) (xy 272.790412 -193.332608)
			(xy 272.785332 -193.34861) (xy 272.772413 -193.387963) (xy 272.740158 -193.464257) (xy 272.700857 -193.537172)
			(xy 272.654859 -193.606059) (xy 272.602574 -193.670304) (xy 272.544468 -193.729337) (xy 272.481056 -193.78263)
			(xy 272.447258 -193.806572) (xy 272.439617 -193.812328) (xy 272.428944 -193.828188) (xy 272.424818 -193.846853)
			(xy 272.425922 -193.856356) (xy 272.428876 -193.875907) (xy 272.432057 -193.915324) (xy 272.432272 -193.935096)
			(xy 272.431782 -193.96693) (xy 272.423632 -194.030074) (xy 272.407465 -194.091655) (xy 272.383547 -194.15066)
			(xy 272.352273 -194.206118) (xy 272.314156 -194.257115) (xy 272.292318 -194.280282) (xy 272.285206 -194.287648)
			(xy 272.27784 -194.305936) (xy 272.278856 -194.397884) (xy 272.28673 -194.416172) (xy 272.293842 -194.423284)
			(xy 272.317327 -194.447246) (xy 272.358437 -194.500272) (xy 272.392219 -194.558242) (xy 272.418086 -194.62015)
			(xy 272.43559 -194.684922) (xy 272.444427 -194.751433) (xy 272.444972 -194.78498) (xy 272.44447 -194.816941)
			(xy 272.436459 -194.880359) (xy 272.420562 -194.942273) (xy 272.39703 -195.001706) (xy 272.366236 -195.057721)
			(xy 272.328663 -195.109436) (xy 272.284906 -195.156033) (xy 272.235653 -195.196778) (xy 272.181682 -195.231029)
			(xy 272.123843 -195.258246) (xy 272.06305 -195.277999) (xy 272.00026 -195.289977) (xy 271.936464 -195.293991)
			(xy 271.872668 -195.289977) (xy 271.809878 -195.277999) (xy 271.749085 -195.258246) (xy 271.691246 -195.231029)
			(xy 271.637275 -195.196778) (xy 271.588022 -195.156033) (xy 271.544265 -195.109436) (xy 271.506692 -195.057721)
			(xy 271.475898 -195.001706) (xy 271.452366 -194.942273) (xy 271.436469 -194.880359) (xy 271.428458 -194.816941)
			(xy 271.427956 -194.78498) (xy 271.428489 -194.75143) (xy 271.437308 -194.684913) (xy 271.454803 -194.620135)
			(xy 271.48067 -194.558222) (xy 271.514459 -194.500251) (xy 271.555582 -194.44723) (xy 271.579086 -194.423284)
			(xy 271.586198 -194.416172) (xy 271.594072 -194.397884) (xy 271.595088 -194.305936) (xy 271.587722 -194.287648)
			(xy 271.58061 -194.280282) (xy 271.558786 -194.2571) (xy 271.52065 -194.206115) (xy 271.489361 -194.150663)
			(xy 271.465436 -194.09166) (xy 271.449267 -194.030078) (xy 271.441123 -193.966931) (xy 271.440656 -193.935096)
			(xy 271.440944 -193.911647) (xy 271.4454 -193.86496) (xy 271.449546 -193.841878) (xy 271.450975 -193.832389)
			(xy 271.447452 -193.81354) (xy 271.437239 -193.797311) (xy 271.429734 -193.791332) (xy 271.398133 -193.767556)
			(xy 271.338893 -193.715158) (xy 271.284616 -193.657635) (xy 271.235744 -193.595455) (xy 271.192673 -193.529124)
			(xy 271.155755 -193.459181) (xy 271.12529 -193.386197) (xy 271.112996 -193.34861) (xy 271.107916 -193.332608)
			(xy 271.081246 -193.31305) (xy 267.035788 -193.31305) (xy 267.024124 -193.313625) (xy 267.003209 -193.323955)
			(xy 266.995656 -193.332862) (xy 266.981808 -193.350271) (xy 266.950611 -193.381983) (xy 266.933426 -193.396108)
			(xy 266.923266 -193.403982) (xy 266.91336 -193.427096) (xy 266.921996 -193.53657) (xy 266.935458 -193.557906)
			(xy 266.946634 -193.564002) (xy 266.973341 -193.579546) (xy 267.023041 -193.616272) (xy 267.067791 -193.658888)
			(xy 267.106899 -193.706736) (xy 267.139757 -193.759072) (xy 267.165858 -193.815085) (xy 267.184795 -193.873908)
			(xy 267.196276 -193.934629) (xy 267.200123 -193.996305) (xy 267.196275 -194.057981) (xy 267.184793 -194.118701)
			(xy 267.165854 -194.177524) (xy 267.139753 -194.233537) (xy 267.106893 -194.285872) (xy 267.067784 -194.333719)
			(xy 267.023033 -194.376335) (xy 266.973333 -194.413059) (xy 266.946634 -194.428618) (xy 266.935458 -194.434714)
			(xy 266.921996 -194.45605) (xy 266.91336 -194.565524) (xy 266.923266 -194.588638) (xy 266.933426 -194.596512)
			(xy 266.954752 -194.61412) (xy 266.992393 -194.654634) (xy 267.023566 -194.700312) (xy 267.047574 -194.750131)
			(xy 267.063879 -194.802974) (xy 267.072115 -194.857659) (xy 267.072618 -194.88531) (xy 267.072102 -194.91291)
			(xy 267.063875 -194.967493) (xy 267.047605 -195.02024) (xy 267.023655 -195.069973) (xy 266.99256 -195.11558)
			(xy 266.955015 -195.156044) (xy 266.911858 -195.190461) (xy 266.864054 -195.21806) (xy 266.81267 -195.238227)
			(xy 266.758855 -195.25051) (xy 266.70381 -195.254635) (xy 266.648765 -195.25051) (xy 266.59495 -195.238227)
			(xy 266.543566 -195.21806) (xy 266.495762 -195.190461) (xy 266.452605 -195.156044) (xy 266.41506 -195.11558)
			(xy 266.383965 -195.069973) (xy 266.360015 -195.02024) (xy 266.343745 -194.967493) (xy 266.335518 -194.91291)
			(xy 266.335002 -194.88531) (xy 266.335474 -194.857656) (xy 266.343694 -194.802964) (xy 266.359994 -194.750114)
			(xy 266.38401 -194.700293) (xy 266.415201 -194.654621) (xy 266.452868 -194.614124) (xy 266.474194 -194.596512)
			(xy 266.484354 -194.588638) (xy 266.49426 -194.565524) (xy 266.485624 -194.45605) (xy 266.472162 -194.434714)
			(xy 266.460986 -194.428618) (xy 266.434276 -194.413074) (xy 266.384573 -194.37635) (xy 266.339818 -194.333733)
			(xy 266.300707 -194.285885) (xy 266.267845 -194.233548) (xy 266.241741 -194.177532) (xy 266.222801 -194.118707)
			(xy 266.211318 -194.057984) (xy 266.20747 -193.996305) (xy 266.211317 -193.934626) (xy 266.222798 -193.873902)
			(xy 266.241737 -193.815077) (xy 266.26784 -193.759061) (xy 266.300701 -193.706723) (xy 266.339812 -193.658874)
			(xy 266.384565 -193.616257) (xy 266.434268 -193.579531) (xy 266.460986 -193.564002) (xy 266.472162 -193.557906)
			(xy 266.485624 -193.53657) (xy 266.49426 -193.427096) (xy 266.484354 -193.403982) (xy 266.474194 -193.396108)
			(xy 266.456993 -193.382) (xy 266.425789 -193.350291) (xy 266.411964 -193.332862) (xy 266.404385 -193.323988)
			(xy 266.383485 -193.313655) (xy 266.371832 -193.31305) (xy 265.273028 -193.31305) (xy 265.246358 -193.332608)
			(xy 265.241278 -193.34861) (xy 265.228359 -193.387962) (xy 265.196102 -193.464255) (xy 265.156799 -193.537168)
			(xy 265.1108 -193.606053) (xy 265.058513 -193.670295) (xy 265.000404 -193.729325) (xy 264.936991 -193.782615)
			(xy 264.903204 -193.806572) (xy 264.895569 -193.812331) (xy 264.884908 -193.828192) (xy 264.880787 -193.846853)
			(xy 264.881868 -193.856356) (xy 264.884822 -193.875907) (xy 264.888003 -193.915324) (xy 264.888218 -193.935096)
			(xy 264.887728 -193.96693) (xy 264.879577 -194.030073) (xy 264.863409 -194.091653) (xy 264.839489 -194.150657)
			(xy 264.808212 -194.206112) (xy 264.770093 -194.257106) (xy 264.748264 -194.280282) (xy 264.741152 -194.287648)
			(xy 264.733786 -194.305936) (xy 264.734802 -194.397884) (xy 264.742676 -194.416172) (xy 264.749788 -194.423284)
			(xy 264.773271 -194.447247) (xy 264.814378 -194.500274) (xy 264.848157 -194.558245) (xy 264.874022 -194.620153)
			(xy 264.891524 -194.684924) (xy 264.90036 -194.751433) (xy 264.900918 -194.78498) (xy 264.900416 -194.816941)
			(xy 264.892405 -194.880359) (xy 264.876508 -194.942273) (xy 264.852976 -195.001706) (xy 264.822182 -195.057721)
			(xy 264.784609 -195.109436) (xy 264.740852 -195.156033) (xy 264.691599 -195.196778) (xy 264.637628 -195.231029)
			(xy 264.579789 -195.258246) (xy 264.518996 -195.277999) (xy 264.456206 -195.289977) (xy 264.39241 -195.293991)
			(xy 264.328614 -195.289977) (xy 264.265824 -195.277999) (xy 264.205031 -195.258246) (xy 264.147192 -195.231029)
			(xy 264.093221 -195.196778) (xy 264.043968 -195.156033) (xy 264.000211 -195.109436) (xy 263.962638 -195.057721)
			(xy 263.931844 -195.001706) (xy 263.908312 -194.942273) (xy 263.892415 -194.880359) (xy 263.884404 -194.816941)
			(xy 263.883902 -194.78498) (xy 263.884435 -194.75143) (xy 263.893253 -194.684912) (xy 263.910747 -194.620132)
			(xy 263.936612 -194.558218) (xy 263.970398 -194.500245) (xy 264.011518 -194.447221) (xy 264.035032 -194.423284)
			(xy 264.042144 -194.416172) (xy 264.050018 -194.397884) (xy 264.051034 -194.305936) (xy 264.043668 -194.287648)
			(xy 264.036556 -194.280282) (xy 264.014734 -194.257099) (xy 263.976602 -194.206112) (xy 263.945317 -194.150661)
			(xy 263.921394 -194.091657) (xy 263.905227 -194.030076) (xy 263.897084 -193.96693) (xy 263.896602 -193.935096)
			(xy 263.89689 -193.911647) (xy 263.901345 -193.86496) (xy 263.905492 -193.841878) (xy 263.90692 -193.832388)
			(xy 263.9034 -193.813537) (xy 263.893193 -193.797302) (xy 263.88568 -193.791332) (xy 263.852923 -193.766675)
			(xy 263.791669 -193.712169) (xy 263.735772 -193.652182) (xy 263.68572 -193.587237) (xy 263.66343 -193.552826)
			(xy 263.660382 -193.548) (xy 263.656572 -193.543936) (xy 263.649138 -193.53722) (xy 263.630638 -193.529584)
			(xy 263.610624 -193.529584) (xy 263.592124 -193.53722) (xy 263.58469 -193.543936) (xy 263.562084 -193.566542)
			(xy 263.555235 -193.573939) (xy 263.547502 -193.592538) (xy 263.547098 -193.60261) (xy 263.547098 -195.2752)
			(xy 263.547641 -195.286736) (xy 263.557684 -195.307506) (xy 263.566402 -195.315078) (xy 263.591964 -195.335796)
			(xy 263.638056 -195.382754) (xy 263.677705 -195.435265) (xy 263.71025 -195.492452) (xy 263.735146 -195.553359)
			(xy 263.751977 -195.616968) (xy 263.760462 -195.682218) (xy 263.76046 -195.748017) (xy 263.75197 -195.813266)
			(xy 263.739827 -195.859146) (xy 267.98397 -195.859146) (xy 267.984518 -195.825987) (xy 267.99313 -195.760232)
			(xy 268.010213 -195.696153) (xy 268.035478 -195.634837) (xy 268.068497 -195.577325) (xy 268.108709 -195.52459)
			(xy 268.155434 -195.477528) (xy 268.181328 -195.45681) (xy 268.190249 -195.44927) (xy 268.200572 -195.428346)
			(xy 268.20114 -195.416678) (xy 268.20114 -195.336414) (xy 268.200511 -195.324764) (xy 268.190196 -195.303864)
			(xy 268.181328 -195.296282) (xy 268.155446 -195.275549) (xy 268.108723 -195.228488) (xy 268.06851 -195.175755)
			(xy 268.035489 -195.118245) (xy 268.010219 -195.056933) (xy 267.993129 -194.992857) (xy 267.984507 -194.927104)
			(xy 267.98397 -194.893946) (xy 267.98454 -194.860172) (xy 267.993485 -194.793219) (xy 268.01121 -194.728038)
			(xy 268.037403 -194.665775) (xy 268.071605 -194.607526) (xy 268.113213 -194.554314) (xy 268.161496 -194.507076)
			(xy 268.215605 -194.466641) (xy 268.244828 -194.4497) (xy 268.256004 -194.443604) (xy 268.26972 -194.422522)
			(xy 268.279118 -194.313556) (xy 268.269466 -194.290188) (xy 268.25956 -194.282314) (xy 268.238699 -194.264719)
			(xy 268.201937 -194.224384) (xy 268.171517 -194.179076) (xy 268.148101 -194.129781) (xy 268.132201 -194.077575)
			(xy 268.124162 -194.023597) (xy 268.12367 -193.99631) (xy 268.124186 -193.96871) (xy 268.132413 -193.914127)
			(xy 268.148683 -193.86138) (xy 268.172633 -193.811648) (xy 268.203728 -193.76604) (xy 268.241273 -193.725576)
			(xy 268.28443 -193.691159) (xy 268.332234 -193.66356) (xy 268.383618 -193.643393) (xy 268.437433 -193.63111)
			(xy 268.492478 -193.626985) (xy 268.547523 -193.63111) (xy 268.601338 -193.643393) (xy 268.652722 -193.66356)
			(xy 268.700526 -193.691159) (xy 268.743683 -193.725576) (xy 268.781228 -193.76604) (xy 268.812323 -193.811648)
			(xy 268.836273 -193.86138) (xy 268.852543 -193.914127) (xy 268.86077 -193.96871) (xy 268.861286 -193.99631)
			(xy 268.860815 -194.023598) (xy 268.852784 -194.077579) (xy 268.836882 -194.129787) (xy 268.813459 -194.17908)
			(xy 268.783025 -194.224382) (xy 268.746245 -194.264703) (xy 268.725396 -194.282314) (xy 268.71549 -194.290188)
			(xy 268.705838 -194.313556) (xy 268.715236 -194.422522) (xy 268.728952 -194.443604) (xy 268.740128 -194.4497)
			(xy 268.769369 -194.466614) (xy 268.823486 -194.507046) (xy 268.871776 -194.554285) (xy 268.913388 -194.607499)
			(xy 268.947591 -194.665754) (xy 268.973782 -194.728022) (xy 268.991502 -194.79321) (xy 269.000437 -194.860169)
			(xy 269.000986 -194.893946) (xy 269.000449 -194.927105) (xy 268.991837 -194.992862) (xy 268.974753 -195.056942)
			(xy 268.949487 -195.118258) (xy 268.916466 -195.17577) (xy 268.876251 -195.228504) (xy 268.829524 -195.275564)
			(xy 268.803628 -195.296282) (xy 268.794703 -195.303818) (xy 268.784384 -195.324746) (xy 268.783816 -195.336414)
			(xy 268.783816 -195.416678) (xy 268.784464 -195.428325) (xy 268.794768 -195.449224) (xy 268.803628 -195.45681)
			(xy 268.829497 -195.477559) (xy 268.876222 -195.524617) (xy 268.916437 -195.577346) (xy 268.949461 -195.634853)
			(xy 268.94957 -195.635118) (xy 270.30807 -195.635118) (xy 270.308581 -195.602397) (xy 270.317183 -195.537524)
			(xy 270.334242 -195.474345) (xy 270.359459 -195.413958) (xy 270.392399 -195.357411) (xy 270.432487 -195.305687)
			(xy 270.45539 -195.282312) (xy 270.462756 -195.2752) (xy 270.47063 -195.256404) (xy 270.47063 -195.163694)
			(xy 270.462756 -195.144898) (xy 270.45539 -195.137786) (xy 270.432478 -195.114421) (xy 270.392395 -195.062692)
			(xy 270.359462 -195.006142) (xy 270.334249 -194.945753) (xy 270.317193 -194.882574) (xy 270.308593 -194.8177)
			(xy 270.30807 -194.78498) (xy 270.308559 -194.753817) (xy 270.316371 -194.691983) (xy 270.331871 -194.631615)
			(xy 270.354814 -194.573667) (xy 270.38484 -194.51905) (xy 270.421474 -194.468628) (xy 270.464139 -194.423194)
			(xy 270.512161 -194.383466) (xy 270.564785 -194.350071) (xy 270.621179 -194.323534) (xy 270.680454 -194.304274)
			(xy 270.741675 -194.292595) (xy 270.803878 -194.288682) (xy 270.866081 -194.292595) (xy 270.927302 -194.304274)
			(xy 270.986577 -194.323534) (xy 271.042971 -194.350071) (xy 271.095595 -194.383466) (xy 271.143617 -194.423194)
			(xy 271.186282 -194.468628) (xy 271.222916 -194.51905) (xy 271.252942 -194.573667) (xy 271.275885 -194.631615)
			(xy 271.291385 -194.691983) (xy 271.299197 -194.753817) (xy 271.299686 -194.78498) (xy 271.299187 -194.817701)
			(xy 271.290584 -194.882575) (xy 271.273524 -194.945755) (xy 271.248304 -195.006142) (xy 271.215362 -195.062689)
			(xy 271.17527 -195.114412) (xy 271.152366 -195.137786) (xy 271.145 -195.144898) (xy 271.137126 -195.163694)
			(xy 271.137126 -195.256404) (xy 271.145 -195.2752) (xy 271.152366 -195.282312) (xy 271.175288 -195.305667)
			(xy 271.215367 -195.3574) (xy 271.248299 -195.413952) (xy 271.27351 -195.474343) (xy 271.290564 -195.537523)
			(xy 271.299164 -195.602397) (xy 271.299686 -195.635118) (xy 271.299197 -195.666281) (xy 271.291385 -195.728115)
			(xy 271.275885 -195.788483) (xy 271.252942 -195.846431) (xy 271.245952 -195.859146) (xy 275.528024 -195.859146)
			(xy 275.52859 -195.825988) (xy 275.5372 -195.760234) (xy 275.554282 -195.696156) (xy 275.579545 -195.634841)
			(xy 275.612561 -195.577328) (xy 275.652769 -195.524593) (xy 275.69949 -195.47753) (xy 275.725382 -195.45681)
			(xy 275.734295 -195.449262) (xy 275.744624 -195.428344) (xy 275.745194 -195.416678) (xy 275.745194 -195.336414)
			(xy 275.744547 -195.324767) (xy 275.734242 -195.303868) (xy 275.725382 -195.296282) (xy 275.699511 -195.275535)
			(xy 275.652786 -195.228477) (xy 275.612571 -195.175748) (xy 275.579547 -195.11824) (xy 275.554275 -195.05693)
			(xy 275.537183 -194.992855) (xy 275.528561 -194.927103) (xy 275.528024 -194.893946) (xy 275.528618 -194.860173)
			(xy 275.537561 -194.793222) (xy 275.555285 -194.728043) (xy 275.581476 -194.665781) (xy 275.615674 -194.607532)
			(xy 275.657278 -194.55432) (xy 275.705557 -194.50708) (xy 275.759661 -194.466643) (xy 275.788882 -194.4497)
			(xy 275.800058 -194.443604) (xy 275.813774 -194.422522) (xy 275.823172 -194.313556) (xy 275.81352 -194.290188)
			(xy 275.803614 -194.282314) (xy 275.782764 -194.264706) (xy 275.745999 -194.224376) (xy 275.715576 -194.17907)
			(xy 275.692158 -194.129778) (xy 275.676256 -194.077573) (xy 275.668216 -194.023596) (xy 275.667724 -193.99631)
			(xy 275.66824 -193.96871) (xy 275.676467 -193.914127) (xy 275.692737 -193.86138) (xy 275.716687 -193.811648)
			(xy 275.747782 -193.76604) (xy 275.785327 -193.725576) (xy 275.828484 -193.691159) (xy 275.876288 -193.66356)
			(xy 275.927672 -193.643393) (xy 275.981487 -193.63111) (xy 276.036532 -193.626985) (xy 276.091577 -193.63111)
			(xy 276.145392 -193.643393) (xy 276.196776 -193.66356) (xy 276.24458 -193.691159) (xy 276.287737 -193.725576)
			(xy 276.325282 -193.76604) (xy 276.356377 -193.811648) (xy 276.380327 -193.86138) (xy 276.396597 -193.914127)
			(xy 276.404824 -193.96871) (xy 276.40534 -193.99631) (xy 276.404886 -194.023599) (xy 276.396853 -194.077581)
			(xy 276.38095 -194.12979) (xy 276.357523 -194.179084) (xy 276.327085 -194.224385) (xy 276.290302 -194.264704)
			(xy 276.26945 -194.282314) (xy 276.259544 -194.290188) (xy 276.249892 -194.313556) (xy 276.25929 -194.422522)
			(xy 276.273006 -194.443604) (xy 276.284182 -194.4497) (xy 276.313412 -194.466632) (xy 276.367532 -194.507059)
			(xy 276.415823 -194.554295) (xy 276.457437 -194.607506) (xy 276.491642 -194.665759) (xy 276.517835 -194.728026)
			(xy 276.535555 -194.793212) (xy 276.544491 -194.86017) (xy 276.54504 -194.893946) (xy 276.544483 -194.927104)
			(xy 276.535872 -194.992859) (xy 276.51879 -195.056938) (xy 276.493526 -195.118253) (xy 276.460509 -195.175766)
			(xy 276.420298 -195.228501) (xy 276.373576 -195.275563) (xy 276.347682 -195.296282) (xy 276.338766 -195.303827)
			(xy 276.32844 -195.324748) (xy 276.32787 -195.336414) (xy 276.32787 -195.416678) (xy 276.328499 -195.428328)
			(xy 276.338814 -195.449228) (xy 276.347682 -195.45681) (xy 276.373563 -195.477545) (xy 276.420285 -195.524606)
			(xy 276.460497 -195.577339) (xy 276.493519 -195.634848) (xy 276.49363 -195.635118) (xy 277.852124 -195.635118)
			(xy 277.852619 -195.602397) (xy 277.861222 -195.537522) (xy 277.878283 -195.474343) (xy 277.903503 -195.413955)
			(xy 277.936446 -195.357409) (xy 277.976539 -195.305686) (xy 277.999444 -195.282312) (xy 278.00681 -195.2752)
			(xy 278.014684 -195.256404) (xy 278.014684 -195.163694) (xy 278.00681 -195.144898) (xy 277.999444 -195.137786)
			(xy 277.976523 -195.11443) (xy 277.936443 -195.062698) (xy 277.903512 -195.006146) (xy 277.8783 -194.945755)
			(xy 277.861246 -194.882575) (xy 277.852646 -194.817701) (xy 277.852124 -194.78498) (xy 277.852613 -194.753817)
			(xy 277.860425 -194.691983) (xy 277.875925 -194.631615) (xy 277.898868 -194.573667) (xy 277.928894 -194.51905)
			(xy 277.965528 -194.468628) (xy 278.008193 -194.423194) (xy 278.056215 -194.383466) (xy 278.108839 -194.350071)
			(xy 278.165233 -194.323534) (xy 278.224508 -194.304274) (xy 278.285729 -194.292595) (xy 278.347932 -194.288682)
			(xy 278.410135 -194.292595) (xy 278.471356 -194.304274) (xy 278.530631 -194.323534) (xy 278.587025 -194.350071)
			(xy 278.639649 -194.383466) (xy 278.687671 -194.423194) (xy 278.730336 -194.468628) (xy 278.76697 -194.51905)
			(xy 278.796996 -194.573667) (xy 278.819939 -194.631615) (xy 278.835439 -194.691983) (xy 278.843251 -194.753817)
			(xy 278.84374 -194.78498) (xy 278.843255 -194.817702) (xy 278.834651 -194.882577) (xy 278.817589 -194.945757)
			(xy 278.792367 -195.006145) (xy 278.759422 -195.062691) (xy 278.719326 -195.114413) (xy 278.69642 -195.137786)
			(xy 278.689054 -195.144898) (xy 278.68118 -195.163694) (xy 278.68118 -195.256404) (xy 278.689054 -195.2752)
			(xy 278.69642 -195.282312) (xy 278.719333 -195.305676) (xy 278.759415 -195.357406) (xy 278.792348 -195.413956)
			(xy 278.817561 -195.474345) (xy 278.834616 -195.537524) (xy 278.843217 -195.602397) (xy 278.84374 -195.635118)
			(xy 278.843251 -195.666281) (xy 278.835439 -195.728115) (xy 278.819939 -195.788483) (xy 278.796996 -195.846431)
			(xy 278.790006 -195.859146) (xy 283.072078 -195.859146) (xy 283.072623 -195.825987) (xy 283.081235 -195.760231)
			(xy 283.098318 -195.696152) (xy 283.123584 -195.634837) (xy 283.156603 -195.577324) (xy 283.196816 -195.52459)
			(xy 283.243541 -195.477528) (xy 283.269436 -195.45681) (xy 283.278359 -195.449272) (xy 283.28868 -195.428346)
			(xy 283.289248 -195.416678) (xy 283.289248 -195.336414) (xy 283.288617 -195.324764) (xy 283.278303 -195.303864)
			(xy 283.269436 -195.296282) (xy 283.243555 -195.275547) (xy 283.196832 -195.228486) (xy 283.156619 -195.175754)
			(xy 283.123598 -195.118244) (xy 283.098327 -195.056932) (xy 283.081237 -194.992857) (xy 283.072615 -194.927104)
			(xy 283.072078 -194.893946) (xy 283.072644 -194.860172) (xy 283.081589 -194.793218) (xy 283.099314 -194.728037)
			(xy 283.125508 -194.665774) (xy 283.15971 -194.607525) (xy 283.201319 -194.554313) (xy 283.249603 -194.507075)
			(xy 283.303713 -194.466641) (xy 283.332936 -194.4497) (xy 283.344112 -194.443604) (xy 283.357828 -194.422522)
			(xy 283.367226 -194.313556) (xy 283.357574 -194.290188) (xy 283.347668 -194.282314) (xy 283.326808 -194.264717)
			(xy 283.290047 -194.224383) (xy 283.259626 -194.179075) (xy 283.23621 -194.12978) (xy 283.220309 -194.077575)
			(xy 283.21227 -194.023597) (xy 283.211778 -193.99631) (xy 283.212294 -193.96871) (xy 283.220521 -193.914127)
			(xy 283.236791 -193.86138) (xy 283.260741 -193.811648) (xy 283.291836 -193.76604) (xy 283.329381 -193.725576)
			(xy 283.372538 -193.691159) (xy 283.420342 -193.66356) (xy 283.471726 -193.643393) (xy 283.525541 -193.63111)
			(xy 283.580586 -193.626985) (xy 283.635631 -193.63111) (xy 283.689446 -193.643393) (xy 283.74083 -193.66356)
			(xy 283.788634 -193.691159) (xy 283.831791 -193.725576) (xy 283.869336 -193.76604) (xy 283.900431 -193.811648)
			(xy 283.924381 -193.86138) (xy 283.940651 -193.914127) (xy 283.948878 -193.96871) (xy 283.949394 -193.99631)
			(xy 283.948957 -194.023599) (xy 283.940923 -194.077584) (xy 283.925017 -194.129793) (xy 283.901588 -194.179087)
			(xy 283.871146 -194.224388) (xy 283.834358 -194.264705) (xy 283.813504 -194.282314) (xy 283.803598 -194.290188)
			(xy 283.793946 -194.313556) (xy 283.803344 -194.422522) (xy 283.81706 -194.443604) (xy 283.828236 -194.4497)
			(xy 283.857479 -194.46661) (xy 283.911596 -194.507043) (xy 283.959885 -194.554282) (xy 284.001497 -194.607498)
			(xy 284.0357 -194.665753) (xy 284.061891 -194.728022) (xy 284.07961 -194.79321) (xy 284.088545 -194.860169)
			(xy 284.089094 -194.893946) (xy 284.088554 -194.927105) (xy 284.079942 -194.992861) (xy 284.062859 -195.056941)
			(xy 284.037592 -195.118257) (xy 284.004572 -195.17577) (xy 283.964358 -195.228504) (xy 283.917631 -195.275564)
			(xy 283.891736 -195.296282) (xy 283.882812 -195.303819) (xy 283.872492 -195.324746) (xy 283.871924 -195.336414)
			(xy 283.871924 -195.416678) (xy 283.872569 -195.428326) (xy 283.882875 -195.449225) (xy 283.891736 -195.45681)
			(xy 283.917607 -195.477557) (xy 283.964331 -195.524615) (xy 284.004546 -195.577345) (xy 284.037569 -195.634852)
			(xy 284.037679 -195.635118) (xy 285.395924 -195.635118) (xy 285.396419 -195.602397) (xy 285.405022 -195.537522)
			(xy 285.422083 -195.474343) (xy 285.447303 -195.413955) (xy 285.480246 -195.357409) (xy 285.520339 -195.305686)
			(xy 285.543244 -195.282312) (xy 285.55061 -195.2752) (xy 285.558484 -195.256404) (xy 285.558484 -195.163694)
			(xy 285.55061 -195.144898) (xy 285.543244 -195.137786) (xy 285.520323 -195.11443) (xy 285.480243 -195.062698)
			(xy 285.447312 -195.006146) (xy 285.4221 -194.945755) (xy 285.405046 -194.882575) (xy 285.396446 -194.817701)
			(xy 285.395924 -194.78498) (xy 285.396413 -194.753817) (xy 285.404225 -194.691983) (xy 285.419725 -194.631615)
			(xy 285.442668 -194.573667) (xy 285.472694 -194.51905) (xy 285.509328 -194.468628) (xy 285.551993 -194.423194)
			(xy 285.600015 -194.383466) (xy 285.652639 -194.350071) (xy 285.709033 -194.323534) (xy 285.768308 -194.304274)
			(xy 285.829529 -194.292595) (xy 285.891732 -194.288682) (xy 285.953935 -194.292595) (xy 286.015156 -194.304274)
			(xy 286.074431 -194.323534) (xy 286.130825 -194.350071) (xy 286.183449 -194.383466) (xy 286.231471 -194.423194)
			(xy 286.274136 -194.468628) (xy 286.31077 -194.51905) (xy 286.340796 -194.573667) (xy 286.363739 -194.631615)
			(xy 286.379239 -194.691983) (xy 286.387051 -194.753817) (xy 286.38754 -194.78498) (xy 286.387055 -194.817702)
			(xy 286.378451 -194.882577) (xy 286.361389 -194.945757) (xy 286.336167 -195.006145) (xy 286.303222 -195.062691)
			(xy 286.263126 -195.114413) (xy 286.24022 -195.137786) (xy 286.232854 -195.144898) (xy 286.22498 -195.163694)
			(xy 286.22498 -195.256404) (xy 286.232854 -195.2752) (xy 286.24022 -195.282312) (xy 286.263133 -195.305676)
			(xy 286.303215 -195.357406) (xy 286.336148 -195.413956) (xy 286.361361 -195.474345) (xy 286.378416 -195.537524)
			(xy 286.387017 -195.602397) (xy 286.38754 -195.635118) (xy 286.387051 -195.666281) (xy 286.379239 -195.728115)
			(xy 286.363739 -195.788483) (xy 286.340796 -195.846431) (xy 286.333806 -195.859146) (xy 290.616132 -195.859146)
			(xy 290.616694 -195.825988) (xy 290.625305 -195.760234) (xy 290.642387 -195.696156) (xy 290.667651 -195.63484)
			(xy 290.700667 -195.577328) (xy 290.740876 -195.524593) (xy 290.787597 -195.477529) (xy 290.81349 -195.45681)
			(xy 290.822405 -195.449263) (xy 290.832732 -195.428344) (xy 290.833302 -195.416678) (xy 290.833302 -195.336414)
			(xy 290.832652 -195.324767) (xy 290.822349 -195.303868) (xy 290.81349 -195.296282) (xy 290.787621 -195.275533)
			(xy 290.740895 -195.228476) (xy 290.700679 -195.175747) (xy 290.667656 -195.11824) (xy 290.642384 -195.056929)
			(xy 290.625292 -194.992855) (xy 290.616669 -194.927103) (xy 290.616132 -194.893946) (xy 290.616721 -194.860173)
			(xy 290.625665 -194.793221) (xy 290.643389 -194.728042) (xy 290.66958 -194.66578) (xy 290.703779 -194.607531)
			(xy 290.745384 -194.554319) (xy 290.793664 -194.507079) (xy 290.847769 -194.466643) (xy 290.87699 -194.4497)
			(xy 290.888166 -194.443604) (xy 290.901882 -194.422522) (xy 290.91128 -194.313556) (xy 290.901628 -194.290188)
			(xy 290.891722 -194.282314) (xy 290.870873 -194.264704) (xy 290.834108 -194.224374) (xy 290.803685 -194.179069)
			(xy 290.780266 -194.129777) (xy 290.764364 -194.077573) (xy 290.756324 -194.023596) (xy 290.755832 -193.99631)
			(xy 290.756348 -193.96871) (xy 290.764575 -193.914127) (xy 290.780845 -193.86138) (xy 290.804795 -193.811648)
			(xy 290.83589 -193.76604) (xy 290.873435 -193.725576) (xy 290.916592 -193.691159) (xy 290.964396 -193.66356)
			(xy 291.01578 -193.643393) (xy 291.069595 -193.63111) (xy 291.12464 -193.626985) (xy 291.179685 -193.63111)
			(xy 291.2335 -193.643393) (xy 291.284884 -193.66356) (xy 291.332688 -193.691159) (xy 291.375845 -193.725576)
			(xy 291.41339 -193.76604) (xy 291.444485 -193.811648) (xy 291.468435 -193.86138) (xy 291.484705 -193.914127)
			(xy 291.492932 -193.96871) (xy 291.493448 -193.99631) (xy 291.492991 -194.023599) (xy 291.484959 -194.077581)
			(xy 291.469055 -194.129789) (xy 291.445629 -194.179083) (xy 291.415192 -194.224384) (xy 291.378409 -194.264704)
			(xy 291.357558 -194.282314) (xy 291.347652 -194.290188) (xy 291.338 -194.313556) (xy 291.347398 -194.422522)
			(xy 291.361114 -194.443604) (xy 291.37229 -194.4497) (xy 291.401522 -194.466629) (xy 291.455641 -194.507057)
			(xy 291.503932 -194.554293) (xy 291.545546 -194.607505) (xy 291.579751 -194.665758) (xy 291.605943 -194.728025)
			(xy 291.617006 -194.768724) (xy 292.93312 -194.768724) (xy 292.933622 -194.736763) (xy 292.941633 -194.673345)
			(xy 292.95753 -194.611431) (xy 292.981062 -194.551998) (xy 293.011856 -194.495983) (xy 293.049429 -194.444268)
			(xy 293.093186 -194.397671) (xy 293.142439 -194.356926) (xy 293.19641 -194.322675) (xy 293.254249 -194.295458)
			(xy 293.315042 -194.275705) (xy 293.377832 -194.263727) (xy 293.441628 -194.259714) (xy 293.505424 -194.263727)
			(xy 293.568214 -194.275705) (xy 293.629007 -194.295458) (xy 293.686846 -194.322675) (xy 293.740817 -194.356926)
			(xy 293.79007 -194.397671) (xy 293.833827 -194.444268) (xy 293.8714 -194.495983) (xy 293.902194 -194.551998)
			(xy 293.925726 -194.611431) (xy 293.941623 -194.673345) (xy 293.949634 -194.736763) (xy 293.950136 -194.768724)
			(xy 293.949751 -194.798418) (xy 293.94284 -194.857401) (xy 293.929103 -194.915178) (xy 293.908728 -194.970961)
			(xy 293.881993 -195.023989) (xy 293.84926 -195.073541) (xy 293.810977 -195.118942) (xy 293.789608 -195.139564)
			(xy 293.781988 -195.146676) (xy 293.77386 -195.165472) (xy 293.772082 -195.258944) (xy 293.779956 -195.277994)
			(xy 293.787068 -195.28536) (xy 293.80954 -195.308665) (xy 293.848882 -195.36008) (xy 293.881191 -195.416182)
			(xy 293.905917 -195.476015) (xy 293.922638 -195.538559) (xy 293.931069 -195.602748) (xy 293.931594 -195.635118)
			(xy 293.931105 -195.666281) (xy 293.923293 -195.728115) (xy 293.907793 -195.788483) (xy 293.88485 -195.846431)
			(xy 293.87786 -195.859146) (xy 298.159932 -195.859146) (xy 298.160494 -195.825988) (xy 298.169105 -195.760234)
			(xy 298.186187 -195.696156) (xy 298.211451 -195.63484) (xy 298.244467 -195.577328) (xy 298.284676 -195.524593)
			(xy 298.331397 -195.477529) (xy 298.35729 -195.45681) (xy 298.366205 -195.449263) (xy 298.376532 -195.428344)
			(xy 298.377102 -195.416678) (xy 298.377102 -195.336414) (xy 298.376452 -195.324767) (xy 298.366149 -195.303868)
			(xy 298.35729 -195.296282) (xy 298.331421 -195.275533) (xy 298.284695 -195.228476) (xy 298.244479 -195.175747)
			(xy 298.211456 -195.11824) (xy 298.186184 -195.056929) (xy 298.169092 -194.992855) (xy 298.160469 -194.927103)
			(xy 298.159932 -194.893946) (xy 298.160521 -194.860173) (xy 298.169465 -194.793221) (xy 298.187189 -194.728042)
			(xy 298.21338 -194.66578) (xy 298.247579 -194.607531) (xy 298.289184 -194.554319) (xy 298.337464 -194.507079)
			(xy 298.391569 -194.466643) (xy 298.42079 -194.4497) (xy 298.431966 -194.443604) (xy 298.445682 -194.422522)
			(xy 298.45508 -194.313556) (xy 298.445428 -194.290188) (xy 298.435522 -194.282314) (xy 298.414673 -194.264704)
			(xy 298.377908 -194.224374) (xy 298.347485 -194.179069) (xy 298.324066 -194.129777) (xy 298.308164 -194.077573)
			(xy 298.300124 -194.023596) (xy 298.299632 -193.99631) (xy 298.300148 -193.96871) (xy 298.308375 -193.914127)
			(xy 298.324645 -193.86138) (xy 298.348595 -193.811648) (xy 298.37969 -193.76604) (xy 298.417235 -193.725576)
			(xy 298.460392 -193.691159) (xy 298.508196 -193.66356) (xy 298.55958 -193.643393) (xy 298.613395 -193.63111)
			(xy 298.66844 -193.626985) (xy 298.723485 -193.63111) (xy 298.7773 -193.643393) (xy 298.828684 -193.66356)
			(xy 298.876488 -193.691159) (xy 298.919645 -193.725576) (xy 298.95719 -193.76604) (xy 298.988285 -193.811648)
			(xy 299.012235 -193.86138) (xy 299.028505 -193.914127) (xy 299.036732 -193.96871) (xy 299.037248 -193.99631)
			(xy 299.036791 -194.023599) (xy 299.028759 -194.077581) (xy 299.012855 -194.129789) (xy 298.989429 -194.179083)
			(xy 298.958992 -194.224384) (xy 298.922209 -194.264704) (xy 298.901358 -194.282314) (xy 298.891452 -194.290188)
			(xy 298.8818 -194.313556) (xy 298.891198 -194.422522) (xy 298.904914 -194.443604) (xy 298.91609 -194.4497)
			(xy 298.945322 -194.466629) (xy 298.999441 -194.507057) (xy 299.047732 -194.554293) (xy 299.089346 -194.607505)
			(xy 299.123551 -194.665758) (xy 299.149743 -194.728025) (xy 299.167463 -194.793212) (xy 299.176399 -194.86017)
			(xy 299.176948 -194.893946) (xy 299.176387 -194.927104) (xy 299.167777 -194.992859) (xy 299.150695 -195.056937)
			(xy 299.125432 -195.118253) (xy 299.092415 -195.175765) (xy 299.052205 -195.2285) (xy 299.005483 -195.275563)
			(xy 298.97959 -195.296282) (xy 298.970676 -195.303829) (xy 298.960348 -195.324748) (xy 298.959778 -195.336414)
			(xy 298.959778 -195.416678) (xy 298.960439 -195.428323) (xy 298.970735 -195.449222) (xy 298.97959 -195.45681)
			(xy 299.005472 -195.477543) (xy 299.052194 -195.524605) (xy 299.092406 -195.577338) (xy 299.125427 -195.634848)
			(xy 299.150697 -195.69616) (xy 299.167788 -195.760235) (xy 299.17641 -195.825988) (xy 299.176948 -195.859146)
			(xy 299.176446 -195.891107) (xy 299.168435 -195.954525) (xy 299.152538 -196.016439) (xy 299.129006 -196.075872)
			(xy 299.098212 -196.131887) (xy 299.060639 -196.183602) (xy 299.016882 -196.230199) (xy 298.967629 -196.270944)
			(xy 298.913658 -196.305195) (xy 298.855819 -196.332412) (xy 298.795026 -196.352165) (xy 298.732236 -196.364143)
			(xy 298.66844 -196.368157) (xy 298.604644 -196.364143) (xy 298.541854 -196.352165) (xy 298.481061 -196.332412)
			(xy 298.423222 -196.305195) (xy 298.369251 -196.270944) (xy 298.319998 -196.230199) (xy 298.276241 -196.183602)
			(xy 298.238668 -196.131887) (xy 298.207874 -196.075872) (xy 298.184342 -196.016439) (xy 298.168445 -195.954525)
			(xy 298.160434 -195.891107) (xy 298.159932 -195.859146) (xy 293.87786 -195.859146) (xy 293.854824 -195.901048)
			(xy 293.81819 -195.95147) (xy 293.775525 -195.996904) (xy 293.727503 -196.036632) (xy 293.674879 -196.070027)
			(xy 293.618485 -196.096564) (xy 293.55921 -196.115824) (xy 293.497989 -196.127503) (xy 293.435786 -196.131416)
			(xy 293.373583 -196.127503) (xy 293.312362 -196.115824) (xy 293.253087 -196.096564) (xy 293.196693 -196.070027)
			(xy 293.144069 -196.036632) (xy 293.096047 -195.996904) (xy 293.053382 -195.95147) (xy 293.016748 -195.901048)
			(xy 292.986722 -195.846431) (xy 292.963779 -195.788483) (xy 292.948279 -195.728115) (xy 292.940467 -195.666281)
			(xy 292.939978 -195.635118) (xy 292.940538 -195.602189) (xy 292.949248 -195.53691) (xy 292.966516 -195.473357)
			(xy 292.99204 -195.412646) (xy 293.025371 -195.355846) (xy 293.065922 -195.303954) (xy 293.089076 -195.280534)
			(xy 293.096442 -195.273422) (xy 293.10457 -195.254372) (xy 293.104062 -195.1609) (xy 293.096188 -195.14185)
			(xy 293.088568 -195.134738) (xy 293.06442 -195.110711) (xy 293.022159 -195.057283) (xy 292.987406 -194.998694)
			(xy 292.96078 -194.935991) (xy 292.94276 -194.870297) (xy 292.933667 -194.802785) (xy 292.93312 -194.768724)
			(xy 291.617006 -194.768724) (xy 291.623663 -194.793212) (xy 291.632599 -194.86017) (xy 291.633148 -194.893946)
			(xy 291.632587 -194.927104) (xy 291.623977 -194.992859) (xy 291.606895 -195.056937) (xy 291.581632 -195.118253)
			(xy 291.548615 -195.175765) (xy 291.508405 -195.2285) (xy 291.461683 -195.275563) (xy 291.43579 -195.296282)
			(xy 291.426876 -195.303829) (xy 291.416548 -195.324748) (xy 291.415978 -195.336414) (xy 291.415978 -195.416678)
			(xy 291.416639 -195.428323) (xy 291.426935 -195.449222) (xy 291.43579 -195.45681) (xy 291.461672 -195.477543)
			(xy 291.508394 -195.524605) (xy 291.548606 -195.577338) (xy 291.581627 -195.634848) (xy 291.606897 -195.69616)
			(xy 291.623988 -195.760235) (xy 291.63261 -195.825988) (xy 291.633148 -195.859146) (xy 291.632646 -195.891107)
			(xy 291.624635 -195.954525) (xy 291.608738 -196.016439) (xy 291.585206 -196.075872) (xy 291.554412 -196.131887)
			(xy 291.516839 -196.183602) (xy 291.473082 -196.230199) (xy 291.423829 -196.270944) (xy 291.369858 -196.305195)
			(xy 291.312019 -196.332412) (xy 291.251226 -196.352165) (xy 291.188436 -196.364143) (xy 291.12464 -196.368157)
			(xy 291.060844 -196.364143) (xy 290.998054 -196.352165) (xy 290.937261 -196.332412) (xy 290.879422 -196.305195)
			(xy 290.825451 -196.270944) (xy 290.776198 -196.230199) (xy 290.732441 -196.183602) (xy 290.694868 -196.131887)
			(xy 290.664074 -196.075872) (xy 290.640542 -196.016439) (xy 290.624645 -195.954525) (xy 290.616634 -195.891107)
			(xy 290.616132 -195.859146) (xy 286.333806 -195.859146) (xy 286.31077 -195.901048) (xy 286.274136 -195.95147)
			(xy 286.231471 -195.996904) (xy 286.183449 -196.036632) (xy 286.130825 -196.070027) (xy 286.074431 -196.096564)
			(xy 286.015156 -196.115824) (xy 285.953935 -196.127503) (xy 285.891732 -196.131416) (xy 285.829529 -196.127503)
			(xy 285.768308 -196.115824) (xy 285.709033 -196.096564) (xy 285.652639 -196.070027) (xy 285.600015 -196.036632)
			(xy 285.551993 -195.996904) (xy 285.509328 -195.95147) (xy 285.472694 -195.901048) (xy 285.442668 -195.846431)
			(xy 285.419725 -195.788483) (xy 285.404225 -195.728115) (xy 285.396413 -195.666281) (xy 285.395924 -195.635118)
			(xy 284.037679 -195.635118) (xy 284.062841 -195.696163) (xy 284.079933 -195.760237) (xy 284.088556 -195.825989)
			(xy 284.089094 -195.859146) (xy 284.088592 -195.891107) (xy 284.080581 -195.954525) (xy 284.064684 -196.016439)
			(xy 284.041152 -196.075872) (xy 284.010358 -196.131887) (xy 283.972785 -196.183602) (xy 283.929028 -196.230199)
			(xy 283.879775 -196.270944) (xy 283.825804 -196.305195) (xy 283.767965 -196.332412) (xy 283.707172 -196.352165)
			(xy 283.644382 -196.364143) (xy 283.580586 -196.368157) (xy 283.51679 -196.364143) (xy 283.454 -196.352165)
			(xy 283.393207 -196.332412) (xy 283.335368 -196.305195) (xy 283.281397 -196.270944) (xy 283.232144 -196.230199)
			(xy 283.188387 -196.183602) (xy 283.150814 -196.131887) (xy 283.12002 -196.075872) (xy 283.096488 -196.016439)
			(xy 283.080591 -195.954525) (xy 283.07258 -195.891107) (xy 283.072078 -195.859146) (xy 278.790006 -195.859146)
			(xy 278.76697 -195.901048) (xy 278.730336 -195.95147) (xy 278.687671 -195.996904) (xy 278.639649 -196.036632)
			(xy 278.587025 -196.070027) (xy 278.530631 -196.096564) (xy 278.471356 -196.115824) (xy 278.410135 -196.127503)
			(xy 278.347932 -196.131416) (xy 278.285729 -196.127503) (xy 278.224508 -196.115824) (xy 278.165233 -196.096564)
			(xy 278.108839 -196.070027) (xy 278.056215 -196.036632) (xy 278.008193 -195.996904) (xy 277.965528 -195.95147)
			(xy 277.928894 -195.901048) (xy 277.898868 -195.846431) (xy 277.875925 -195.788483) (xy 277.860425 -195.728115)
			(xy 277.852613 -195.666281) (xy 277.852124 -195.635118) (xy 276.49363 -195.635118) (xy 276.518789 -195.69616)
			(xy 276.53588 -195.760236) (xy 276.544502 -195.825988) (xy 276.54504 -195.859146) (xy 276.544538 -195.891107)
			(xy 276.536527 -195.954525) (xy 276.52063 -196.016439) (xy 276.497098 -196.075872) (xy 276.466304 -196.131887)
			(xy 276.428731 -196.183602) (xy 276.384974 -196.230199) (xy 276.335721 -196.270944) (xy 276.28175 -196.305195)
			(xy 276.223911 -196.332412) (xy 276.163118 -196.352165) (xy 276.100328 -196.364143) (xy 276.036532 -196.368157)
			(xy 275.972736 -196.364143) (xy 275.909946 -196.352165) (xy 275.849153 -196.332412) (xy 275.791314 -196.305195)
			(xy 275.737343 -196.270944) (xy 275.68809 -196.230199) (xy 275.644333 -196.183602) (xy 275.60676 -196.131887)
			(xy 275.575966 -196.075872) (xy 275.552434 -196.016439) (xy 275.536537 -195.954525) (xy 275.528526 -195.891107)
			(xy 275.528024 -195.859146) (xy 271.245952 -195.859146) (xy 271.222916 -195.901048) (xy 271.186282 -195.95147)
			(xy 271.143617 -195.996904) (xy 271.095595 -196.036632) (xy 271.042971 -196.070027) (xy 270.986577 -196.096564)
			(xy 270.927302 -196.115824) (xy 270.866081 -196.127503) (xy 270.803878 -196.131416) (xy 270.741675 -196.127503)
			(xy 270.680454 -196.115824) (xy 270.621179 -196.096564) (xy 270.564785 -196.070027) (xy 270.512161 -196.036632)
			(xy 270.464139 -195.996904) (xy 270.421474 -195.95147) (xy 270.38484 -195.901048) (xy 270.354814 -195.846431)
			(xy 270.331871 -195.788483) (xy 270.316371 -195.728115) (xy 270.308559 -195.666281) (xy 270.30807 -195.635118)
			(xy 268.94957 -195.635118) (xy 268.974733 -195.696163) (xy 268.991825 -195.760237) (xy 269.000448 -195.825989)
			(xy 269.000986 -195.859146) (xy 269.000484 -195.891107) (xy 268.992473 -195.954525) (xy 268.976576 -196.016439)
			(xy 268.953044 -196.075872) (xy 268.92225 -196.131887) (xy 268.884677 -196.183602) (xy 268.84092 -196.230199)
			(xy 268.791667 -196.270944) (xy 268.737696 -196.305195) (xy 268.679857 -196.332412) (xy 268.619064 -196.352165)
			(xy 268.556274 -196.364143) (xy 268.492478 -196.368157) (xy 268.428682 -196.364143) (xy 268.365892 -196.352165)
			(xy 268.305099 -196.332412) (xy 268.24726 -196.305195) (xy 268.193289 -196.270944) (xy 268.144036 -196.230199)
			(xy 268.100279 -196.183602) (xy 268.062706 -196.131887) (xy 268.031912 -196.075872) (xy 268.00838 -196.016439)
			(xy 267.992483 -195.954525) (xy 267.984472 -195.891107) (xy 267.98397 -195.859146) (xy 263.739827 -195.859146)
			(xy 263.735135 -195.876874) (xy 263.710235 -195.937779) (xy 263.677686 -195.994964) (xy 263.638033 -196.047472)
			(xy 263.591938 -196.094427) (xy 263.566402 -196.115178) (xy 263.557684 -196.122753) (xy 263.547627 -196.143519)
			(xy 263.547098 -196.155056) (xy 263.547098 -196.27215) (xy 263.547705 -196.284574) (xy 263.559274 -196.306562)
			(xy 263.569196 -196.31406) (xy 263.649206 -196.368416) (xy 263.674098 -196.37121) (xy 263.686036 -196.366638)
			(xy 263.715789 -196.355459) (xy 263.777374 -196.339741) (xy 263.840438 -196.331822) (xy 263.872218 -196.331332)
			(xy 263.902949 -196.331779) (xy 263.963961 -196.339189) (xy 264.023636 -196.3539) (xy 264.081102 -196.375697)
			(xy 264.135522 -196.404263) (xy 264.186101 -196.439179) (xy 264.232103 -196.479938) (xy 264.272857 -196.525944)
			(xy 264.307768 -196.576528) (xy 264.336326 -196.630951) (xy 264.358117 -196.68842) (xy 264.372821 -196.748096)
			(xy 264.380225 -196.809109) (xy 264.380726 -196.83984) (xy 264.380044 -196.87676) (xy 264.369328 -196.949818)
			(xy 264.35939 -196.985382) (xy 264.356088 -196.996812) (xy 264.360152 -197.020434) (xy 264.416032 -197.095364)
			(xy 264.423643 -197.104592) (xy 264.44498 -197.115335) (xy 264.456926 -197.115938) (xy 265.2268 -197.115938)
			(xy 265.237971 -197.115413) (xy 265.258252 -197.106051) (xy 265.265916 -197.097904) (xy 265.283517 -197.077688)
			(xy 265.323565 -197.042062) (xy 265.36835 -197.012613) (xy 265.416929 -196.989961) (xy 265.468277 -196.974584)
			(xy 265.52131 -196.966808) (xy 265.54811 -196.966332) (xy 265.574907 -196.966834) (xy 265.627931 -196.97463)
			(xy 265.679271 -196.990014) (xy 265.727845 -197.012662) (xy 265.772632 -197.042098) (xy 265.812691 -197.077702)
			(xy 265.830304 -197.097904) (xy 265.837941 -197.106089) (xy 265.858238 -197.115466) (xy 265.86942 -197.115938)
			(xy 269.172944 -197.115938) (xy 269.181895 -197.115585) (xy 269.198706 -197.109428) (xy 269.212384 -197.097876)
			(xy 269.21714 -197.090284) (xy 269.232531 -197.064084) (xy 269.268742 -197.015287) (xy 269.310637 -196.971273)
			(xy 269.357591 -196.932701) (xy 269.383002 -196.91604) (xy 269.393162 -196.90969) (xy 269.405354 -196.889878)
			(xy 269.415006 -196.785738) (xy 269.406624 -196.763894) (xy 269.397734 -196.755766) (xy 269.379413 -196.738245)
			(xy 269.347265 -196.699047) (xy 269.32079 -196.655815) (xy 269.300488 -196.609363) (xy 269.286742 -196.560568)
			(xy 269.27981 -196.510349) (xy 269.27937 -196.485002) (xy 269.279886 -196.457402) (xy 269.288113 -196.402819)
			(xy 269.304383 -196.350072) (xy 269.328333 -196.30034) (xy 269.359428 -196.254732) (xy 269.396973 -196.214268)
			(xy 269.44013 -196.179851) (xy 269.487934 -196.152252) (xy 269.539318 -196.132085) (xy 269.593133 -196.119802)
			(xy 269.648178 -196.115677) (xy 269.703223 -196.119802) (xy 269.757038 -196.132085) (xy 269.808422 -196.152252)
			(xy 269.856226 -196.179851) (xy 269.899383 -196.214268) (xy 269.936928 -196.254732) (xy 269.968023 -196.30034)
			(xy 269.991973 -196.350072) (xy 270.008243 -196.402819) (xy 270.01647 -196.457402) (xy 270.016986 -196.485002)
			(xy 270.016566 -196.51035) (xy 270.009625 -196.56057) (xy 269.995874 -196.609366) (xy 269.975573 -196.65582)
			(xy 269.949103 -196.699057) (xy 269.916962 -196.738264) (xy 269.898622 -196.755766) (xy 269.889732 -196.763894)
			(xy 269.88135 -196.785738) (xy 269.891002 -196.889878) (xy 269.903194 -196.90969) (xy 269.913354 -196.91604)
			(xy 269.938774 -196.93269) (xy 269.985744 -196.971247) (xy 270.027641 -197.015263) (xy 270.063836 -197.064076)
			(xy 270.079216 -197.090284) (xy 270.083941 -197.097906) (xy 270.097617 -197.109489) (xy 270.11445 -197.115639)
			(xy 270.123412 -197.115938) (xy 270.517874 -197.115938) (xy 270.527937 -197.1155) (xy 270.546516 -197.107759)
			(xy 270.553942 -197.100952) (xy 270.600932 -197.053962) (xy 270.608329 -197.047114) (xy 270.626928 -197.039381)
			(xy 270.637 -197.038976) (xy 272.856198 -197.038976) (xy 272.863776 -197.038668) (xy 272.87825 -197.034161)
			(xy 272.884646 -197.030086) (xy 272.907729 -197.015026) (xy 272.957419 -196.991187) (xy 273.010102 -196.975006)
			(xy 273.064607 -196.966845) (xy 273.092164 -196.966332) (xy 273.119721 -196.966827) (xy 273.174226 -196.974995)
			(xy 273.226908 -196.991183) (xy 273.276595 -197.015032) (xy 273.299682 -197.030086) (xy 273.306092 -197.034135)
			(xy 273.320555 -197.03865) (xy 273.32813 -197.038976) (xy 276.76983 -197.038976) (xy 276.781115 -197.038366)
			(xy 276.801532 -197.028737) (xy 276.8092 -197.020434) (xy 276.826172 -197.000264) (xy 276.863719 -196.963259)
			(xy 276.904984 -196.930452) (xy 276.927056 -196.91604) (xy 276.937216 -196.90969) (xy 276.949408 -196.889878)
			(xy 276.95906 -196.785738) (xy 276.950678 -196.763894) (xy 276.941788 -196.755766) (xy 276.923464 -196.738246)
			(xy 276.891312 -196.69905) (xy 276.864833 -196.655818) (xy 276.844528 -196.609366) (xy 276.83078 -196.56057)
			(xy 276.823847 -196.51035) (xy 276.823424 -196.485002) (xy 276.82394 -196.457402) (xy 276.832167 -196.402819)
			(xy 276.848437 -196.350072) (xy 276.872387 -196.30034) (xy 276.903482 -196.254732) (xy 276.941027 -196.214268)
			(xy 276.984184 -196.179851) (xy 277.031988 -196.152252) (xy 277.083372 -196.132085) (xy 277.137187 -196.119802)
			(xy 277.192232 -196.115677) (xy 277.247277 -196.119802) (xy 277.301092 -196.132085) (xy 277.352476 -196.152252)
			(xy 277.40028 -196.179851) (xy 277.443437 -196.214268) (xy 277.480982 -196.254732) (xy 277.512077 -196.30034)
			(xy 277.536027 -196.350072) (xy 277.552297 -196.402819) (xy 277.560524 -196.457402) (xy 277.56104 -196.485002)
			(xy 277.56062 -196.51035) (xy 277.553678 -196.560568) (xy 277.539926 -196.609364) (xy 277.519623 -196.655816)
			(xy 277.49315 -196.699051) (xy 277.461008 -196.738255) (xy 277.442676 -196.755766) (xy 277.433786 -196.763894)
			(xy 277.425404 -196.785738) (xy 277.435056 -196.889878) (xy 277.447248 -196.90969) (xy 277.457408 -196.91604)
			(xy 277.479474 -196.93046) (xy 277.520735 -196.963271) (xy 277.558287 -197.000268) (xy 277.575264 -197.020434)
			(xy 277.582885 -197.028799) (xy 277.603331 -197.038425) (xy 277.614634 -197.038976) (xy 280.399998 -197.038976)
			(xy 280.407576 -197.038668) (xy 280.42205 -197.034161) (xy 280.428446 -197.030086) (xy 280.451529 -197.015026)
			(xy 280.501219 -196.991187) (xy 280.553902 -196.975006) (xy 280.608407 -196.966845) (xy 280.635964 -196.966332)
			(xy 280.663521 -196.966827) (xy 280.718026 -196.974995) (xy 280.770708 -196.991183) (xy 280.820395 -197.015032)
			(xy 280.843482 -197.030086) (xy 280.849892 -197.034135) (xy 280.864355 -197.03865) (xy 280.87193 -197.038976)
			(xy 284.31363 -197.038976) (xy 284.324915 -197.038366) (xy 284.345332 -197.028737) (xy 284.353 -197.020434)
			(xy 284.369972 -197.000264) (xy 284.407519 -196.963259) (xy 284.448784 -196.930452) (xy 284.470856 -196.91604)
			(xy 284.481016 -196.90969) (xy 284.493208 -196.889878) (xy 284.50286 -196.785738) (xy 284.494478 -196.763894)
			(xy 284.485588 -196.755766) (xy 284.467264 -196.738246) (xy 284.435112 -196.69905) (xy 284.408633 -196.655818)
			(xy 284.388328 -196.609366) (xy 284.37458 -196.56057) (xy 284.367647 -196.51035) (xy 284.367224 -196.485002)
			(xy 284.36774 -196.457402) (xy 284.375967 -196.402819) (xy 284.392237 -196.350072) (xy 284.416187 -196.30034)
			(xy 284.447282 -196.254732) (xy 284.484827 -196.214268) (xy 284.527984 -196.179851) (xy 284.575788 -196.152252)
			(xy 284.627172 -196.132085) (xy 284.680987 -196.119802) (xy 284.736032 -196.115677) (xy 284.791077 -196.119802)
			(xy 284.844892 -196.132085) (xy 284.896276 -196.152252) (xy 284.94408 -196.179851) (xy 284.987237 -196.214268)
			(xy 285.024782 -196.254732) (xy 285.055877 -196.30034) (xy 285.079827 -196.350072) (xy 285.096097 -196.402819)
			(xy 285.104324 -196.457402) (xy 285.10484 -196.485002) (xy 285.10442 -196.51035) (xy 285.097478 -196.560568)
			(xy 285.083726 -196.609364) (xy 285.063423 -196.655816) (xy 285.03695 -196.699051) (xy 285.004808 -196.738255)
			(xy 284.986476 -196.755766) (xy 284.977586 -196.763894) (xy 284.969204 -196.785738) (xy 284.978856 -196.889878)
			(xy 284.991048 -196.90969) (xy 285.001208 -196.91604) (xy 285.023274 -196.93046) (xy 285.064535 -196.963271)
			(xy 285.102087 -197.000268) (xy 285.119064 -197.020434) (xy 285.126685 -197.028799) (xy 285.147131 -197.038425)
			(xy 285.158434 -197.038976) (xy 287.944052 -197.038976) (xy 287.951628 -197.03866) (xy 287.966093 -197.03414)
			(xy 287.9725 -197.030086) (xy 287.995582 -197.015023) (xy 288.045271 -196.991178) (xy 288.097955 -196.974991)
			(xy 288.15246 -196.966822) (xy 288.180018 -196.966332) (xy 288.207576 -196.966824) (xy 288.262084 -196.974985)
			(xy 288.31477 -196.991168) (xy 288.364461 -197.015012) (xy 288.387536 -197.030086) (xy 288.393944 -197.034141)
			(xy 288.408408 -197.038669) (xy 288.415984 -197.038976) (xy 291.857684 -197.038976) (xy 291.868974 -197.038375)
			(xy 291.889405 -197.028758) (xy 291.897054 -197.020434) (xy 291.914027 -197.000265) (xy 291.951576 -196.963264)
			(xy 291.992844 -196.930461) (xy 292.01491 -196.91604) (xy 292.02507 -196.90969) (xy 292.037262 -196.889878)
			(xy 292.046914 -196.785738) (xy 292.038532 -196.763894) (xy 292.029642 -196.755766) (xy 292.01132 -196.738245)
			(xy 291.979172 -196.699048) (xy 291.952697 -196.655815) (xy 291.932394 -196.609364) (xy 291.918647 -196.560568)
			(xy 291.911715 -196.51035) (xy 291.911278 -196.485002) (xy 291.911794 -196.457402) (xy 291.920021 -196.402819)
			(xy 291.936291 -196.350072) (xy 291.960241 -196.30034) (xy 291.991336 -196.254732) (xy 292.028881 -196.214268)
			(xy 292.072038 -196.179851) (xy 292.119842 -196.152252) (xy 292.171226 -196.132085) (xy 292.225041 -196.119802)
			(xy 292.280086 -196.115677) (xy 292.335131 -196.119802) (xy 292.388946 -196.132085) (xy 292.44033 -196.152252)
			(xy 292.488134 -196.179851) (xy 292.531291 -196.214268) (xy 292.568836 -196.254732) (xy 292.599931 -196.30034)
			(xy 292.623881 -196.350072) (xy 292.640151 -196.402819) (xy 292.648378 -196.457402) (xy 292.648894 -196.485002)
			(xy 292.648474 -196.51035) (xy 292.641531 -196.560567) (xy 292.627778 -196.609361) (xy 292.607473 -196.655812)
			(xy 292.580998 -196.699045) (xy 292.548853 -196.738246) (xy 292.53053 -196.755766) (xy 292.52164 -196.763894)
			(xy 292.513258 -196.785738) (xy 292.52291 -196.889878) (xy 292.535102 -196.90969) (xy 292.545262 -196.91604)
			(xy 292.56733 -196.930459) (xy 292.608593 -196.963267) (xy 292.646148 -197.000262) (xy 292.663118 -197.020434)
			(xy 292.670736 -197.028807) (xy 292.691182 -197.038451) (xy 292.702488 -197.038976) (xy 295.488106 -197.038976)
			(xy 295.495684 -197.038667) (xy 295.510156 -197.034158) (xy 295.516554 -197.030086) (xy 295.539637 -197.015027)
			(xy 295.589327 -196.991188) (xy 295.642011 -196.975009) (xy 295.696515 -196.966849) (xy 295.724072 -196.966332)
			(xy 295.751629 -196.966828) (xy 295.806133 -196.974996) (xy 295.858815 -196.991186) (xy 295.908501 -197.015035)
			(xy 295.93159 -197.030086) (xy 295.938 -197.034134) (xy 295.952464 -197.038647) (xy 295.960038 -197.038976)
			(xy 299.401738 -197.038976) (xy 299.413022 -197.038364) (xy 299.433436 -197.028734) (xy 299.441108 -197.020434)
			(xy 299.45808 -197.000264) (xy 299.495627 -196.96326) (xy 299.536893 -196.930453) (xy 299.558964 -196.91604)
			(xy 299.569124 -196.90969) (xy 299.581316 -196.889878) (xy 299.590968 -196.785738) (xy 299.582586 -196.763894)
			(xy 299.573696 -196.755766) (xy 299.555372 -196.738246) (xy 299.523219 -196.699051) (xy 299.49674 -196.655819)
			(xy 299.476434 -196.609367) (xy 299.462685 -196.56057) (xy 299.455752 -196.51035) (xy 299.455332 -196.485002)
			(xy 299.455848 -196.457402) (xy 299.464075 -196.402819) (xy 299.480345 -196.350072) (xy 299.504295 -196.30034)
			(xy 299.53539 -196.254732) (xy 299.572935 -196.214268) (xy 299.616092 -196.179851) (xy 299.663896 -196.152252)
			(xy 299.71528 -196.132085) (xy 299.769095 -196.119802) (xy 299.82414 -196.115677) (xy 299.879185 -196.119802)
			(xy 299.933 -196.132085) (xy 299.984384 -196.152252) (xy 300.032188 -196.179851) (xy 300.075345 -196.214268)
			(xy 300.11289 -196.254732) (xy 300.143985 -196.30034) (xy 300.167935 -196.350072) (xy 300.184205 -196.402819)
			(xy 300.192432 -196.457402) (xy 300.192948 -196.485002) (xy 306.998893 -196.485002) (xy 307.002828 -196.431231)
			(xy 307.014551 -196.378607) (xy 307.033811 -196.32825) (xy 307.060197 -196.281233) (xy 307.093149 -196.23856)
			(xy 307.131962 -196.201139) (xy 307.17581 -196.169769) (xy 307.223758 -196.145117) (xy 307.274785 -196.127709)
			(xy 307.327803 -196.117916) (xy 307.381682 -196.115947) (xy 307.435273 -196.121844) (xy 307.487434 -196.13548)
			(xy 307.537054 -196.156567) (xy 307.539989 -196.158358) (xy 308.073296 -196.158358) (xy 308.07737 -196.09489)
			(xy 308.089528 -196.032465) (xy 308.109568 -195.972106) (xy 308.137162 -195.914806) (xy 308.171858 -195.861505)
			(xy 308.213084 -195.813078) (xy 308.260164 -195.770321) (xy 308.312326 -195.733935) (xy 308.368713 -195.704518)
			(xy 308.428398 -195.682553) (xy 308.490402 -195.668401) (xy 308.553706 -195.662295) (xy 308.617272 -195.664333)
			(xy 308.680055 -195.674483) (xy 308.741025 -195.692579) (xy 308.79918 -195.718322) (xy 308.853566 -195.751291)
			(xy 308.903289 -195.790944) (xy 308.947534 -195.83663) (xy 308.985573 -195.887599) (xy 309.016782 -195.943013)
			(xy 309.040648 -196.001964) (xy 309.05678 -196.063482) (xy 309.064913 -196.126559) (xy 309.065422 -196.158358)
			(xy 309.064913 -196.190157) (xy 309.05678 -196.253234) (xy 309.040648 -196.314752) (xy 309.016782 -196.373703)
			(xy 308.985573 -196.429117) (xy 308.947534 -196.480086) (xy 308.903289 -196.525772) (xy 308.853566 -196.565425)
			(xy 308.79918 -196.598394) (xy 308.741025 -196.624137) (xy 308.680055 -196.642233) (xy 308.617272 -196.652383)
			(xy 308.553706 -196.654421) (xy 308.490402 -196.648315) (xy 308.428398 -196.634163) (xy 308.368713 -196.612198)
			(xy 308.312326 -196.582781) (xy 308.260164 -196.546395) (xy 308.213084 -196.503638) (xy 308.171858 -196.455211)
			(xy 308.137162 -196.40191) (xy 308.109568 -196.34461) (xy 308.089528 -196.284251) (xy 308.07737 -196.221826)
			(xy 308.073296 -196.158358) (xy 307.539989 -196.158358) (xy 307.583075 -196.184653) (xy 307.624517 -196.219141)
			(xy 307.660495 -196.259295) (xy 307.690243 -196.304259) (xy 307.713128 -196.353076) (xy 307.72866 -196.404705)
			(xy 307.73651 -196.458045) (xy 307.737002 -196.485002) (xy 307.73651 -196.511959) (xy 307.72866 -196.565299)
			(xy 307.713128 -196.616928) (xy 307.690243 -196.665745) (xy 307.660495 -196.710709) (xy 307.624517 -196.750863)
			(xy 307.583075 -196.785351) (xy 307.537054 -196.813437) (xy 307.487434 -196.834524) (xy 307.435273 -196.84816)
			(xy 307.381682 -196.854057) (xy 307.327803 -196.852088) (xy 307.274785 -196.842295) (xy 307.223758 -196.824887)
			(xy 307.17581 -196.800235) (xy 307.131962 -196.768865) (xy 307.093149 -196.731444) (xy 307.060197 -196.688771)
			(xy 307.033811 -196.641754) (xy 307.014551 -196.591397) (xy 307.002828 -196.538773) (xy 306.998893 -196.485002)
			(xy 300.192948 -196.485002) (xy 300.192528 -196.51035) (xy 300.185586 -196.560569) (xy 300.171835 -196.609364)
			(xy 300.151531 -196.655817) (xy 300.125059 -196.699053) (xy 300.092917 -196.738257) (xy 300.074584 -196.755766)
			(xy 300.065694 -196.763894) (xy 300.057312 -196.785738) (xy 300.066964 -196.889878) (xy 300.079156 -196.90969)
			(xy 300.089316 -196.91604) (xy 300.111382 -196.93046) (xy 300.152642 -196.963272) (xy 300.190194 -197.000269)
			(xy 300.207172 -197.020434) (xy 300.214794 -197.028798) (xy 300.235239 -197.038421) (xy 300.246542 -197.038976)
			(xy 303.03216 -197.038976) (xy 303.039735 -197.038659) (xy 303.054199 -197.034137) (xy 303.060608 -197.030086)
			(xy 303.08369 -197.015024) (xy 303.133379 -196.991179) (xy 303.186063 -196.974993) (xy 303.240569 -196.966826)
			(xy 303.268126 -196.966332) (xy 303.294469 -196.966782) (xy 303.346619 -196.974284) (xy 303.397171 -196.989131)
			(xy 303.445095 -197.011022) (xy 303.489415 -197.03951) (xy 303.52923 -197.074016) (xy 303.563729 -197.113838)
			(xy 303.59221 -197.158163) (xy 303.614092 -197.206091) (xy 303.62893 -197.256645) (xy 303.636423 -197.308797)
			(xy 303.636934 -197.33514) (xy 303.636336 -197.364693) (xy 303.626872 -197.423037) (xy 303.60821 -197.47912)
			(xy 303.595024 -197.505574) (xy 303.587404 -197.52056) (xy 303.592484 -197.553326) (xy 304.224182 -198.185024)
			(xy 306.998893 -198.185024) (xy 307.002828 -198.131253) (xy 307.014551 -198.078629) (xy 307.033811 -198.028272)
			(xy 307.060197 -197.981255) (xy 307.093149 -197.938582) (xy 307.131962 -197.901161) (xy 307.17581 -197.869791)
			(xy 307.223758 -197.845139) (xy 307.274785 -197.827731) (xy 307.327803 -197.817938) (xy 307.381682 -197.815969)
			(xy 307.435273 -197.821866) (xy 307.487434 -197.835502) (xy 307.537054 -197.856589) (xy 307.583075 -197.884675)
			(xy 307.624517 -197.919163) (xy 307.660495 -197.959317) (xy 307.690243 -198.004281) (xy 307.713128 -198.053098)
			(xy 307.72866 -198.104727) (xy 307.73651 -198.158067) (xy 307.737002 -198.185024) (xy 307.73651 -198.211981)
			(xy 307.72866 -198.265321) (xy 307.713128 -198.31695) (xy 307.690243 -198.365767) (xy 307.660495 -198.410731)
			(xy 307.624517 -198.450885) (xy 307.583075 -198.485373) (xy 307.537054 -198.513459) (xy 307.487434 -198.534546)
			(xy 307.435273 -198.548182) (xy 307.381682 -198.554079) (xy 307.327803 -198.55211) (xy 307.274785 -198.542317)
			(xy 307.223758 -198.524909) (xy 307.17581 -198.500257) (xy 307.131962 -198.468887) (xy 307.093149 -198.431466)
			(xy 307.060197 -198.388793) (xy 307.033811 -198.341776) (xy 307.014551 -198.291419) (xy 307.002828 -198.238795)
			(xy 306.998893 -198.185024) (xy 304.224182 -198.185024) (xy 305.642772 -199.603614) (xy 305.650074 -199.61023)
			(xy 305.668239 -199.617815) (xy 305.678078 -199.618346) (xy 305.708558 -199.618854) (xy 305.717792 -199.618549)
			(xy 305.735111 -199.612162) (xy 305.74234 -199.606408) (xy 305.762539 -199.589477) (xy 305.806865 -199.560961)
			(xy 305.854802 -199.539052) (xy 305.905371 -199.524198) (xy 305.957541 -199.516701) (xy 305.983894 -199.516238)
			(xy 306.010239 -199.516686) (xy 306.062392 -199.524184) (xy 306.112947 -199.539029) (xy 306.160874 -199.560918)
			(xy 306.205199 -199.589405) (xy 306.245017 -199.623911) (xy 306.279519 -199.663734) (xy 306.308001 -199.708061)
			(xy 306.329885 -199.755991) (xy 306.344725 -199.806547) (xy 306.352217 -199.858701) (xy 306.352702 -199.885046)
			(xy 306.352162 -199.913252) (xy 306.343564 -199.969006) (xy 306.326576 -200.0228) (xy 306.301593 -200.073379)
			(xy 306.269198 -200.119564) (xy 306.250086 -200.140316) (xy 306.235608 -200.155556) (xy 306.235862 -200.196704)
			(xy 307.970131 -201.930973) (xy 317.290952 -201.930973) (xy 317.290952 -201.867051) (xy 317.298963 -201.803633)
			(xy 317.31486 -201.741719) (xy 317.338392 -201.682286) (xy 317.369186 -201.626271) (xy 317.406759 -201.574556)
			(xy 317.450516 -201.527959) (xy 317.499769 -201.487214) (xy 317.55374 -201.452963) (xy 317.611579 -201.425746)
			(xy 317.672372 -201.405993) (xy 317.735162 -201.394015) (xy 317.798958 -201.390002) (xy 317.862754 -201.394015)
			(xy 317.925544 -201.405993) (xy 317.986337 -201.425746) (xy 318.044176 -201.452963) (xy 318.098147 -201.487214)
			(xy 318.1474 -201.527959) (xy 318.191157 -201.574556) (xy 318.22873 -201.626271) (xy 318.259524 -201.682286)
			(xy 318.283056 -201.741719) (xy 318.298953 -201.803633) (xy 318.306964 -201.867051) (xy 318.307466 -201.899012)
			(xy 318.306964 -201.930973) (xy 318.298953 -201.994391) (xy 318.283056 -202.056305) (xy 318.259524 -202.115738)
			(xy 318.22873 -202.171753) (xy 318.191157 -202.223468) (xy 318.1474 -202.270065) (xy 318.098147 -202.31081)
			(xy 318.044176 -202.345061) (xy 317.986337 -202.372278) (xy 317.925544 -202.392031) (xy 317.862754 -202.404009)
			(xy 317.798958 -202.408023) (xy 317.735162 -202.404009) (xy 317.672372 -202.392031) (xy 317.611579 -202.372278)
			(xy 317.55374 -202.345061) (xy 317.499769 -202.31081) (xy 317.450516 -202.270065) (xy 317.406759 -202.223468)
			(xy 317.369186 -202.171753) (xy 317.338392 -202.115738) (xy 317.31486 -202.056305) (xy 317.298963 -201.994391)
			(xy 317.290952 -201.930973) (xy 307.970131 -201.930973) (xy 308.962255 -202.923097) (xy 319.353432 -202.923097)
			(xy 319.353432 -202.859175) (xy 319.361443 -202.795757) (xy 319.37734 -202.733843) (xy 319.400872 -202.67441)
			(xy 319.431666 -202.618395) (xy 319.469239 -202.56668) (xy 319.512996 -202.520083) (xy 319.562249 -202.479338)
			(xy 319.61622 -202.445087) (xy 319.674059 -202.41787) (xy 319.734852 -202.398117) (xy 319.797642 -202.386139)
			(xy 319.861438 -202.382126) (xy 319.925234 -202.386139) (xy 319.988024 -202.398117) (xy 320.048817 -202.41787)
			(xy 320.106656 -202.445087) (xy 320.160627 -202.479338) (xy 320.20988 -202.520083) (xy 320.253637 -202.56668)
			(xy 320.29121 -202.618395) (xy 320.322004 -202.67441) (xy 320.345536 -202.733843) (xy 320.361433 -202.795757)
			(xy 320.369444 -202.859175) (xy 320.369946 -202.891136) (xy 320.369444 -202.923097) (xy 320.361433 -202.986515)
			(xy 320.345536 -203.048429) (xy 320.322004 -203.107862) (xy 320.29121 -203.163877) (xy 320.253637 -203.215592)
			(xy 320.20988 -203.262189) (xy 320.160627 -203.302934) (xy 320.106656 -203.337185) (xy 320.048817 -203.364402)
			(xy 319.988024 -203.384155) (xy 319.925234 -203.396133) (xy 319.861438 -203.400147) (xy 319.797642 -203.396133)
			(xy 319.734852 -203.384155) (xy 319.674059 -203.364402) (xy 319.61622 -203.337185) (xy 319.562249 -203.302934)
			(xy 319.512996 -203.262189) (xy 319.469239 -203.215592) (xy 319.431666 -203.163877) (xy 319.400872 -203.107862)
			(xy 319.37734 -203.048429) (xy 319.361443 -202.986515) (xy 319.353432 -202.923097) (xy 308.962255 -202.923097)
			(xy 310.554624 -204.515466) (xy 310.562022 -204.522312) (xy 310.580621 -204.530044) (xy 310.590692 -204.530452)
		)
		(stroke
			(width 0)
			(type solid)
		)
		(fill yes)
		(layer "In15.Cu")
		(net "P3V3_AUX")
	)
	(gr_poly
		(pts
			(xy 418.036756 -156.826458) (xy 418.045113 -156.826075) (xy 418.060921 -156.820631) (xy 418.067744 -156.81579)
			(xy 418.094527 -156.795832) (xy 418.152326 -156.762357) (xy 418.21401 -156.736734) (xy 418.278516 -156.719403)
			(xy 418.344735 -156.710663) (xy 418.411529 -156.710663) (xy 418.477748 -156.719403) (xy 418.542254 -156.736734)
			(xy 418.603938 -156.762357) (xy 418.661737 -156.795832) (xy 418.68852 -156.81579) (xy 418.695307 -156.820699)
			(xy 418.711138 -156.826144) (xy 418.719508 -156.826458) (xy 429.95977 -156.826458) (xy 429.969834 -156.826021)
			(xy 429.988416 -156.818284) (xy 429.995838 -156.811472) (xy 438.756044 -148.051266) (xy 438.763442 -148.044419)
			(xy 438.782041 -148.03669) (xy 438.792112 -148.03628) (xy 452.553832 -148.03628) (xy 452.563708 -148.035817)
			(xy 452.582001 -148.028368) (xy 452.589392 -148.021802) (xy 452.589646 -148.021548) (xy 454.527158 -146.084036)
			(xy 454.533963 -146.076689) (xy 454.541679 -146.058226) (xy 454.542144 -146.048222) (xy 454.542144 -141.404848)
			(xy 454.541614 -141.394858) (xy 454.533906 -141.376419) (xy 454.527158 -141.369034) (xy 444.49238 -131.334256)
			(xy 444.484983 -131.327407) (xy 444.466384 -131.319671) (xy 444.456312 -131.31927) (xy 383.973832 -131.31927)
			(xy 383.968877 -131.319155) (xy 383.959152 -131.317244) (xy 383.954528 -131.31546) (xy 383.95148 -131.31419)
			(xy 383.946852 -131.31242) (xy 383.93713 -131.310506) (xy 383.932176 -131.31038) (xy 373.820182 -131.31038)
			(xy 373.810114 -131.309953) (xy 373.791516 -131.302232) (xy 373.784114 -131.295394) (xy 369.60556 -127.11684)
			(xy 369.598189 -127.1101) (xy 369.579727 -127.102516) (xy 369.569746 -127.102108) (xy 298.90085 -127.102108)
			(xy 298.890887 -127.102591) (xy 298.872459 -127.110176) (xy 298.865036 -127.11684) (xy 296.142707 -129.839169)
			(xy 348.452942 -129.839169) (xy 348.452942 -129.775247) (xy 348.460953 -129.711829) (xy 348.47685 -129.649915)
			(xy 348.500382 -129.590482) (xy 348.531176 -129.534467) (xy 348.568749 -129.482752) (xy 348.612506 -129.436155)
			(xy 348.661759 -129.39541) (xy 348.71573 -129.361159) (xy 348.773569 -129.333942) (xy 348.834362 -129.314189)
			(xy 348.897152 -129.302211) (xy 348.960948 -129.298198) (xy 349.024744 -129.302211) (xy 349.087534 -129.314189)
			(xy 349.148327 -129.333942) (xy 349.206166 -129.361159) (xy 349.260137 -129.39541) (xy 349.30939 -129.436155)
			(xy 349.353147 -129.482752) (xy 349.39072 -129.534467) (xy 349.421514 -129.590482) (xy 349.445046 -129.649915)
			(xy 349.460943 -129.711829) (xy 349.468954 -129.775247) (xy 349.469456 -129.807208) (xy 349.469028 -129.834454)
			(xy 349.595863 -129.834454) (xy 349.595863 -129.779946) (xy 349.603622 -129.725992) (xy 349.61898 -129.673691)
			(xy 349.641625 -129.624109) (xy 349.671097 -129.578254) (xy 349.706795 -129.537061) (xy 349.747993 -129.501368)
			(xy 349.793851 -129.471902) (xy 349.843436 -129.449263) (xy 349.895738 -129.433911) (xy 349.949693 -129.42616)
			(xy 349.976948 -129.4257) (xy 350.00579 -129.426224) (xy 350.062816 -129.434908) (xy 350.117886 -129.452072)
			(xy 350.169748 -129.477325) (xy 350.217222 -129.510092) (xy 350.259226 -129.549627) (xy 350.27743 -129.572004)
			(xy 350.28671 -129.582886) (xy 350.30991 -129.599577) (xy 350.336825 -129.60919) (xy 350.36535 -129.610974)
			(xy 350.393252 -129.604787) (xy 350.41835 -129.591115) (xy 350.43868 -129.571027) (xy 350.446086 -129.558796)
			(xy 350.463041 -129.529608) (xy 350.503456 -129.475542) (xy 350.550668 -129.427299) (xy 350.603848 -129.385726)
			(xy 350.662061 -129.351554) (xy 350.724283 -129.325385) (xy 350.78942 -129.307678) (xy 350.856327 -129.298744)
			(xy 350.890078 -129.298192) (xy 350.922041 -129.298672) (xy 350.985464 -129.306681) (xy 351.047383 -129.322577)
			(xy 351.106821 -129.346108) (xy 351.162841 -129.376903) (xy 351.214559 -129.414477) (xy 351.261161 -129.458236)
			(xy 351.30191 -129.507492) (xy 351.336164 -129.561466) (xy 351.363384 -129.619308) (xy 351.383138 -129.680106)
			(xy 351.395117 -129.7429) (xy 351.399132 -129.8067) (xy 351.395117 -129.8705) (xy 351.383138 -129.933294)
			(xy 351.363384 -129.994092) (xy 351.336164 -130.051934) (xy 351.30191 -130.105908) (xy 351.261161 -130.155164)
			(xy 351.214559 -130.198923) (xy 351.162841 -130.236497) (xy 351.106821 -130.267292) (xy 351.047383 -130.290823)
			(xy 350.985464 -130.306719) (xy 350.922041 -130.314728) (xy 350.890078 -130.315208) (xy 350.85636 -130.314678)
			(xy 350.789514 -130.305773) (xy 350.724432 -130.28811) (xy 350.662257 -130.261998) (xy 350.604079 -130.227895)
			(xy 350.55092 -130.186401) (xy 350.503713 -130.138243) (xy 350.463287 -130.084267) (xy 350.44634 -130.055112)
			(xy 350.438925 -130.042871) (xy 350.41858 -130.022761) (xy 350.393454 -130.009086) (xy 350.365521 -130.00292)
			(xy 350.336973 -130.004746) (xy 350.310053 -130.014422) (xy 350.286874 -130.031188) (xy 350.277684 -130.042158)
			(xy 350.25947 -130.064566) (xy 350.217445 -130.104168) (xy 350.169937 -130.136991) (xy 350.118029 -130.162288)
			(xy 350.062905 -130.179483) (xy 350.00582 -130.188183) (xy 349.976948 -130.188716) (xy 349.949693 -130.18824)
			(xy 349.895738 -130.180489) (xy 349.843436 -130.165137) (xy 349.793851 -130.142498) (xy 349.747993 -130.113032)
			(xy 349.706795 -130.077339) (xy 349.671097 -130.036146) (xy 349.641625 -129.990291) (xy 349.61898 -129.940709)
			(xy 349.603622 -129.888408) (xy 349.595863 -129.834454) (xy 349.469028 -129.834454) (xy 349.468954 -129.839169)
			(xy 349.460943 -129.902587) (xy 349.445046 -129.964501) (xy 349.421514 -130.023934) (xy 349.39072 -130.079949)
			(xy 349.353147 -130.131664) (xy 349.30939 -130.178261) (xy 349.260137 -130.219006) (xy 349.206166 -130.253257)
			(xy 349.148327 -130.280474) (xy 349.087534 -130.300227) (xy 349.024744 -130.312205) (xy 348.960948 -130.316219)
			(xy 348.897152 -130.312205) (xy 348.834362 -130.300227) (xy 348.773569 -130.280474) (xy 348.71573 -130.253257)
			(xy 348.661759 -130.219006) (xy 348.612506 -130.178261) (xy 348.568749 -130.131664) (xy 348.531176 -130.079949)
			(xy 348.500382 -130.023934) (xy 348.47685 -129.964501) (xy 348.460953 -129.902587) (xy 348.452942 -129.839169)
			(xy 296.142707 -129.839169) (xy 294.392604 -131.589272) (xy 294.38346 -131.597908) (xy 294.382952 -131.598416)
			(xy 293.9669 -132.014468) (xy 293.959503 -132.021318) (xy 293.940905 -132.029057) (xy 293.930832 -132.029454)
			(xy 288.212022 -132.029454) (xy 288.201959 -132.029015) (xy 288.18338 -132.021276) (xy 288.175954 -132.014468)
			(xy 287.410652 -131.249166) (xy 287.403254 -131.24232) (xy 287.384655 -131.234592) (xy 287.374584 -131.23418)
			(xy 274.800822 -131.23418) (xy 274.790758 -131.234617) (xy 274.772172 -131.242349) (xy 274.764754 -131.249166)
			(xy 274.357592 -131.656328) (xy 274.350226 -131.66344) (xy 274.342606 -131.682236) (xy 274.342606 -132.88391)
			(xy 274.343065 -132.893788) (xy 274.350507 -132.912088) (xy 274.357084 -132.91947) (xy 274.357338 -132.919724)
			(xy 275.858478 -134.420864) (xy 275.865317 -134.428265) (xy 275.873031 -134.446863) (xy 275.873464 -134.456932)
			(xy 275.873464 -134.549642) (xy 275.873896 -134.559707) (xy 275.881629 -134.578295) (xy 275.88845 -134.58571)
			(xy 280.446734 -139.143994) (xy 280.454134 -139.150836) (xy 280.472732 -139.158559) (xy 280.482802 -139.15898)
			(xy 321.695318 -139.15898) (xy 321.705386 -139.158553) (xy 321.723984 -139.150832) (xy 321.731386 -139.143994)
			(xy 330.371196 -130.504184) (xy 330.378608 -130.4975) (xy 330.397041 -130.489903) (xy 330.416979 -130.489903)
			(xy 330.435412 -130.4975) (xy 330.442824 -130.504184) (xy 330.535534 -130.596894) (xy 330.542934 -130.603736)
			(xy 330.561532 -130.611459) (xy 330.571602 -130.61188) (xy 339.998558 -130.61188) (xy 340.008624 -130.612313)
			(xy 340.027215 -130.62004) (xy 340.034626 -130.626866) (xy 341.948473 -132.540713) (xy 406.125166 -132.540713)
			(xy 406.125166 -132.476791) (xy 406.133177 -132.413373) (xy 406.149074 -132.351459) (xy 406.172606 -132.292026)
			(xy 406.2034 -132.236011) (xy 406.240973 -132.184296) (xy 406.28473 -132.137699) (xy 406.333983 -132.096954)
			(xy 406.387954 -132.062703) (xy 406.445793 -132.035486) (xy 406.506586 -132.015733) (xy 406.569376 -132.003755)
			(xy 406.633172 -131.999742) (xy 406.696968 -132.003755) (xy 406.759758 -132.015733) (xy 406.820551 -132.035486)
			(xy 406.87839 -132.062703) (xy 406.932361 -132.096954) (xy 406.981614 -132.137699) (xy 407.025371 -132.184296)
			(xy 407.062944 -132.236011) (xy 407.093738 -132.292026) (xy 407.11727 -132.351459) (xy 407.133167 -132.413373)
			(xy 407.141178 -132.476791) (xy 407.14168 -132.508752) (xy 407.141178 -132.540713) (xy 407.133167 -132.604131)
			(xy 407.11727 -132.666045) (xy 407.093738 -132.725478) (xy 407.062944 -132.781493) (xy 407.025371 -132.833208)
			(xy 406.981614 -132.879805) (xy 406.932361 -132.92055) (xy 406.87839 -132.954801) (xy 406.820551 -132.982018)
			(xy 406.759758 -133.001771) (xy 406.696968 -133.013749) (xy 406.633172 -133.017763) (xy 406.569376 -133.013749)
			(xy 406.506586 -133.001771) (xy 406.445793 -132.982018) (xy 406.387954 -132.954801) (xy 406.333983 -132.92055)
			(xy 406.28473 -132.879805) (xy 406.240973 -132.833208) (xy 406.2034 -132.781493) (xy 406.172606 -132.725478)
			(xy 406.149074 -132.666045) (xy 406.133177 -132.604131) (xy 406.125166 -132.540713) (xy 341.948473 -132.540713)
			(xy 344.262921 -134.855161) (xy 364.083594 -134.855161) (xy 364.083594 -134.791239) (xy 364.091605 -134.727821)
			(xy 364.107502 -134.665907) (xy 364.131034 -134.606474) (xy 364.161828 -134.550459) (xy 364.199401 -134.498744)
			(xy 364.243158 -134.452147) (xy 364.292411 -134.411402) (xy 364.346382 -134.377151) (xy 364.404221 -134.349934)
			(xy 364.465014 -134.330181) (xy 364.527804 -134.318203) (xy 364.5916 -134.31419) (xy 364.655396 -134.318203)
			(xy 364.718186 -134.330181) (xy 364.778979 -134.349934) (xy 364.836818 -134.377151) (xy 364.890789 -134.411402)
			(xy 364.940042 -134.452147) (xy 364.983799 -134.498744) (xy 365.021372 -134.550459) (xy 365.052166 -134.606474)
			(xy 365.075698 -134.665907) (xy 365.091595 -134.727821) (xy 365.099606 -134.791239) (xy 365.100108 -134.8232)
			(xy 365.099606 -134.855161) (xy 365.091595 -134.918579) (xy 365.075698 -134.980493) (xy 365.052166 -135.039926)
			(xy 365.021372 -135.095941) (xy 364.983799 -135.147656) (xy 364.940042 -135.194253) (xy 364.890789 -135.234998)
			(xy 364.836818 -135.269249) (xy 364.778979 -135.296466) (xy 364.718186 -135.316219) (xy 364.655396 -135.328197)
			(xy 364.5916 -135.332211) (xy 364.527804 -135.328197) (xy 364.465014 -135.316219) (xy 364.404221 -135.296466)
			(xy 364.346382 -135.269249) (xy 364.292411 -135.234998) (xy 364.243158 -135.194253) (xy 364.199401 -135.147656)
			(xy 364.161828 -135.095941) (xy 364.131034 -135.039926) (xy 364.107502 -134.980493) (xy 364.091605 -134.918579)
			(xy 364.083594 -134.855161) (xy 344.262921 -134.855161) (xy 345.065053 -135.657293) (xy 360.003084 -135.657293)
			(xy 360.003084 -135.593371) (xy 360.011095 -135.529953) (xy 360.026992 -135.468039) (xy 360.050524 -135.408606)
			(xy 360.081318 -135.352591) (xy 360.118891 -135.300876) (xy 360.162648 -135.254279) (xy 360.211901 -135.213534)
			(xy 360.265872 -135.179283) (xy 360.323711 -135.152066) (xy 360.384504 -135.132313) (xy 360.447294 -135.120335)
			(xy 360.51109 -135.116322) (xy 360.574886 -135.120335) (xy 360.637676 -135.132313) (xy 360.698469 -135.152066)
			(xy 360.756308 -135.179283) (xy 360.810279 -135.213534) (xy 360.859532 -135.254279) (xy 360.903289 -135.300876)
			(xy 360.940862 -135.352591) (xy 360.971656 -135.408606) (xy 360.995188 -135.468039) (xy 361.00739 -135.515561)
			(xy 363.067594 -135.515561) (xy 363.067594 -135.451639) (xy 363.075605 -135.388221) (xy 363.091502 -135.326307)
			(xy 363.115034 -135.266874) (xy 363.145828 -135.210859) (xy 363.183401 -135.159144) (xy 363.227158 -135.112547)
			(xy 363.276411 -135.071802) (xy 363.330382 -135.037551) (xy 363.388221 -135.010334) (xy 363.449014 -134.990581)
			(xy 363.511804 -134.978603) (xy 363.5756 -134.97459) (xy 363.639396 -134.978603) (xy 363.702186 -134.990581)
			(xy 363.762979 -135.010334) (xy 363.820818 -135.037551) (xy 363.874789 -135.071802) (xy 363.924042 -135.112547)
			(xy 363.967799 -135.159144) (xy 364.005372 -135.210859) (xy 364.036166 -135.266874) (xy 364.059698 -135.326307)
			(xy 364.075595 -135.388221) (xy 364.083606 -135.451639) (xy 364.084108 -135.4836) (xy 364.083606 -135.515561)
			(xy 364.075595 -135.578979) (xy 364.059698 -135.640893) (xy 364.036166 -135.700326) (xy 364.005372 -135.756341)
			(xy 363.967799 -135.808056) (xy 363.924042 -135.854653) (xy 363.874789 -135.895398) (xy 363.820818 -135.929649)
			(xy 363.762979 -135.956866) (xy 363.702186 -135.976619) (xy 363.639396 -135.988597) (xy 363.5756 -135.992611)
			(xy 363.511804 -135.988597) (xy 363.449014 -135.976619) (xy 363.388221 -135.956866) (xy 363.330382 -135.929649)
			(xy 363.276411 -135.895398) (xy 363.227158 -135.854653) (xy 363.183401 -135.808056) (xy 363.145828 -135.756341)
			(xy 363.115034 -135.700326) (xy 363.091502 -135.640893) (xy 363.075605 -135.578979) (xy 363.067594 -135.515561)
			(xy 361.00739 -135.515561) (xy 361.011085 -135.529953) (xy 361.019096 -135.593371) (xy 361.019598 -135.625332)
			(xy 361.019096 -135.657293) (xy 361.011085 -135.720711) (xy 360.995188 -135.782625) (xy 360.971656 -135.842058)
			(xy 360.940862 -135.898073) (xy 360.903289 -135.949788) (xy 360.859532 -135.996385) (xy 360.810279 -136.03713)
			(xy 360.756308 -136.071381) (xy 360.698469 -136.098598) (xy 360.637676 -136.118351) (xy 360.574886 -136.130329)
			(xy 360.51109 -136.134343) (xy 360.447294 -136.130329) (xy 360.384504 -136.118351) (xy 360.323711 -136.098598)
			(xy 360.265872 -136.071381) (xy 360.211901 -136.03713) (xy 360.162648 -135.996385) (xy 360.118891 -135.949788)
			(xy 360.081318 -135.898073) (xy 360.050524 -135.842058) (xy 360.026992 -135.782625) (xy 360.011095 -135.720711)
			(xy 360.003084 -135.657293) (xy 345.065053 -135.657293) (xy 345.656154 -136.248394) (xy 345.663555 -136.255233)
			(xy 345.682153 -136.262948) (xy 345.692222 -136.26338) (xy 363.982508 -136.26338) (xy 363.992141 -136.262914)
			(xy 364.010024 -136.255733) (xy 364.017306 -136.24941) (xy 364.075218 -136.194546) (xy 364.083346 -136.17702)
			(xy 364.083854 -136.167368) (xy 364.08608 -136.135293) (xy 364.097615 -136.072039) (xy 364.117032 -136.010744)
			(xy 364.144021 -135.952386) (xy 364.178152 -135.897896) (xy 364.21888 -135.848143) (xy 364.265555 -135.803921)
			(xy 364.317433 -135.765937) (xy 364.373685 -135.734795) (xy 364.433414 -135.710994) (xy 364.495668 -135.694912)
			(xy 364.559452 -135.686806) (xy 364.5916 -135.686292) (xy 364.623996 -135.686794) (xy 364.688264 -135.695015)
			(xy 364.750967 -135.711337) (xy 364.811087 -135.735493) (xy 364.86765 -135.767094) (xy 364.919739 -135.805627)
			(xy 364.966509 -135.850466) (xy 365.007201 -135.900885) (xy 365.041157 -135.956067) (xy 365.067825 -136.015116)
			(xy 365.077756 -136.045956) (xy 365.08182 -136.05891) (xy 365.101124 -136.077198) (xy 365.19866 -136.101582)
			(xy 365.207243 -136.103317) (xy 365.224651 -136.10154) (xy 365.240457 -136.09403) (xy 365.24692 -136.08812)
			(xy 367.718594 -133.616446) (xy 367.72599 -133.609594) (xy 367.744588 -133.60185) (xy 367.754662 -133.60146)
			(xy 382.109218 -133.60146) (xy 382.119285 -133.601888) (xy 382.137879 -133.609614) (xy 382.145286 -133.616446)
			(xy 382.46304 -133.9342) (xy 407.838656 -133.9342) (xy 407.839077 -133.894289) (xy 407.846217 -133.814788)
			(xy 407.860458 -133.736247) (xy 407.881685 -133.6593) (xy 407.895298 -133.62178) (xy 407.898138 -133.613113)
			(xy 407.898138 -133.594887) (xy 407.895298 -133.58622) (xy 407.881715 -133.548691) (xy 407.860501 -133.471743)
			(xy 407.84626 -133.393206) (xy 407.839106 -133.313709) (xy 407.838656 -133.2738) (xy 407.839167 -133.232699)
			(xy 407.846751 -133.150846) (xy 407.861855 -133.070043) (xy 407.884351 -132.990978) (xy 407.914045 -132.914326)
			(xy 407.950685 -132.84074) (xy 407.993958 -132.77085) (xy 408.043496 -132.705249) (xy 408.098874 -132.6445)
			(xy 408.159622 -132.589119) (xy 408.22522 -132.539579) (xy 408.295109 -132.496303) (xy 408.368693 -132.45966)
			(xy 408.445344 -132.429962) (xy 408.524408 -132.407464) (xy 408.605211 -132.392356) (xy 408.687063 -132.384768)
			(xy 408.728164 -132.384292) (xy 408.768213 -132.384742) (xy 408.847984 -132.391967) (xy 408.926782 -132.406335)
			(xy 409.003969 -132.42773) (xy 409.0416 -132.441442) (xy 409.050333 -132.444278) (xy 409.068681 -132.444278)
			(xy 409.077414 -132.441442) (xy 409.115046 -132.427732) (xy 409.192232 -132.406336) (xy 409.271031 -132.391968)
			(xy 409.350801 -132.384743) (xy 409.39085 -132.384292) (xy 409.431953 -132.384719) (xy 409.513809 -132.392308)
			(xy 409.594615 -132.407418) (xy 409.673683 -132.429918) (xy 409.740793 -132.45592) (xy 414.117788 -132.45592)
			(xy 414.121859 -132.400298) (xy 414.133985 -132.345861) (xy 414.153908 -132.29377) (xy 414.181204 -132.245135)
			(xy 414.21529 -132.200992) (xy 414.255439 -132.162283) (xy 414.300797 -132.129832) (xy 414.350397 -132.104331)
			(xy 414.403181 -132.086324) (xy 414.458024 -132.076194) (xy 414.513758 -132.074157) (xy 414.569195 -132.080257)
			(xy 414.623152 -132.094363) (xy 414.674481 -132.116175) (xy 414.722087 -132.145229) (xy 414.764955 -132.180904)
			(xy 414.802172 -132.222441) (xy 414.832945 -132.268954) (xy 414.856617 -132.319451) (xy 414.872685 -132.372858)
			(xy 414.880805 -132.428034) (xy 414.881314 -132.45592) (xy 414.880805 -132.483806) (xy 414.872685 -132.538982)
			(xy 414.856617 -132.592389) (xy 414.832945 -132.642886) (xy 414.802172 -132.689399) (xy 414.764955 -132.730936)
			(xy 414.722087 -132.766611) (xy 414.674481 -132.795665) (xy 414.623152 -132.817477) (xy 414.569195 -132.831583)
			(xy 414.513758 -132.837683) (xy 414.458024 -132.835646) (xy 414.403181 -132.825516) (xy 414.350397 -132.807509)
			(xy 414.300797 -132.782008) (xy 414.255439 -132.749557) (xy 414.21529 -132.710848) (xy 414.181204 -132.666705)
			(xy 414.153908 -132.61807) (xy 414.133985 -132.565979) (xy 414.121859 -132.511542) (xy 414.117788 -132.45592)
			(xy 409.740793 -132.45592) (xy 409.750337 -132.459618) (xy 409.823924 -132.496264) (xy 409.893816 -132.539542)
			(xy 409.959416 -132.589085) (xy 410.020166 -132.644469) (xy 410.075547 -132.705222) (xy 410.125086 -132.770826)
			(xy 410.168361 -132.84072) (xy 410.205002 -132.914309) (xy 410.234698 -132.990965) (xy 410.257194 -133.070034)
			(xy 410.272299 -133.150841) (xy 410.279883 -133.232697) (xy 410.280329 -133.27126) (xy 415.397948 -133.27126)
			(xy 415.402019 -133.215638) (xy 415.414145 -133.161201) (xy 415.434068 -133.10911) (xy 415.461364 -133.060475)
			(xy 415.49545 -133.016332) (xy 415.535599 -132.977623) (xy 415.580957 -132.945172) (xy 415.630557 -132.919671)
			(xy 415.683341 -132.901664) (xy 415.738184 -132.891534) (xy 415.793918 -132.889497) (xy 415.849355 -132.895597)
			(xy 415.903312 -132.909703) (xy 415.954641 -132.931515) (xy 416.002247 -132.960569) (xy 416.045115 -132.996244)
			(xy 416.082332 -133.037781) (xy 416.113105 -133.084294) (xy 416.136777 -133.134791) (xy 416.152845 -133.188198)
			(xy 416.160965 -133.243374) (xy 416.161474 -133.27126) (xy 416.160965 -133.299146) (xy 416.152845 -133.354322)
			(xy 416.136777 -133.407729) (xy 416.113105 -133.458226) (xy 416.082332 -133.504739) (xy 416.045115 -133.546276)
			(xy 416.002247 -133.581951) (xy 415.954641 -133.611005) (xy 415.903312 -133.632817) (xy 415.849355 -133.646923)
			(xy 415.793918 -133.653023) (xy 415.738184 -133.650986) (xy 415.683341 -133.640856) (xy 415.630557 -133.622849)
			(xy 415.580957 -133.597348) (xy 415.535599 -133.564897) (xy 415.49545 -133.526188) (xy 415.461364 -133.482045)
			(xy 415.434068 -133.43341) (xy 415.414145 -133.381319) (xy 415.402019 -133.326882) (xy 415.397948 -133.27126)
			(xy 410.280329 -133.27126) (xy 410.280358 -133.2738) (xy 410.279942 -133.313711) (xy 410.272802 -133.393213)
			(xy 410.258559 -133.471753) (xy 410.237331 -133.548701) (xy 410.223716 -133.58622) (xy 410.220876 -133.594887)
			(xy 410.220876 -133.613113) (xy 410.223716 -133.62178) (xy 410.237299 -133.659309) (xy 410.258513 -133.736257)
			(xy 410.272754 -133.814794) (xy 410.279908 -133.894291) (xy 410.280358 -133.9342) (xy 410.279855 -133.977974)
			(xy 410.271244 -134.065096) (xy 410.254106 -134.15095) (xy 410.251271 -134.16026) (xy 415.397948 -134.16026)
			(xy 415.402019 -134.104638) (xy 415.414145 -134.050201) (xy 415.434068 -133.99811) (xy 415.461364 -133.949475)
			(xy 415.49545 -133.905332) (xy 415.535599 -133.866623) (xy 415.580957 -133.834172) (xy 415.630557 -133.808671)
			(xy 415.683341 -133.790664) (xy 415.738184 -133.780534) (xy 415.793918 -133.778497) (xy 415.849355 -133.784597)
			(xy 415.903312 -133.798703) (xy 415.954641 -133.820515) (xy 416.002247 -133.849569) (xy 416.045115 -133.885244)
			(xy 416.082332 -133.926781) (xy 416.113105 -133.973294) (xy 416.136777 -134.023791) (xy 416.152845 -134.077198)
			(xy 416.160965 -134.132374) (xy 416.161474 -134.16026) (xy 416.160965 -134.188146) (xy 416.152845 -134.243322)
			(xy 416.136777 -134.296729) (xy 416.113105 -134.347226) (xy 416.082332 -134.393739) (xy 416.045115 -134.435276)
			(xy 416.002247 -134.470951) (xy 415.954641 -134.500005) (xy 415.903312 -134.521817) (xy 415.849355 -134.535923)
			(xy 415.793918 -134.542023) (xy 415.738184 -134.539986) (xy 415.683341 -134.529856) (xy 415.630557 -134.511849)
			(xy 415.580957 -134.486348) (xy 415.535599 -134.453897) (xy 415.49545 -134.415188) (xy 415.461364 -134.371045)
			(xy 415.434068 -134.32241) (xy 415.414145 -134.270319) (xy 415.402019 -134.215882) (xy 415.397948 -134.16026)
			(xy 410.251271 -134.16026) (xy 410.228607 -134.234702) (xy 410.212286 -134.275322) (xy 410.208332 -134.286436)
			(xy 410.209963 -134.309946) (xy 410.221834 -134.330305) (xy 410.231336 -134.337298) (xy 410.268016 -134.361857)
			(xy 410.336779 -134.417218) (xy 410.39972 -134.479118) (xy 410.456219 -134.546948) (xy 410.505722 -134.620041)
			(xy 410.547741 -134.697679) (xy 410.581862 -134.779097) (xy 410.607751 -134.863495) (xy 410.625152 -134.950042)
			(xy 410.633894 -135.037887) (xy 410.634033 -135.04926) (xy 415.397948 -135.04926) (xy 415.402019 -134.993638)
			(xy 415.414145 -134.939201) (xy 415.434068 -134.88711) (xy 415.461364 -134.838475) (xy 415.49545 -134.794332)
			(xy 415.535599 -134.755623) (xy 415.580957 -134.723172) (xy 415.630557 -134.697671) (xy 415.683341 -134.679664)
			(xy 415.738184 -134.669534) (xy 415.793918 -134.667497) (xy 415.849355 -134.673597) (xy 415.903312 -134.687703)
			(xy 415.954641 -134.709515) (xy 416.002247 -134.738569) (xy 416.045115 -134.774244) (xy 416.082332 -134.815781)
			(xy 416.113105 -134.862294) (xy 416.136777 -134.912791) (xy 416.152845 -134.966198) (xy 416.160965 -135.021374)
			(xy 416.161474 -135.04926) (xy 416.160965 -135.077146) (xy 416.152845 -135.132322) (xy 416.136777 -135.185729)
			(xy 416.113105 -135.236226) (xy 416.082332 -135.282739) (xy 416.045115 -135.324276) (xy 416.002247 -135.359951)
			(xy 415.954641 -135.389005) (xy 415.903312 -135.410817) (xy 415.849355 -135.424923) (xy 415.793918 -135.431023)
			(xy 415.738184 -135.428986) (xy 415.683341 -135.418856) (xy 415.630557 -135.400849) (xy 415.580957 -135.375348)
			(xy 415.535599 -135.342897) (xy 415.49545 -135.304188) (xy 415.461364 -135.260045) (xy 415.434068 -135.21141)
			(xy 415.414145 -135.159319) (xy 415.402019 -135.104882) (xy 415.397948 -135.04926) (xy 410.634033 -135.04926)
			(xy 410.634434 -135.082026) (xy 410.63393 -135.124374) (xy 410.625879 -135.208688) (xy 410.60985 -135.291854)
			(xy 410.585989 -135.373121) (xy 410.55451 -135.451751) (xy 410.539662 -135.480552) (xy 410.814518 -135.480552)
			(xy 410.818589 -135.42493) (xy 410.830715 -135.370493) (xy 410.850638 -135.318402) (xy 410.877934 -135.269767)
			(xy 410.91202 -135.225624) (xy 410.952169 -135.186915) (xy 410.997527 -135.154464) (xy 411.047127 -135.128963)
			(xy 411.099911 -135.110956) (xy 411.154754 -135.100826) (xy 411.210488 -135.098789) (xy 411.265925 -135.104889)
			(xy 411.319882 -135.118995) (xy 411.371211 -135.140807) (xy 411.418817 -135.169861) (xy 411.461685 -135.205536)
			(xy 411.498902 -135.247073) (xy 411.529675 -135.293586) (xy 411.553347 -135.344083) (xy 411.569415 -135.39749)
			(xy 411.577535 -135.452666) (xy 411.578044 -135.480552) (xy 411.577535 -135.508438) (xy 411.569415 -135.563614)
			(xy 411.553347 -135.617021) (xy 411.529675 -135.667518) (xy 411.498902 -135.714031) (xy 411.461685 -135.755568)
			(xy 411.418817 -135.791243) (xy 411.371211 -135.820297) (xy 411.319882 -135.842109) (xy 411.265925 -135.856215)
			(xy 411.210488 -135.862315) (xy 411.154754 -135.860278) (xy 411.099911 -135.850148) (xy 411.047127 -135.832141)
			(xy 410.997527 -135.80664) (xy 410.952169 -135.774189) (xy 410.91202 -135.73548) (xy 410.877934 -135.691337)
			(xy 410.850638 -135.642702) (xy 410.830715 -135.590611) (xy 410.818589 -135.536174) (xy 410.814518 -135.480552)
			(xy 410.539662 -135.480552) (xy 410.515699 -135.527032) (xy 410.469909 -135.598284) (xy 410.417553 -135.66486)
			(xy 410.359105 -135.726158) (xy 410.295095 -135.781623) (xy 410.226103 -135.830752) (xy 410.152753 -135.873101)
			(xy 410.07571 -135.908285) (xy 409.995671 -135.935987) (xy 409.986302 -135.93826) (xy 415.397948 -135.93826)
			(xy 415.402019 -135.882638) (xy 415.414145 -135.828201) (xy 415.434068 -135.77611) (xy 415.461364 -135.727475)
			(xy 415.49545 -135.683332) (xy 415.535599 -135.644623) (xy 415.580957 -135.612172) (xy 415.630557 -135.586671)
			(xy 415.683341 -135.568664) (xy 415.738184 -135.558534) (xy 415.793918 -135.556497) (xy 415.849355 -135.562597)
			(xy 415.903312 -135.576703) (xy 415.954641 -135.598515) (xy 416.002247 -135.627569) (xy 416.045115 -135.663244)
			(xy 416.082332 -135.704781) (xy 416.113105 -135.751294) (xy 416.136777 -135.801791) (xy 416.152845 -135.855198)
			(xy 416.160965 -135.910374) (xy 416.161474 -135.93826) (xy 416.160965 -135.966146) (xy 416.152845 -136.021322)
			(xy 416.136777 -136.074729) (xy 416.113105 -136.125226) (xy 416.082332 -136.171739) (xy 416.045115 -136.213276)
			(xy 416.002247 -136.248951) (xy 415.954641 -136.278005) (xy 415.903312 -136.299817) (xy 415.849355 -136.313923)
			(xy 415.793918 -136.320023) (xy 415.738184 -136.317986) (xy 415.683341 -136.307856) (xy 415.630557 -136.289849)
			(xy 415.580957 -136.264348) (xy 415.535599 -136.231897) (xy 415.49545 -136.193188) (xy 415.461364 -136.149045)
			(xy 415.434068 -136.10041) (xy 415.414145 -136.048319) (xy 415.402019 -135.993882) (xy 415.397948 -135.93826)
			(xy 409.986302 -135.93826) (xy 409.913362 -135.955955) (xy 409.829527 -135.968008) (xy 409.744926 -135.972039)
			(xy 409.660325 -135.968008) (xy 409.57649 -135.955955) (xy 409.494181 -135.935987) (xy 409.414142 -135.908285)
			(xy 409.337099 -135.873101) (xy 409.263749 -135.830752) (xy 409.194757 -135.781623) (xy 409.130747 -135.726158)
			(xy 409.072299 -135.66486) (xy 409.019943 -135.598284) (xy 408.974153 -135.527032) (xy 408.935342 -135.451751)
			(xy 408.903863 -135.373121) (xy 408.880002 -135.291854) (xy 408.863973 -135.208688) (xy 408.855922 -135.124374)
			(xy 408.855418 -135.082026) (xy 408.855747 -135.046567) (xy 408.861344 -134.975872) (xy 408.866594 -134.940802)
			(xy 408.868626 -134.929118) (xy 408.862276 -134.907528) (xy 408.794712 -134.831328) (xy 408.774138 -134.822692)
			(xy 408.762454 -134.822946) (xy 408.728164 -134.823708) (xy 408.687061 -134.823268) (xy 408.605206 -134.81568)
			(xy 408.5244 -134.800571) (xy 408.445332 -134.778072) (xy 408.368678 -134.748373) (xy 408.295091 -134.711729)
			(xy 408.225199 -134.668451) (xy 408.159599 -134.618909) (xy 408.098849 -134.563526) (xy 408.043468 -134.502774)
			(xy 407.993929 -134.437171) (xy 407.950654 -134.367277) (xy 407.914012 -134.293689) (xy 407.884317 -134.217033)
			(xy 407.86182 -134.137965) (xy 407.846715 -134.057159) (xy 407.839131 -133.975303) (xy 407.838656 -133.9342)
			(xy 382.46304 -133.9342) (xy 383.358093 -134.829253) (xy 393.64386 -134.829253) (xy 393.64386 -134.765331)
			(xy 393.651871 -134.701913) (xy 393.667768 -134.639999) (xy 393.6913 -134.580566) (xy 393.722094 -134.524551)
			(xy 393.759667 -134.472836) (xy 393.803424 -134.426239) (xy 393.852677 -134.385494) (xy 393.906648 -134.351243)
			(xy 393.964487 -134.324026) (xy 394.02528 -134.304273) (xy 394.08807 -134.292295) (xy 394.151866 -134.288282)
			(xy 394.215662 -134.292295) (xy 394.278452 -134.304273) (xy 394.339245 -134.324026) (xy 394.397084 -134.351243)
			(xy 394.451055 -134.385494) (xy 394.500308 -134.426239) (xy 394.544065 -134.472836) (xy 394.581638 -134.524551)
			(xy 394.612432 -134.580566) (xy 394.635964 -134.639999) (xy 394.651861 -134.701913) (xy 394.659872 -134.765331)
			(xy 394.660374 -134.797292) (xy 394.659872 -134.829253) (xy 394.651861 -134.892671) (xy 394.641916 -134.931404)
			(xy 404.294338 -134.931404) (xy 404.298409 -134.875782) (xy 404.310535 -134.821345) (xy 404.330458 -134.769254)
			(xy 404.357754 -134.720619) (xy 404.39184 -134.676476) (xy 404.431989 -134.637767) (xy 404.477347 -134.605316)
			(xy 404.526947 -134.579815) (xy 404.579731 -134.561808) (xy 404.634574 -134.551678) (xy 404.690308 -134.549641)
			(xy 404.745745 -134.555741) (xy 404.799702 -134.569847) (xy 404.851031 -134.591659) (xy 404.898637 -134.620713)
			(xy 404.941505 -134.656388) (xy 404.978722 -134.697925) (xy 405.009495 -134.744438) (xy 405.033167 -134.794935)
			(xy 405.049235 -134.848342) (xy 405.057355 -134.903518) (xy 405.057864 -134.931404) (xy 407.260042 -134.931404)
			(xy 407.264113 -134.875782) (xy 407.276239 -134.821345) (xy 407.296162 -134.769254) (xy 407.323458 -134.720619)
			(xy 407.357544 -134.676476) (xy 407.397693 -134.637767) (xy 407.443051 -134.605316) (xy 407.492651 -134.579815)
			(xy 407.545435 -134.561808) (xy 407.600278 -134.551678) (xy 407.656012 -134.549641) (xy 407.711449 -134.555741)
			(xy 407.765406 -134.569847) (xy 407.816735 -134.591659) (xy 407.864341 -134.620713) (xy 407.907209 -134.656388)
			(xy 407.944426 -134.697925) (xy 407.975199 -134.744438) (xy 407.998871 -134.794935) (xy 408.014939 -134.848342)
			(xy 408.023059 -134.903518) (xy 408.023568 -134.931404) (xy 408.023059 -134.95929) (xy 408.014939 -135.014466)
			(xy 407.998871 -135.067873) (xy 407.975199 -135.11837) (xy 407.944426 -135.164883) (xy 407.907209 -135.20642)
			(xy 407.864341 -135.242095) (xy 407.816735 -135.271149) (xy 407.765406 -135.292961) (xy 407.711449 -135.307067)
			(xy 407.656012 -135.313167) (xy 407.600278 -135.31113) (xy 407.545435 -135.301) (xy 407.492651 -135.282993)
			(xy 407.443051 -135.257492) (xy 407.397693 -135.225041) (xy 407.357544 -135.186332) (xy 407.323458 -135.142189)
			(xy 407.296162 -135.093554) (xy 407.276239 -135.041463) (xy 407.264113 -134.987026) (xy 407.260042 -134.931404)
			(xy 405.057864 -134.931404) (xy 405.057355 -134.95929) (xy 405.049235 -135.014466) (xy 405.033167 -135.067873)
			(xy 405.009495 -135.11837) (xy 404.978722 -135.164883) (xy 404.941505 -135.20642) (xy 404.898637 -135.242095)
			(xy 404.851031 -135.271149) (xy 404.799702 -135.292961) (xy 404.745745 -135.307067) (xy 404.690308 -135.313167)
			(xy 404.634574 -135.31113) (xy 404.579731 -135.301) (xy 404.526947 -135.282993) (xy 404.477347 -135.257492)
			(xy 404.431989 -135.225041) (xy 404.39184 -135.186332) (xy 404.357754 -135.142189) (xy 404.330458 -135.093554)
			(xy 404.310535 -135.041463) (xy 404.298409 -134.987026) (xy 404.294338 -134.931404) (xy 394.641916 -134.931404)
			(xy 394.635964 -134.954585) (xy 394.612432 -135.014018) (xy 394.581638 -135.070033) (xy 394.544065 -135.121748)
			(xy 394.500308 -135.168345) (xy 394.451055 -135.20909) (xy 394.397084 -135.243341) (xy 394.339245 -135.270558)
			(xy 394.278452 -135.290311) (xy 394.215662 -135.302289) (xy 394.151866 -135.306303) (xy 394.08807 -135.302289)
			(xy 394.02528 -135.290311) (xy 393.964487 -135.270558) (xy 393.906648 -135.243341) (xy 393.852677 -135.20909)
			(xy 393.803424 -135.168345) (xy 393.759667 -135.121748) (xy 393.722094 -135.070033) (xy 393.6913 -135.014018)
			(xy 393.667768 -134.954585) (xy 393.651871 -134.892671) (xy 393.64386 -134.829253) (xy 383.358093 -134.829253)
			(xy 384.472688 -135.943848) (xy 390.700004 -135.943848) (xy 390.704075 -135.888226) (xy 390.716201 -135.833789)
			(xy 390.736124 -135.781698) (xy 390.76342 -135.733063) (xy 390.797506 -135.68892) (xy 390.837655 -135.650211)
			(xy 390.883013 -135.61776) (xy 390.932613 -135.592259) (xy 390.985397 -135.574252) (xy 391.04024 -135.564122)
			(xy 391.095974 -135.562085) (xy 391.151411 -135.568185) (xy 391.205368 -135.582291) (xy 391.256697 -135.604103)
			(xy 391.304303 -135.633157) (xy 391.347171 -135.668832) (xy 391.368011 -135.692091) (xy 398.289266 -135.692091)
			(xy 398.289266 -135.628169) (xy 398.297277 -135.564751) (xy 398.313174 -135.502837) (xy 398.336706 -135.443404)
			(xy 398.3675 -135.387389) (xy 398.405073 -135.335674) (xy 398.44883 -135.289077) (xy 398.498083 -135.248332)
			(xy 398.552054 -135.214081) (xy 398.609893 -135.186864) (xy 398.670686 -135.167111) (xy 398.733476 -135.155133)
			(xy 398.797272 -135.15112) (xy 398.861068 -135.155133) (xy 398.923858 -135.167111) (xy 398.984651 -135.186864)
			(xy 399.04249 -135.214081) (xy 399.096461 -135.248332) (xy 399.145714 -135.289077) (xy 399.189471 -135.335674)
			(xy 399.227044 -135.387389) (xy 399.257838 -135.443404) (xy 399.28137 -135.502837) (xy 399.297267 -135.564751)
			(xy 399.305278 -135.628169) (xy 399.30578 -135.66013) (xy 399.305278 -135.692091) (xy 399.297267 -135.755509)
			(xy 399.28137 -135.817423) (xy 399.257838 -135.876856) (xy 399.227044 -135.932871) (xy 399.189471 -135.984586)
			(xy 399.145714 -136.031183) (xy 399.096461 -136.071928) (xy 399.04249 -136.106179) (xy 398.984651 -136.133396)
			(xy 398.923858 -136.153149) (xy 398.861068 -136.165127) (xy 398.797272 -136.169141) (xy 398.733476 -136.165127)
			(xy 398.670686 -136.153149) (xy 398.609893 -136.133396) (xy 398.552054 -136.106179) (xy 398.498083 -136.071928)
			(xy 398.44883 -136.031183) (xy 398.405073 -135.984586) (xy 398.3675 -135.932871) (xy 398.336706 -135.876856)
			(xy 398.313174 -135.817423) (xy 398.297277 -135.755509) (xy 398.289266 -135.692091) (xy 391.368011 -135.692091)
			(xy 391.384388 -135.710369) (xy 391.415161 -135.756882) (xy 391.438833 -135.807379) (xy 391.454901 -135.860786)
			(xy 391.463021 -135.915962) (xy 391.46353 -135.943848) (xy 391.463021 -135.971734) (xy 391.454901 -136.02691)
			(xy 391.438833 -136.080317) (xy 391.415161 -136.130814) (xy 391.384388 -136.177327) (xy 391.347171 -136.218864)
			(xy 391.332136 -136.231376) (xy 400.873974 -136.231376) (xy 400.878045 -136.175754) (xy 400.890171 -136.121317)
			(xy 400.910094 -136.069226) (xy 400.93739 -136.020591) (xy 400.971476 -135.976448) (xy 401.011625 -135.937739)
			(xy 401.056983 -135.905288) (xy 401.106583 -135.879787) (xy 401.159367 -135.86178) (xy 401.21421 -135.85165)
			(xy 401.269944 -135.849613) (xy 401.325381 -135.855713) (xy 401.379338 -135.869819) (xy 401.430667 -135.891631)
			(xy 401.478273 -135.920685) (xy 401.521141 -135.95636) (xy 401.558358 -135.997897) (xy 401.589131 -136.04441)
			(xy 401.612803 -136.094907) (xy 401.628871 -136.148314) (xy 401.636991 -136.20349) (xy 401.6375 -136.231376)
			(xy 401.636991 -136.259262) (xy 401.636391 -136.263337) (xy 404.95194 -136.263337) (xy 404.95194 -136.199415)
			(xy 404.959951 -136.135997) (xy 404.975848 -136.074083) (xy 404.99938 -136.01465) (xy 405.030174 -135.958635)
			(xy 405.067747 -135.90692) (xy 405.111504 -135.860323) (xy 405.160757 -135.819578) (xy 405.214728 -135.785327)
			(xy 405.272567 -135.75811) (xy 405.33336 -135.738357) (xy 405.39615 -135.726379) (xy 405.459946 -135.722366)
			(xy 405.523742 -135.726379) (xy 405.586532 -135.738357) (xy 405.647325 -135.75811) (xy 405.705164 -135.785327)
			(xy 405.759135 -135.819578) (xy 405.808388 -135.860323) (xy 405.852145 -135.90692) (xy 405.889718 -135.958635)
			(xy 405.920512 -136.01465) (xy 405.944044 -136.074083) (xy 405.959941 -136.135997) (xy 405.967952 -136.199415)
			(xy 405.968454 -136.231376) (xy 405.967952 -136.263337) (xy 407.159708 -136.263337) (xy 407.159708 -136.199415)
			(xy 407.167719 -136.135997) (xy 407.183616 -136.074083) (xy 407.207148 -136.01465) (xy 407.237942 -135.958635)
			(xy 407.275515 -135.90692) (xy 407.319272 -135.860323) (xy 407.368525 -135.819578) (xy 407.422496 -135.785327)
			(xy 407.480335 -135.75811) (xy 407.541128 -135.738357) (xy 407.603918 -135.726379) (xy 407.667714 -135.722366)
			(xy 407.73151 -135.726379) (xy 407.7943 -135.738357) (xy 407.855093 -135.75811) (xy 407.912932 -135.785327)
			(xy 407.966903 -135.819578) (xy 408.016156 -135.860323) (xy 408.059913 -135.90692) (xy 408.097486 -135.958635)
			(xy 408.12828 -136.01465) (xy 408.151812 -136.074083) (xy 408.167709 -136.135997) (xy 408.17572 -136.199415)
			(xy 408.176222 -136.231376) (xy 408.17572 -136.263337) (xy 408.167709 -136.326755) (xy 408.151812 -136.388669)
			(xy 408.12828 -136.448102) (xy 408.097486 -136.504117) (xy 408.059913 -136.555832) (xy 408.016156 -136.602429)
			(xy 407.966903 -136.643174) (xy 407.912932 -136.677425) (xy 407.855093 -136.704642) (xy 407.7943 -136.724395)
			(xy 407.73151 -136.736373) (xy 407.667714 -136.740387) (xy 407.603918 -136.736373) (xy 407.541128 -136.724395)
			(xy 407.480335 -136.704642) (xy 407.422496 -136.677425) (xy 407.368525 -136.643174) (xy 407.319272 -136.602429)
			(xy 407.275515 -136.555832) (xy 407.237942 -136.504117) (xy 407.207148 -136.448102) (xy 407.183616 -136.388669)
			(xy 407.167719 -136.326755) (xy 407.159708 -136.263337) (xy 405.967952 -136.263337) (xy 405.959941 -136.326755)
			(xy 405.944044 -136.388669) (xy 405.920512 -136.448102) (xy 405.889718 -136.504117) (xy 405.852145 -136.555832)
			(xy 405.808388 -136.602429) (xy 405.759135 -136.643174) (xy 405.705164 -136.677425) (xy 405.647325 -136.704642)
			(xy 405.586532 -136.724395) (xy 405.523742 -136.736373) (xy 405.459946 -136.740387) (xy 405.39615 -136.736373)
			(xy 405.33336 -136.724395) (xy 405.272567 -136.704642) (xy 405.214728 -136.677425) (xy 405.160757 -136.643174)
			(xy 405.111504 -136.602429) (xy 405.067747 -136.555832) (xy 405.030174 -136.504117) (xy 404.99938 -136.448102)
			(xy 404.975848 -136.388669) (xy 404.959951 -136.326755) (xy 404.95194 -136.263337) (xy 401.636391 -136.263337)
			(xy 401.628871 -136.314438) (xy 401.612803 -136.367845) (xy 401.589131 -136.418342) (xy 401.558358 -136.464855)
			(xy 401.521141 -136.506392) (xy 401.478273 -136.542067) (xy 401.430667 -136.571121) (xy 401.379338 -136.592933)
			(xy 401.325381 -136.607039) (xy 401.269944 -136.613139) (xy 401.21421 -136.611102) (xy 401.159367 -136.600972)
			(xy 401.106583 -136.582965) (xy 401.056983 -136.557464) (xy 401.011625 -136.525013) (xy 400.971476 -136.486304)
			(xy 400.93739 -136.442161) (xy 400.910094 -136.393526) (xy 400.890171 -136.341435) (xy 400.878045 -136.286998)
			(xy 400.873974 -136.231376) (xy 391.332136 -136.231376) (xy 391.304303 -136.254539) (xy 391.256697 -136.283593)
			(xy 391.205368 -136.305405) (xy 391.151411 -136.319511) (xy 391.095974 -136.325611) (xy 391.04024 -136.323574)
			(xy 390.985397 -136.313444) (xy 390.932613 -136.295437) (xy 390.883013 -136.269936) (xy 390.837655 -136.237485)
			(xy 390.797506 -136.198776) (xy 390.76342 -136.154633) (xy 390.736124 -136.105998) (xy 390.716201 -136.053907)
			(xy 390.704075 -135.99947) (xy 390.700004 -135.943848) (xy 384.472688 -135.943848) (xy 384.716274 -136.187434)
			(xy 384.718306 -136.189466) (xy 384.725672 -136.197594) (xy 384.745484 -136.20623) (xy 384.843782 -136.205214)
			(xy 384.863594 -136.19607) (xy 384.870706 -136.187688) (xy 384.891455 -136.164288) (xy 384.937735 -136.122222)
			(xy 384.988824 -136.086147) (xy 385.04395 -136.056608) (xy 385.102282 -136.034051) (xy 385.16294 -136.018817)
			(xy 385.225007 -136.011134) (xy 385.256278 -136.01065) (xy 385.288244 -136.01113) (xy 385.351672 -136.01914)
			(xy 385.413596 -136.035037) (xy 385.473039 -136.05857) (xy 385.529063 -136.089367) (xy 385.580786 -136.126944)
			(xy 385.627391 -136.170708) (xy 385.668144 -136.219967) (xy 385.702401 -136.273946) (xy 385.729623 -136.331793)
			(xy 385.749379 -136.392595) (xy 385.761359 -136.455394) (xy 385.765374 -136.5192) (xy 385.761359 -136.583006)
			(xy 385.749379 -136.645805) (xy 385.729623 -136.706607) (xy 385.702401 -136.764454) (xy 385.668144 -136.818433)
			(xy 385.660841 -136.82726) (xy 415.397948 -136.82726) (xy 415.402019 -136.771638) (xy 415.414145 -136.717201)
			(xy 415.434068 -136.66511) (xy 415.461364 -136.616475) (xy 415.49545 -136.572332) (xy 415.535599 -136.533623)
			(xy 415.580957 -136.501172) (xy 415.630557 -136.475671) (xy 415.683341 -136.457664) (xy 415.738184 -136.447534)
			(xy 415.793918 -136.445497) (xy 415.849355 -136.451597) (xy 415.903312 -136.465703) (xy 415.954641 -136.487515)
			(xy 416.002247 -136.516569) (xy 416.045115 -136.552244) (xy 416.082332 -136.593781) (xy 416.113105 -136.640294)
			(xy 416.136777 -136.690791) (xy 416.152845 -136.744198) (xy 416.160965 -136.799374) (xy 416.161474 -136.82726)
			(xy 416.160965 -136.855146) (xy 416.152845 -136.910322) (xy 416.136777 -136.963729) (xy 416.113105 -137.014226)
			(xy 416.082332 -137.060739) (xy 416.045115 -137.102276) (xy 416.002247 -137.137951) (xy 415.954641 -137.167005)
			(xy 415.903312 -137.188817) (xy 415.849355 -137.202923) (xy 415.793918 -137.209023) (xy 415.738184 -137.206986)
			(xy 415.683341 -137.196856) (xy 415.630557 -137.178849) (xy 415.580957 -137.153348) (xy 415.535599 -137.120897)
			(xy 415.49545 -137.082188) (xy 415.461364 -137.038045) (xy 415.434068 -136.98941) (xy 415.414145 -136.937319)
			(xy 415.402019 -136.882882) (xy 415.397948 -136.82726) (xy 385.660841 -136.82726) (xy 385.627391 -136.867692)
			(xy 385.580786 -136.911456) (xy 385.529063 -136.949033) (xy 385.473039 -136.97983) (xy 385.413596 -137.003363)
			(xy 385.351672 -137.01926) (xy 385.288244 -137.02727) (xy 385.256278 -137.027666) (xy 385.22377 -137.02713)
			(xy 385.159288 -137.018806) (xy 385.096391 -137.002335) (xy 385.036106 -136.977984) (xy 384.979415 -136.946152)
			(xy 384.927241 -136.907356) (xy 384.903472 -136.885172) (xy 384.892296 -136.874758) (xy 384.862324 -136.86917)
			(xy 384.762248 -136.911588) (xy 384.753287 -136.915901) (xy 384.73931 -136.930021) (xy 384.73174 -136.948391)
			(xy 384.73126 -136.958324) (xy 384.73126 -137.488887) (xy 392.21384 -137.488887) (xy 392.21384 -137.424965)
			(xy 392.221851 -137.361547) (xy 392.237748 -137.299633) (xy 392.26128 -137.2402) (xy 392.292074 -137.184185)
			(xy 392.329647 -137.13247) (xy 392.373404 -137.085873) (xy 392.422657 -137.045128) (xy 392.476628 -137.010877)
			(xy 392.534467 -136.98366) (xy 392.59526 -136.963907) (xy 392.65805 -136.951929) (xy 392.721846 -136.947916)
			(xy 392.785642 -136.951929) (xy 392.848432 -136.963907) (xy 392.909225 -136.98366) (xy 392.967064 -137.010877)
			(xy 393.021035 -137.045128) (xy 393.070288 -137.085873) (xy 393.114045 -137.13247) (xy 393.151618 -137.184185)
			(xy 393.182412 -137.2402) (xy 393.205944 -137.299633) (xy 393.221841 -137.361547) (xy 393.229852 -137.424965)
			(xy 393.230354 -137.456926) (xy 393.229852 -137.488887) (xy 393.221841 -137.552305) (xy 393.205944 -137.614219)
			(xy 393.182412 -137.673652) (xy 393.151618 -137.729667) (xy 393.114045 -137.781382) (xy 393.070288 -137.827979)
			(xy 393.021035 -137.868724) (xy 392.967064 -137.902975) (xy 392.909225 -137.930192) (xy 392.848432 -137.949945)
			(xy 392.785642 -137.961923) (xy 392.721846 -137.965937) (xy 392.65805 -137.961923) (xy 392.59526 -137.949945)
			(xy 392.534467 -137.930192) (xy 392.476628 -137.902975) (xy 392.422657 -137.868724) (xy 392.373404 -137.827979)
			(xy 392.329647 -137.781382) (xy 392.292074 -137.729667) (xy 392.26128 -137.673652) (xy 392.237748 -137.614219)
			(xy 392.221851 -137.552305) (xy 392.21384 -137.488887) (xy 384.73126 -137.488887) (xy 384.73126 -138.04138)
			(xy 385.680202 -138.04138) (xy 385.684273 -137.985758) (xy 385.696399 -137.931321) (xy 385.716322 -137.87923)
			(xy 385.743618 -137.830595) (xy 385.777704 -137.786452) (xy 385.817853 -137.747743) (xy 385.863211 -137.715292)
			(xy 385.912811 -137.689791) (xy 385.965595 -137.671784) (xy 386.020438 -137.661654) (xy 386.076172 -137.659617)
			(xy 386.131609 -137.665717) (xy 386.185566 -137.679823) (xy 386.236895 -137.701635) (xy 386.284501 -137.730689)
			(xy 386.327369 -137.766364) (xy 386.364586 -137.807901) (xy 386.395359 -137.854414) (xy 386.419031 -137.904911)
			(xy 386.435099 -137.958318) (xy 386.443219 -138.013494) (xy 386.443728 -138.04138) (xy 386.443219 -138.069266)
			(xy 386.441978 -138.0777) (xy 390.57297 -138.0777) (xy 390.576985 -138.0139) (xy 390.588963 -137.951106)
			(xy 390.608718 -137.890309) (xy 390.635937 -137.832467) (xy 390.670192 -137.778493) (xy 390.710941 -137.729238)
			(xy 390.757542 -137.685478) (xy 390.80926 -137.647905) (xy 390.86528 -137.61711) (xy 390.924718 -137.593579)
			(xy 390.986636 -137.577683) (xy 391.050059 -137.569674) (xy 391.082022 -137.569194) (xy 391.11219 -137.569641)
			(xy 391.172104 -137.576777) (xy 391.23075 -137.590956) (xy 391.287305 -137.611981) (xy 391.340973 -137.639554)
			(xy 391.390998 -137.673288) (xy 391.436677 -137.712709) (xy 391.477366 -137.757261) (xy 391.49528 -137.781538)
			(xy 391.50163 -137.790174) (xy 391.519918 -137.801096) (xy 391.616438 -137.812018) (xy 391.636758 -137.805668)
			(xy 391.644886 -137.798556) (xy 391.665887 -137.780689) (xy 391.712078 -137.750579) (xy 391.762121 -137.72743)
			(xy 391.814975 -137.711725) (xy 391.869539 -137.703791) (xy 391.897108 -137.703306) (xy 391.92436 -137.703764)
			(xy 391.978309 -137.711522) (xy 392.030604 -137.726878) (xy 392.080182 -137.749521) (xy 392.126034 -137.778988)
			(xy 392.167224 -137.814681) (xy 392.202916 -137.855873) (xy 392.232383 -137.901725) (xy 392.255024 -137.951303)
			(xy 392.27038 -138.003599) (xy 392.271466 -138.011154) (xy 399.116296 -138.011154) (xy 399.116798 -137.979193)
			(xy 399.124809 -137.915775) (xy 399.140706 -137.853861) (xy 399.164238 -137.794428) (xy 399.195032 -137.738413)
			(xy 399.232605 -137.686698) (xy 399.276362 -137.640101) (xy 399.325615 -137.599356) (xy 399.379586 -137.565105)
			(xy 399.437425 -137.537888) (xy 399.498218 -137.518135) (xy 399.561008 -137.506157) (xy 399.624804 -137.502144)
			(xy 399.6886 -137.506157) (xy 399.75139 -137.518135) (xy 399.812183 -137.537888) (xy 399.870022 -137.565105)
			(xy 399.923993 -137.599356) (xy 399.973246 -137.640101) (xy 400.017003 -137.686698) (xy 400.054576 -137.738413)
			(xy 400.08537 -137.794428) (xy 400.108902 -137.853861) (xy 400.122865 -137.908241) (xy 410.68218 -137.908241)
			(xy 410.68218 -137.844319) (xy 410.690191 -137.780901) (xy 410.706088 -137.718987) (xy 410.72962 -137.659554)
			(xy 410.760414 -137.603539) (xy 410.797987 -137.551824) (xy 410.841744 -137.505227) (xy 410.890997 -137.464482)
			(xy 410.944968 -137.430231) (xy 411.002807 -137.403014) (xy 411.0636 -137.383261) (xy 411.12639 -137.371283)
			(xy 411.190186 -137.36727) (xy 411.253982 -137.371283) (xy 411.316772 -137.383261) (xy 411.377565 -137.403014)
			(xy 411.435404 -137.430231) (xy 411.489375 -137.464482) (xy 411.538628 -137.505227) (xy 411.582385 -137.551824)
			(xy 411.619958 -137.603539) (xy 411.650752 -137.659554) (xy 411.674284 -137.718987) (xy 411.690181 -137.780901)
			(xy 411.698192 -137.844319) (xy 411.698694 -137.87628) (xy 411.698192 -137.908241) (xy 411.690181 -137.971659)
			(xy 411.674284 -138.033573) (xy 411.650752 -138.093006) (xy 411.619958 -138.149021) (xy 411.582385 -138.200736)
			(xy 411.538628 -138.247333) (xy 411.489375 -138.288078) (xy 411.435404 -138.322329) (xy 411.383923 -138.346554)
			(xy 414.349634 -138.346554) (xy 414.349634 -138.292046) (xy 414.357391 -138.238093) (xy 414.372748 -138.185793)
			(xy 414.395391 -138.13621) (xy 414.42486 -138.090355) (xy 414.460554 -138.04916) (xy 414.501748 -138.013464)
			(xy 414.547603 -137.983995) (xy 414.597185 -137.96135) (xy 414.649485 -137.945993) (xy 414.703438 -137.938234)
			(xy 414.730692 -137.937748) (xy 414.758331 -137.938217) (xy 414.813027 -137.946215) (xy 414.865998 -137.962014)
			(xy 414.916138 -137.985286) (xy 414.962399 -138.015544) (xy 415.003815 -138.052156) (xy 415.039518 -138.094356)
			(xy 415.068765 -138.141263) (xy 415.090943 -138.191897) (xy 415.098738 -138.218418) (xy 415.10204 -138.230864)
			(xy 415.119312 -138.249152) (xy 415.22396 -138.28395) (xy 415.248598 -138.279632) (xy 415.258758 -138.271758)
			(xy 415.277667 -138.257567) (xy 415.318335 -138.233455) (xy 415.361667 -138.214545) (xy 415.384234 -138.207496)
			(xy 415.396426 -138.20394) (xy 415.414206 -138.186668) (xy 415.448496 -138.083798) (xy 415.444432 -138.059414)
			(xy 415.437066 -138.049254) (xy 415.419268 -138.024421) (xy 415.391019 -137.97025) (xy 415.371764 -137.91227)
			(xy 415.361994 -137.851963) (xy 415.361374 -137.821416) (xy 415.361893 -137.794166) (xy 415.369647 -137.74022)
			(xy 415.384999 -137.687927) (xy 415.407637 -137.638352) (xy 415.4371 -137.592502) (xy 415.472788 -137.551312)
			(xy 415.513975 -137.51562) (xy 415.559822 -137.486153) (xy 415.609396 -137.463511) (xy 415.661687 -137.448154)
			(xy 415.715632 -137.440396) (xy 415.742882 -137.439908) (xy 415.771389 -137.440431) (xy 415.827766 -137.448926)
			(xy 415.882253 -137.465714) (xy 415.933635 -137.490421) (xy 415.980769 -137.522499) (xy 416.022606 -137.561232)
			(xy 416.040824 -137.583164) (xy 416.048444 -137.592562) (xy 416.070796 -137.602722) (xy 416.17773 -137.597134)
			(xy 416.198812 -137.584942) (xy 416.205416 -137.574528) (xy 416.220542 -137.551845) (xy 416.256253 -137.510649)
			(xy 416.297463 -137.474954) (xy 416.343334 -137.445487) (xy 416.392931 -137.422848) (xy 416.445246 -137.407498)
			(xy 416.499212 -137.399749) (xy 416.526472 -137.399268) (xy 416.553723 -137.399781) (xy 416.607671 -137.407534)
			(xy 416.659966 -137.422885) (xy 416.709545 -137.445523) (xy 416.755397 -137.474985) (xy 416.796589 -137.510674)
			(xy 416.832283 -137.551861) (xy 416.861752 -137.597709) (xy 416.884397 -137.647285) (xy 416.899755 -137.699578)
			(xy 416.907515 -137.753525) (xy 416.90798 -137.780776) (xy 416.907598 -137.807116) (xy 416.900366 -137.859297)
			(xy 416.886021 -137.909987) (xy 416.864837 -137.95822) (xy 416.837217 -138.003079) (xy 416.803687 -138.043711)
			(xy 416.764885 -138.079341) (xy 416.721548 -138.109293) (xy 416.674502 -138.132997) (xy 416.624641 -138.15)
			(xy 416.598862 -138.155426) (xy 416.5854 -138.157966) (xy 416.564826 -138.175746) (xy 416.527488 -138.284966)
			(xy 416.532822 -138.311636) (xy 416.541712 -138.32205) (xy 416.559451 -138.342991) (xy 416.589326 -138.389029)
			(xy 416.612287 -138.438875) (xy 416.627861 -138.4915) (xy 416.635726 -138.545815) (xy 416.6362 -138.573256)
			(xy 416.635775 -138.599636) (xy 416.628515 -138.651894) (xy 416.614127 -138.702655) (xy 416.592885 -138.75095)
			(xy 416.565195 -138.79586) (xy 416.531583 -138.836528) (xy 416.492691 -138.87218) (xy 416.44926 -138.902135)
			(xy 416.425888 -138.914378) (xy 416.41268 -138.920728) (xy 416.397694 -138.945112) (xy 416.397694 -139.065)
			(xy 416.41268 -139.089384) (xy 416.425888 -139.095734) (xy 416.449237 -139.108014) (xy 416.492661 -139.137971)
			(xy 416.531548 -139.17362) (xy 416.565156 -139.214283) (xy 416.592845 -139.259187) (xy 416.614089 -139.307475)
			(xy 416.628483 -139.358228) (xy 416.635752 -139.410479) (xy 416.6362 -139.436856) (xy 416.635711 -139.464114)
			(xy 416.627949 -139.518074) (xy 416.61259 -139.570381) (xy 416.589948 -139.619972) (xy 416.560482 -139.665837)
			(xy 416.524791 -139.707046) (xy 416.483602 -139.742758) (xy 416.46094 -139.757912) (xy 416.453949 -139.762733)
			(xy 416.443433 -139.776057) (xy 416.437881 -139.792097) (xy 416.437572 -139.800584) (xy 416.437572 -139.885928)
			(xy 416.437905 -139.894406) (xy 416.443491 -139.910419) (xy 416.453981 -139.923744) (xy 416.46094 -139.9286)
			(xy 416.483559 -139.943814) (xy 416.52474 -139.979522) (xy 416.560424 -140.020726) (xy 416.589883 -140.066586)
			(xy 416.61252 -140.11617) (xy 416.627872 -140.16847) (xy 416.635629 -140.222423) (xy 416.635633 -140.27693)
			(xy 416.627883 -140.330883) (xy 416.612536 -140.383185) (xy 416.589906 -140.432772) (xy 416.560452 -140.478636)
			(xy 416.549574 -140.4912) (xy 429.506399 -140.4912) (xy 429.510413 -140.427406) (xy 429.522391 -140.364617)
			(xy 429.542143 -140.303825) (xy 429.569359 -140.245988) (xy 429.603609 -140.192018) (xy 429.644353 -140.142767)
			(xy 429.690949 -140.09901) (xy 429.742662 -140.061438) (xy 429.798676 -140.030644) (xy 429.858107 -140.007113)
			(xy 429.920019 -139.991216) (xy 429.983436 -139.983204) (xy 430.015396 -139.982702) (xy 430.046674 -139.983164)
			(xy 430.10876 -139.990826) (xy 430.169436 -140.006049) (xy 430.227786 -140.0286) (xy 430.282928 -140.058141)
			(xy 430.334029 -140.094224) (xy 430.380317 -140.136305) (xy 430.421092 -140.183746) (xy 430.438814 -140.209524)
			(xy 430.446266 -140.219684) (xy 430.468397 -140.231669) (xy 430.480978 -140.232384) (xy 430.565814 -140.232384)
			(xy 430.578396 -140.231698) (xy 430.600514 -140.21968) (xy 430.607978 -140.209524) (xy 430.625702 -140.183747)
			(xy 430.666479 -140.136306) (xy 430.712767 -140.094225) (xy 430.763868 -140.058139) (xy 430.819009 -140.028594)
			(xy 430.877357 -140.006036) (xy 430.938032 -139.990805) (xy 431.000117 -139.983132) (xy 431.062675 -139.983132)
			(xy 431.12476 -139.990805) (xy 431.185435 -140.006036) (xy 431.243783 -140.028594) (xy 431.298924 -140.058139)
			(xy 431.350025 -140.094225) (xy 431.396313 -140.136306) (xy 431.43709 -140.183747) (xy 431.454814 -140.209524)
			(xy 431.462266 -140.219684) (xy 431.484397 -140.231669) (xy 431.496978 -140.232384) (xy 431.581814 -140.232384)
			(xy 431.594396 -140.231698) (xy 431.616514 -140.21968) (xy 431.623978 -140.209524) (xy 431.641702 -140.183747)
			(xy 431.682479 -140.136306) (xy 431.728767 -140.094225) (xy 431.779868 -140.058139) (xy 431.835009 -140.028594)
			(xy 431.893357 -140.006036) (xy 431.954032 -139.990805) (xy 432.016117 -139.983132) (xy 432.078675 -139.983132)
			(xy 432.14076 -139.990805) (xy 432.201435 -140.006036) (xy 432.259783 -140.028594) (xy 432.314924 -140.058139)
			(xy 432.366025 -140.094225) (xy 432.412313 -140.136306) (xy 432.45309 -140.183747) (xy 432.470814 -140.209524)
			(xy 432.478266 -140.219684) (xy 432.500397 -140.231669) (xy 432.512978 -140.232384) (xy 432.597814 -140.232384)
			(xy 432.610396 -140.231698) (xy 432.632514 -140.21968) (xy 432.639978 -140.209524) (xy 432.657681 -140.183735)
			(xy 432.698469 -140.136307) (xy 432.744765 -140.094238) (xy 432.795871 -140.058164) (xy 432.851014 -140.028628)
			(xy 432.909362 -140.006077) (xy 432.970036 -139.990851) (xy 433.032119 -139.98318) (xy 433.063396 -139.982702)
			(xy 433.095359 -139.983163) (xy 433.158781 -139.991174) (xy 433.220699 -140.007072) (xy 433.280137 -140.030604)
			(xy 433.336156 -140.061401) (xy 433.387874 -140.098975) (xy 433.434474 -140.142736) (xy 433.475222 -140.191992)
			(xy 433.509476 -140.245966) (xy 433.536694 -140.303808) (xy 433.556449 -140.364606) (xy 433.568428 -140.4274)
			(xy 433.572442 -140.4912) (xy 433.568428 -140.555) (xy 433.556449 -140.617794) (xy 433.536694 -140.678592)
			(xy 433.509476 -140.736434) (xy 433.475222 -140.790408) (xy 433.434474 -140.839664) (xy 433.387874 -140.883425)
			(xy 433.336156 -140.920999) (xy 433.280137 -140.951796) (xy 433.220699 -140.975328) (xy 433.158781 -140.991226)
			(xy 433.095359 -140.999237) (xy 433.063396 -140.999718) (xy 433.032116 -140.999298) (xy 432.970028 -140.991633)
			(xy 432.909349 -140.976407) (xy 432.850997 -140.95385) (xy 432.795855 -140.924304) (xy 432.744754 -140.888214)
			(xy 432.698469 -140.846127) (xy 432.657697 -140.798677) (xy 432.639978 -140.772896) (xy 432.632526 -140.762735)
			(xy 432.610395 -140.75075) (xy 432.597814 -140.750036) (xy 432.512978 -140.750036) (xy 432.500401 -140.75075)
			(xy 432.478284 -140.762751) (xy 432.470814 -140.772896) (xy 432.45309 -140.798673) (xy 432.412313 -140.846114)
			(xy 432.366025 -140.888195) (xy 432.314924 -140.924281) (xy 432.259783 -140.953826) (xy 432.201435 -140.976384)
			(xy 432.14076 -140.991615) (xy 432.078675 -140.999288) (xy 432.016117 -140.999288) (xy 431.954032 -140.991615)
			(xy 431.893357 -140.976384) (xy 431.835009 -140.953826) (xy 431.779868 -140.924281) (xy 431.728767 -140.888195)
			(xy 431.682479 -140.846114) (xy 431.641702 -140.798673) (xy 431.623978 -140.772896) (xy 431.616526 -140.762735)
			(xy 431.594395 -140.75075) (xy 431.581814 -140.750036) (xy 431.496978 -140.750036) (xy 431.484401 -140.75075)
			(xy 431.462284 -140.762751) (xy 431.454814 -140.772896) (xy 431.43709 -140.798673) (xy 431.396313 -140.846114)
			(xy 431.350025 -140.888195) (xy 431.298924 -140.924281) (xy 431.243783 -140.953826) (xy 431.185435 -140.976384)
			(xy 431.12476 -140.991615) (xy 431.062675 -140.999288) (xy 431.000117 -140.999288) (xy 430.938032 -140.991615)
			(xy 430.877357 -140.976384) (xy 430.819009 -140.953826) (xy 430.763868 -140.924281) (xy 430.712767 -140.888195)
			(xy 430.666479 -140.846114) (xy 430.625702 -140.798673) (xy 430.607978 -140.772896) (xy 430.600526 -140.762735)
			(xy 430.578395 -140.75075) (xy 430.565814 -140.750036) (xy 430.480978 -140.750036) (xy 430.468401 -140.75075)
			(xy 430.446284 -140.762751) (xy 430.438814 -140.772896) (xy 430.421058 -140.798647) (xy 430.380277 -140.846075)
			(xy 430.333988 -140.888145) (xy 430.282891 -140.924222) (xy 430.227755 -140.953762) (xy 430.169414 -140.976319)
			(xy 430.108748 -140.991553) (xy 430.046671 -140.999234) (xy 430.015396 -140.999718) (xy 429.983436 -140.999196)
			(xy 429.920019 -140.991184) (xy 429.858107 -140.975287) (xy 429.798676 -140.951756) (xy 429.742662 -140.920962)
			(xy 429.690949 -140.88339) (xy 429.644353 -140.839633) (xy 429.603609 -140.790382) (xy 429.569359 -140.736412)
			(xy 429.542143 -140.678575) (xy 429.522391 -140.617783) (xy 429.510413 -140.554994) (xy 429.506399 -140.4912)
			(xy 416.549574 -140.4912) (xy 416.524774 -140.519844) (xy 416.483597 -140.555557) (xy 416.46094 -140.570712)
			(xy 416.453949 -140.575533) (xy 416.443433 -140.588857) (xy 416.437881 -140.604897) (xy 416.437572 -140.613384)
			(xy 416.437572 -140.698728) (xy 416.437905 -140.707206) (xy 416.443491 -140.723219) (xy 416.453981 -140.736544)
			(xy 416.46094 -140.7414) (xy 416.483622 -140.756529) (xy 416.524823 -140.792237) (xy 416.560522 -140.833446)
			(xy 416.589993 -140.879315) (xy 416.612636 -140.928913) (xy 416.627989 -140.981228) (xy 416.635741 -141.035195)
			(xy 416.6362 -141.062456) (xy 416.635704 -141.089708) (xy 416.627953 -141.143658) (xy 416.612602 -141.195956)
			(xy 416.589964 -141.245537) (xy 416.5605 -141.29139) (xy 416.524809 -141.332584) (xy 416.49271 -141.3604)
			(xy 448.573366 -141.3604) (xy 448.577381 -141.2966) (xy 448.589359 -141.233806) (xy 448.609114 -141.173009)
			(xy 448.636333 -141.115167) (xy 448.670587 -141.061193) (xy 448.711335 -141.011938) (xy 448.757936 -140.968178)
			(xy 448.809654 -140.930604) (xy 448.865673 -140.899808) (xy 448.925111 -140.876277) (xy 448.987029 -140.860381)
			(xy 449.050451 -140.85237) (xy 449.082414 -140.85189) (xy 449.115433 -140.85243) (xy 449.180914 -140.860981)
			(xy 449.244738 -140.877936) (xy 449.305829 -140.903012) (xy 449.36316 -140.935785) (xy 449.415766 -140.975703)
			(xy 449.462762 -141.022097) (xy 449.503357 -141.074183) (xy 449.536867 -141.131087) (xy 449.550282 -141.161262)
			(xy 449.554854 -141.171676) (xy 449.570856 -141.186408) (xy 449.665344 -141.216888) (xy 449.68668 -141.214348)
			(xy 449.696332 -141.208506) (xy 449.718794 -141.195459) (xy 449.766473 -141.174842) (xy 449.816507 -141.160879)
			(xy 449.867971 -141.153829) (xy 449.893944 -141.153388) (xy 449.920878 -141.153854) (xy 449.97421 -141.161442)
			(xy 450.025943 -141.17646) (xy 450.075047 -141.198609) (xy 450.120545 -141.227449) (xy 450.14134 -141.244574)
			(xy 450.148605 -141.250205) (xy 450.165931 -141.256312) (xy 450.175122 -141.256512) (xy 450.20611 -141.256004)
			(xy 450.215433 -141.255481) (xy 450.232765 -141.248576) (xy 450.239892 -141.242542) (xy 450.263489 -141.221207)
			(xy 450.31505 -141.183945) (xy 450.370859 -141.153411) (xy 450.430043 -141.130082) (xy 450.491676 -141.114324)
			(xy 450.554794 -141.106383) (xy 450.586602 -141.10589) (xy 450.618563 -141.106396) (xy 450.68198 -141.114408)
			(xy 450.743894 -141.130305) (xy 450.803327 -141.153836) (xy 450.859341 -141.184631) (xy 450.911055 -141.222203)
			(xy 450.957652 -141.26596) (xy 450.998397 -141.315213) (xy 451.032648 -141.369184) (xy 451.059864 -141.427022)
			(xy 451.079617 -141.487815) (xy 451.091595 -141.550604) (xy 451.095609 -141.6144) (xy 451.091595 -141.678196)
			(xy 451.079617 -141.740985) (xy 451.059864 -141.801778) (xy 451.032648 -141.859616) (xy 450.998397 -141.913587)
			(xy 450.957652 -141.96284) (xy 450.911055 -142.006597) (xy 450.859341 -142.044169) (xy 450.803327 -142.074964)
			(xy 450.743894 -142.098495) (xy 450.68198 -142.114392) (xy 450.618563 -142.122404) (xy 450.586602 -142.122906)
			(xy 450.555472 -142.12247) (xy 450.493677 -142.114873) (xy 450.433271 -142.09979) (xy 450.375157 -142.077449)
			(xy 450.320204 -142.048183) (xy 450.269234 -142.012429) (xy 450.223007 -141.970722) (xy 450.182216 -141.923686)
			(xy 450.164454 -141.898116) (xy 450.158913 -141.890584) (xy 450.143677 -141.879771) (xy 450.134736 -141.877034)
			(xy 450.104764 -141.869668) (xy 450.09577 -141.867835) (xy 450.077548 -141.86991) (xy 450.069204 -141.873732)
			(xy 450.041955 -141.887151) (xy 449.984277 -141.906174) (xy 449.924311 -141.915811) (xy 449.893944 -141.916404)
			(xy 449.867564 -141.915932) (xy 449.815308 -141.908668) (xy 449.764551 -141.894272) (xy 449.716262 -141.873018)
			(xy 449.671362 -141.845313) (xy 449.630709 -141.811685) (xy 449.595078 -141.772775) (xy 449.579746 -141.751304)
			(xy 449.573396 -141.741906) (xy 449.5546 -141.73073) (xy 449.456048 -141.719808) (xy 449.435474 -141.726666)
			(xy 449.427092 -141.734286) (xy 449.403555 -141.755333) (xy 449.352185 -141.79205) (xy 449.296665 -141.822125)
			(xy 449.237849 -141.845096) (xy 449.176642 -141.86061) (xy 449.113985 -141.868428) (xy 449.082414 -141.868906)
			(xy 449.050451 -141.86843) (xy 448.987029 -141.860419) (xy 448.925111 -141.844523) (xy 448.865673 -141.820992)
			(xy 448.809654 -141.790196) (xy 448.757936 -141.752622) (xy 448.711335 -141.708862) (xy 448.670587 -141.659607)
			(xy 448.636333 -141.605633) (xy 448.609114 -141.547791) (xy 448.589359 -141.486994) (xy 448.577381 -141.4242)
			(xy 448.573366 -141.3604) (xy 416.49271 -141.3604) (xy 416.483619 -141.368278) (xy 416.437768 -141.397746)
			(xy 416.38819 -141.420389) (xy 416.335894 -141.435745) (xy 416.281944 -141.443501) (xy 416.254692 -141.443964)
			(xy 416.225777 -141.443393) (xy 416.168608 -141.434677) (xy 416.113409 -141.41743) (xy 416.061447 -141.392048)
			(xy 416.013912 -141.359113) (xy 415.971893 -141.31938) (xy 415.953702 -141.296898) (xy 415.946135 -141.288141)
			(xy 415.92538 -141.277955) (xy 415.913824 -141.27734) (xy 415.83356 -141.27734) (xy 415.821994 -141.277931)
			(xy 415.801222 -141.288109) (xy 415.793682 -141.296898) (xy 415.7789 -141.315294) (xy 415.745532 -141.348667)
			(xy 415.727134 -141.363446) (xy 415.718345 -141.370981) (xy 415.708179 -141.391761) (xy 415.707576 -141.403324)
			(xy 415.707576 -141.483588) (xy 415.708127 -141.495159) (xy 415.718333 -141.515931) (xy 415.727134 -141.523466)
			(xy 415.749608 -141.541668) (xy 415.789343 -141.583686) (xy 415.822282 -141.631219) (xy 415.847671 -141.683178)
			(xy 415.86493 -141.738373) (xy 415.873663 -141.795541) (xy 415.8742 -141.824456) (xy 415.873635 -141.854718)
			(xy 415.864083 -141.914484) (xy 415.845213 -141.971991) (xy 415.817497 -142.025796) (xy 415.800032 -142.050516)
			(xy 415.794444 -142.058136) (xy 415.789364 -142.07617) (xy 415.797492 -142.162276) (xy 415.805874 -142.178786)
			(xy 415.812732 -142.18539) (xy 415.83437 -142.206042) (xy 415.873166 -142.25157) (xy 415.906352 -142.301337)
			(xy 415.93347 -142.354653) (xy 415.954143 -142.410783) (xy 415.968088 -142.468951) (xy 415.975112 -142.528354)
			(xy 415.975546 -142.558262) (xy 415.975044 -142.590223) (xy 415.967033 -142.653641) (xy 415.951136 -142.715555)
			(xy 415.927604 -142.774988) (xy 415.89681 -142.831003) (xy 415.859237 -142.882718) (xy 415.81548 -142.929315)
			(xy 415.766227 -142.97006) (xy 415.712256 -143.004311) (xy 415.654417 -143.031528) (xy 415.593624 -143.051281)
			(xy 415.530834 -143.063259) (xy 415.467038 -143.067273) (xy 415.403242 -143.063259) (xy 415.340452 -143.051281)
			(xy 415.279659 -143.031528) (xy 415.22182 -143.004311) (xy 415.167849 -142.97006) (xy 415.118596 -142.929315)
			(xy 415.074839 -142.882718) (xy 415.037266 -142.831003) (xy 415.006472 -142.774988) (xy 414.98294 -142.715555)
			(xy 414.967043 -142.653641) (xy 414.959032 -142.590223) (xy 414.95853 -142.558262) (xy 414.959068 -142.525802)
			(xy 414.967313 -142.461409) (xy 414.983689 -142.398589) (xy 415.00793 -142.338365) (xy 415.039642 -142.281718)
			(xy 415.078307 -142.229569) (xy 415.123298 -142.182768) (xy 415.148268 -142.162022) (xy 415.155634 -142.15618)
			(xy 415.165032 -142.140178) (xy 415.179256 -142.054834) (xy 415.175446 -142.036546) (xy 415.170366 -142.028672)
			(xy 415.156373 -142.005642) (xy 415.134249 -141.956506) (xy 415.119245 -141.90475) (xy 415.111656 -141.851399)
			(xy 415.111184 -141.824456) (xy 415.111711 -141.795539) (xy 415.120434 -141.738367) (xy 415.137688 -141.683167)
			(xy 415.163078 -141.631204) (xy 415.196022 -141.583671) (xy 415.235764 -141.541655) (xy 415.25825 -141.523466)
			(xy 415.267031 -141.515923) (xy 415.277202 -141.49515) (xy 415.277808 -141.483588) (xy 415.277808 -141.403324)
			(xy 415.277221 -141.391758) (xy 415.267038 -141.370988) (xy 415.25825 -141.363446) (xy 415.235778 -141.345242)
			(xy 415.196044 -141.303223) (xy 415.163106 -141.255691) (xy 415.137716 -141.203732) (xy 415.120456 -141.148538)
			(xy 415.111722 -141.091371) (xy 415.111184 -141.062456) (xy 415.111689 -141.035199) (xy 415.11945 -140.98124)
			(xy 415.134806 -140.928934) (xy 415.157446 -140.879343) (xy 415.186909 -140.833477) (xy 415.222597 -140.792268)
			(xy 415.263783 -140.756555) (xy 415.286444 -140.7414) (xy 415.293426 -140.736567) (xy 415.303945 -140.723249)
			(xy 415.309501 -140.707214) (xy 415.309812 -140.698728) (xy 415.309812 -140.613384) (xy 415.309478 -140.604906)
			(xy 415.303893 -140.588892) (xy 415.293403 -140.575567) (xy 415.286444 -140.570712) (xy 415.263739 -140.55562)
			(xy 415.222545 -140.519903) (xy 415.186852 -140.47869) (xy 415.157386 -140.432817) (xy 415.134746 -140.383219)
			(xy 415.119393 -140.330904) (xy 415.111639 -140.276937) (xy 415.111642 -140.222416) (xy 415.119403 -140.16845)
			(xy 415.134762 -140.116137) (xy 415.157409 -140.066541) (xy 415.186881 -140.020672) (xy 415.222579 -139.979463)
			(xy 415.263777 -139.943752) (xy 415.286444 -139.9286) (xy 415.293426 -139.923767) (xy 415.303945 -139.910449)
			(xy 415.309501 -139.894414) (xy 415.309812 -139.885928) (xy 415.309812 -139.800584) (xy 415.309478 -139.792106)
			(xy 415.303893 -139.776092) (xy 415.293403 -139.762767) (xy 415.286444 -139.757912) (xy 415.263778 -139.742762)
			(xy 415.22258 -139.707056) (xy 415.186883 -139.66585) (xy 415.157414 -139.619983) (xy 415.134773 -139.57039)
			(xy 415.119419 -139.518079) (xy 415.111667 -139.464115) (xy 415.111184 -139.436856) (xy 415.111628 -139.410477)
			(xy 415.118886 -139.358219) (xy 415.133272 -139.30746) (xy 415.154511 -139.259165) (xy 415.182199 -139.214256)
			(xy 415.215808 -139.173587) (xy 415.254697 -139.137934) (xy 415.298126 -139.107977) (xy 415.321496 -139.095734)
			(xy 415.334704 -139.089384) (xy 415.34969 -139.065) (xy 415.34969 -138.945112) (xy 415.334704 -138.920728)
			(xy 415.321496 -138.914378) (xy 415.297876 -138.901988) (xy 415.254014 -138.871641) (xy 415.214801 -138.835486)
			(xy 415.181 -138.794227) (xy 415.153269 -138.748666) (xy 415.132146 -138.69969) (xy 415.124646 -138.674094)
			(xy 415.121344 -138.661648) (xy 415.104072 -138.64336) (xy 414.999424 -138.608562) (xy 414.974786 -138.61288)
			(xy 414.964626 -138.620754) (xy 414.944473 -138.635871) (xy 414.900951 -138.661243) (xy 414.854465 -138.680659)
			(xy 414.805825 -138.693781) (xy 414.755881 -138.700378) (xy 414.730692 -138.700764) (xy 414.703438 -138.700366)
			(xy 414.649485 -138.692607) (xy 414.597185 -138.67725) (xy 414.547603 -138.654605) (xy 414.501748 -138.625136)
			(xy 414.460554 -138.58944) (xy 414.42486 -138.548245) (xy 414.395391 -138.50239) (xy 414.372748 -138.452807)
			(xy 414.357391 -138.400507) (xy 414.349634 -138.346554) (xy 411.383923 -138.346554) (xy 411.377565 -138.349546)
			(xy 411.316772 -138.369299) (xy 411.253982 -138.381277) (xy 411.190186 -138.385291) (xy 411.12639 -138.381277)
			(xy 411.0636 -138.369299) (xy 411.002807 -138.349546) (xy 410.944968 -138.322329) (xy 410.890997 -138.288078)
			(xy 410.841744 -138.247333) (xy 410.797987 -138.200736) (xy 410.760414 -138.149021) (xy 410.72962 -138.093006)
			(xy 410.706088 -138.033573) (xy 410.690191 -137.971659) (xy 410.68218 -137.908241) (xy 400.122865 -137.908241)
			(xy 400.124799 -137.915775) (xy 400.13281 -137.979193) (xy 400.133312 -138.011154) (xy 400.132854 -138.040896)
			(xy 400.125912 -138.099973) (xy 400.11213 -138.157838) (xy 400.091696 -138.213702) (xy 400.064888 -138.266802)
			(xy 400.032071 -138.316414) (xy 399.993695 -138.361862) (xy 399.972276 -138.382502) (xy 399.964148 -138.390122)
			(xy 399.955766 -138.410442) (xy 399.960084 -138.51001) (xy 399.970244 -138.529568) (xy 399.979134 -138.53668)
			(xy 400.004754 -138.557385) (xy 400.050954 -138.60434) (xy 400.090702 -138.656869) (xy 400.12333 -138.714094)
			(xy 400.148293 -138.775053) (xy 400.165172 -138.838727) (xy 400.173683 -138.904048) (xy 400.174206 -138.936984)
			(xy 400.173704 -138.968945) (xy 400.165693 -139.032363) (xy 400.149796 -139.094277) (xy 400.126264 -139.15371)
			(xy 400.09547 -139.209725) (xy 400.057897 -139.26144) (xy 400.01414 -139.308037) (xy 399.964887 -139.348782)
			(xy 399.910916 -139.383033) (xy 399.853077 -139.41025) (xy 399.792284 -139.430003) (xy 399.729494 -139.441981)
			(xy 399.665698 -139.445995) (xy 399.601902 -139.441981) (xy 399.539112 -139.430003) (xy 399.478319 -139.41025)
			(xy 399.42048 -139.383033) (xy 399.366509 -139.348782) (xy 399.317256 -139.308037) (xy 399.273499 -139.26144)
			(xy 399.235926 -139.209725) (xy 399.205132 -139.15371) (xy 399.1816 -139.094277) (xy 399.165703 -139.032363)
			(xy 399.157692 -138.968945) (xy 399.15719 -138.936984) (xy 399.157606 -138.907241) (xy 399.164555 -138.848162)
			(xy 399.178344 -138.790296) (xy 399.198785 -138.734432) (xy 399.2256 -138.681333) (xy 399.258422 -138.631721)
			(xy 399.296805 -138.586275) (xy 399.318226 -138.565636) (xy 399.326354 -138.558016) (xy 399.334736 -138.537696)
			(xy 399.330418 -138.438128) (xy 399.320258 -138.41857) (xy 399.311368 -138.411458) (xy 399.285719 -138.390788)
			(xy 399.23952 -138.343827) (xy 399.199775 -138.291291) (xy 399.16715 -138.234061) (xy 399.142192 -138.173096)
			(xy 399.125319 -138.109417) (xy 399.116815 -138.044092) (xy 399.116296 -138.011154) (xy 392.271466 -138.011154)
			(xy 392.278136 -138.057548) (xy 392.278136 -138.112052) (xy 392.27038 -138.166001) (xy 392.255024 -138.218297)
			(xy 392.232383 -138.267875) (xy 392.202916 -138.313727) (xy 392.167224 -138.354919) (xy 392.126034 -138.390612)
			(xy 392.080182 -138.420079) (xy 392.030604 -138.442722) (xy 391.978309 -138.458078) (xy 391.92436 -138.465836)
			(xy 391.897108 -138.466322) (xy 391.868891 -138.465791) (xy 391.813071 -138.457491) (xy 391.759084 -138.441056)
			(xy 391.708108 -138.416845) (xy 391.661256 -138.385387) (xy 391.64006 -138.366754) (xy 391.631932 -138.359388)
			(xy 391.611866 -138.35253) (xy 391.515092 -138.361928) (xy 391.49655 -138.372342) (xy 391.489946 -138.381232)
			(xy 391.469333 -138.408065) (xy 391.422105 -138.456522) (xy 391.368866 -138.498285) (xy 391.310557 -138.532615)
			(xy 391.248208 -138.558905) (xy 391.182923 -138.576691) (xy 391.115855 -138.585658) (xy 391.082022 -138.58621)
			(xy 391.050059 -138.585726) (xy 390.986636 -138.577717) (xy 390.924718 -138.561821) (xy 390.86528 -138.53829)
			(xy 390.80926 -138.507495) (xy 390.757542 -138.469922) (xy 390.710941 -138.426162) (xy 390.670192 -138.376907)
			(xy 390.635937 -138.322933) (xy 390.608718 -138.265091) (xy 390.588963 -138.204294) (xy 390.576985 -138.1415)
			(xy 390.57297 -138.0777) (xy 386.441978 -138.0777) (xy 386.435099 -138.124442) (xy 386.419031 -138.177849)
			(xy 386.395359 -138.228346) (xy 386.364586 -138.274859) (xy 386.327369 -138.316396) (xy 386.284501 -138.352071)
			(xy 386.236895 -138.381125) (xy 386.185566 -138.402937) (xy 386.131609 -138.417043) (xy 386.076172 -138.423143)
			(xy 386.020438 -138.421106) (xy 385.965595 -138.410976) (xy 385.912811 -138.392969) (xy 385.863211 -138.367468)
			(xy 385.817853 -138.335017) (xy 385.777704 -138.296308) (xy 385.743618 -138.252165) (xy 385.716322 -138.20353)
			(xy 385.696399 -138.151439) (xy 385.684273 -138.097002) (xy 385.680202 -138.04138) (xy 384.73126 -138.04138)
			(xy 384.73126 -138.240516) (xy 384.73191 -138.252493) (xy 384.74279 -138.273831) (xy 384.752088 -138.28141)
			(xy 384.817874 -138.329924) (xy 384.827971 -138.336473) (xy 384.851695 -138.340324) (xy 384.86334 -138.33729)
			(xy 384.906474 -138.324385) (xy 384.994679 -138.306302) (xy 385.084258 -138.297208) (xy 385.129278 -138.29665)
			(xy 385.133088 -138.29665) (xy 385.174076 -138.297294) (xy 385.255677 -138.305186) (xy 385.336204 -138.320553)
			(xy 385.414976 -138.343266) (xy 385.491324 -138.373131) (xy 385.5646 -138.409895) (xy 385.634181 -138.453246)
			(xy 385.699478 -138.502816) (xy 385.759937 -138.558184) (xy 385.815043 -138.618881) (xy 385.864331 -138.684392)
			(xy 385.90738 -138.754161) (xy 385.943827 -138.827594) (xy 385.973362 -138.904071) (xy 385.995733 -138.98294)
			(xy 386.010752 -139.063534) (xy 386.018291 -139.145167) (xy 386.018786 -139.186158) (xy 386.018328 -139.227262)
			(xy 386.010746 -139.30912) (xy 385.995643 -139.389929) (xy 385.973149 -139.468999) (xy 385.971727 -139.47267)
			(xy 409.722322 -139.47267) (xy 409.726366 -139.394216) (xy 409.738455 -139.316594) (xy 409.758462 -139.240626)
			(xy 409.786173 -139.167118) (xy 409.821296 -139.096849) (xy 409.863458 -139.030564) (xy 409.912212 -138.968965)
			(xy 409.967041 -138.912705) (xy 410.027364 -138.862381) (xy 410.092542 -138.818527) (xy 410.161883 -138.781606)
			(xy 410.234654 -138.752011) (xy 410.310081 -138.730056) (xy 410.387366 -138.715972) (xy 410.46569 -138.709909)
			(xy 410.544222 -138.711932) (xy 410.62213 -138.722018) (xy 410.698587 -138.740062) (xy 410.772785 -138.765872)
			(xy 410.843935 -138.799174) (xy 410.911284 -138.839615) (xy 410.974118 -138.886766) (xy 411.03177 -138.940129)
			(xy 411.08363 -138.999136) (xy 411.129149 -139.063163) (xy 411.167842 -139.131531) (xy 411.199301 -139.203515)
			(xy 411.223192 -139.278352) (xy 411.239261 -139.355249) (xy 411.247338 -139.433391) (xy 411.247844 -139.47267)
			(xy 411.247338 -139.511949) (xy 411.239261 -139.590091) (xy 411.223192 -139.666988) (xy 411.199301 -139.741825)
			(xy 411.167842 -139.813809) (xy 411.129149 -139.882177) (xy 411.08363 -139.946204) (xy 411.03177 -140.005211)
			(xy 410.974118 -140.058574) (xy 410.911284 -140.105725) (xy 410.843935 -140.146166) (xy 410.772785 -140.179468)
			(xy 410.698587 -140.205278) (xy 410.62213 -140.223322) (xy 410.544222 -140.233408) (xy 410.46569 -140.235431)
			(xy 410.387366 -140.229368) (xy 410.310081 -140.215284) (xy 410.234654 -140.193329) (xy 410.161883 -140.163734)
			(xy 410.092542 -140.126813) (xy 410.027364 -140.082959) (xy 409.967041 -140.032635) (xy 409.912212 -139.976375)
			(xy 409.863458 -139.914776) (xy 409.821296 -139.848491) (xy 409.786173 -139.778222) (xy 409.758462 -139.704714)
			(xy 409.738455 -139.628746) (xy 409.726366 -139.551124) (xy 409.722322 -139.47267) (xy 385.971727 -139.47267)
			(xy 385.943454 -139.545657) (xy 385.906813 -139.619247) (xy 385.863537 -139.689143) (xy 385.813997 -139.754747)
			(xy 385.758615 -139.815501) (xy 385.697863 -139.870884) (xy 385.63226 -139.920426) (xy 385.562365 -139.963703)
			(xy 385.488775 -140.000346) (xy 385.412118 -140.030043) (xy 385.333048 -140.052539) (xy 385.25224 -140.067643)
			(xy 385.170382 -140.075227) (xy 385.129278 -140.075666) (xy 385.129024 -140.075666) (xy 385.084046 -140.075104)
			(xy 384.994549 -140.066022) (xy 384.906429 -140.047938) (xy 384.86334 -140.035026) (xy 384.851696 -140.032002)
			(xy 384.827984 -140.035865) (xy 384.817874 -140.042392) (xy 384.752088 -140.090906) (xy 384.742824 -140.098509)
			(xy 384.731959 -140.119836) (xy 384.73126 -140.1318) (xy 384.73126 -140.537438) (xy 407.677872 -140.537438)
			(xy 407.681943 -140.481816) (xy 407.694069 -140.427379) (xy 407.713992 -140.375288) (xy 407.741288 -140.326653)
			(xy 407.775374 -140.28251) (xy 407.815523 -140.243801) (xy 407.860881 -140.21135) (xy 407.910481 -140.185849)
			(xy 407.963265 -140.167842) (xy 408.018108 -140.157712) (xy 408.073842 -140.155675) (xy 408.129279 -140.161775)
			(xy 408.183236 -140.175881) (xy 408.234565 -140.197693) (xy 408.282171 -140.226747) (xy 408.325039 -140.262422)
			(xy 408.362256 -140.303959) (xy 408.393029 -140.350472) (xy 408.416701 -140.400969) (xy 408.432769 -140.454376)
			(xy 408.440889 -140.509552) (xy 408.441398 -140.537438) (xy 408.440889 -140.565324) (xy 408.432769 -140.6205)
			(xy 408.416701 -140.673907) (xy 408.393029 -140.724404) (xy 408.362256 -140.770917) (xy 408.325039 -140.812454)
			(xy 408.282171 -140.848129) (xy 408.234565 -140.877183) (xy 408.183236 -140.898995) (xy 408.129279 -140.913101)
			(xy 408.073842 -140.919201) (xy 408.018108 -140.917164) (xy 407.963265 -140.907034) (xy 407.910481 -140.889027)
			(xy 407.860881 -140.863526) (xy 407.815523 -140.831075) (xy 407.775374 -140.792366) (xy 407.741288 -140.748223)
			(xy 407.713992 -140.699588) (xy 407.694069 -140.647497) (xy 407.681943 -140.59306) (xy 407.677872 -140.537438)
			(xy 384.73126 -140.537438) (xy 384.73126 -140.6906) (xy 384.731686 -140.700351) (xy 384.738963 -140.718442)
			(xy 384.752494 -140.732482) (xy 384.761232 -140.736828) (xy 384.85953 -140.781024) (xy 384.889248 -140.776452)
			(xy 384.900424 -140.766292) (xy 384.921525 -140.748127) (xy 384.968 -140.71747) (xy 385.018433 -140.693884)
			(xy 385.071757 -140.677872) (xy 385.12684 -140.66977) (xy 385.154678 -140.669264) (xy 385.18419 -140.669818)
			(xy 385.24251 -140.678903) (xy 385.298741 -140.696845) (xy 385.351545 -140.723218) (xy 385.375912 -140.739876)
			(xy 385.385548 -140.745969) (xy 385.407974 -140.749909) (xy 385.429921 -140.743846) (xy 385.438904 -140.736828)
			(xy 385.46874 -140.71131) (xy 385.532757 -140.665854) (xy 385.601105 -140.627215) (xy 385.673061 -140.595804)
			(xy 385.747864 -140.571951) (xy 385.824722 -140.555911) (xy 385.902821 -140.547852) (xy 385.942078 -140.547344)
			(xy 385.980269 -140.547805) (xy 386.056268 -140.555432) (xy 386.131124 -140.570622) (xy 386.204085 -140.593222)
			(xy 386.27442 -140.623006) (xy 386.341424 -140.659676) (xy 386.404424 -140.702862) (xy 386.462789 -140.752134)
			(xy 386.515933 -140.806995) (xy 386.563324 -140.866897) (xy 386.604487 -140.931238) (xy 386.639008 -140.999373)
			(xy 386.666541 -141.07062) (xy 386.686811 -141.144262) (xy 386.693664 -141.181836) (xy 386.696966 -141.200124)
			(xy 386.72516 -141.224) (xy 388.799832 -141.224) (xy 388.828788 -141.197076) (xy 388.830566 -141.177264)
			(xy 388.83364 -141.145869) (xy 388.846577 -141.084127) (xy 388.867052 -141.02446) (xy 388.894751 -140.967784)
			(xy 388.929249 -140.91497) (xy 388.970015 -140.866828) (xy 389.016423 -140.8241) (xy 389.06776 -140.787441)
			(xy 389.123238 -140.757414) (xy 389.182005 -140.734481) (xy 389.243157 -140.718993) (xy 389.305755 -140.71119)
			(xy 389.368837 -140.71119) (xy 389.431435 -140.718993) (xy 389.492587 -140.734481) (xy 389.551354 -140.757414)
			(xy 389.606832 -140.787441) (xy 389.658169 -140.8241) (xy 389.704577 -140.866828) (xy 389.745343 -140.91497)
			(xy 389.779841 -140.967784) (xy 389.80754 -141.02446) (xy 389.828015 -141.084127) (xy 389.840952 -141.145869)
			(xy 389.844026 -141.177264) (xy 389.845804 -141.197076) (xy 389.87476 -141.224) (xy 403.234906 -141.224)
			(xy 403.245356 -141.223443) (xy 403.264509 -141.21506) (xy 403.27199 -141.207744) (xy 403.330156 -141.145514)
			(xy 403.337014 -141.125702) (xy 403.336252 -141.115034) (xy 403.335236 -141.087602) (xy 403.335699 -141.06035)
			(xy 403.343456 -141.006401) (xy 403.358813 -140.954106) (xy 403.381456 -140.904528) (xy 403.410924 -140.858678)
			(xy 403.446618 -140.817489) (xy 403.487812 -140.781799) (xy 403.533665 -140.752335) (xy 403.583245 -140.729698)
			(xy 403.635542 -140.714347) (xy 403.689492 -140.706596) (xy 403.716744 -140.706094) (xy 403.744455 -140.706587)
			(xy 403.799294 -140.714605) (xy 403.852394 -140.730479) (xy 403.902635 -140.753875) (xy 403.94896 -140.7843)
			(xy 403.969982 -140.80236) (xy 403.977094 -140.80871) (xy 403.994366 -140.81506) (xy 404.080726 -140.81506)
			(xy 404.097998 -140.80871) (xy 404.10511 -140.80236) (xy 404.126153 -140.784325) (xy 404.172473 -140.753898)
			(xy 404.222709 -140.730496) (xy 404.275804 -140.714612) (xy 404.330638 -140.706582) (xy 404.358348 -140.706094)
			(xy 404.38828 -140.706674) (xy 404.447412 -140.716011) (xy 404.504361 -140.734465) (xy 404.557731 -140.761583)
			(xy 404.606213 -140.7967) (xy 404.648618 -140.838955) (xy 404.666704 -140.862812) (xy 404.674307 -140.872076)
			(xy 404.695634 -140.882942) (xy 404.707598 -140.88364) (xy 404.789894 -140.88364) (xy 404.801873 -140.882995)
			(xy 404.823219 -140.87212) (xy 404.830788 -140.862812) (xy 404.848903 -140.838979) (xy 404.891306 -140.796726)
			(xy 404.939782 -140.761608) (xy 404.993146 -140.734485) (xy 405.050088 -140.716022) (xy 405.109214 -140.706672)
			(xy 405.139144 -140.706094) (xy 405.166855 -140.706587) (xy 405.221694 -140.714605) (xy 405.274794 -140.730479)
			(xy 405.325035 -140.753875) (xy 405.37136 -140.7843) (xy 405.392382 -140.80236) (xy 405.399494 -140.80871)
			(xy 405.416766 -140.81506) (xy 405.503126 -140.81506) (xy 405.520398 -140.80871) (xy 405.52751 -140.80236)
			(xy 405.548553 -140.784325) (xy 405.594873 -140.753898) (xy 405.645109 -140.730496) (xy 405.698204 -140.714612)
			(xy 405.753038 -140.706582) (xy 405.780748 -140.706094) (xy 405.807997 -140.706583) (xy 405.861939 -140.714345)
			(xy 405.914228 -140.729704) (xy 405.963799 -140.752348) (xy 406.009643 -140.781815) (xy 406.050827 -140.817507)
			(xy 406.086513 -140.858696) (xy 406.115975 -140.904543) (xy 406.138613 -140.954117) (xy 406.153965 -141.006408)
			(xy 406.16172 -141.060351) (xy 406.16172 -141.114849) (xy 406.153965 -141.168792) (xy 406.138613 -141.221083)
			(xy 406.115975 -141.270657) (xy 406.086513 -141.316504) (xy 406.058864 -141.348417) (xy 410.006286 -141.348417)
			(xy 410.006286 -141.284495) (xy 410.014297 -141.221077) (xy 410.030194 -141.159163) (xy 410.053726 -141.09973)
			(xy 410.08452 -141.043715) (xy 410.122093 -140.992) (xy 410.16585 -140.945403) (xy 410.215103 -140.904658)
			(xy 410.269074 -140.870407) (xy 410.326913 -140.84319) (xy 410.387706 -140.823437) (xy 410.450496 -140.811459)
			(xy 410.514292 -140.807446) (xy 410.578088 -140.811459) (xy 410.640878 -140.823437) (xy 410.701671 -140.84319)
			(xy 410.75951 -140.870407) (xy 410.813481 -140.904658) (xy 410.862734 -140.945403) (xy 410.906491 -140.992)
			(xy 410.944064 -141.043715) (xy 410.974858 -141.09973) (xy 410.99839 -141.159163) (xy 411.014287 -141.221077)
			(xy 411.022298 -141.284495) (xy 411.0228 -141.316456) (xy 411.022298 -141.348417) (xy 411.014287 -141.411835)
			(xy 410.99839 -141.473749) (xy 410.974858 -141.533182) (xy 410.944064 -141.589197) (xy 410.906491 -141.640912)
			(xy 410.862734 -141.687509) (xy 410.813481 -141.728254) (xy 410.75951 -141.762505) (xy 410.701671 -141.789722)
			(xy 410.640878 -141.809475) (xy 410.578088 -141.821453) (xy 410.514292 -141.825467) (xy 410.450496 -141.821453)
			(xy 410.387706 -141.809475) (xy 410.326913 -141.789722) (xy 410.269074 -141.762505) (xy 410.215103 -141.728254)
			(xy 410.16585 -141.687509) (xy 410.122093 -141.640912) (xy 410.08452 -141.589197) (xy 410.053726 -141.533182)
			(xy 410.030194 -141.473749) (xy 410.014297 -141.411835) (xy 410.006286 -141.348417) (xy 406.058864 -141.348417)
			(xy 406.050827 -141.357693) (xy 406.009643 -141.393385) (xy 405.963799 -141.422852) (xy 405.914228 -141.445496)
			(xy 405.861939 -141.460855) (xy 405.807997 -141.468617) (xy 405.780748 -141.46911) (xy 405.753037 -141.468616)
			(xy 405.698199 -141.460598) (xy 405.645099 -141.444723) (xy 405.594858 -141.421326) (xy 405.548535 -141.390901)
			(xy 405.52751 -141.372844) (xy 405.520398 -141.366494) (xy 405.503126 -141.360144) (xy 405.416766 -141.360144)
			(xy 405.399494 -141.366494) (xy 405.392382 -141.372844) (xy 405.371338 -141.390878) (xy 405.325019 -141.421305)
			(xy 405.274782 -141.444705) (xy 405.221688 -141.460587) (xy 405.166853 -141.468616) (xy 405.139144 -141.46911)
			(xy 405.109212 -141.46853) (xy 405.050081 -141.459191) (xy 404.993133 -141.440737) (xy 404.939764 -141.413618)
			(xy 404.891282 -141.378501) (xy 404.848877 -141.336246) (xy 404.830788 -141.312392) (xy 404.823185 -141.303129)
			(xy 404.801857 -141.292266) (xy 404.789894 -141.291564) (xy 404.707598 -141.291564) (xy 404.69562 -141.292211)
			(xy 404.674277 -141.303088) (xy 404.666704 -141.312392) (xy 404.65019 -141.334247) (xy 404.611928 -141.373445)
			(xy 404.568454 -141.40677) (xy 404.520663 -141.433537) (xy 404.469536 -141.453197) (xy 404.44293 -141.459712)
			(xy 404.429214 -141.46276) (xy 404.409148 -141.481556) (xy 404.3807 -141.580616) (xy 404.378565 -141.589432)
			(xy 404.379949 -141.607506) (xy 404.38751 -141.623981) (xy 404.393654 -141.630654) (xy 405.34082 -142.57782)
			(xy 407.889708 -142.57782) (xy 407.893779 -142.522198) (xy 407.905905 -142.467761) (xy 407.925828 -142.41567)
			(xy 407.953124 -142.367035) (xy 407.98721 -142.322892) (xy 408.027359 -142.284183) (xy 408.072717 -142.251732)
			(xy 408.122317 -142.226231) (xy 408.175101 -142.208224) (xy 408.229944 -142.198094) (xy 408.285678 -142.196057)
			(xy 408.341115 -142.202157) (xy 408.395072 -142.216263) (xy 408.446401 -142.238075) (xy 408.494007 -142.267129)
			(xy 408.536875 -142.302804) (xy 408.574092 -142.344341) (xy 408.604865 -142.390854) (xy 408.628537 -142.441351)
			(xy 408.644605 -142.494758) (xy 408.652725 -142.549934) (xy 408.653234 -142.57782) (xy 408.652725 -142.605706)
			(xy 408.644605 -142.660882) (xy 408.628537 -142.714289) (xy 408.604865 -142.764786) (xy 408.574092 -142.811299)
			(xy 408.536875 -142.852836) (xy 408.494007 -142.888511) (xy 408.446401 -142.917565) (xy 408.395072 -142.939377)
			(xy 408.341115 -142.953483) (xy 408.285678 -142.959583) (xy 408.229944 -142.957546) (xy 408.175101 -142.947416)
			(xy 408.122317 -142.929409) (xy 408.072717 -142.903908) (xy 408.027359 -142.871457) (xy 407.98721 -142.832748)
			(xy 407.953124 -142.788605) (xy 407.925828 -142.73997) (xy 407.905905 -142.687879) (xy 407.893779 -142.633442)
			(xy 407.889708 -142.57782) (xy 405.34082 -142.57782) (xy 406.061926 -143.298926) (xy 411.705296 -143.298926)
			(xy 411.709367 -143.243304) (xy 411.721493 -143.188867) (xy 411.741416 -143.136776) (xy 411.768712 -143.088141)
			(xy 411.802798 -143.043998) (xy 411.842947 -143.005289) (xy 411.888305 -142.972838) (xy 411.937905 -142.947337)
			(xy 411.990689 -142.92933) (xy 412.045532 -142.9192) (xy 412.101266 -142.917163) (xy 412.156703 -142.923263)
			(xy 412.21066 -142.937369) (xy 412.261989 -142.959181) (xy 412.309595 -142.988235) (xy 412.352463 -143.02391)
			(xy 412.38968 -143.065447) (xy 412.420453 -143.11196) (xy 412.444125 -143.162457) (xy 412.460193 -143.215864)
			(xy 412.468313 -143.27104) (xy 412.468822 -143.298926) (xy 412.468313 -143.326812) (xy 412.460193 -143.381988)
			(xy 412.444125 -143.435395) (xy 412.420453 -143.485892) (xy 412.38968 -143.532405) (xy 412.352463 -143.573942)
			(xy 412.309595 -143.609617) (xy 412.261989 -143.638671) (xy 412.21066 -143.660483) (xy 412.156703 -143.674589)
			(xy 412.101266 -143.680689) (xy 412.045532 -143.678652) (xy 411.990689 -143.668522) (xy 411.937905 -143.650515)
			(xy 411.888305 -143.625014) (xy 411.842947 -143.592563) (xy 411.802798 -143.553854) (xy 411.768712 -143.509711)
			(xy 411.741416 -143.461076) (xy 411.721493 -143.408985) (xy 411.709367 -143.354548) (xy 411.705296 -143.298926)
			(xy 406.061926 -143.298926) (xy 410.229558 -147.466558) (xy 410.2364 -147.473958) (xy 410.24412 -147.492556)
			(xy 410.244544 -147.502626) (xy 410.244544 -149.52935) (xy 411.400492 -149.52935) (xy 411.400492 -149.47485)
			(xy 411.408248 -149.420904) (xy 411.423603 -149.368612) (xy 411.446243 -149.319037) (xy 411.475708 -149.273188)
			(xy 411.511398 -149.231999) (xy 411.552586 -149.196309) (xy 411.598435 -149.166844) (xy 411.64801 -149.144204)
			(xy 411.700302 -149.128849) (xy 411.754248 -149.121092) (xy 411.781498 -149.120606) (xy 411.807541 -149.121039)
			(xy 411.859144 -149.128126) (xy 411.909302 -149.142167) (xy 411.957084 -149.162901) (xy 412.0016 -149.189944)
			(xy 412.042023 -149.222792) (xy 412.060136 -149.24151) (xy 412.067756 -149.249638) (xy 412.08833 -149.258274)
			(xy 412.18739 -149.25421) (xy 412.207202 -149.24405) (xy 412.21406 -149.235414) (xy 412.232259 -149.213287)
			(xy 412.274154 -149.174213) (xy 412.321423 -149.141843) (xy 412.373001 -149.116908) (xy 412.427728 -149.099967)
			(xy 412.484373 -149.091401) (xy 412.513018 -149.090888) (xy 412.540268 -149.091383) (xy 412.594213 -149.099142)
			(xy 412.646505 -149.114498) (xy 412.69608 -149.13714) (xy 412.741928 -149.166606) (xy 412.783115 -149.202298)
			(xy 412.818804 -149.243487) (xy 412.848269 -149.289336) (xy 412.870908 -149.338911) (xy 412.886262 -149.391204)
			(xy 412.894018 -149.44515) (xy 412.894018 -149.49965) (xy 412.889747 -149.529353) (xy 413.322969 -149.529353)
			(xy 413.322969 -149.474847) (xy 413.330727 -149.420896) (xy 413.346083 -149.368598) (xy 413.368727 -149.319018)
			(xy 413.398196 -149.273166) (xy 413.433891 -149.231974) (xy 413.475085 -149.196282) (xy 413.520939 -149.166815)
			(xy 413.570521 -149.144175) (xy 413.622819 -149.128822) (xy 413.676771 -149.121068) (xy 413.704024 -149.120606)
			(xy 413.729483 -149.121027) (xy 413.77995 -149.127792) (xy 413.829068 -149.141212) (xy 413.875963 -149.161049)
			(xy 413.919802 -149.186949) (xy 413.959805 -149.218452) (xy 413.977836 -149.23643) (xy 413.985456 -149.244304)
			(xy 414.00476 -149.252178) (xy 414.101534 -149.249384) (xy 414.12033 -149.240494) (xy 414.127442 -149.232366)
			(xy 414.145677 -149.21212) (xy 414.186869 -149.176457) (xy 414.232714 -149.147013) (xy 414.28228 -149.124388)
			(xy 414.334559 -149.109041) (xy 414.388489 -149.101284) (xy 414.415732 -149.100794) (xy 414.442982 -149.101278)
			(xy 414.496926 -149.109038) (xy 414.549218 -149.124396) (xy 414.598791 -149.147039) (xy 414.644638 -149.176507)
			(xy 414.685824 -149.212198) (xy 414.721513 -149.253388) (xy 414.750976 -149.299237) (xy 414.773615 -149.348812)
			(xy 414.788969 -149.401105) (xy 414.796724 -149.45505) (xy 414.796724 -149.50955) (xy 414.788969 -149.563495)
			(xy 414.773615 -149.615788) (xy 414.750976 -149.665363) (xy 414.721513 -149.711212) (xy 414.685824 -149.752402)
			(xy 414.644638 -149.788093) (xy 414.598791 -149.817561) (xy 414.549218 -149.840204) (xy 414.496926 -149.855562)
			(xy 414.442982 -149.863322) (xy 414.415732 -149.86381) (xy 414.390272 -149.863413) (xy 414.339805 -149.856642)
			(xy 414.290686 -149.843217) (xy 414.243791 -149.823376) (xy 414.199953 -149.797472) (xy 414.159951 -149.765966)
			(xy 414.14192 -149.747986) (xy 414.1343 -149.740112) (xy 414.114996 -149.732238) (xy 414.018222 -149.735032)
			(xy 413.999426 -149.743922) (xy 413.992314 -149.75205) (xy 413.974105 -149.772321) (xy 413.932907 -149.807981)
			(xy 413.887057 -149.837421) (xy 413.837486 -149.860042) (xy 413.785202 -149.875384) (xy 413.731268 -149.883136)
			(xy 413.704024 -149.883622) (xy 413.676771 -149.883132) (xy 413.622819 -149.875378) (xy 413.570521 -149.860025)
			(xy 413.520939 -149.837385) (xy 413.475085 -149.807918) (xy 413.433891 -149.772226) (xy 413.398196 -149.731034)
			(xy 413.368727 -149.685182) (xy 413.346083 -149.635602) (xy 413.330727 -149.583304) (xy 413.322969 -149.529353)
			(xy 412.889747 -149.529353) (xy 412.886262 -149.553596) (xy 412.870908 -149.605889) (xy 412.848269 -149.655464)
			(xy 412.818804 -149.701313) (xy 412.783115 -149.742502) (xy 412.741928 -149.778194) (xy 412.69608 -149.80766)
			(xy 412.646505 -149.830302) (xy 412.594213 -149.845658) (xy 412.540268 -149.853417) (xy 412.513018 -149.853904)
			(xy 412.486975 -149.853457) (xy 412.435374 -149.846373) (xy 412.385216 -149.832334) (xy 412.337434 -149.811602)
			(xy 412.292917 -149.784562) (xy 412.252494 -149.751717) (xy 412.23438 -149.733) (xy 412.22676 -149.724872)
			(xy 412.206186 -149.716236) (xy 412.107126 -149.7203) (xy 412.087314 -149.73046) (xy 412.080456 -149.739096)
			(xy 412.062251 -149.761217) (xy 412.020356 -149.800292) (xy 411.973089 -149.832661) (xy 411.921512 -149.857598)
			(xy 411.866787 -149.87454) (xy 411.810142 -149.883108) (xy 411.781498 -149.883622) (xy 411.754248 -149.883108)
			(xy 411.700302 -149.875351) (xy 411.64801 -149.859996) (xy 411.598435 -149.837356) (xy 411.552586 -149.807891)
			(xy 411.511398 -149.772201) (xy 411.475708 -149.731012) (xy 411.446243 -149.685163) (xy 411.423603 -149.635588)
			(xy 411.408248 -149.583296) (xy 411.400492 -149.52935) (xy 410.244544 -149.52935) (xy 410.244544 -152.416048)
			(xy 423.422102 -152.416048) (xy 423.422102 -152.361552) (xy 423.429857 -152.307611) (xy 423.44521 -152.255322)
			(xy 423.467847 -152.205751) (xy 423.497308 -152.159905) (xy 423.532993 -152.118718) (xy 423.574176 -152.083029)
			(xy 423.620019 -152.053564) (xy 423.669589 -152.030922) (xy 423.721876 -152.015565) (xy 423.775816 -152.007805)
			(xy 423.803064 -152.007316) (xy 423.83198 -152.007854) (xy 423.889151 -152.016578) (xy 423.944349 -152.033832)
			(xy 423.996311 -152.05922) (xy 424.043846 -152.09216) (xy 424.085863 -152.131898) (xy 424.104054 -152.154382)
			(xy 424.111626 -152.163133) (xy 424.132378 -152.173319) (xy 424.143932 -152.17394) (xy 424.224196 -152.17394)
			(xy 424.235767 -152.173388) (xy 424.256539 -152.163183) (xy 424.264074 -152.154382) (xy 424.280827 -152.133599)
			(xy 424.319181 -152.096469) (xy 424.362335 -152.065047) (xy 424.409449 -152.039948) (xy 424.459601 -152.021662)
			(xy 424.511812 -152.010545) (xy 424.565064 -152.006815) (xy 424.618316 -152.010545) (xy 424.670527 -152.021662)
			(xy 424.720679 -152.039948) (xy 424.767793 -152.065047) (xy 424.810947 -152.096469) (xy 424.849301 -152.133599)
			(xy 424.866054 -152.154382) (xy 424.873626 -152.163133) (xy 424.894378 -152.173319) (xy 424.905932 -152.17394)
			(xy 424.986196 -152.17394) (xy 424.997767 -152.173388) (xy 425.018539 -152.163183) (xy 425.026074 -152.154382)
			(xy 425.042827 -152.133599) (xy 425.081181 -152.096469) (xy 425.124335 -152.065047) (xy 425.171449 -152.039948)
			(xy 425.221601 -152.021662) (xy 425.273812 -152.010545) (xy 425.327064 -152.006815) (xy 425.380316 -152.010545)
			(xy 425.432527 -152.021662) (xy 425.482679 -152.039948) (xy 425.529793 -152.065047) (xy 425.572947 -152.096469)
			(xy 425.611301 -152.133599) (xy 425.628054 -152.154382) (xy 425.635626 -152.163133) (xy 425.656378 -152.173319)
			(xy 425.667932 -152.17394) (xy 425.748196 -152.17394) (xy 425.759767 -152.173388) (xy 425.780539 -152.163183)
			(xy 425.788074 -152.154382) (xy 425.806275 -152.131907) (xy 425.848293 -152.092172) (xy 425.895826 -152.059233)
			(xy 425.947785 -152.033843) (xy 426.002981 -152.016585) (xy 426.060149 -152.007853) (xy 426.089064 -152.007316)
			(xy 426.11632 -152.007728) (xy 426.170279 -152.015482) (xy 426.222584 -152.030836) (xy 426.272172 -152.053478)
			(xy 426.318032 -152.082946) (xy 426.359232 -152.118642) (xy 426.394932 -152.159839) (xy 426.424405 -152.205696)
			(xy 426.447052 -152.255282) (xy 426.462411 -152.307586) (xy 426.470169 -152.361544) (xy 426.470169 -152.416056)
			(xy 426.462411 -152.470014) (xy 426.447052 -152.522318) (xy 426.424405 -152.571904) (xy 426.394932 -152.617761)
			(xy 426.359232 -152.658958) (xy 426.318032 -152.694654) (xy 426.272172 -152.724122) (xy 426.222584 -152.746764)
			(xy 426.170279 -152.762118) (xy 426.11632 -152.769872) (xy 426.089064 -152.770332) (xy 426.060148 -152.769793)
			(xy 426.002976 -152.761072) (xy 425.947777 -152.74382) (xy 425.895814 -152.718432) (xy 425.84828 -152.685491)
			(xy 425.806264 -152.645751) (xy 425.788074 -152.623266) (xy 425.780525 -152.614491) (xy 425.759756 -152.604316)
			(xy 425.748196 -152.603708) (xy 425.667932 -152.603708) (xy 425.656366 -152.604294) (xy 425.635595 -152.614477)
			(xy 425.628054 -152.623266) (xy 425.611301 -152.644049) (xy 425.572947 -152.681179) (xy 425.529793 -152.712601)
			(xy 425.482679 -152.7377) (xy 425.432527 -152.755986) (xy 425.380316 -152.767103) (xy 425.327064 -152.770833)
			(xy 425.273812 -152.767103) (xy 425.221601 -152.755986) (xy 425.171449 -152.7377) (xy 425.124335 -152.712601)
			(xy 425.081181 -152.681179) (xy 425.042827 -152.644049) (xy 425.026074 -152.623266) (xy 425.018525 -152.614491)
			(xy 424.997756 -152.604316) (xy 424.986196 -152.603708) (xy 424.905932 -152.603708) (xy 424.894366 -152.604294)
			(xy 424.873595 -152.614477) (xy 424.866054 -152.623266) (xy 424.849301 -152.644049) (xy 424.810947 -152.681179)
			(xy 424.767793 -152.712601) (xy 424.720679 -152.7377) (xy 424.670527 -152.755986) (xy 424.618316 -152.767103)
			(xy 424.565064 -152.770833) (xy 424.511812 -152.767103) (xy 424.459601 -152.755986) (xy 424.409449 -152.7377)
			(xy 424.362335 -152.712601) (xy 424.319181 -152.681179) (xy 424.280827 -152.644049) (xy 424.264074 -152.623266)
			(xy 424.256525 -152.614491) (xy 424.235756 -152.604316) (xy 424.224196 -152.603708) (xy 424.143932 -152.603708)
			(xy 424.132366 -152.604294) (xy 424.111595 -152.614477) (xy 424.104054 -152.623266) (xy 424.085824 -152.645717)
			(xy 424.043813 -152.685455) (xy 423.996287 -152.718399) (xy 423.944333 -152.743794) (xy 423.889142 -152.761057)
			(xy 423.831978 -152.769793) (xy 423.803064 -152.770332) (xy 423.775816 -152.769795) (xy 423.721876 -152.762035)
			(xy 423.669589 -152.746678) (xy 423.620019 -152.724036) (xy 423.574176 -152.694571) (xy 423.532993 -152.658882)
			(xy 423.497308 -152.617695) (xy 423.467847 -152.571849) (xy 423.44521 -152.522278) (xy 423.429857 -152.469989)
			(xy 423.422102 -152.416048) (xy 410.244544 -152.416048) (xy 410.244544 -154.82755) (xy 423.422078 -154.82755)
			(xy 423.422078 -154.77305) (xy 423.429833 -154.719106) (xy 423.445187 -154.666814) (xy 423.467825 -154.617239)
			(xy 423.497288 -154.57139) (xy 423.532976 -154.530201) (xy 423.574162 -154.49451) (xy 423.620007 -154.465042)
			(xy 423.66958 -154.442399) (xy 423.721871 -154.427041) (xy 423.775814 -154.41928) (xy 423.803064 -154.418792)
			(xy 423.831982 -154.419302) (xy 423.889155 -154.428028) (xy 423.944355 -154.445285) (xy 423.996318 -154.470678)
			(xy 424.043851 -154.503625) (xy 424.085865 -154.54337) (xy 424.104054 -154.565858) (xy 424.11163 -154.574605)
			(xy 424.132378 -154.584794) (xy 424.143932 -154.585416) (xy 424.224196 -154.585416) (xy 424.235763 -154.584838)
			(xy 424.256533 -154.574648) (xy 424.264074 -154.565858) (xy 424.280827 -154.545075) (xy 424.319181 -154.507945)
			(xy 424.362335 -154.476523) (xy 424.409449 -154.451424) (xy 424.459601 -154.433138) (xy 424.511812 -154.422021)
			(xy 424.565064 -154.418291) (xy 424.618316 -154.422021) (xy 424.670527 -154.433138) (xy 424.720679 -154.451424)
			(xy 424.767793 -154.476523) (xy 424.810947 -154.507945) (xy 424.849301 -154.545075) (xy 424.866054 -154.565858)
			(xy 424.87363 -154.574605) (xy 424.894378 -154.584794) (xy 424.905932 -154.585416) (xy 424.986196 -154.585416)
			(xy 424.997763 -154.584838) (xy 425.018533 -154.574648) (xy 425.026074 -154.565858) (xy 425.042827 -154.545075)
			(xy 425.081181 -154.507945) (xy 425.124335 -154.476523) (xy 425.171449 -154.451424) (xy 425.221601 -154.433138)
			(xy 425.273812 -154.422021) (xy 425.327064 -154.418291) (xy 425.380316 -154.422021) (xy 425.432527 -154.433138)
			(xy 425.482679 -154.451424) (xy 425.529793 -154.476523) (xy 425.572947 -154.507945) (xy 425.611301 -154.545075)
			(xy 425.628054 -154.565858) (xy 425.63563 -154.574605) (xy 425.656378 -154.584794) (xy 425.667932 -154.585416)
			(xy 425.748196 -154.585416) (xy 425.759763 -154.584838) (xy 425.780533 -154.574648) (xy 425.788074 -154.565858)
			(xy 425.806269 -154.543378) (xy 425.848289 -154.503645) (xy 425.895824 -154.470707) (xy 425.947784 -154.445318)
			(xy 426.00298 -154.42806) (xy 426.060148 -154.419329) (xy 426.089064 -154.418792) (xy 426.116319 -154.419253)
			(xy 426.170273 -154.427006) (xy 426.222576 -154.442359) (xy 426.27216 -154.464999) (xy 426.318018 -154.494466)
			(xy 426.359215 -154.53016) (xy 426.394912 -154.571353) (xy 426.424384 -154.617208) (xy 426.447029 -154.666791)
			(xy 426.462387 -154.719091) (xy 426.470145 -154.773046) (xy 426.470145 -154.827554) (xy 426.462387 -154.881509)
			(xy 426.447029 -154.933809) (xy 426.424384 -154.983392) (xy 426.394912 -155.029247) (xy 426.359215 -155.07044)
			(xy 426.318018 -155.106134) (xy 426.27216 -155.135601) (xy 426.222576 -155.158241) (xy 426.170273 -155.173594)
			(xy 426.116319 -155.181347) (xy 426.089064 -155.181808) (xy 426.060147 -155.181278) (xy 426.002975 -155.172557)
			(xy 425.947775 -155.155303) (xy 425.895812 -155.129914) (xy 425.848278 -155.09697) (xy 425.806263 -155.057228)
			(xy 425.788074 -155.034742) (xy 425.780529 -155.025963) (xy 425.759757 -155.015791) (xy 425.748196 -155.015184)
			(xy 425.667932 -155.015184) (xy 425.656367 -155.015779) (xy 425.635597 -155.025957) (xy 425.628054 -155.034742)
			(xy 425.611301 -155.055525) (xy 425.572947 -155.092655) (xy 425.529793 -155.124077) (xy 425.482679 -155.149176)
			(xy 425.432527 -155.167462) (xy 425.380316 -155.178579) (xy 425.327064 -155.182309) (xy 425.273812 -155.178579)
			(xy 425.221601 -155.167462) (xy 425.171449 -155.149176) (xy 425.124335 -155.124077) (xy 425.081181 -155.092655)
			(xy 425.042827 -155.055525) (xy 425.026074 -155.034742) (xy 425.018529 -155.025963) (xy 424.997757 -155.015791)
			(xy 424.986196 -155.015184) (xy 424.905932 -155.015184) (xy 424.894367 -155.015779) (xy 424.873597 -155.025957)
			(xy 424.866054 -155.034742) (xy 424.849301 -155.055525) (xy 424.810947 -155.092655) (xy 424.767793 -155.124077)
			(xy 424.720679 -155.149176) (xy 424.670527 -155.167462) (xy 424.618316 -155.178579) (xy 424.565064 -155.182309)
			(xy 424.511812 -155.178579) (xy 424.459601 -155.167462) (xy 424.409449 -155.149176) (xy 424.362335 -155.124077)
			(xy 424.319181 -155.092655) (xy 424.280827 -155.055525) (xy 424.264074 -155.034742) (xy 424.256529 -155.025963)
			(xy 424.235757 -155.015791) (xy 424.224196 -155.015184) (xy 424.143932 -155.015184) (xy 424.132367 -155.015779)
			(xy 424.111597 -155.025957) (xy 424.104054 -155.034742) (xy 424.085843 -155.057208) (xy 424.043826 -155.096943)
			(xy 423.996295 -155.129883) (xy 423.944338 -155.155273) (xy 423.889145 -155.172534) (xy 423.831979 -155.181269)
			(xy 423.803064 -155.181808) (xy 423.775814 -155.18132) (xy 423.721871 -155.173559) (xy 423.66958 -155.158201)
			(xy 423.620007 -155.135558) (xy 423.574162 -155.10609) (xy 423.532976 -155.070399) (xy 423.497288 -155.02921)
			(xy 423.467825 -154.983361) (xy 423.445187 -154.933786) (xy 423.429833 -154.881494) (xy 423.422078 -154.82755)
			(xy 410.244544 -154.82755) (xy 410.244544 -155.456636) (xy 410.244975 -155.466702) (xy 410.252704 -155.485293)
			(xy 410.25953 -155.492704) (xy 411.578298 -156.811472) (xy 411.585695 -156.818322) (xy 411.604293 -156.826061)
			(xy 411.614366 -156.826458)
		)
		(stroke
			(width 0)
			(type solid)
		)
		(fill yes)
		(layer "In15.Cu")
		(net "P5V_AUX")
	)
	(gr_poly
		(pts
			(xy 352.655378 -440.717686) (xy 352.66383 -440.71628) (xy 352.679151 -440.708632) (xy 352.691083 -440.696351)
			(xy 352.695002 -440.68873) (xy 352.695256 -440.688222) (xy 352.739452 -440.589924) (xy 352.73488 -440.56046)
			(xy 352.724974 -440.549284) (xy 352.704914 -440.525981) (xy 352.669972 -440.475385) (xy 352.641384 -440.420945)
			(xy 352.619568 -440.363456) (xy 352.604842 -440.303756) (xy 352.59742 -440.242717) (xy 352.596958 -440.211972)
			(xy 352.597423 -440.181241) (xy 352.604834 -440.120228) (xy 352.619545 -440.060553) (xy 352.641341 -440.003087)
			(xy 352.669905 -439.948666) (xy 352.704819 -439.898084) (xy 352.745576 -439.85208) (xy 352.79158 -439.811323)
			(xy 352.842161 -439.776408) (xy 352.896581 -439.747844) (xy 352.954048 -439.726047) (xy 353.013722 -439.711335)
			(xy 353.074735 -439.703924) (xy 353.105466 -439.703464) (xy 353.137614 -439.703961) (xy 353.201395 -439.712075)
			(xy 353.263645 -439.728166) (xy 353.323369 -439.751977) (xy 353.379615 -439.783127) (xy 353.431485 -439.82112)
			(xy 353.47815 -439.86535) (xy 353.498912 -439.8899) (xy 353.505262 -439.89752) (xy 353.52228 -439.906918)
			(xy 353.601782 -439.91657) (xy 353.611491 -439.917367) (xy 353.630311 -439.912407) (xy 353.638358 -439.906918)
			(xy 353.638612 -439.906664) (xy 353.663545 -439.888752) (xy 353.717933 -439.860282) (xy 353.776175 -439.840883)
			(xy 353.836772 -439.831054) (xy 353.867466 -439.830464) (xy 353.895648 -439.830967) (xy 353.951399 -439.839255)
			(xy 354.005325 -439.855654) (xy 354.056251 -439.879808) (xy 354.103069 -439.911192) (xy 354.12426 -439.929778)
			(xy 354.1395 -439.943748) (xy 354.179886 -439.942732) (xy 354.426774 -439.695844) (xy 354.427282 -439.695336)
			(xy 354.433859 -439.687953) (xy 354.441301 -439.669654) (xy 354.44176 -439.659776) (xy 354.44176 -431.135028)
			(xy 354.442198 -431.124965) (xy 354.449937 -431.106385) (xy 354.456746 -431.09896) (xy 357.423466 -428.13224)
			(xy 357.423974 -428.131732) (xy 357.430552 -428.124349) (xy 357.437994 -428.10605) (xy 357.438452 -428.096172)
			(xy 357.438452 -423.10558) (xy 357.43888 -423.095513) (xy 357.446606 -423.076918) (xy 357.453438 -423.069512)
			(xy 358.767888 -421.755062) (xy 358.775283 -421.748207) (xy 358.793881 -421.740458) (xy 358.803956 -421.740076)
			(xy 361.412536 -421.740076) (xy 361.422604 -421.740505) (xy 361.441201 -421.748226) (xy 361.448604 -421.755062)
			(xy 362.110274 -422.416732) (xy 362.117118 -422.424131) (xy 362.124845 -422.442729) (xy 362.12526 -422.4528)
			(xy 362.12526 -423.182753) (xy 364.314988 -423.182753) (xy 364.314988 -423.118831) (xy 364.322999 -423.055413)
			(xy 364.338896 -422.993499) (xy 364.362428 -422.934066) (xy 364.393222 -422.878051) (xy 364.430795 -422.826336)
			(xy 364.474552 -422.779739) (xy 364.523805 -422.738994) (xy 364.577776 -422.704743) (xy 364.635615 -422.677526)
			(xy 364.696408 -422.657773) (xy 364.759198 -422.645795) (xy 364.822994 -422.641782) (xy 364.88679 -422.645795)
			(xy 364.94958 -422.657773) (xy 365.010373 -422.677526) (xy 365.068212 -422.704743) (xy 365.122183 -422.738994)
			(xy 365.171436 -422.779739) (xy 365.215193 -422.826336) (xy 365.252766 -422.878051) (xy 365.28356 -422.934066)
			(xy 365.307092 -422.993499) (xy 365.322989 -423.055413) (xy 365.331 -423.118831) (xy 365.331502 -423.150792)
			(xy 365.331 -423.182753) (xy 365.322989 -423.246171) (xy 365.307092 -423.308085) (xy 365.28356 -423.367518)
			(xy 365.252766 -423.423533) (xy 365.215193 -423.475248) (xy 365.171436 -423.521845) (xy 365.122183 -423.56259)
			(xy 365.068212 -423.596841) (xy 365.010373 -423.624058) (xy 364.94958 -423.643811) (xy 364.88679 -423.655789)
			(xy 364.822994 -423.659803) (xy 364.759198 -423.655789) (xy 364.696408 -423.643811) (xy 364.635615 -423.624058)
			(xy 364.577776 -423.596841) (xy 364.523805 -423.56259) (xy 364.474552 -423.521845) (xy 364.430795 -423.475248)
			(xy 364.393222 -423.423533) (xy 364.362428 -423.367518) (xy 364.338896 -423.308085) (xy 364.322999 -423.246171)
			(xy 364.314988 -423.182753) (xy 362.12526 -423.182753) (xy 362.12526 -424.209929) (xy 364.763806 -424.209929)
			(xy 364.763806 -424.146007) (xy 364.771817 -424.082589) (xy 364.787714 -424.020675) (xy 364.811246 -423.961242)
			(xy 364.84204 -423.905227) (xy 364.879613 -423.853512) (xy 364.92337 -423.806915) (xy 364.972623 -423.76617)
			(xy 365.026594 -423.731919) (xy 365.084433 -423.704702) (xy 365.145226 -423.684949) (xy 365.208016 -423.672971)
			(xy 365.271812 -423.668958) (xy 365.335608 -423.672971) (xy 365.398398 -423.684949) (xy 365.459191 -423.704702)
			(xy 365.51703 -423.731919) (xy 365.571001 -423.76617) (xy 365.620254 -423.806915) (xy 365.664011 -423.853512)
			(xy 365.701584 -423.905227) (xy 365.732378 -423.961242) (xy 365.75591 -424.020675) (xy 365.771807 -424.082589)
			(xy 365.779818 -424.146007) (xy 365.78032 -424.177968) (xy 365.779818 -424.209929) (xy 365.771807 -424.273347)
			(xy 365.75591 -424.335261) (xy 365.732378 -424.394694) (xy 365.701584 -424.450709) (xy 365.664011 -424.502424)
			(xy 365.620254 -424.549021) (xy 365.571001 -424.589766) (xy 365.51703 -424.624017) (xy 365.459191 -424.651234)
			(xy 365.398398 -424.670987) (xy 365.335608 -424.682965) (xy 365.271812 -424.686979) (xy 365.208016 -424.682965)
			(xy 365.145226 -424.670987) (xy 365.084433 -424.651234) (xy 365.026594 -424.624017) (xy 364.972623 -424.589766)
			(xy 364.92337 -424.549021) (xy 364.879613 -424.502424) (xy 364.84204 -424.450709) (xy 364.811246 -424.394694)
			(xy 364.787714 -424.335261) (xy 364.771817 -424.273347) (xy 364.763806 -424.209929) (xy 362.12526 -424.209929)
			(xy 362.12526 -425.459798) (xy 365.077418 -425.459798) (xy 365.082625 -425.396935) (xy 365.095567 -425.335199)
			(xy 365.116046 -425.275538) (xy 365.143747 -425.218868) (xy 365.178245 -425.16606) (xy 365.21901 -425.117924)
			(xy 365.265415 -425.075199) (xy 365.316749 -425.038543) (xy 365.372223 -425.008518) (xy 365.430985 -424.985585)
			(xy 365.492132 -424.970096) (xy 365.554725 -424.96229) (xy 365.586264 -424.961812) (xy 365.617172 -424.962238)
			(xy 365.678536 -424.969701) (xy 365.73854 -424.984558) (xy 365.796297 -425.00659) (xy 365.850952 -425.03547)
			(xy 365.876586 -425.052744) (xy 365.889327 -425.060844) (xy 365.918032 -425.070121) (xy 365.948195 -425.070595)
			(xy 365.977178 -425.062225) (xy 366.002444 -425.045744) (xy 366.021784 -425.022592) (xy 366.033506 -424.994795)
			(xy 366.03559 -424.979846) (xy 366.038919 -424.952021) (xy 366.052752 -424.897715) (xy 366.074381 -424.846018)
			(xy 366.103341 -424.798042) (xy 366.13901 -424.754819) (xy 366.180618 -424.71728) (xy 366.227271 -424.686233)
			(xy 366.277965 -424.662346) (xy 366.331608 -424.646133) (xy 366.387046 -424.637943) (xy 366.415066 -424.637454)
			(xy 366.442318 -424.637991) (xy 366.496267 -424.645743) (xy 366.548564 -424.661095) (xy 366.598143 -424.683733)
			(xy 366.643996 -424.713197) (xy 366.685189 -424.748887) (xy 366.720882 -424.790077) (xy 366.750351 -424.835927)
			(xy 366.772993 -424.885504) (xy 366.78835 -424.9378) (xy 366.796107 -424.991748) (xy 366.796107 -425.046252)
			(xy 366.78835 -425.1002) (xy 366.772993 -425.152496) (xy 366.750351 -425.202073) (xy 366.720882 -425.247923)
			(xy 366.685189 -425.289113) (xy 366.643996 -425.324803) (xy 366.598143 -425.354267) (xy 366.548564 -425.376905)
			(xy 366.496267 -425.392257) (xy 366.442318 -425.400009) (xy 366.415066 -425.40047) (xy 366.385127 -425.399944)
			(xy 366.325981 -425.390623) (xy 366.269025 -425.372152) (xy 366.242092 -425.359068) (xy 366.228395 -425.352693)
			(xy 366.198664 -425.347417) (xy 366.168691 -425.351075) (xy 366.141101 -425.363346) (xy 366.118312 -425.383156)
			(xy 366.10232 -425.408768) (xy 366.094525 -425.43794) (xy 366.094518 -425.453048) (xy 366.094772 -425.47032)
			(xy 366.094311 -425.501859) (xy 366.086507 -425.564452) (xy 366.07102 -425.6256) (xy 366.048089 -425.684362)
			(xy 366.037461 -425.704) (xy 367.283492 -425.704) (xy 367.283947 -425.674068) (xy 367.290979 -425.614618)
			(xy 367.304946 -425.556406) (xy 367.325654 -425.500238) (xy 367.352817 -425.446891) (xy 367.386059 -425.397105)
			(xy 367.405158 -425.374054) (xy 367.410815 -425.366728) (xy 367.41693 -425.349273) (xy 367.417096 -425.340018)
			(xy 367.416588 -425.309284) (xy 367.415969 -425.300095) (xy 367.409083 -425.283032) (xy 367.403126 -425.27601)
			(xy 367.384514 -425.254796) (xy 367.353055 -425.207947) (xy 367.328837 -425.156975) (xy 367.31239 -425.102993)
			(xy 367.304071 -425.047178) (xy 367.303558 -425.018962) (xy 367.304044 -424.991711) (xy 367.3118 -424.937763)
			(xy 367.327155 -424.885468) (xy 367.349797 -424.835891) (xy 367.379263 -424.790041) (xy 367.414954 -424.74885)
			(xy 367.456145 -424.713159) (xy 367.501995 -424.683693) (xy 367.551572 -424.661051) (xy 367.603867 -424.645696)
			(xy 367.657815 -424.63794) (xy 367.712317 -424.63794) (xy 367.766265 -424.645696) (xy 367.81856 -424.661051)
			(xy 367.868137 -424.683693) (xy 367.913987 -424.713159) (xy 367.955178 -424.74885) (xy 367.990869 -424.790041)
			(xy 368.020335 -424.835891) (xy 368.042977 -424.885468) (xy 368.058332 -424.937763) (xy 368.066088 -424.991711)
			(xy 368.066574 -425.018962) (xy 368.573048 -425.018962) (xy 368.577119 -424.96334) (xy 368.589245 -424.908903)
			(xy 368.609168 -424.856812) (xy 368.636464 -424.808177) (xy 368.67055 -424.764034) (xy 368.710699 -424.725325)
			(xy 368.756057 -424.692874) (xy 368.805657 -424.667373) (xy 368.858441 -424.649366) (xy 368.913284 -424.639236)
			(xy 368.969018 -424.637199) (xy 369.024455 -424.643299) (xy 369.078412 -424.657405) (xy 369.129741 -424.679217)
			(xy 369.177347 -424.708271) (xy 369.220215 -424.743946) (xy 369.257432 -424.785483) (xy 369.288205 -424.831996)
			(xy 369.311877 -424.882493) (xy 369.327945 -424.9359) (xy 369.336065 -424.991076) (xy 369.336574 -425.018962)
			(xy 369.336495 -425.02328) (xy 369.65839 -425.02328) (xy 369.662461 -424.967658) (xy 369.674587 -424.913221)
			(xy 369.69451 -424.86113) (xy 369.721806 -424.812495) (xy 369.755892 -424.768352) (xy 369.796041 -424.729643)
			(xy 369.841399 -424.697192) (xy 369.890999 -424.671691) (xy 369.943783 -424.653684) (xy 369.998626 -424.643554)
			(xy 370.05436 -424.641517) (xy 370.109797 -424.647617) (xy 370.163754 -424.661723) (xy 370.215083 -424.683535)
			(xy 370.262689 -424.712589) (xy 370.305557 -424.748264) (xy 370.342774 -424.789801) (xy 370.373547 -424.836314)
			(xy 370.397219 -424.886811) (xy 370.413287 -424.940218) (xy 370.421407 -424.995394) (xy 370.421916 -425.02328)
			(xy 370.421407 -425.051166) (xy 370.413287 -425.106342) (xy 370.397219 -425.159749) (xy 370.373547 -425.210246)
			(xy 370.342774 -425.256759) (xy 370.305557 -425.298296) (xy 370.262689 -425.333971) (xy 370.215083 -425.363025)
			(xy 370.163754 -425.384837) (xy 370.109797 -425.398943) (xy 370.05436 -425.405043) (xy 369.998626 -425.403006)
			(xy 369.943783 -425.392876) (xy 369.890999 -425.374869) (xy 369.841399 -425.349368) (xy 369.796041 -425.316917)
			(xy 369.755892 -425.278208) (xy 369.721806 -425.234065) (xy 369.69451 -425.18543) (xy 369.674587 -425.133339)
			(xy 369.662461 -425.078902) (xy 369.65839 -425.02328) (xy 369.336495 -425.02328) (xy 369.336065 -425.046848)
			(xy 369.327945 -425.102024) (xy 369.311877 -425.155431) (xy 369.288205 -425.205928) (xy 369.257432 -425.252441)
			(xy 369.220215 -425.293978) (xy 369.177347 -425.329653) (xy 369.129741 -425.358707) (xy 369.078412 -425.380519)
			(xy 369.024455 -425.394625) (xy 368.969018 -425.400725) (xy 368.913284 -425.398688) (xy 368.858441 -425.388558)
			(xy 368.805657 -425.370551) (xy 368.756057 -425.34505) (xy 368.710699 -425.312599) (xy 368.67055 -425.27389)
			(xy 368.636464 -425.229747) (xy 368.609168 -425.181112) (xy 368.589245 -425.129021) (xy 368.577119 -425.074584)
			(xy 368.573048 -425.018962) (xy 368.066574 -425.018962) (xy 368.066104 -425.046314) (xy 368.058269 -425.100454)
			(xy 368.04277 -425.152916) (xy 368.031776 -425.177966) (xy 368.028296 -425.186426) (xy 368.026994 -425.204657)
			(xy 368.029236 -425.213526) (xy 368.038126 -425.24299) (xy 368.041116 -425.251809) (xy 368.052298 -425.266672)
			(xy 368.05997 -425.271946) (xy 368.087153 -425.289377) (xy 368.137292 -425.330074) (xy 368.181873 -425.376793)
			(xy 368.220177 -425.428782) (xy 368.251589 -425.485204) (xy 368.275601 -425.545151) (xy 368.291827 -425.607655)
			(xy 368.300006 -425.671712) (xy 368.300508 -425.704) (xy 368.300006 -425.735961) (xy 368.291995 -425.799379)
			(xy 368.276098 -425.861293) (xy 368.252566 -425.920726) (xy 368.221772 -425.976741) (xy 368.184199 -426.028456)
			(xy 368.140442 -426.075053) (xy 368.091189 -426.115798) (xy 368.037218 -426.150049) (xy 367.979379 -426.177266)
			(xy 367.918586 -426.197019) (xy 367.855796 -426.208997) (xy 367.792 -426.213011) (xy 367.728204 -426.208997)
			(xy 367.665414 -426.197019) (xy 367.604621 -426.177266) (xy 367.546782 -426.150049) (xy 367.492811 -426.115798)
			(xy 367.443558 -426.075053) (xy 367.399801 -426.028456) (xy 367.362228 -425.976741) (xy 367.331434 -425.920726)
			(xy 367.307902 -425.861293) (xy 367.292005 -425.799379) (xy 367.283994 -425.735961) (xy 367.283492 -425.704)
			(xy 366.037461 -425.704) (xy 366.018065 -425.739837) (xy 365.981411 -425.791172) (xy 365.938688 -425.837579)
			(xy 365.890553 -425.878346) (xy 365.837746 -425.912845) (xy 365.781077 -425.940548) (xy 365.721416 -425.961029)
			(xy 365.65968 -425.973973) (xy 365.596818 -425.979182) (xy 365.533793 -425.976575) (xy 365.471576 -425.966193)
			(xy 365.41112 -425.948195) (xy 365.353354 -425.922857) (xy 365.299166 -425.890569) (xy 365.249388 -425.851826)
			(xy 365.204785 -425.807224) (xy 365.16604 -425.757447) (xy 365.133751 -425.70326) (xy 365.108411 -425.645495)
			(xy 365.090411 -425.58504) (xy 365.080027 -425.522822) (xy 365.077418 -425.459798) (xy 362.12526 -425.459798)
			(xy 362.12526 -425.791122) (xy 362.12572 -425.801) (xy 362.13316 -425.819301) (xy 362.139738 -425.826682)
			(xy 362.139992 -425.826936) (xy 362.88091 -426.567854) (xy 372.134128 -426.567854) (xy 372.138199 -426.512232)
			(xy 372.150325 -426.457795) (xy 372.170248 -426.405704) (xy 372.197544 -426.357069) (xy 372.23163 -426.312926)
			(xy 372.271779 -426.274217) (xy 372.317137 -426.241766) (xy 372.366737 -426.216265) (xy 372.419521 -426.198258)
			(xy 372.474364 -426.188128) (xy 372.530098 -426.186091) (xy 372.585535 -426.192191) (xy 372.639492 -426.206297)
			(xy 372.690821 -426.228109) (xy 372.738427 -426.257163) (xy 372.781295 -426.292838) (xy 372.818512 -426.334375)
			(xy 372.849285 -426.380888) (xy 372.872957 -426.431385) (xy 372.889025 -426.484792) (xy 372.897145 -426.539968)
			(xy 372.897654 -426.567854) (xy 372.897145 -426.59574) (xy 372.889025 -426.650916) (xy 372.872957 -426.704323)
			(xy 372.849285 -426.75482) (xy 372.818512 -426.801333) (xy 372.781295 -426.84287) (xy 372.738427 -426.878545)
			(xy 372.690821 -426.907599) (xy 372.639492 -426.929411) (xy 372.585535 -426.943517) (xy 372.530098 -426.949617)
			(xy 372.474364 -426.94758) (xy 372.419521 -426.93745) (xy 372.366737 -426.919443) (xy 372.317137 -426.893942)
			(xy 372.271779 -426.861491) (xy 372.23163 -426.822782) (xy 372.197544 -426.778639) (xy 372.170248 -426.730004)
			(xy 372.150325 -426.677913) (xy 372.138199 -426.623476) (xy 372.134128 -426.567854) (xy 362.88091 -426.567854)
			(xy 363.401356 -427.0883) (xy 368.921282 -427.0883) (xy 368.925353 -427.032678) (xy 368.937479 -426.978241)
			(xy 368.957402 -426.92615) (xy 368.984698 -426.877515) (xy 369.018784 -426.833372) (xy 369.058933 -426.794663)
			(xy 369.104291 -426.762212) (xy 369.153891 -426.736711) (xy 369.206675 -426.718704) (xy 369.261518 -426.708574)
			(xy 369.317252 -426.706537) (xy 369.372689 -426.712637) (xy 369.426646 -426.726743) (xy 369.477975 -426.748555)
			(xy 369.525581 -426.777609) (xy 369.568449 -426.813284) (xy 369.605666 -426.854821) (xy 369.636439 -426.901334)
			(xy 369.660111 -426.951831) (xy 369.676179 -427.005238) (xy 369.684299 -427.060414) (xy 369.684808 -427.0883)
			(xy 369.684299 -427.116186) (xy 369.676179 -427.171362) (xy 369.660111 -427.224769) (xy 369.636439 -427.275266)
			(xy 369.605666 -427.321779) (xy 369.568449 -427.363316) (xy 369.525581 -427.398991) (xy 369.477975 -427.428045)
			(xy 369.426646 -427.449857) (xy 369.372689 -427.463963) (xy 369.317252 -427.470063) (xy 369.261518 -427.468026)
			(xy 369.206675 -427.457896) (xy 369.153891 -427.439889) (xy 369.104291 -427.414388) (xy 369.058933 -427.381937)
			(xy 369.018784 -427.343228) (xy 368.984698 -427.299085) (xy 368.957402 -427.25045) (xy 368.937479 -427.198359)
			(xy 368.925353 -427.143922) (xy 368.921282 -427.0883) (xy 363.401356 -427.0883) (xy 364.815585 -428.502529)
			(xy 368.694456 -428.502529) (xy 368.694456 -428.438607) (xy 368.702467 -428.375189) (xy 368.718364 -428.313275)
			(xy 368.741896 -428.253842) (xy 368.77269 -428.197827) (xy 368.810263 -428.146112) (xy 368.85402 -428.099515)
			(xy 368.903273 -428.05877) (xy 368.957244 -428.024519) (xy 369.015083 -427.997302) (xy 369.075876 -427.977549)
			(xy 369.138666 -427.965571) (xy 369.202462 -427.961558) (xy 369.266258 -427.965571) (xy 369.329048 -427.977549)
			(xy 369.389841 -427.997302) (xy 369.44768 -428.024519) (xy 369.501651 -428.05877) (xy 369.550904 -428.099515)
			(xy 369.594661 -428.146112) (xy 369.632234 -428.197827) (xy 369.663028 -428.253842) (xy 369.68656 -428.313275)
			(xy 369.702457 -428.375189) (xy 369.710468 -428.438607) (xy 369.71097 -428.470568) (xy 369.710468 -428.502529)
			(xy 369.708377 -428.519082) (xy 370.025422 -428.519082) (xy 370.025959 -428.486672) (xy 370.03421 -428.42238)
			(xy 370.050564 -428.359657) (xy 370.074756 -428.29952) (xy 370.106393 -428.242945) (xy 370.144963 -428.190849)
			(xy 370.18984 -428.144076) (xy 370.240296 -428.103385) (xy 370.295514 -428.069435) (xy 370.354598 -428.042777)
			(xy 370.416591 -428.023842) (xy 370.480487 -428.012939) (xy 370.512848 -428.011082) (xy 370.521335 -428.010422)
			(xy 370.537165 -428.00418) (xy 370.543836 -427.99889) (xy 370.566188 -427.97984) (xy 370.572371 -427.974179)
			(xy 370.580943 -427.959784) (xy 370.582952 -427.951646) (xy 370.589394 -427.923486) (xy 370.609738 -427.869418)
			(xy 370.638001 -427.819036) (xy 370.673537 -427.773491) (xy 370.715535 -427.733826) (xy 370.763033 -427.700946)
			(xy 370.814946 -427.675604) (xy 370.870087 -427.658379) (xy 370.927194 -427.649666) (xy 370.956078 -427.649132)
			(xy 370.984998 -427.649623) (xy 371.042175 -427.65835) (xy 371.097379 -427.675609) (xy 371.149346 -427.701002)
			(xy 371.196885 -427.733949) (xy 371.238905 -427.773695) (xy 371.274444 -427.819328) (xy 371.302687 -427.869803)
			(xy 371.322988 -427.923962) (xy 371.329458 -427.952154) (xy 371.331744 -427.962568) (xy 371.34419 -427.980094)
			(xy 371.427756 -428.028862) (xy 371.448838 -428.031402) (xy 371.459252 -428.0281) (xy 371.496402 -428.017182)
			(xy 371.572937 -428.005453) (xy 371.611652 -428.004732) (xy 371.648973 -428.005417) (xy 371.722807 -428.01639)
			(xy 371.758718 -428.026576) (xy 371.769386 -428.029624) (xy 371.791484 -428.026576) (xy 371.87505 -427.973236)
			(xy 371.887242 -427.95444) (xy 371.888766 -427.943518) (xy 371.893964 -427.910862) (xy 371.911644 -427.847145)
			(xy 371.937436 -427.786258) (xy 371.970903 -427.729229) (xy 372.011482 -427.67702) (xy 372.058487 -427.630512)
			(xy 372.111125 -427.590491) (xy 372.168507 -427.557631) (xy 372.229664 -427.532489) (xy 372.293566 -427.515487)
			(xy 372.359132 -427.506914) (xy 372.392194 -427.506384) (xy 372.424156 -427.506881) (xy 372.487576 -427.514892)
			(xy 372.549492 -427.530788) (xy 372.608928 -427.55432) (xy 372.664945 -427.585115) (xy 372.716661 -427.622689)
			(xy 372.76326 -427.666447) (xy 372.804007 -427.715702) (xy 372.83826 -427.769674) (xy 372.865478 -427.827515)
			(xy 372.885231 -427.88831) (xy 372.89721 -427.951102) (xy 372.901224 -428.0149) (xy 372.89721 -428.078698)
			(xy 372.885231 -428.14149) (xy 372.882804 -428.148961) (xy 372.998994 -428.148961) (xy 372.998994 -428.085039)
			(xy 373.007005 -428.021621) (xy 373.022902 -427.959707) (xy 373.046434 -427.900274) (xy 373.077228 -427.844259)
			(xy 373.114801 -427.792544) (xy 373.158558 -427.745947) (xy 373.207811 -427.705202) (xy 373.261782 -427.670951)
			(xy 373.319621 -427.643734) (xy 373.380414 -427.623981) (xy 373.443204 -427.612003) (xy 373.507 -427.60799)
			(xy 373.570796 -427.612003) (xy 373.633586 -427.623981) (xy 373.694379 -427.643734) (xy 373.752218 -427.670951)
			(xy 373.806189 -427.705202) (xy 373.855442 -427.745947) (xy 373.899199 -427.792544) (xy 373.936772 -427.844259)
			(xy 373.967566 -427.900274) (xy 373.991098 -427.959707) (xy 374.006995 -428.021621) (xy 374.015006 -428.085039)
			(xy 374.015508 -428.117) (xy 374.015006 -428.148961) (xy 374.006995 -428.212379) (xy 373.999919 -428.239936)
			(xy 375.379232 -428.239936) (xy 375.383303 -428.184314) (xy 375.395429 -428.129877) (xy 375.415352 -428.077786)
			(xy 375.442648 -428.029151) (xy 375.476734 -427.985008) (xy 375.516883 -427.946299) (xy 375.562241 -427.913848)
			(xy 375.611841 -427.888347) (xy 375.664625 -427.87034) (xy 375.719468 -427.86021) (xy 375.775202 -427.858173)
			(xy 375.830639 -427.864273) (xy 375.884596 -427.878379) (xy 375.935925 -427.900191) (xy 375.983531 -427.929245)
			(xy 376.026399 -427.96492) (xy 376.063616 -428.006457) (xy 376.094389 -428.05297) (xy 376.118061 -428.103467)
			(xy 376.134129 -428.156874) (xy 376.142249 -428.21205) (xy 376.142758 -428.239936) (xy 376.142249 -428.267822)
			(xy 376.134129 -428.322998) (xy 376.118061 -428.376405) (xy 376.094389 -428.426902) (xy 376.063616 -428.473415)
			(xy 376.026399 -428.514952) (xy 375.983531 -428.550627) (xy 375.935925 -428.579681) (xy 375.884596 -428.601493)
			(xy 375.830639 -428.615599) (xy 375.775202 -428.621699) (xy 375.719468 -428.619662) (xy 375.664625 -428.609532)
			(xy 375.611841 -428.591525) (xy 375.562241 -428.566024) (xy 375.516883 -428.533573) (xy 375.476734 -428.494864)
			(xy 375.442648 -428.450721) (xy 375.415352 -428.402086) (xy 375.395429 -428.349995) (xy 375.383303 -428.295558)
			(xy 375.379232 -428.239936) (xy 373.999919 -428.239936) (xy 373.991098 -428.274293) (xy 373.967566 -428.333726)
			(xy 373.936772 -428.389741) (xy 373.899199 -428.441456) (xy 373.855442 -428.488053) (xy 373.806189 -428.528798)
			(xy 373.752218 -428.563049) (xy 373.694379 -428.590266) (xy 373.633586 -428.610019) (xy 373.570796 -428.621997)
			(xy 373.507 -428.626011) (xy 373.443204 -428.621997) (xy 373.380414 -428.610019) (xy 373.319621 -428.590266)
			(xy 373.261782 -428.563049) (xy 373.207811 -428.528798) (xy 373.158558 -428.488053) (xy 373.114801 -428.441456)
			(xy 373.077228 -428.389741) (xy 373.046434 -428.333726) (xy 373.022902 -428.274293) (xy 373.007005 -428.212379)
			(xy 372.998994 -428.148961) (xy 372.882804 -428.148961) (xy 372.865478 -428.202285) (xy 372.83826 -428.260126)
			(xy 372.804007 -428.314098) (xy 372.76326 -428.363353) (xy 372.716661 -428.407111) (xy 372.664945 -428.444685)
			(xy 372.608928 -428.47548) (xy 372.549492 -428.499012) (xy 372.487576 -428.514908) (xy 372.424156 -428.522919)
			(xy 372.392194 -428.5234) (xy 372.354873 -428.522704) (xy 372.28104 -428.511738) (xy 372.245128 -428.501556)
			(xy 372.23446 -428.498508) (xy 372.212362 -428.501556) (xy 372.128796 -428.554896) (xy 372.116604 -428.573692)
			(xy 372.11508 -428.584614) (xy 372.109959 -428.617284) (xy 372.092272 -428.681004) (xy 372.066474 -428.741894)
			(xy 372.032998 -428.798926) (xy 371.992412 -428.851136) (xy 371.945399 -428.897643) (xy 371.892753 -428.937663)
			(xy 371.835363 -428.970519) (xy 371.774198 -428.995658) (xy 371.710289 -429.012654) (xy 371.644717 -429.021222)
			(xy 371.611652 -429.021748) (xy 371.581205 -429.021293) (xy 371.520745 -429.014034) (xy 371.461586 -428.9996)
			(xy 371.404576 -428.9782) (xy 371.350533 -428.950139) (xy 371.300231 -428.915821) (xy 371.25439 -428.875737)
			(xy 371.213669 -428.830461) (xy 371.178651 -428.780643) (xy 371.16385 -428.754032) (xy 371.156992 -428.741586)
			(xy 371.133116 -428.727362) (xy 371.014752 -428.72787) (xy 370.990876 -428.742348) (xy 370.984272 -428.755048)
			(xy 370.969612 -428.782081) (xy 370.934719 -428.832722) (xy 370.893971 -428.878784) (xy 370.847965 -428.919594)
			(xy 370.797371 -428.954556) (xy 370.74293 -428.983159) (xy 370.685435 -429.004987) (xy 370.625728 -429.019719)
			(xy 370.564679 -429.027141) (xy 370.53393 -429.02759) (xy 370.503198 -429.027134) (xy 370.442181 -429.019729)
			(xy 370.382502 -429.005022) (xy 370.325031 -428.983228) (xy 370.270607 -428.954666) (xy 370.220022 -428.919752)
			(xy 370.174014 -428.878994) (xy 370.133256 -428.832988) (xy 370.09834 -428.782404) (xy 370.069776 -428.727979)
			(xy 370.047982 -428.670509) (xy 370.033274 -428.610831) (xy 370.025867 -428.549814) (xy 370.025422 -428.519082)
			(xy 369.708377 -428.519082) (xy 369.702457 -428.565947) (xy 369.68656 -428.627861) (xy 369.663028 -428.687294)
			(xy 369.632234 -428.743309) (xy 369.594661 -428.795024) (xy 369.550904 -428.841621) (xy 369.501651 -428.882366)
			(xy 369.44768 -428.916617) (xy 369.389841 -428.943834) (xy 369.329048 -428.963587) (xy 369.266258 -428.975565)
			(xy 369.202462 -428.979579) (xy 369.138666 -428.975565) (xy 369.075876 -428.963587) (xy 369.015083 -428.943834)
			(xy 368.957244 -428.916617) (xy 368.903273 -428.882366) (xy 368.85402 -428.841621) (xy 368.810263 -428.795024)
			(xy 368.77269 -428.743309) (xy 368.741896 -428.687294) (xy 368.718364 -428.627861) (xy 368.702467 -428.565947)
			(xy 368.694456 -428.502529) (xy 364.815585 -428.502529) (xy 365.875062 -429.562006) (xy 365.87557 -429.562514)
			(xy 365.88295 -429.569098) (xy 365.90125 -429.576548) (xy 365.91113 -429.576992) (xy 376.39371 -429.576992)
			(xy 376.403588 -429.576533) (xy 376.421887 -429.569091) (xy 376.42927 -429.562514) (xy 376.429524 -429.56226)
			(xy 376.974354 -429.01743) (xy 376.974862 -429.016922) (xy 376.98144 -429.009539) (xy 376.98888 -428.99124)
			(xy 376.98934 -428.981362) (xy 376.98934 -428.483522) (xy 376.989221 -428.477874) (xy 376.986796 -428.466845)
			(xy 376.984514 -428.461678) (xy 376.972797 -428.436103) (xy 376.954443 -428.382924) (xy 376.942081 -428.328041)
			(xy 376.935862 -428.272129) (xy 376.935492 -428.244) (xy 376.935884 -428.215873) (xy 376.942116 -428.159964)
			(xy 376.954472 -428.105082) (xy 376.9728 -428.051897) (xy 376.984514 -428.026322) (xy 376.98934 -428.015908)
			(xy 376.98934 -427.838108) (xy 376.988917 -427.828038) (xy 376.981198 -427.809438) (xy 376.974354 -427.80204)
			(xy 374.115838 -424.943524) (xy 374.108726 -424.936158) (xy 374.08993 -424.928538) (xy 373.88546 -424.928538)
			(xy 373.882412 -424.928538) (xy 373.877463 -424.928966) (xy 373.867864 -424.931518) (xy 373.863362 -424.933618)
			(xy 373.859531 -424.93558) (xy 373.852512 -424.940559) (xy 373.849392 -424.943524) (xy 373.79148 -425.001436)
			(xy 373.78386 -425.019724) (xy 373.78386 -425.029884) (xy 373.783339 -425.060575) (xy 373.77583 -425.121499)
			(xy 373.761042 -425.181075) (xy 373.739188 -425.238437) (xy 373.710587 -425.292751) (xy 373.675654 -425.343227)
			(xy 373.634899 -425.38913) (xy 373.588914 -425.429792) (xy 373.538368 -425.464621) (xy 373.483996 -425.493112)
			(xy 373.426589 -425.51485) (xy 373.366983 -425.529517) (xy 373.306044 -425.536902) (xy 373.275352 -425.537376)
			(xy 373.275098 -425.537376) (xy 373.242711 -425.536854) (xy 373.178464 -425.528595) (xy 373.115788 -425.512238)
			(xy 373.055699 -425.488047) (xy 372.999173 -425.456414) (xy 372.972838 -425.437554) (xy 372.961408 -425.429172)
			(xy 372.933976 -425.426378) (xy 372.82755 -425.475908) (xy 372.811802 -425.499022) (xy 372.810786 -425.512992)
			(xy 372.808474 -425.541696) (xy 372.796301 -425.59798) (xy 372.775809 -425.651795) (xy 372.747461 -425.701918)
			(xy 372.711902 -425.747213) (xy 372.669941 -425.786649) (xy 372.622529 -425.819331) (xy 372.570744 -425.844517)
			(xy 372.515762 -425.861634) (xy 372.458832 -425.870294) (xy 372.43004 -425.870878) (xy 372.402787 -425.870417)
			(xy 372.348836 -425.862666) (xy 372.296538 -425.847314) (xy 372.246957 -425.824676) (xy 372.201102 -425.795211)
			(xy 372.159908 -425.75952) (xy 372.124213 -425.71833) (xy 372.094743 -425.672479) (xy 372.0721 -425.6229)
			(xy 372.056743 -425.570603) (xy 372.048985 -425.516653) (xy 372.048985 -425.462147) (xy 372.056743 -425.408197)
			(xy 372.0721 -425.3559) (xy 372.094743 -425.306321) (xy 372.124213 -425.26047) (xy 372.159908 -425.21928)
			(xy 372.201102 -425.183589) (xy 372.246957 -425.154124) (xy 372.296538 -425.131486) (xy 372.348836 -425.116134)
			(xy 372.402787 -425.108383) (xy 372.43004 -425.107862) (xy 372.454433 -425.108245) (xy 372.502822 -425.114454)
			(xy 372.550026 -425.12678) (xy 372.595273 -425.145021) (xy 372.61673 -425.15663) (xy 372.628922 -425.163488)
			(xy 372.656862 -425.162726) (xy 372.756176 -425.100242) (xy 372.768876 -425.075604) (xy 372.76786 -425.061634)
			(xy 372.766844 -425.030138) (xy 372.766844 -425.019724) (xy 372.759224 -425.001436) (xy 372.701312 -424.943524)
			(xy 372.693915 -424.936673) (xy 372.675317 -424.928931) (xy 372.665244 -424.928538) (xy 371.942614 -424.928538)
			(xy 371.932552 -424.928098) (xy 371.913976 -424.920354) (xy 371.906546 -424.913552) (xy 370.316252 -423.323258)
			(xy 370.307583 -423.315414) (xy 370.285487 -423.307857) (xy 370.273834 -423.30878) (xy 370.181886 -423.320718)
			(xy 370.162582 -423.333672) (xy 370.156486 -423.344086) (xy 370.139326 -423.372479) (xy 370.09876 -423.424974)
			(xy 370.05171 -423.471746) (xy 369.998976 -423.512001) (xy 369.941454 -423.545053) (xy 369.88012 -423.570343)
			(xy 369.816018 -423.587439) (xy 369.750237 -423.596052) (xy 369.717066 -423.596562) (xy 369.686336 -423.596114)
			(xy 369.625325 -423.588702) (xy 369.565653 -423.57399) (xy 369.508188 -423.552192) (xy 369.453771 -423.523626)
			(xy 369.403193 -423.488709) (xy 369.357193 -423.44795) (xy 369.316442 -423.401944) (xy 369.281533 -423.351361)
			(xy 369.252976 -423.296939) (xy 369.231187 -423.239471) (xy 369.216484 -423.179796) (xy 369.209081 -423.118784)
			(xy 369.208558 -423.088054) (xy 369.209159 -423.053428) (xy 369.218586 -422.984821) (xy 369.237233 -422.918126)
			(xy 369.250468 -422.886124) (xy 369.255548 -422.874186) (xy 369.253262 -422.848786) (xy 369.199668 -422.766998)
			(xy 369.192196 -422.756733) (xy 369.169927 -422.74461) (xy 369.15725 -422.743884) (xy 365.362236 -422.743884)
			(xy 365.352237 -422.743371) (xy 365.333769 -422.735688) (xy 365.319623 -422.721548) (xy 365.311933 -422.703083)
			(xy 365.311436 -422.693084) (xy 365.311436 -415.898076) (xy 365.31186 -415.888061) (xy 365.319536 -415.869558)
			(xy 365.333708 -415.855402) (xy 365.35222 -415.847749) (xy 365.362236 -415.847276) (xy 368.992912 -415.847276)
			(xy 369.002419 -415.846153) (xy 369.01965 -415.837844) (xy 369.032673 -415.823832) (xy 369.0397 -415.806039)
			(xy 369.040156 -415.796476) (xy 369.040156 -407.12771) (xy 369.039743 -407.118124) (xy 369.032719 -407.100285)
			(xy 369.019673 -407.086235) (xy 369.0112 -407.081736) (xy 368.914934 -407.036016) (xy 368.885978 -407.039572)
			(xy 368.874548 -407.048716) (xy 368.847242 -407.070129) (xy 368.787925 -407.10614) (xy 368.724265 -407.133753)
			(xy 368.657441 -407.152456) (xy 368.588696 -407.161903) (xy 368.554 -407.162508) (xy 368.523577 -407.162062)
			(xy 368.463168 -407.154799) (xy 368.404057 -407.140375) (xy 368.34709 -407.118999) (xy 368.293083 -407.090975)
			(xy 368.242808 -407.056703) (xy 368.196983 -407.016676) (xy 368.176302 -406.99436) (xy 368.170714 -406.988518)
			(xy 368.149378 -406.976326) (xy 368.145684 -406.974277) (xy 368.137767 -406.971335) (xy 368.13363 -406.970484)
			(xy 368.112802 -406.966674) (xy 368.104572 -406.965458) (xy 368.08811 -406.967787) (xy 368.080544 -406.971246)
			(xy 368.055396 -406.983496) (xy 368.002209 -407.000813) (xy 367.946967 -407.009595) (xy 367.919 -407.010108)
			(xy 367.889176 -407.009508) (xy 367.830361 -406.999566) (xy 367.774032 -406.979946) (xy 367.721768 -406.951198)
			(xy 367.69802 -406.933146) (xy 367.69167 -406.92832) (xy 367.668556 -406.919684) (xy 367.66451 -406.918242)
			(xy 367.656083 -406.916577) (xy 367.651792 -406.916382) (xy 367.63833 -406.916382) (xy 367.633941 -406.91637)
			(xy 367.625257 -406.917643) (xy 367.621058 -406.918922) (xy 367.598452 -406.926796) (xy 367.591848 -406.931622)
			(xy 367.565208 -406.951247) (xy 367.507812 -406.984169) (xy 367.446628 -407.009362) (xy 367.382691 -407.026398)
			(xy 367.317084 -407.034988) (xy 367.284 -407.035508) (xy 367.252039 -407.035006) (xy 367.188621 -407.026995)
			(xy 367.126707 -407.011098) (xy 367.067274 -406.987566) (xy 367.011259 -406.956772) (xy 366.959544 -406.919199)
			(xy 366.912947 -406.875442) (xy 366.872202 -406.826189) (xy 366.837951 -406.772218) (xy 366.810734 -406.714379)
			(xy 366.790981 -406.653586) (xy 366.779003 -406.590796) (xy 366.77499 -406.527) (xy 366.779003 -406.463204)
			(xy 366.790981 -406.400414) (xy 366.810734 -406.339621) (xy 366.837951 -406.281782) (xy 366.872202 -406.227811)
			(xy 366.912947 -406.178558) (xy 366.959544 -406.134801) (xy 367.011259 -406.097228) (xy 367.067274 -406.066434)
			(xy 367.126707 -406.042902) (xy 367.188621 -406.027005) (xy 367.252039 -406.018994) (xy 367.284 -406.018492)
			(xy 367.317729 -406.019042) (xy 367.384593 -406.027963) (xy 367.449691 -406.045647) (xy 367.511878 -406.071786)
			(xy 367.570063 -406.105918) (xy 367.623222 -406.147445) (xy 367.670423 -406.195638) (xy 367.710837 -406.249649)
			(xy 367.727738 -406.278842) (xy 367.732378 -406.286265) (xy 367.745622 -406.297696) (xy 367.753646 -406.301194)
			(xy 367.780316 -406.311862) (xy 367.786612 -406.314051) (xy 367.799861 -406.31546) (xy 367.806478 -406.314656)
			(xy 367.81486 -406.313386) (xy 367.818416 -406.31237) (xy 367.842638 -406.305687) (xy 367.892355 -406.298421)
			(xy 367.917476 -406.297892) (xy 367.922302 -406.297892) (xy 367.94971 -406.298674) (xy 368.003804 -406.307625)
			(xy 368.055886 -406.324761) (xy 368.080544 -406.336754) (xy 368.088115 -406.3402) (xy 368.104574 -406.342543)
			(xy 368.112802 -406.341326) (xy 368.13363 -406.337516) (xy 368.137753 -406.336617) (xy 368.145665 -406.33368)
			(xy 368.149378 -406.331674) (xy 368.170714 -406.319482) (xy 368.176302 -406.31364) (xy 368.19699 -406.291329)
			(xy 368.24281 -406.251295) (xy 368.293083 -406.217018) (xy 368.347089 -406.188989) (xy 368.404055 -406.167608)
			(xy 368.463166 -406.153182) (xy 368.523577 -406.145917) (xy 368.554 -406.145492) (xy 368.586406 -406.146001)
			(xy 368.650693 -406.15424) (xy 368.71341 -406.170584) (xy 368.773542 -406.194767) (xy 368.830111 -406.226398)
			(xy 368.882201 -406.264964) (xy 368.928966 -406.309838) (xy 368.949732 -406.334722) (xy 368.957098 -406.343866)
			(xy 368.977672 -406.353772) (xy 368.989356 -406.353772) (xy 368.999381 -406.353359) (xy 369.017908 -406.345696)
			(xy 369.032087 -406.331522) (xy 369.039756 -406.312997) (xy 369.040156 -406.302972) (xy 369.040156 -406.202388)
			(xy 369.039729 -406.19232) (xy 369.032007 -406.173723) (xy 369.02517 -406.16632) (xy 368.094768 -405.235918)
			(xy 368.087656 -405.228552) (xy 368.06886 -405.220932) (xy 365.078264 -405.220932) (xy 365.065056 -405.220932)
			(xy 365.04245 -405.233124) (xy 364.982252 -405.327104) (xy 364.98022 -405.352758) (xy 364.985554 -405.364696)
			(xy 364.996347 -405.389579) (xy 365.01159 -405.441629) (xy 365.019323 -405.495312) (xy 365.019844 -405.52243)
			(xy 365.019358 -405.549681) (xy 365.011602 -405.603629) (xy 364.996247 -405.655924) (xy 364.973605 -405.705501)
			(xy 364.944139 -405.751351) (xy 364.908448 -405.792542) (xy 364.867257 -405.828233) (xy 364.821407 -405.857699)
			(xy 364.77183 -405.880341) (xy 364.719535 -405.895696) (xy 364.665587 -405.903452) (xy 364.611085 -405.903452)
			(xy 364.557137 -405.895696) (xy 364.504842 -405.880341) (xy 364.455265 -405.857699) (xy 364.409415 -405.828233)
			(xy 364.368224 -405.792542) (xy 364.332533 -405.751351) (xy 364.303067 -405.705501) (xy 364.280425 -405.655924)
			(xy 364.26507 -405.603629) (xy 364.257314 -405.549681) (xy 364.256828 -405.52243) (xy 364.25732 -405.49531)
			(xy 364.265043 -405.441622) (xy 364.280309 -405.389574) (xy 364.291118 -405.364696) (xy 364.296452 -405.352758)
			(xy 364.29442 -405.327104) (xy 364.241334 -405.2443) (xy 364.236444 -405.237321) (xy 364.22303 -405.226827)
			(xy 364.206924 -405.221291) (xy 364.198408 -405.220932) (xy 356.882954 -405.220932) (xy 356.872888 -405.221364)
			(xy 356.854299 -405.229094) (xy 356.846886 -405.235918) (xy 354.4951 -407.587704) (xy 354.487734 -407.594816)
			(xy 354.480114 -407.613612) (xy 354.480114 -407.904145) (xy 357.450638 -407.904145) (xy 357.450638 -407.840223)
			(xy 357.458649 -407.776805) (xy 357.474546 -407.714891) (xy 357.498078 -407.655458) (xy 357.528872 -407.599443)
			(xy 357.566445 -407.547728) (xy 357.610202 -407.501131) (xy 357.659455 -407.460386) (xy 357.713426 -407.426135)
			(xy 357.771265 -407.398918) (xy 357.832058 -407.379165) (xy 357.894848 -407.367187) (xy 357.958644 -407.363174)
			(xy 358.02244 -407.367187) (xy 358.08523 -407.379165) (xy 358.146023 -407.398918) (xy 358.203862 -407.426135)
			(xy 358.257833 -407.460386) (xy 358.307086 -407.501131) (xy 358.350843 -407.547728) (xy 358.388416 -407.599443)
			(xy 358.41921 -407.655458) (xy 358.442742 -407.714891) (xy 358.458639 -407.776805) (xy 358.46665 -407.840223)
			(xy 358.467152 -407.872184) (xy 358.46665 -407.904145) (xy 358.458639 -407.967563) (xy 358.442742 -408.029477)
			(xy 358.41921 -408.08891) (xy 358.388416 -408.144925) (xy 358.350843 -408.19664) (xy 358.307086 -408.243237)
			(xy 358.257833 -408.283982) (xy 358.224714 -408.305) (xy 359.66299 -408.305) (xy 359.667003 -408.241204)
			(xy 359.678981 -408.178414) (xy 359.698734 -408.117621) (xy 359.725951 -408.059782) (xy 359.760202 -408.005811)
			(xy 359.800947 -407.956558) (xy 359.847544 -407.912801) (xy 359.899259 -407.875228) (xy 359.955274 -407.844434)
			(xy 360.014707 -407.820902) (xy 360.076621 -407.805005) (xy 360.140039 -407.796994) (xy 360.172 -407.796492)
			(xy 360.204067 -407.797) (xy 360.26769 -407.805068) (xy 360.329794 -407.821075) (xy 360.389391 -407.844767)
			(xy 360.445533 -407.875768) (xy 360.47172 -407.894282) (xy 360.48188 -407.901648) (xy 360.50601 -407.905458)
			(xy 360.607864 -407.871676) (xy 360.625136 -407.854404) (xy 360.628692 -407.842466) (xy 360.635545 -407.821404)
			(xy 360.653502 -407.780915) (xy 360.664506 -407.761694) (xy 360.67111 -407.750772) (xy 360.672126 -407.725372)
			(xy 360.623866 -407.626058) (xy 360.603292 -407.611072) (xy 360.590592 -407.609294) (xy 360.557724 -407.60432)
			(xy 360.493547 -407.586993) (xy 360.432177 -407.561449) (xy 360.374659 -407.528123) (xy 360.321977 -407.487584)
			(xy 360.275027 -407.440525) (xy 360.234612 -407.387747) (xy 360.201422 -407.330151) (xy 360.176022 -407.268721)
			(xy 360.158846 -407.204503) (xy 360.150186 -407.138595) (xy 360.149648 -407.105358) (xy 360.150138 -407.074499)
			(xy 360.157605 -407.013235) (xy 360.172437 -406.953326) (xy 360.194414 -406.895654) (xy 360.223214 -406.841068)
			(xy 360.258412 -406.790371) (xy 360.29949 -406.74431) (xy 360.322368 -406.723596) (xy 360.331004 -406.715976)
			(xy 360.339894 -406.695402) (xy 360.3371 -406.594564) (xy 360.32694 -406.574244) (xy 360.31805 -406.567386)
			(xy 360.292497 -406.546659) (xy 360.246411 -406.499696) (xy 360.206766 -406.447183) (xy 360.174225 -406.389996)
			(xy 360.14933 -406.32909) (xy 360.132497 -406.265482) (xy 360.124007 -406.200235) (xy 360.123486 -406.167336)
			(xy 360.123988 -406.135375) (xy 360.131999 -406.071957) (xy 360.147896 -406.010043) (xy 360.171428 -405.95061)
			(xy 360.202222 -405.894595) (xy 360.239795 -405.84288) (xy 360.283552 -405.796283) (xy 360.332805 -405.755538)
			(xy 360.386776 -405.721287) (xy 360.444615 -405.69407) (xy 360.505408 -405.674317) (xy 360.568198 -405.662339)
			(xy 360.631994 -405.658326) (xy 360.69579 -405.662339) (xy 360.75858 -405.674317) (xy 360.819373 -405.69407)
			(xy 360.877212 -405.721287) (xy 360.931183 -405.755538) (xy 360.980436 -405.796283) (xy 361.024193 -405.84288)
			(xy 361.061766 -405.894595) (xy 361.09256 -405.95061) (xy 361.116092 -406.010043) (xy 361.131989 -406.071957)
			(xy 361.14 -406.135375) (xy 361.140502 -406.167336) (xy 361.13992 -406.200658) (xy 361.131207 -406.266731)
			(xy 361.113934 -406.331099) (xy 361.088398 -406.392657) (xy 361.055037 -406.450351) (xy 361.014423 -406.503191)
			(xy 360.967253 -406.550271) (xy 360.941112 -406.570942) (xy 360.931951 -406.578867) (xy 360.921617 -406.600742)
			(xy 360.9213 -406.612852) (xy 360.922824 -406.671272) (xy 360.93781 -406.68067) (xy 360.9467 -406.686512)
			(xy 360.967782 -406.690068) (xy 361.061508 -406.666192) (xy 361.078272 -406.652984) (xy 361.083352 -406.643332)
			(xy 361.097678 -406.617534) (xy 361.133056 -406.570307) (xy 361.175288 -406.529094) (xy 361.223364 -406.494879)
			(xy 361.276137 -406.468479) (xy 361.332347 -406.450523) (xy 361.390652 -406.441442) (xy 361.420156 -406.440894)
			(xy 361.447411 -406.44135) (xy 361.501367 -406.449102) (xy 361.55367 -406.464455) (xy 361.603256 -406.487095)
			(xy 361.649115 -406.516562) (xy 361.690313 -406.552255) (xy 361.726012 -406.59345) (xy 361.755484 -406.639305)
			(xy 361.77813 -406.688888) (xy 361.793488 -406.74119) (xy 361.801247 -406.795145) (xy 361.801247 -406.849655)
			(xy 361.793488 -406.90361) (xy 361.77813 -406.955912) (xy 361.755484 -407.005495) (xy 361.726012 -407.05135)
			(xy 361.690313 -407.092545) (xy 361.649115 -407.128238) (xy 361.603256 -407.157705) (xy 361.55367 -407.180345)
			(xy 361.501367 -407.195698) (xy 361.447411 -407.20345) (xy 361.420156 -407.20391) (xy 361.396541 -407.203553)
			(xy 361.349667 -407.197757) (xy 361.303867 -407.186222) (xy 361.281726 -407.178002) (xy 361.27182 -407.173938)
			(xy 361.250484 -407.174954) (xy 361.16387 -407.21788) (xy 361.150154 -407.23439) (xy 361.147106 -407.244804)
			(xy 361.13704 -407.278078) (xy 361.109083 -407.341725) (xy 361.07271 -407.400967) (xy 361.051094 -407.428192)
			(xy 361.042966 -407.438098) (xy 361.037886 -407.46299) (xy 361.070398 -407.5684) (xy 361.088432 -407.586434)
			(xy 361.100878 -407.58999) (xy 361.126866 -407.598136) (xy 361.176377 -407.620821) (xy 361.22216 -407.650315)
			(xy 361.263283 -407.68602) (xy 361.298911 -407.72721) (xy 361.328321 -407.773048) (xy 361.350913 -407.822601)
			(xy 361.36623 -407.874864) (xy 361.373959 -407.928773) (xy 361.374436 -407.956004) (xy 361.373926 -407.983254)
			(xy 361.36617 -408.037199) (xy 361.350815 -408.089492) (xy 361.328176 -408.139067) (xy 361.298712 -408.184916)
			(xy 361.263023 -408.226106) (xy 361.221836 -408.261797) (xy 361.175989 -408.291264) (xy 361.126415 -408.313907)
			(xy 361.074123 -408.329265) (xy 361.020178 -408.337024) (xy 360.992928 -408.337512) (xy 360.963371 -408.336964)
			(xy 360.904962 -408.327878) (xy 360.848658 -408.309872) (xy 360.821986 -408.297126) (xy 360.81081 -408.291538)
			(xy 360.786426 -408.291792) (xy 360.69143 -408.34183) (xy 360.67746 -408.361896) (xy 360.675682 -408.374088)
			(xy 360.670656 -408.406874) (xy 360.653176 -408.470859) (xy 360.627525 -408.532027) (xy 360.594138 -408.589342)
			(xy 360.553583 -408.641829) (xy 360.506548 -408.688597) (xy 360.45383 -408.728852) (xy 360.396327 -408.761912)
			(xy 360.335013 -408.787213) (xy 360.270929 -408.804328) (xy 360.205165 -408.812965) (xy 360.172 -408.813508)
			(xy 360.140039 -408.813006) (xy 360.076621 -408.804995) (xy 360.014707 -408.789098) (xy 359.955274 -408.765566)
			(xy 359.899259 -408.734772) (xy 359.847544 -408.697199) (xy 359.800947 -408.653442) (xy 359.760202 -408.604189)
			(xy 359.725951 -408.550218) (xy 359.698734 -408.492379) (xy 359.678981 -408.431586) (xy 359.667003 -408.368796)
			(xy 359.66299 -408.305) (xy 358.224714 -408.305) (xy 358.203862 -408.318233) (xy 358.146023 -408.34545)
			(xy 358.08523 -408.365203) (xy 358.02244 -408.377181) (xy 357.958644 -408.381195) (xy 357.894848 -408.377181)
			(xy 357.832058 -408.365203) (xy 357.771265 -408.34545) (xy 357.713426 -408.318233) (xy 357.659455 -408.283982)
			(xy 357.610202 -408.243237) (xy 357.566445 -408.19664) (xy 357.528872 -408.144925) (xy 357.498078 -408.08891)
			(xy 357.474546 -408.029477) (xy 357.458649 -407.967563) (xy 357.450638 -407.904145) (xy 354.480114 -407.904145)
			(xy 354.480114 -410.185108) (xy 354.480807 -410.19727) (xy 354.491944 -410.218894) (xy 354.50145 -410.22651)
			(xy 354.579174 -410.281882) (xy 354.603304 -410.285184) (xy 354.615242 -410.28112) (xy 354.64226 -410.272103)
			(xy 354.697798 -410.259448) (xy 354.754402 -410.253079) (xy 354.782882 -410.252672) (xy 354.818803 -410.25329)
			(xy 354.88993 -410.263401) (xy 354.958926 -410.283424) (xy 354.991924 -410.29763) (xy 355.001576 -410.301948)
			(xy 355.022658 -410.302202) (xy 355.11105 -410.264864) (xy 355.125274 -410.249624) (xy 355.129084 -410.239464)
			(xy 355.140103 -410.210337) (xy 355.168249 -410.154785) (xy 355.202969 -410.103087) (xy 355.243742 -410.056014)
			(xy 355.289958 -410.014273) (xy 355.340925 -409.978487) (xy 355.395881 -409.949194) (xy 355.454002 -409.92683)
			(xy 355.514419 -409.91173) (xy 355.576228 -409.904122) (xy 355.607366 -409.903676) (xy 355.639331 -409.904155)
			(xy 355.702757 -409.912164) (xy 355.764678 -409.928059) (xy 355.82412 -409.95159) (xy 355.880143 -409.982385)
			(xy 355.931864 -410.01996) (xy 355.978468 -410.063721) (xy 356.01922 -410.112978) (xy 356.053476 -410.166955)
			(xy 356.080697 -410.2248) (xy 356.100453 -410.2856) (xy 356.112433 -410.348397) (xy 356.116448 -410.4122)
			(xy 356.112433 -410.476003) (xy 356.100453 -410.5388) (xy 356.080697 -410.5996) (xy 356.053476 -410.657445)
			(xy 356.01922 -410.711422) (xy 355.978468 -410.760679) (xy 355.931864 -410.80444) (xy 355.880143 -410.842015)
			(xy 355.82412 -410.87281) (xy 355.764678 -410.896341) (xy 355.702757 -410.912236) (xy 355.639331 -410.920245)
			(xy 355.607366 -410.920692) (xy 355.571446 -410.92007) (xy 355.500321 -410.909954) (xy 355.431327 -410.889927)
			(xy 355.398324 -410.875734) (xy 355.388672 -410.871416) (xy 355.36759 -410.871162) (xy 355.289104 -410.904182)
			(xy 355.279707 -410.908763) (xy 355.265412 -410.923985) (xy 355.261418 -410.933646) (xy 355.26091 -410.934408)
			(xy 355.26091 -410.934916) (xy 355.256592 -410.945838) (xy 355.25329 -410.954474) (xy 355.253036 -410.972254)
			(xy 355.27742 -411.04312) (xy 355.279014 -411.047381) (xy 355.283485 -411.055302) (xy 355.28631 -411.058868)
			(xy 355.292152 -411.06598) (xy 355.299772 -411.070552) (xy 355.323973 -411.085337) (xy 355.368113 -411.12094)
			(xy 355.406493 -411.162689) (xy 355.438266 -411.209662) (xy 355.462731 -411.260823) (xy 355.479348 -411.315044)
			(xy 355.48775 -411.371127) (xy 355.487753 -411.371288) (xy 356.72903 -411.371288) (xy 356.729597 -411.336957)
			(xy 356.738822 -411.268917) (xy 356.757116 -411.202736) (xy 356.784146 -411.139618) (xy 356.819422 -411.08071)
			(xy 356.862301 -411.027082) (xy 356.886764 -411.002988) (xy 356.893876 -410.996384) (xy 356.90175 -410.979366)
			(xy 356.907846 -410.891482) (xy 356.902004 -410.873448) (xy 356.896162 -410.866082) (xy 356.875167 -410.838906)
			(xy 356.839855 -410.780008) (xy 356.812792 -410.716894) (xy 356.79447 -410.650711) (xy 356.785223 -410.582664)
			(xy 356.784656 -410.548328) (xy 356.785158 -410.516367) (xy 356.793169 -410.452949) (xy 356.809066 -410.391035)
			(xy 356.832598 -410.331602) (xy 356.863392 -410.275587) (xy 356.900965 -410.223872) (xy 356.944722 -410.177275)
			(xy 356.993975 -410.13653) (xy 357.047946 -410.102279) (xy 357.105785 -410.075062) (xy 357.166578 -410.055309)
			(xy 357.229368 -410.043331) (xy 357.293164 -410.039318) (xy 357.35696 -410.043331) (xy 357.41975 -410.055309)
			(xy 357.480543 -410.075062) (xy 357.538382 -410.102279) (xy 357.592353 -410.13653) (xy 357.641606 -410.177275)
			(xy 357.685363 -410.223872) (xy 357.722936 -410.275587) (xy 357.75373 -410.331602) (xy 357.777262 -410.391035)
			(xy 357.793159 -410.452949) (xy 357.80117 -410.516367) (xy 357.801672 -410.548328) (xy 357.801115 -410.58266)
			(xy 357.791888 -410.6507) (xy 357.773974 -410.7155) (xy 361.923228 -410.7155) (xy 361.927243 -410.651693)
			(xy 361.939224 -410.588892) (xy 361.958981 -410.528088) (xy 361.986204 -410.47024) (xy 362.020463 -410.41626)
			(xy 362.061218 -410.367) (xy 362.107825 -410.323237) (xy 362.159551 -410.285661) (xy 362.215578 -410.254864)
			(xy 362.275023 -410.231333) (xy 362.336949 -410.215438) (xy 362.400379 -410.20743) (xy 362.432346 -410.206952)
			(xy 362.466837 -410.207563) (xy 362.535184 -410.216893) (xy 362.601644 -410.235375) (xy 362.664996 -410.262669)
			(xy 362.724078 -410.298275) (xy 362.777805 -410.34154) (xy 362.801916 -410.36621) (xy 362.808774 -410.373322)
			(xy 362.826554 -410.38145) (xy 362.916978 -410.385514) (xy 362.935774 -410.37891) (xy 362.94314 -410.372306)
			(xy 362.96346 -410.355288) (xy 362.971842 -410.34843) (xy 362.982002 -410.329126) (xy 362.987082 -410.231336)
			(xy 362.979208 -410.211016) (xy 362.971334 -410.203396) (xy 362.950201 -410.18172) (xy 362.914313 -410.132972)
			(xy 362.886577 -410.079167) (xy 362.867689 -410.021656) (xy 362.858124 -409.961883) (xy 362.857542 -409.931616)
			(xy 362.858028 -409.904365) (xy 362.865784 -409.850417) (xy 362.881139 -409.798122) (xy 362.903781 -409.748545)
			(xy 362.933247 -409.702695) (xy 362.968938 -409.661504) (xy 363.010129 -409.625813) (xy 363.055979 -409.596347)
			(xy 363.105556 -409.573705) (xy 363.157851 -409.55835) (xy 363.211799 -409.550594) (xy 363.266301 -409.550594)
			(xy 363.320249 -409.55835) (xy 363.372544 -409.573705) (xy 363.422121 -409.596347) (xy 363.467971 -409.625813)
			(xy 363.509162 -409.661504) (xy 363.544853 -409.702695) (xy 363.574319 -409.748545) (xy 363.596961 -409.798122)
			(xy 363.612316 -409.850417) (xy 363.620072 -409.904365) (xy 363.620558 -409.931616) (xy 363.62013 -409.958048)
			(xy 363.612828 -410.010406) (xy 363.598367 -410.061255) (xy 363.577024 -410.109619) (xy 363.549207 -410.154573)
			(xy 363.532674 -410.175202) (xy 363.525816 -410.183584) (xy 363.519974 -410.204412) (xy 363.53496 -410.301186)
			(xy 363.546644 -410.319474) (xy 363.555788 -410.325316) (xy 363.582195 -410.342945) (xy 363.630887 -410.383692)
			(xy 363.674125 -410.430187) (xy 363.711236 -410.481704) (xy 363.741644 -410.537441) (xy 363.764874 -410.596531)
			(xy 363.780564 -410.658054) (xy 363.783147 -410.67863) (xy 364.640368 -410.67863) (xy 364.640901 -410.647016)
			(xy 364.648713 -410.584273) (xy 364.664246 -410.522984) (xy 364.68726 -410.464094) (xy 364.717399 -410.408512)
			(xy 364.754198 -410.357097) (xy 364.797089 -410.310642) (xy 364.84541 -410.269865) (xy 364.898415 -410.235395)
			(xy 364.955285 -410.207764) (xy 365.015143 -410.187399) (xy 365.046006 -410.180536) (xy 365.060738 -410.177488)
			(xy 365.08182 -410.156914) (xy 365.109252 -410.03728) (xy 365.099092 -410.009594) (xy 365.087154 -410.00045)
			(xy 365.060894 -409.979796) (xy 365.013536 -409.932669) (xy 364.972757 -409.879746) (xy 364.939259 -409.82194)
			(xy 364.913617 -409.760245) (xy 364.896274 -409.695724) (xy 364.887529 -409.629488) (xy 364.887002 -409.596082)
			(xy 364.887439 -409.56535) (xy 364.89485 -409.504335) (xy 364.909561 -409.444658) (xy 364.931358 -409.387189)
			(xy 364.959923 -409.332767) (xy 364.99484 -409.282184) (xy 365.035599 -409.236179) (xy 365.081606 -409.195423)
			(xy 365.132191 -409.160509) (xy 365.186615 -409.131947) (xy 365.244085 -409.110153) (xy 365.303763 -409.095445)
			(xy 365.364778 -409.088038) (xy 365.39551 -409.087574) (xy 365.428096 -409.088084) (xy 365.492732 -409.096412)
			(xy 365.555776 -409.112929) (xy 365.616192 -409.137365) (xy 365.672991 -409.16932) (xy 365.725243 -409.20827)
			(xy 365.77209 -409.253576) (xy 365.812764 -409.304496) (xy 365.8466 -409.360195) (xy 365.873043 -409.419761)
			(xy 365.891658 -409.482217) (xy 365.897414 -409.514294) (xy 365.899354 -409.523576) (xy 365.908998 -409.539888)
			(xy 365.91621 -409.546044) (xy 365.94034 -409.565094) (xy 365.948055 -409.570616) (xy 365.966161 -409.576224)
			(xy 365.975646 -409.576016) (xy 366.014 -409.574492) (xy 366.045961 -409.574994) (xy 366.109379 -409.583005)
			(xy 366.171293 -409.598902) (xy 366.230726 -409.622434) (xy 366.286741 -409.653228) (xy 366.338456 -409.690801)
			(xy 366.385053 -409.734558) (xy 366.425798 -409.783811) (xy 366.460049 -409.837782) (xy 366.487266 -409.895621)
			(xy 366.507019 -409.956414) (xy 366.518997 -410.019204) (xy 366.523011 -410.083) (xy 366.648492 -410.083)
			(xy 366.649037 -410.049334) (xy 366.657907 -409.982589) (xy 366.675504 -409.917597) (xy 366.701521 -409.855495)
			(xy 366.735503 -409.797368) (xy 366.776857 -409.744232) (xy 366.824859 -409.697017) (xy 366.851438 -409.676346)
			(xy 366.85982 -409.67025) (xy 366.86998 -409.653232) (xy 366.882934 -409.561792) (xy 366.878108 -409.542742)
			(xy 366.871758 -409.53436) (xy 366.855094 -409.511099) (xy 366.828593 -409.460391) (xy 366.810553 -409.406093)
			(xy 366.80144 -409.349608) (xy 366.800892 -409.321) (xy 366.80139 -409.294351) (xy 366.809333 -409.241647)
			(xy 366.825043 -409.190717) (xy 366.848169 -409.142696) (xy 366.878193 -409.098659) (xy 366.914445 -409.059588)
			(xy 366.956116 -409.026357) (xy 367.002274 -408.999708) (xy 367.051888 -408.980236) (xy 367.10385 -408.968376)
			(xy 367.157 -408.964393) (xy 367.21015 -408.968376) (xy 367.262112 -408.980236) (xy 367.311726 -408.999708)
			(xy 367.357884 -409.026357) (xy 367.399555 -409.059588) (xy 367.435807 -409.098659) (xy 367.465831 -409.142696)
			(xy 367.488957 -409.190717) (xy 367.504667 -409.241647) (xy 367.51261 -409.294351) (xy 367.513108 -409.321)
			(xy 367.512563 -409.349607) (xy 367.503426 -409.406087) (xy 367.485386 -409.460383) (xy 367.458907 -409.511101)
			(xy 367.442242 -409.53436) (xy 367.435892 -409.542742) (xy 367.431066 -409.561792) (xy 367.44402 -409.653232)
			(xy 367.45418 -409.67025) (xy 367.462562 -409.676346) (xy 367.489154 -409.697003) (xy 367.537173 -409.744209)
			(xy 367.578539 -409.797342) (xy 367.612527 -409.855471) (xy 367.638543 -409.917579) (xy 367.65613 -409.982579)
			(xy 367.664982 -410.049331) (xy 367.665508 -410.083) (xy 367.665006 -410.114961) (xy 367.656995 -410.178379)
			(xy 367.641098 -410.240293) (xy 367.617566 -410.299726) (xy 367.586772 -410.355741) (xy 367.549199 -410.407456)
			(xy 367.505442 -410.454053) (xy 367.456189 -410.494798) (xy 367.402218 -410.529049) (xy 367.344379 -410.556266)
			(xy 367.283586 -410.576019) (xy 367.220796 -410.587997) (xy 367.157 -410.592011) (xy 367.093204 -410.587997)
			(xy 367.030414 -410.576019) (xy 366.969621 -410.556266) (xy 366.911782 -410.529049) (xy 366.857811 -410.494798)
			(xy 366.808558 -410.454053) (xy 366.764801 -410.407456) (xy 366.727228 -410.355741) (xy 366.696434 -410.299726)
			(xy 366.672902 -410.240293) (xy 366.657005 -410.178379) (xy 366.648994 -410.114961) (xy 366.648492 -410.083)
			(xy 366.523011 -410.083) (xy 366.518997 -410.146796) (xy 366.507019 -410.209586) (xy 366.487266 -410.270379)
			(xy 366.460049 -410.328218) (xy 366.425798 -410.382189) (xy 366.385053 -410.431442) (xy 366.338456 -410.475199)
			(xy 366.286741 -410.512772) (xy 366.230726 -410.543566) (xy 366.171293 -410.567098) (xy 366.109379 -410.582995)
			(xy 366.045961 -410.591006) (xy 366.014 -410.591508) (xy 365.977198 -410.590891) (xy 365.904356 -410.580345)
			(xy 365.833801 -410.559388) (xy 365.800132 -410.544518) (xy 365.78794 -410.538676) (xy 365.76127 -410.540962)
			(xy 365.667036 -410.605986) (xy 365.655352 -410.630116) (xy 365.656114 -410.643578) (xy 365.657384 -410.67863)
			(xy 365.656882 -410.710591) (xy 365.648871 -410.774009) (xy 365.632974 -410.835923) (xy 365.609442 -410.895356)
			(xy 365.578648 -410.951371) (xy 365.541075 -411.003086) (xy 365.497318 -411.049683) (xy 365.448065 -411.090428)
			(xy 365.394094 -411.124679) (xy 365.336255 -411.151896) (xy 365.275462 -411.171649) (xy 365.212672 -411.183627)
			(xy 365.148876 -411.187641) (xy 365.08508 -411.183627) (xy 365.02229 -411.171649) (xy 364.961497 -411.151896)
			(xy 364.903658 -411.124679) (xy 364.849687 -411.090428) (xy 364.800434 -411.049683) (xy 364.756677 -411.003086)
			(xy 364.719104 -410.951371) (xy 364.68831 -410.895356) (xy 364.664778 -410.835923) (xy 364.648881 -410.774009)
			(xy 364.64087 -410.710591) (xy 364.640368 -410.67863) (xy 363.783147 -410.67863) (xy 363.788471 -410.721052)
			(xy 363.78896 -410.752798) (xy 363.78856 -410.783532) (xy 363.781151 -410.844552) (xy 363.76644 -410.904233)
			(xy 363.744642 -410.961706) (xy 363.716075 -411.016132) (xy 363.681156 -411.066718) (xy 363.640393 -411.112726)
			(xy 363.594382 -411.153484) (xy 363.543793 -411.188399) (xy 363.489364 -411.216961) (xy 363.431889 -411.238754)
			(xy 363.372206 -411.253459) (xy 363.311186 -411.260863) (xy 363.280452 -411.261306) (xy 363.245961 -411.260709)
			(xy 363.177612 -411.251378) (xy 363.111151 -411.232895) (xy 363.047799 -411.205598) (xy 362.988718 -411.169988)
			(xy 362.934992 -411.126719) (xy 362.910882 -411.102048) (xy 362.904024 -411.094936) (xy 362.886244 -411.086808)
			(xy 362.79582 -411.082744) (xy 362.777024 -411.089348) (xy 362.769658 -411.095952) (xy 362.74636 -411.11602)
			(xy 362.695769 -411.150975) (xy 362.64133 -411.17957) (xy 362.583839 -411.201389) (xy 362.524136 -411.216112)
			(xy 362.463092 -411.223524) (xy 362.432346 -411.223968) (xy 362.400379 -411.22357) (xy 362.336949 -411.215562)
			(xy 362.275023 -411.199667) (xy 362.215578 -411.176136) (xy 362.159551 -411.145339) (xy 362.107825 -411.107763)
			(xy 362.061218 -411.064) (xy 362.020463 -411.01474) (xy 361.986204 -410.96076) (xy 361.958981 -410.902912)
			(xy 361.939224 -410.842108) (xy 361.927243 -410.779307) (xy 361.923228 -410.7155) (xy 357.773974 -410.7155)
			(xy 357.773592 -410.716881) (xy 357.74656 -410.779999) (xy 357.711282 -410.838907) (xy 357.668401 -410.892534)
			(xy 357.643938 -410.916628) (xy 357.636826 -410.923232) (xy 357.628952 -410.94025) (xy 357.622856 -411.028134)
			(xy 357.628698 -411.046168) (xy 357.63454 -411.053534) (xy 357.645225 -411.067156) (xy 357.66493 -411.095628)
			(xy 357.67391 -411.11043) (xy 357.679752 -411.119828) (xy 357.697024 -411.13202) (xy 357.793036 -411.150562)
			(xy 357.813864 -411.145736) (xy 357.822754 -411.139132) (xy 357.8478 -411.120812) (xy 357.902602 -411.091713)
			(xy 357.96139 -411.071862) (xy 358.022616 -411.061782) (xy 358.05364 -411.061154) (xy 358.080887 -411.061719)
			(xy 358.134825 -411.069479) (xy 358.187109 -411.084836) (xy 358.236676 -411.107477) (xy 358.282517 -411.136942)
			(xy 358.323699 -411.17263) (xy 358.359382 -411.213815) (xy 358.388842 -411.259659) (xy 358.411478 -411.309228)
			(xy 358.426829 -411.361515) (xy 358.434584 -411.415453) (xy 358.434584 -411.469947) (xy 358.426829 -411.523885)
			(xy 358.411478 -411.576172) (xy 358.388842 -411.625741) (xy 358.359382 -411.671585) (xy 358.323699 -411.71277)
			(xy 358.282517 -411.748458) (xy 358.236676 -411.777923) (xy 358.187109 -411.800564) (xy 358.134825 -411.815921)
			(xy 358.080887 -411.823681) (xy 358.05364 -411.82417) (xy 358.027402 -411.823762) (xy 357.975424 -411.816558)
			(xy 357.924924 -411.802294) (xy 357.876858 -411.78124) (xy 357.832132 -411.753794) (xy 357.791593 -411.720474)
			(xy 357.773478 -411.701488) (xy 357.765858 -411.693614) (xy 357.7463 -411.685232) (xy 357.64851 -411.686756)
			(xy 357.629206 -411.695646) (xy 357.622094 -411.704028) (xy 357.601337 -411.727268) (xy 357.555109 -411.769052)
			(xy 357.504123 -411.804874) (xy 357.449142 -411.8342) (xy 357.390991 -411.856589) (xy 357.33054 -411.871705)
			(xy 357.268694 -411.879322) (xy 357.237538 -411.879796) (xy 357.206806 -411.879327) (xy 357.14579 -411.871922)
			(xy 357.086112 -411.857217) (xy 357.028642 -411.835424) (xy 356.974217 -411.806863) (xy 356.923632 -411.77195)
			(xy 356.877625 -411.731193) (xy 356.836866 -411.685188) (xy 356.80195 -411.634605) (xy 356.773386 -411.580182)
			(xy 356.751591 -411.522713) (xy 356.736883 -411.463035) (xy 356.729475 -411.40202) (xy 356.72903 -411.371288)
			(xy 355.487753 -411.371288) (xy 355.48824 -411.399482) (xy 355.487754 -411.426733) (xy 355.479998 -411.480681)
			(xy 355.464643 -411.532976) (xy 355.442001 -411.582553) (xy 355.412535 -411.628403) (xy 355.376844 -411.669594)
			(xy 355.335653 -411.705285) (xy 355.289803 -411.734751) (xy 355.240226 -411.757393) (xy 355.187931 -411.772748)
			(xy 355.133983 -411.780504) (xy 355.079481 -411.780504) (xy 355.025533 -411.772748) (xy 354.973238 -411.757393)
			(xy 354.923661 -411.734751) (xy 354.877811 -411.705285) (xy 354.83662 -411.669594) (xy 354.800929 -411.628403)
			(xy 354.771463 -411.582553) (xy 354.748821 -411.532976) (xy 354.733466 -411.480681) (xy 354.72571 -411.426733)
			(xy 354.725224 -411.399482) (xy 354.725268 -411.388792) (xy 354.726411 -411.367443) (xy 354.72751 -411.35681)
			(xy 354.728018 -411.351984) (xy 354.725732 -411.343094) (xy 354.724501 -411.33884) (xy 354.720789 -411.330799)
			(xy 354.718366 -411.327092) (xy 354.67544 -411.265116) (xy 354.661216 -411.254956) (xy 354.652072 -411.25267)
			(xy 354.630736 -411.24632) (xy 354.615242 -411.24124) (xy 354.603304 -411.237176) (xy 354.579174 -411.240478)
			(xy 354.50145 -411.29585) (xy 354.49195 -411.303471) (xy 354.480818 -411.325092) (xy 354.480114 -411.337252)
			(xy 354.480114 -412.244349) (xy 359.978986 -412.244349) (xy 359.978986 -412.189851) (xy 359.986741 -412.135908)
			(xy 360.002094 -412.083618) (xy 360.024731 -412.034044) (xy 360.054193 -411.988197) (xy 360.08988 -411.947008)
			(xy 360.131064 -411.911317) (xy 360.176909 -411.881851) (xy 360.22648 -411.859208) (xy 360.278769 -411.843849)
			(xy 360.332711 -411.836088) (xy 360.35996 -411.8356) (xy 360.388388 -411.836149) (xy 360.444609 -411.844634)
			(xy 360.49895 -411.861362) (xy 360.524806 -411.873192) (xy 360.53522 -411.878018) (xy 360.557318 -411.878272)
			(xy 360.649012 -411.83687) (xy 360.66349 -411.820106) (xy 360.666538 -411.809184) (xy 360.674542 -411.782927)
			(xy 360.696934 -411.732814) (xy 360.726276 -411.686426) (xy 360.761964 -411.644723) (xy 360.803261 -411.608565)
			(xy 360.849313 -411.578699) (xy 360.89917 -411.555742) (xy 360.951802 -411.540167) (xy 361.006124 -411.532295)
			(xy 361.033568 -411.531816) (xy 361.060824 -411.532229) (xy 361.114782 -411.539982) (xy 361.167087 -411.555337)
			(xy 361.216674 -411.577979) (xy 361.262534 -411.607448) (xy 361.303734 -411.643144) (xy 361.339433 -411.68434)
			(xy 361.368906 -411.730198) (xy 361.391552 -411.779783) (xy 361.406911 -411.832087) (xy 361.414669 -411.886044)
			(xy 361.414669 -411.940556) (xy 361.406911 -411.994513) (xy 361.391552 -412.046817) (xy 361.368906 -412.096402)
			(xy 361.339433 -412.14226) (xy 361.303734 -412.183456) (xy 361.262534 -412.219152) (xy 361.216674 -412.248621)
			(xy 361.167087 -412.271263) (xy 361.114782 -412.286618) (xy 361.060824 -412.294371) (xy 361.033568 -412.294832)
			(xy 361.00514 -412.29427) (xy 360.94892 -412.28579) (xy 360.894578 -412.269067) (xy 360.868722 -412.25724)
			(xy 360.858308 -412.252414) (xy 360.83621 -412.25216) (xy 360.744516 -412.293562) (xy 360.730038 -412.310326)
			(xy 360.72699 -412.321248) (xy 360.71907 -412.347532) (xy 360.70902 -412.370016) (xy 362.919008 -412.370016)
			(xy 362.923079 -412.314394) (xy 362.935205 -412.259957) (xy 362.955128 -412.207866) (xy 362.982424 -412.159231)
			(xy 363.01651 -412.115088) (xy 363.056659 -412.076379) (xy 363.102017 -412.043928) (xy 363.151617 -412.018427)
			(xy 363.204401 -412.00042) (xy 363.259244 -411.99029) (xy 363.314978 -411.988253) (xy 363.370415 -411.994353)
			(xy 363.424372 -412.008459) (xy 363.475701 -412.030271) (xy 363.523307 -412.059325) (xy 363.566175 -412.095)
			(xy 363.603392 -412.136537) (xy 363.634165 -412.18305) (xy 363.657837 -412.233547) (xy 363.673905 -412.286954)
			(xy 363.682025 -412.34213) (xy 363.682534 -412.370016) (xy 363.682025 -412.397902) (xy 363.673905 -412.453078)
			(xy 363.657837 -412.506485) (xy 363.647769 -412.527961) (xy 367.918994 -412.527961) (xy 367.918994 -412.464039)
			(xy 367.927005 -412.400621) (xy 367.942902 -412.338707) (xy 367.966434 -412.279274) (xy 367.997228 -412.223259)
			(xy 368.034801 -412.171544) (xy 368.078558 -412.124947) (xy 368.127811 -412.084202) (xy 368.181782 -412.049951)
			(xy 368.239621 -412.022734) (xy 368.300414 -412.002981) (xy 368.363204 -411.991003) (xy 368.427 -411.98699)
			(xy 368.490796 -411.991003) (xy 368.553586 -412.002981) (xy 368.614379 -412.022734) (xy 368.672218 -412.049951)
			(xy 368.726189 -412.084202) (xy 368.775442 -412.124947) (xy 368.819199 -412.171544) (xy 368.856772 -412.223259)
			(xy 368.887566 -412.279274) (xy 368.911098 -412.338707) (xy 368.926995 -412.400621) (xy 368.935006 -412.464039)
			(xy 368.935508 -412.496) (xy 368.935006 -412.527961) (xy 368.926995 -412.591379) (xy 368.911098 -412.653293)
			(xy 368.887566 -412.712726) (xy 368.856772 -412.768741) (xy 368.819199 -412.820456) (xy 368.775442 -412.867053)
			(xy 368.726189 -412.907798) (xy 368.672218 -412.942049) (xy 368.614379 -412.969266) (xy 368.553586 -412.989019)
			(xy 368.490796 -413.000997) (xy 368.427 -413.005011) (xy 368.363204 -413.000997) (xy 368.300414 -412.989019)
			(xy 368.239621 -412.969266) (xy 368.181782 -412.942049) (xy 368.127811 -412.907798) (xy 368.078558 -412.867053)
			(xy 368.034801 -412.820456) (xy 367.997228 -412.768741) (xy 367.966434 -412.712726) (xy 367.942902 -412.653293)
			(xy 367.927005 -412.591379) (xy 367.918994 -412.527961) (xy 363.647769 -412.527961) (xy 363.634165 -412.556982)
			(xy 363.603392 -412.603495) (xy 363.566175 -412.645032) (xy 363.523307 -412.680707) (xy 363.475701 -412.709761)
			(xy 363.424372 -412.731573) (xy 363.370415 -412.745679) (xy 363.314978 -412.751779) (xy 363.259244 -412.749742)
			(xy 363.204401 -412.739612) (xy 363.151617 -412.721605) (xy 363.102017 -412.696104) (xy 363.056659 -412.663653)
			(xy 363.01651 -412.624944) (xy 362.982424 -412.580801) (xy 362.955128 -412.532166) (xy 362.935205 -412.480075)
			(xy 362.923079 -412.425638) (xy 362.919008 -412.370016) (xy 360.70902 -412.370016) (xy 360.696669 -412.397649)
			(xy 360.667316 -412.444038) (xy 360.631617 -412.485741) (xy 360.59031 -412.521897) (xy 360.544247 -412.551759)
			(xy 360.49438 -412.574711) (xy 360.441738 -412.590279) (xy 360.387408 -412.598142) (xy 360.35996 -412.598616)
			(xy 360.332711 -412.598112) (xy 360.278769 -412.590351) (xy 360.22648 -412.574992) (xy 360.176909 -412.552349)
			(xy 360.131064 -412.522883) (xy 360.08988 -412.487192) (xy 360.054193 -412.446003) (xy 360.024731 -412.400156)
			(xy 360.002094 -412.350582) (xy 359.986741 -412.298292) (xy 359.978986 -412.244349) (xy 354.480114 -412.244349)
			(xy 354.480114 -413.07258) (xy 360.718608 -413.07258) (xy 360.71911 -413.040619) (xy 360.727121 -412.977201)
			(xy 360.743018 -412.915287) (xy 360.76655 -412.855854) (xy 360.797344 -412.799839) (xy 360.834917 -412.748124)
			(xy 360.878674 -412.701527) (xy 360.927927 -412.660782) (xy 360.981898 -412.626531) (xy 361.039737 -412.599314)
			(xy 361.10053 -412.579561) (xy 361.16332 -412.567583) (xy 361.227116 -412.56357) (xy 361.290912 -412.567583)
			(xy 361.353702 -412.579561) (xy 361.414495 -412.599314) (xy 361.472334 -412.626531) (xy 361.526305 -412.660782)
			(xy 361.575558 -412.701527) (xy 361.619315 -412.748124) (xy 361.656888 -412.799839) (xy 361.687682 -412.855854)
			(xy 361.711214 -412.915287) (xy 361.727111 -412.977201) (xy 361.735122 -413.040619) (xy 361.735624 -413.07258)
			(xy 361.735163 -413.103737) (xy 361.727541 -413.165584) (xy 361.712419 -413.226037) (xy 361.690026 -413.284189)
			(xy 361.660696 -413.33917) (xy 361.643168 -413.364934) (xy 361.637263 -413.374384) (xy 361.633412 -413.396303)
			(xy 361.639216 -413.417788) (xy 361.645962 -413.426656) (xy 361.66452 -413.449571) (xy 361.696809 -413.498912)
			(xy 361.723177 -413.551655) (xy 361.743271 -413.607094) (xy 361.756821 -413.664483) (xy 361.763645 -413.723054)
			(xy 361.764072 -413.752538) (xy 361.76357 -413.784499) (xy 361.755559 -413.847917) (xy 361.739662 -413.909831)
			(xy 361.71613 -413.969264) (xy 361.685336 -414.025279) (xy 361.647763 -414.076994) (xy 361.604006 -414.123591)
			(xy 361.554753 -414.164336) (xy 361.500782 -414.198587) (xy 361.442943 -414.225804) (xy 361.38215 -414.245557)
			(xy 361.31936 -414.257535) (xy 361.255564 -414.261549) (xy 361.191768 -414.257535) (xy 361.128978 -414.245557)
			(xy 361.068185 -414.225804) (xy 361.010346 -414.198587) (xy 360.956375 -414.164336) (xy 360.907122 -414.123591)
			(xy 360.863365 -414.076994) (xy 360.825792 -414.025279) (xy 360.794998 -413.969264) (xy 360.771466 -413.909831)
			(xy 360.755569 -413.847917) (xy 360.747558 -413.784499) (xy 360.747056 -413.752538) (xy 360.74753 -413.721381)
			(xy 360.75515 -413.659535) (xy 360.770268 -413.599082) (xy 360.792659 -413.54093) (xy 360.821985 -413.485948)
			(xy 360.839512 -413.460184) (xy 360.845403 -413.450726) (xy 360.849262 -413.428812) (xy 360.843462 -413.407329)
			(xy 360.836718 -413.398462) (xy 360.818181 -413.375531) (xy 360.785887 -413.326194) (xy 360.759514 -413.273455)
			(xy 360.739417 -413.21802) (xy 360.725863 -413.160632) (xy 360.719036 -413.102063) (xy 360.718608 -413.07258)
			(xy 354.480114 -413.07258) (xy 354.480114 -415.417) (xy 360.651089 -415.417) (xy 360.655103 -415.353207)
			(xy 360.667079 -415.29042) (xy 360.68683 -415.22963) (xy 360.714045 -415.171794) (xy 360.748292 -415.117824)
			(xy 360.789034 -415.068572) (xy 360.835627 -415.024815) (xy 360.887337 -414.987242) (xy 360.943348 -414.956446)
			(xy 361.002777 -414.932912) (xy 361.064686 -414.917012) (xy 361.128101 -414.908996) (xy 361.16006 -414.908492)
			(xy 361.19273 -414.908997) (xy 361.25753 -414.91738) (xy 361.320724 -414.933988) (xy 361.381272 -414.958547)
			(xy 361.43818 -414.990654) (xy 361.49051 -415.02978) (xy 361.537402 -415.075282) (xy 361.578084 -415.126412)
			(xy 361.595416 -415.15411) (xy 361.601766 -415.164524) (xy 361.62234 -415.177478) (xy 361.728766 -415.186368)
			(xy 361.751372 -415.17697) (xy 361.7595 -415.167572) (xy 361.777729 -415.147098) (xy 361.819008 -415.111028)
			(xy 361.865023 -415.081237) (xy 361.914829 -415.058339) (xy 361.967399 -415.042804) (xy 362.021651 -415.034953)
			(xy 362.04906 -415.034476) (xy 362.076314 -415.034969) (xy 362.130267 -415.042721) (xy 362.182567 -415.058073)
			(xy 362.23215 -415.080712) (xy 362.278006 -415.110177) (xy 362.319202 -415.14587) (xy 362.354899 -415.187062)
			(xy 362.384369 -415.232915) (xy 362.407013 -415.282495) (xy 362.422371 -415.334794) (xy 362.430129 -415.388746)
			(xy 362.430129 -415.443254) (xy 362.422371 -415.497206) (xy 362.407013 -415.549505) (xy 362.384369 -415.599085)
			(xy 362.354899 -415.644938) (xy 362.319202 -415.68613) (xy 362.278006 -415.721823) (xy 362.23215 -415.751288)
			(xy 362.182567 -415.773927) (xy 362.130267 -415.789279) (xy 362.076314 -415.797031) (xy 362.04906 -415.797492)
			(xy 362.02171 -415.797008) (xy 361.96757 -415.789209) (xy 361.915102 -415.773751) (xy 361.865382 -415.750948)
			(xy 361.819434 -415.721272) (xy 361.778201 -415.68533) (xy 361.760008 -415.664904) (xy 361.75188 -415.65576)
			(xy 361.729274 -415.646362) (xy 361.622848 -415.655506) (xy 361.602274 -415.66846) (xy 361.595924 -415.678874)
			(xy 361.578639 -415.706684) (xy 361.537994 -415.758025) (xy 361.491094 -415.803722) (xy 361.438715 -415.843019)
			(xy 361.381724 -415.875266) (xy 361.321065 -415.899929) (xy 361.257741 -415.9166) (xy 361.192801 -415.925002)
			(xy 361.16006 -415.925508) (xy 361.128101 -415.925004) (xy 361.064686 -415.916988) (xy 361.002777 -415.901088)
			(xy 360.943348 -415.877554) (xy 360.887337 -415.846758) (xy 360.835627 -415.809185) (xy 360.789034 -415.765428)
			(xy 360.748292 -415.716176) (xy 360.714045 -415.662206) (xy 360.68683 -415.60437) (xy 360.667079 -415.54358)
			(xy 360.655103 -415.480793) (xy 360.651089 -415.417) (xy 354.480114 -415.417) (xy 354.480114 -415.830258)
			(xy 355.202742 -415.830258) (xy 355.206813 -415.774636) (xy 355.218939 -415.720199) (xy 355.238862 -415.668108)
			(xy 355.266158 -415.619473) (xy 355.300244 -415.57533) (xy 355.340393 -415.536621) (xy 355.385751 -415.50417)
			(xy 355.435351 -415.478669) (xy 355.488135 -415.460662) (xy 355.542978 -415.450532) (xy 355.598712 -415.448495)
			(xy 355.654149 -415.454595) (xy 355.708106 -415.468701) (xy 355.759435 -415.490513) (xy 355.807041 -415.519567)
			(xy 355.849909 -415.555242) (xy 355.887126 -415.596779) (xy 355.917899 -415.643292) (xy 355.941571 -415.693789)
			(xy 355.957639 -415.747196) (xy 355.965759 -415.802372) (xy 355.966268 -415.830258) (xy 355.965759 -415.858144)
			(xy 355.957639 -415.91332) (xy 355.941571 -415.966727) (xy 355.917899 -416.017224) (xy 355.887126 -416.063737)
			(xy 355.849909 -416.105274) (xy 355.807041 -416.140949) (xy 355.759435 -416.170003) (xy 355.708106 -416.191815)
			(xy 355.654149 -416.205921) (xy 355.598712 -416.212021) (xy 355.542978 -416.209984) (xy 355.488135 -416.199854)
			(xy 355.435351 -416.181847) (xy 355.385751 -416.156346) (xy 355.340393 -416.123895) (xy 355.300244 -416.085186)
			(xy 355.266158 -416.041043) (xy 355.238862 -415.992408) (xy 355.218939 -415.940317) (xy 355.206813 -415.88588)
			(xy 355.202742 -415.830258) (xy 354.480114 -415.830258) (xy 354.480114 -416.214052) (xy 354.480564 -416.224189)
			(xy 354.488417 -416.242883) (xy 354.502881 -416.257091) (xy 354.512118 -416.261296) (xy 354.599494 -416.296094)
			(xy 354.606621 -416.298707) (xy 354.621741 -416.299987) (xy 354.629212 -416.298634) (xy 354.636832 -416.29711)
			(xy 354.649786 -416.289744) (xy 354.65512 -416.284156) (xy 354.673194 -416.265839) (xy 354.713412 -416.233734)
			(xy 354.757577 -416.207323) (xy 354.804891 -416.187085) (xy 354.854494 -416.173387) (xy 354.905488 -416.166476)
			(xy 354.931218 -416.166046) (xy 354.95847 -416.166533) (xy 355.012418 -416.174291) (xy 355.064713 -416.189648)
			(xy 355.114291 -416.212289) (xy 355.160142 -416.241755) (xy 355.201334 -416.277446) (xy 355.237028 -416.318635)
			(xy 355.266497 -416.364484) (xy 355.289143 -416.414061) (xy 355.302689 -416.460178) (xy 356.502714 -416.460178)
			(xy 356.506785 -416.404556) (xy 356.518911 -416.350119) (xy 356.538834 -416.298028) (xy 356.56613 -416.249393)
			(xy 356.600216 -416.20525) (xy 356.640365 -416.166541) (xy 356.685723 -416.13409) (xy 356.735323 -416.108589)
			(xy 356.788107 -416.090582) (xy 356.84295 -416.080452) (xy 356.898684 -416.078415) (xy 356.954121 -416.084515)
			(xy 357.008078 -416.098621) (xy 357.059407 -416.120433) (xy 357.107013 -416.149487) (xy 357.149881 -416.185162)
			(xy 357.187098 -416.226699) (xy 357.217871 -416.273212) (xy 357.241543 -416.323709) (xy 357.257611 -416.377116)
			(xy 357.265731 -416.432292) (xy 357.26624 -416.460178) (xy 357.265731 -416.488064) (xy 357.257611 -416.54324)
			(xy 357.241543 -416.596647) (xy 357.217871 -416.647144) (xy 357.187098 -416.693657) (xy 357.149881 -416.735194)
			(xy 357.107013 -416.770869) (xy 357.059407 -416.799923) (xy 357.008078 -416.821735) (xy 356.954121 -416.835841)
			(xy 356.898684 -416.841941) (xy 356.84295 -416.839904) (xy 356.788107 -416.829774) (xy 356.735323 -416.811767)
			(xy 356.685723 -416.786266) (xy 356.640365 -416.753815) (xy 356.600216 -416.715106) (xy 356.56613 -416.670963)
			(xy 356.538834 -416.622328) (xy 356.518911 -416.570237) (xy 356.506785 -416.5158) (xy 356.502714 -416.460178)
			(xy 355.302689 -416.460178) (xy 355.304503 -416.466355) (xy 355.312265 -416.520302) (xy 355.312726 -416.547554)
			(xy 355.312225 -416.575293) (xy 355.304186 -416.630186) (xy 355.288286 -416.683336) (xy 355.264859 -416.733626)
			(xy 355.2344 -416.779994) (xy 355.197549 -416.821465) (xy 355.155082 -416.857164) (xy 355.107896 -416.88634)
			(xy 355.056983 -416.908378) (xy 355.003416 -416.922814) (xy 354.975922 -416.926522) (xy 354.962206 -416.928046)
			(xy 354.931218 -416.929316) (xy 354.905488 -416.928896) (xy 354.854493 -416.921985) (xy 354.804889 -416.908285)
			(xy 354.757576 -416.888044) (xy 354.713411 -416.861631) (xy 354.673195 -416.829524) (xy 354.65512 -416.811206)
			(xy 354.644198 -416.799776) (xy 354.613972 -416.793172) (xy 354.512118 -416.833812) (xy 354.502854 -416.83797)
			(xy 354.488379 -416.852188) (xy 354.480559 -416.87091) (xy 354.480114 -416.881056) (xy 354.480114 -417.582956)
			(xy 358.571435 -417.582956) (xy 358.571435 -417.528444) (xy 358.579194 -417.474486) (xy 358.594553 -417.422181)
			(xy 358.6172 -417.372596) (xy 358.646674 -417.326738) (xy 358.682374 -417.285542) (xy 358.723575 -417.249846)
			(xy 358.769436 -417.220378) (xy 358.819025 -417.197737) (xy 358.871331 -417.182384) (xy 358.92529 -417.174632)
			(xy 358.952546 -417.174172) (xy 358.980184 -417.17471) (xy 359.034883 -417.18268) (xy 359.087859 -417.198461)
			(xy 359.138003 -417.221724) (xy 359.184264 -417.251979) (xy 359.225674 -417.288595) (xy 359.261366 -417.330804)
			(xy 359.276396 -417.354004) (xy 359.284347 -417.365835) (xy 359.305497 -417.384928) (xy 359.331097 -417.397435)
			(xy 359.359156 -417.402386) (xy 359.38749 -417.399393) (xy 359.413896 -417.388691) (xy 359.436319 -417.371112)
			(xy 359.445052 -417.359846) (xy 359.46045 -417.339129) (xy 359.496004 -417.301707) (xy 359.536278 -417.269419)
			(xy 359.580537 -417.242854) (xy 359.627972 -417.222496) (xy 359.677719 -417.208718) (xy 359.728868 -417.201771)
			(xy 359.754678 -417.20135) (xy 359.781929 -417.201896) (xy 359.835876 -417.209649) (xy 359.888171 -417.225002)
			(xy 359.937748 -417.24764) (xy 359.983599 -417.277105) (xy 360.02479 -417.312794) (xy 360.060482 -417.353983)
			(xy 360.089949 -417.399832) (xy 360.112591 -417.449408) (xy 360.127946 -417.501702) (xy 360.130625 -417.520331)
			(xy 362.476282 -417.520331) (xy 362.476282 -417.456409) (xy 362.484293 -417.392991) (xy 362.50019 -417.331077)
			(xy 362.523722 -417.271644) (xy 362.554516 -417.215629) (xy 362.592089 -417.163914) (xy 362.635846 -417.117317)
			(xy 362.685099 -417.076572) (xy 362.73907 -417.042321) (xy 362.796909 -417.015104) (xy 362.857702 -416.995351)
			(xy 362.920492 -416.983373) (xy 362.984288 -416.97936) (xy 363.048084 -416.983373) (xy 363.110874 -416.995351)
			(xy 363.171667 -417.015104) (xy 363.229506 -417.042321) (xy 363.283477 -417.076572) (xy 363.33273 -417.117317)
			(xy 363.376487 -417.163914) (xy 363.41406 -417.215629) (xy 363.444854 -417.271644) (xy 363.468386 -417.331077)
			(xy 363.484283 -417.392991) (xy 363.484524 -417.394898) (xy 363.68304 -417.394898) (xy 363.687111 -417.339276)
			(xy 363.699237 -417.284839) (xy 363.71916 -417.232748) (xy 363.746456 -417.184113) (xy 363.780542 -417.13997)
			(xy 363.820691 -417.101261) (xy 363.866049 -417.06881) (xy 363.915649 -417.043309) (xy 363.968433 -417.025302)
			(xy 364.023276 -417.015172) (xy 364.07901 -417.013135) (xy 364.134447 -417.019235) (xy 364.188404 -417.033341)
			(xy 364.239733 -417.055153) (xy 364.287339 -417.084207) (xy 364.330207 -417.119882) (xy 364.367424 -417.161419)
			(xy 364.398197 -417.207932) (xy 364.421869 -417.258429) (xy 364.437937 -417.311836) (xy 364.446057 -417.367012)
			(xy 364.446566 -417.394898) (xy 364.446057 -417.422784) (xy 364.437937 -417.47796) (xy 364.421869 -417.531367)
			(xy 364.398197 -417.581864) (xy 364.367424 -417.628377) (xy 364.330207 -417.669914) (xy 364.287339 -417.705589)
			(xy 364.239733 -417.734643) (xy 364.188404 -417.756455) (xy 364.134447 -417.770561) (xy 364.07901 -417.776661)
			(xy 364.023276 -417.774624) (xy 363.968433 -417.764494) (xy 363.915649 -417.746487) (xy 363.866049 -417.720986)
			(xy 363.820691 -417.688535) (xy 363.780542 -417.649826) (xy 363.746456 -417.605683) (xy 363.71916 -417.557048)
			(xy 363.699237 -417.504957) (xy 363.687111 -417.45052) (xy 363.68304 -417.394898) (xy 363.484524 -417.394898)
			(xy 363.492294 -417.456409) (xy 363.492796 -417.48837) (xy 363.492294 -417.520331) (xy 363.484283 -417.583749)
			(xy 363.468386 -417.645663) (xy 363.444854 -417.705096) (xy 363.41406 -417.761111) (xy 363.376487 -417.812826)
			(xy 363.33273 -417.859423) (xy 363.283477 -417.900168) (xy 363.229506 -417.934419) (xy 363.171667 -417.961636)
			(xy 363.110874 -417.981389) (xy 363.048084 -417.993367) (xy 362.984288 -417.997381) (xy 362.920492 -417.993367)
			(xy 362.857702 -417.981389) (xy 362.796909 -417.961636) (xy 362.73907 -417.934419) (xy 362.685099 -417.900168)
			(xy 362.635846 -417.859423) (xy 362.592089 -417.812826) (xy 362.554516 -417.761111) (xy 362.523722 -417.705096)
			(xy 362.50019 -417.645663) (xy 362.484293 -417.583749) (xy 362.476282 -417.520331) (xy 360.130625 -417.520331)
			(xy 360.135703 -417.555649) (xy 360.135703 -417.610151) (xy 360.127946 -417.664098) (xy 360.112591 -417.716392)
			(xy 360.089949 -417.765968) (xy 360.060482 -417.811817) (xy 360.02479 -417.853006) (xy 359.983599 -417.888695)
			(xy 359.937748 -417.91816) (xy 359.888171 -417.940798) (xy 359.835876 -417.956151) (xy 359.781929 -417.963904)
			(xy 359.754678 -417.964366) (xy 359.727036 -417.963916) (xy 359.672332 -417.955934) (xy 359.619353 -417.940139)
			(xy 359.569208 -417.916863) (xy 359.522947 -417.886593) (xy 359.481541 -417.849963) (xy 359.445854 -417.80774)
			(xy 359.430828 -417.784534) (xy 359.422845 -417.772729) (xy 359.401698 -417.753649) (xy 359.376106 -417.741148)
			(xy 359.348057 -417.736198) (xy 359.319732 -417.739184) (xy 359.293332 -417.749873) (xy 359.270908 -417.767435)
			(xy 359.262172 -417.778692) (xy 359.246742 -417.799384) (xy 359.211195 -417.836809) (xy 359.170927 -417.869102)
			(xy 359.126674 -417.895671) (xy 359.079243 -417.916032) (xy 359.029501 -417.929814) (xy 358.978354 -417.936765)
			(xy 358.952546 -417.937188) (xy 358.92529 -417.936768) (xy 358.871331 -417.929016) (xy 358.819025 -417.913663)
			(xy 358.769436 -417.891022) (xy 358.723575 -417.861554) (xy 358.682374 -417.825858) (xy 358.646674 -417.784662)
			(xy 358.6172 -417.738804) (xy 358.594553 -417.689219) (xy 358.579194 -417.636914) (xy 358.571435 -417.582956)
			(xy 354.480114 -417.582956) (xy 354.480114 -418.981128) (xy 355.833932 -418.981128) (xy 355.838003 -418.925506)
			(xy 355.850129 -418.871069) (xy 355.870052 -418.818978) (xy 355.897348 -418.770343) (xy 355.931434 -418.7262)
			(xy 355.971583 -418.687491) (xy 356.016941 -418.65504) (xy 356.066541 -418.629539) (xy 356.119325 -418.611532)
			(xy 356.174168 -418.601402) (xy 356.229902 -418.599365) (xy 356.285339 -418.605465) (xy 356.339296 -418.619571)
			(xy 356.390625 -418.641383) (xy 356.438231 -418.670437) (xy 356.481099 -418.706112) (xy 356.518316 -418.747649)
			(xy 356.549089 -418.794162) (xy 356.572761 -418.844659) (xy 356.588829 -418.898066) (xy 356.596949 -418.953242)
			(xy 356.597458 -418.981128) (xy 356.596949 -419.009014) (xy 356.594175 -419.027864) (xy 360.30865 -419.027864)
			(xy 360.312721 -418.972242) (xy 360.324847 -418.917805) (xy 360.34477 -418.865714) (xy 360.372066 -418.817079)
			(xy 360.406152 -418.772936) (xy 360.446301 -418.734227) (xy 360.491659 -418.701776) (xy 360.541259 -418.676275)
			(xy 360.594043 -418.658268) (xy 360.648886 -418.648138) (xy 360.70462 -418.646101) (xy 360.760057 -418.652201)
			(xy 360.814014 -418.666307) (xy 360.865343 -418.688119) (xy 360.912949 -418.717173) (xy 360.955817 -418.752848)
			(xy 360.993034 -418.794385) (xy 361.023807 -418.840898) (xy 361.047479 -418.891395) (xy 361.063547 -418.944802)
			(xy 361.071667 -418.999978) (xy 361.072176 -419.027864) (xy 361.071667 -419.05575) (xy 361.063547 -419.110926)
			(xy 361.047479 -419.164333) (xy 361.023807 -419.21483) (xy 360.993034 -419.261343) (xy 360.955817 -419.30288)
			(xy 360.912949 -419.338555) (xy 360.865343 -419.367609) (xy 360.814014 -419.389421) (xy 360.760057 -419.403527)
			(xy 360.70462 -419.409627) (xy 360.648886 -419.40759) (xy 360.594043 -419.39746) (xy 360.541259 -419.379453)
			(xy 360.491659 -419.353952) (xy 360.446301 -419.321501) (xy 360.406152 -419.282792) (xy 360.372066 -419.238649)
			(xy 360.34477 -419.190014) (xy 360.324847 -419.137923) (xy 360.312721 -419.083486) (xy 360.30865 -419.027864)
			(xy 356.594175 -419.027864) (xy 356.588829 -419.06419) (xy 356.572761 -419.117597) (xy 356.549089 -419.168094)
			(xy 356.518316 -419.214607) (xy 356.481099 -419.256144) (xy 356.438231 -419.291819) (xy 356.390625 -419.320873)
			(xy 356.339296 -419.342685) (xy 356.285339 -419.356791) (xy 356.229902 -419.362891) (xy 356.174168 -419.360854)
			(xy 356.119325 -419.350724) (xy 356.066541 -419.332717) (xy 356.016941 -419.307216) (xy 355.971583 -419.274765)
			(xy 355.931434 -419.236056) (xy 355.897348 -419.191913) (xy 355.870052 -419.143278) (xy 355.850129 -419.091187)
			(xy 355.838003 -419.03675) (xy 355.833932 -418.981128) (xy 354.480114 -418.981128) (xy 354.480114 -419.602158)
			(xy 363.51337 -419.602158) (xy 363.513872 -419.570197) (xy 363.521883 -419.506779) (xy 363.53778 -419.444865)
			(xy 363.561312 -419.385432) (xy 363.592106 -419.329417) (xy 363.629679 -419.277702) (xy 363.673436 -419.231105)
			(xy 363.722689 -419.19036) (xy 363.77666 -419.156109) (xy 363.834499 -419.128892) (xy 363.895292 -419.109139)
			(xy 363.958082 -419.097161) (xy 364.021878 -419.093148) (xy 364.085674 -419.097161) (xy 364.148464 -419.109139)
			(xy 364.209257 -419.128892) (xy 364.267096 -419.156109) (xy 364.321067 -419.19036) (xy 364.37032 -419.231105)
			(xy 364.414077 -419.277702) (xy 364.45165 -419.329417) (xy 364.482444 -419.385432) (xy 364.505976 -419.444865)
			(xy 364.521873 -419.506779) (xy 364.529884 -419.570197) (xy 364.530386 -419.602158) (xy 364.529906 -419.635149)
			(xy 364.521364 -419.700575) (xy 364.504433 -419.764347) (xy 364.479395 -419.825394) (xy 364.446672 -419.88269)
			(xy 364.406814 -419.935272) (xy 364.360489 -419.982257) (xy 364.334806 -420.00297) (xy 364.323884 -420.011352)
			(xy 364.313724 -420.037006) (xy 364.331758 -420.152322) (xy 364.349284 -420.173404) (xy 364.362492 -420.17823)
			(xy 364.389592 -420.188746) (xy 364.440456 -420.21689) (xy 364.486463 -420.252421) (xy 364.52655 -420.294518)
			(xy 364.55979 -420.342207) (xy 364.585414 -420.394385) (xy 364.60283 -420.449845) (xy 364.611634 -420.507305)
			(xy 364.612174 -420.53637) (xy 364.611659 -420.56515) (xy 364.603003 -420.622057) (xy 364.585898 -420.677018)
			(xy 364.560733 -420.728786) (xy 364.528077 -420.776188) (xy 364.488672 -420.818146) (xy 364.443412 -420.853711)
			(xy 364.418626 -420.868348) (xy 364.406942 -420.874952) (xy 364.393226 -420.897812) (xy 364.390178 -421.011604)
			(xy 364.402624 -421.034972) (xy 364.4138 -421.042338) (xy 364.440282 -421.059916) (xy 364.489066 -421.100661)
			(xy 364.532391 -421.14717) (xy 364.569579 -421.198717) (xy 364.600052 -421.254498) (xy 364.623334 -421.313642)
			(xy 364.639061 -421.375228) (xy 364.646988 -421.438293) (xy 364.64748 -421.470074) (xy 364.646978 -421.502035)
			(xy 364.638967 -421.565453) (xy 364.62307 -421.627367) (xy 364.599538 -421.6868) (xy 364.568744 -421.742815)
			(xy 364.531171 -421.79453) (xy 364.487414 -421.841127) (xy 364.438161 -421.881872) (xy 364.38419 -421.916123)
			(xy 364.326351 -421.94334) (xy 364.265558 -421.963093) (xy 364.202768 -421.975071) (xy 364.138972 -421.979085)
			(xy 364.075176 -421.975071) (xy 364.012386 -421.963093) (xy 363.951593 -421.94334) (xy 363.893754 -421.916123)
			(xy 363.839783 -421.881872) (xy 363.79053 -421.841127) (xy 363.746773 -421.79453) (xy 363.7092 -421.742815)
			(xy 363.678406 -421.6868) (xy 363.654874 -421.627367) (xy 363.638977 -421.565453) (xy 363.630966 -421.502035)
			(xy 363.630464 -421.470074) (xy 363.630909 -421.439668) (xy 363.638172 -421.379291) (xy 363.65258 -421.320211)
			(xy 363.673926 -421.263268) (xy 363.701907 -421.209276) (xy 363.736124 -421.159004) (xy 363.77609 -421.113168)
			(xy 363.821233 -421.072423) (xy 363.870911 -421.037348) (xy 363.924415 -421.008445) (xy 363.952536 -420.996872)
			(xy 363.965236 -420.992046) (xy 363.981746 -420.971472) (xy 364.000796 -420.859204) (xy 363.991906 -420.834312)
			(xy 363.981746 -420.825422) (xy 363.961344 -420.807204) (xy 363.925412 -420.765968) (xy 363.895737 -420.720023)
			(xy 363.872929 -420.670311) (xy 363.857455 -420.61785) (xy 363.849633 -420.563717) (xy 363.849158 -420.53637)
			(xy 363.849764 -420.506645) (xy 363.858988 -420.447914) (xy 363.877209 -420.391324) (xy 363.903985 -420.338245)
			(xy 363.938668 -420.28996) (xy 363.95914 -420.2684) (xy 363.968792 -420.258494) (xy 363.97565 -420.231824)
			(xy 363.942884 -420.120064) (xy 363.922818 -420.101014) (xy 363.909356 -420.097966) (xy 363.879074 -420.090614)
			(xy 363.820439 -420.069517) (xy 363.764823 -420.041409) (xy 363.713059 -420.006714) (xy 363.665925 -419.965951)
			(xy 363.624128 -419.919733) (xy 363.588294 -419.868751) (xy 363.55896 -419.813772) (xy 363.536568 -419.755619)
			(xy 363.521452 -419.695164) (xy 363.513839 -419.633316) (xy 363.51337 -419.602158) (xy 354.480114 -419.602158)
			(xy 354.480114 -420.272718) (xy 354.479688 -420.282787) (xy 354.471971 -420.301388) (xy 354.465128 -420.308786)
			(xy 354.372207 -420.401707) (xy 359.855764 -420.401707) (xy 359.855764 -420.337785) (xy 359.863775 -420.274367)
			(xy 359.879672 -420.212453) (xy 359.903204 -420.15302) (xy 359.933998 -420.097005) (xy 359.971571 -420.04529)
			(xy 360.015328 -419.998693) (xy 360.064581 -419.957948) (xy 360.118552 -419.923697) (xy 360.176391 -419.89648)
			(xy 360.237184 -419.876727) (xy 360.299974 -419.864749) (xy 360.36377 -419.860736) (xy 360.427566 -419.864749)
			(xy 360.490356 -419.876727) (xy 360.551149 -419.89648) (xy 360.608988 -419.923697) (xy 360.662959 -419.957948)
			(xy 360.712212 -419.998693) (xy 360.755969 -420.04529) (xy 360.793542 -420.097005) (xy 360.824336 -420.15302)
			(xy 360.847868 -420.212453) (xy 360.863765 -420.274367) (xy 360.871776 -420.337785) (xy 360.872278 -420.369746)
			(xy 360.871776 -420.401707) (xy 360.863765 -420.465125) (xy 360.847868 -420.527039) (xy 360.824336 -420.586472)
			(xy 360.793542 -420.642487) (xy 360.755969 -420.694202) (xy 360.712212 -420.740799) (xy 360.662959 -420.781544)
			(xy 360.608988 -420.815795) (xy 360.551149 -420.843012) (xy 360.490356 -420.862765) (xy 360.427566 -420.874743)
			(xy 360.36377 -420.878757) (xy 360.299974 -420.874743) (xy 360.237184 -420.862765) (xy 360.176391 -420.843012)
			(xy 360.118552 -420.815795) (xy 360.064581 -420.781544) (xy 360.015328 -420.740799) (xy 359.971571 -420.694202)
			(xy 359.933998 -420.642487) (xy 359.903204 -420.586472) (xy 359.879672 -420.527039) (xy 359.863775 -420.465125)
			(xy 359.855764 -420.401707) (xy 354.372207 -420.401707) (xy 352.773234 -422.00068) (xy 352.765868 -422.007792)
			(xy 352.758248 -422.026588) (xy 352.758248 -422.423082) (xy 352.758658 -422.432701) (xy 352.765745 -422.450585)
			(xy 352.778925 -422.464597) (xy 352.787458 -422.469056) (xy 352.883978 -422.514522) (xy 352.912934 -422.510966)
			(xy 352.924364 -422.501568) (xy 352.951783 -422.479767) (xy 353.011473 -422.44311) (xy 353.075631 -422.414993)
			(xy 353.143041 -422.39595) (xy 353.212428 -422.386341) (xy 353.247452 -422.385744) (xy 353.28048 -422.386274)
			(xy 353.34598 -422.394834) (xy 353.40982 -422.411802) (xy 353.470926 -422.436894) (xy 353.528269 -422.469686)
			(xy 353.580883 -422.509627) (xy 353.627882 -422.556043) (xy 353.668477 -422.608155) (xy 353.701982 -422.665084)
			(xy 353.727833 -422.725872) (xy 353.745597 -422.789495) (xy 353.754973 -422.854883) (xy 353.75596 -422.887902)
			(xy 353.75596 -422.894506) (xy 353.755394 -422.928249) (xy 353.746429 -422.995136) (xy 353.728684 -423.060247)
			(xy 353.702472 -423.122434) (xy 353.685856 -423.151808) (xy 353.680268 -423.16146) (xy 353.677982 -423.18305)
			(xy 353.70897 -423.276776) (xy 353.723702 -423.292778) (xy 353.733862 -423.297096) (xy 353.759402 -423.308404)
			(xy 353.807142 -423.337399) (xy 353.850137 -423.373052) (xy 353.887468 -423.414599) (xy 353.918335 -423.46115)
			(xy 353.942076 -423.511708) (xy 353.958182 -423.56519) (xy 353.96631 -423.62045) (xy 353.96678 -423.648378)
			(xy 353.966294 -423.675629) (xy 353.958538 -423.729577) (xy 353.943183 -423.781872) (xy 353.920541 -423.831449)
			(xy 353.891075 -423.877299) (xy 353.855384 -423.91849) (xy 353.814193 -423.954181) (xy 353.768343 -423.983647)
			(xy 353.718766 -424.006289) (xy 353.666471 -424.021644) (xy 353.612523 -424.0294) (xy 353.558021 -424.0294)
			(xy 353.504073 -424.021644) (xy 353.451778 -424.006289) (xy 353.402201 -423.983647) (xy 353.356351 -423.954181)
			(xy 353.31516 -423.91849) (xy 353.279469 -423.877299) (xy 353.250003 -423.831449) (xy 353.227361 -423.781872)
			(xy 353.212006 -423.729577) (xy 353.20425 -423.675629) (xy 353.203764 -423.648378) (xy 353.203764 -423.647616)
			(xy 353.204427 -423.616435) (xy 353.214637 -423.554911) (xy 353.224084 -423.525188) (xy 353.22764 -423.514774)
			(xy 353.225608 -423.49293) (xy 353.176332 -423.40784) (xy 353.158552 -423.39514) (xy 353.147884 -423.392854)
			(xy 353.116834 -423.386154) (xy 353.056577 -423.366053) (xy 352.999293 -423.338604) (xy 352.945872 -423.304236)
			(xy 352.897147 -423.263482) (xy 352.853876 -423.216979) (xy 352.816732 -423.165449) (xy 352.786295 -423.109694)
			(xy 352.763038 -423.050584) (xy 352.747322 -422.989037) (xy 352.739393 -422.926013) (xy 352.738944 -422.894252)
			(xy 352.740214 -422.859962) (xy 352.74123 -422.84396) (xy 352.724974 -422.816782) (xy 352.623628 -422.771062)
			(xy 352.614044 -422.767291) (xy 352.593472 -422.766901) (xy 352.574379 -422.774575) (xy 352.566732 -422.781476)
			(xy 352.283776 -423.064432) (xy 352.279712 -423.074338) (xy 352.266431 -423.106166) (xy 352.23251 -423.166212)
			(xy 352.190783 -423.221122) (xy 352.142016 -423.269888) (xy 352.087106 -423.311614) (xy 352.027059 -423.345534)
			(xy 351.995232 -423.358818) (xy 351.985326 -423.362882) (xy 348.509633 -426.838575) (xy 354.808276 -426.838575)
			(xy 354.808276 -426.774653) (xy 354.816287 -426.711235) (xy 354.832184 -426.649321) (xy 354.855716 -426.589888)
			(xy 354.88651 -426.533873) (xy 354.924083 -426.482158) (xy 354.96784 -426.435561) (xy 355.017093 -426.394816)
			(xy 355.071064 -426.360565) (xy 355.128903 -426.333348) (xy 355.189696 -426.313595) (xy 355.252486 -426.301617)
			(xy 355.316282 -426.297604) (xy 355.380078 -426.301617) (xy 355.442868 -426.313595) (xy 355.503661 -426.333348)
			(xy 355.5615 -426.360565) (xy 355.615471 -426.394816) (xy 355.664724 -426.435561) (xy 355.708481 -426.482158)
			(xy 355.746054 -426.533873) (xy 355.776848 -426.589888) (xy 355.80038 -426.649321) (xy 355.816277 -426.711235)
			(xy 355.824288 -426.774653) (xy 355.82479 -426.806614) (xy 355.824288 -426.838575) (xy 355.816277 -426.901993)
			(xy 355.80038 -426.963907) (xy 355.776848 -427.02334) (xy 355.746054 -427.079355) (xy 355.708481 -427.13107)
			(xy 355.664724 -427.177667) (xy 355.615471 -427.218412) (xy 355.5615 -427.252663) (xy 355.503661 -427.27988)
			(xy 355.442868 -427.299633) (xy 355.380078 -427.311611) (xy 355.316282 -427.315625) (xy 355.252486 -427.311611)
			(xy 355.189696 -427.299633) (xy 355.128903 -427.27988) (xy 355.071064 -427.252663) (xy 355.017093 -427.218412)
			(xy 354.96784 -427.177667) (xy 354.924083 -427.13107) (xy 354.88651 -427.079355) (xy 354.855716 -427.02334)
			(xy 354.832184 -426.963907) (xy 354.816287 -426.901993) (xy 354.808276 -426.838575) (xy 348.509633 -426.838575)
			(xy 348.305628 -427.04258) (xy 348.298262 -427.049692) (xy 348.290642 -427.068488) (xy 348.290642 -427.716442)
			(xy 348.290414 -427.72348) (xy 348.286538 -427.73701) (xy 348.283022 -427.743112) (xy 348.279466 -427.749208)
			(xy 348.275656 -427.762416) (xy 348.275656 -428.091092) (xy 351.103182 -428.091092) (xy 351.107253 -428.03547)
			(xy 351.119379 -427.981033) (xy 351.139302 -427.928942) (xy 351.166598 -427.880307) (xy 351.200684 -427.836164)
			(xy 351.240833 -427.797455) (xy 351.286191 -427.765004) (xy 351.335791 -427.739503) (xy 351.388575 -427.721496)
			(xy 351.443418 -427.711366) (xy 351.499152 -427.709329) (xy 351.554589 -427.715429) (xy 351.608546 -427.729535)
			(xy 351.659875 -427.751347) (xy 351.707481 -427.780401) (xy 351.750349 -427.816076) (xy 351.787566 -427.857613)
			(xy 351.818339 -427.904126) (xy 351.842011 -427.954623) (xy 351.858079 -428.00803) (xy 351.866199 -428.063206)
			(xy 351.866708 -428.091092) (xy 351.866199 -428.118978) (xy 351.858079 -428.174154) (xy 351.842011 -428.227561)
			(xy 351.818339 -428.278058) (xy 351.787566 -428.324571) (xy 351.750349 -428.366108) (xy 351.707481 -428.401783)
			(xy 351.659875 -428.430837) (xy 351.608546 -428.452649) (xy 351.554589 -428.466755) (xy 351.499152 -428.472855)
			(xy 351.443418 -428.470818) (xy 351.388575 -428.460688) (xy 351.335791 -428.442681) (xy 351.286191 -428.41718)
			(xy 351.240833 -428.384729) (xy 351.200684 -428.34602) (xy 351.166598 -428.301877) (xy 351.139302 -428.253242)
			(xy 351.119379 -428.201151) (xy 351.107253 -428.146714) (xy 351.103182 -428.091092) (xy 348.275656 -428.091092)
			(xy 348.275656 -428.721012) (xy 352.403154 -428.721012) (xy 352.407225 -428.66539) (xy 352.419351 -428.610953)
			(xy 352.439274 -428.558862) (xy 352.46657 -428.510227) (xy 352.500656 -428.466084) (xy 352.540805 -428.427375)
			(xy 352.586163 -428.394924) (xy 352.635763 -428.369423) (xy 352.688547 -428.351416) (xy 352.74339 -428.341286)
			(xy 352.799124 -428.339249) (xy 352.854561 -428.345349) (xy 352.908518 -428.359455) (xy 352.959847 -428.381267)
			(xy 353.007453 -428.410321) (xy 353.050321 -428.445996) (xy 353.087538 -428.487533) (xy 353.118311 -428.534046)
			(xy 353.141983 -428.584543) (xy 353.158051 -428.63795) (xy 353.166171 -428.693126) (xy 353.16668 -428.721012)
			(xy 353.166171 -428.748898) (xy 353.158051 -428.804074) (xy 353.141983 -428.857481) (xy 353.118311 -428.907978)
			(xy 353.087538 -428.954491) (xy 353.050321 -428.996028) (xy 353.007453 -429.031703) (xy 352.959847 -429.060757)
			(xy 352.908518 -429.082569) (xy 352.854561 -429.096675) (xy 352.799124 -429.102775) (xy 352.74339 -429.100738)
			(xy 352.688547 -429.090608) (xy 352.635763 -429.072601) (xy 352.586163 -429.0471) (xy 352.540805 -429.014649)
			(xy 352.500656 -428.97594) (xy 352.46657 -428.931797) (xy 352.439274 -428.883162) (xy 352.419351 -428.831071)
			(xy 352.407225 -428.776634) (xy 352.403154 -428.721012) (xy 348.275656 -428.721012) (xy 348.275656 -431.841613)
			(xy 350.531424 -431.841613) (xy 350.531424 -431.777691) (xy 350.539435 -431.714273) (xy 350.555332 -431.652359)
			(xy 350.578864 -431.592926) (xy 350.609658 -431.536911) (xy 350.647231 -431.485196) (xy 350.690988 -431.438599)
			(xy 350.740241 -431.397854) (xy 350.794212 -431.363603) (xy 350.852051 -431.336386) (xy 350.912844 -431.316633)
			(xy 350.975634 -431.304655) (xy 351.03943 -431.300642) (xy 351.103226 -431.304655) (xy 351.166016 -431.316633)
			(xy 351.226809 -431.336386) (xy 351.284648 -431.363603) (xy 351.338619 -431.397854) (xy 351.387872 -431.438599)
			(xy 351.431629 -431.485196) (xy 351.469202 -431.536911) (xy 351.499996 -431.592926) (xy 351.523528 -431.652359)
			(xy 351.539425 -431.714273) (xy 351.547436 -431.777691) (xy 351.547938 -431.809652) (xy 351.547436 -431.841613)
			(xy 351.539425 -431.905031) (xy 351.523528 -431.966945) (xy 351.499996 -432.026378) (xy 351.469202 -432.082393)
			(xy 351.431629 -432.134108) (xy 351.387872 -432.180705) (xy 351.338619 -432.22145) (xy 351.284648 -432.255701)
			(xy 351.226809 -432.282918) (xy 351.166016 -432.302671) (xy 351.103226 -432.314649) (xy 351.03943 -432.318663)
			(xy 350.975634 -432.314649) (xy 350.912844 -432.302671) (xy 350.852051 -432.282918) (xy 350.794212 -432.255701)
			(xy 350.740241 -432.22145) (xy 350.690988 -432.180705) (xy 350.647231 -432.134108) (xy 350.609658 -432.082393)
			(xy 350.578864 -432.026378) (xy 350.555332 -431.966945) (xy 350.539435 -431.905031) (xy 350.531424 -431.841613)
			(xy 348.275656 -431.841613) (xy 348.275656 -433.841652) (xy 350.657412 -433.841652) (xy 350.661483 -433.78603)
			(xy 350.673609 -433.731593) (xy 350.693532 -433.679502) (xy 350.720828 -433.630867) (xy 350.754914 -433.586724)
			(xy 350.795063 -433.548015) (xy 350.840421 -433.515564) (xy 350.890021 -433.490063) (xy 350.942805 -433.472056)
			(xy 350.997648 -433.461926) (xy 351.053382 -433.459889) (xy 351.108819 -433.465989) (xy 351.162776 -433.480095)
			(xy 351.214105 -433.501907) (xy 351.261711 -433.530961) (xy 351.304579 -433.566636) (xy 351.341796 -433.608173)
			(xy 351.372569 -433.654686) (xy 351.396241 -433.705183) (xy 351.412309 -433.75859) (xy 351.420429 -433.813766)
			(xy 351.420938 -433.841652) (xy 351.420429 -433.869538) (xy 351.412309 -433.924714) (xy 351.396241 -433.978121)
			(xy 351.372569 -434.028618) (xy 351.341796 -434.075131) (xy 351.304579 -434.116668) (xy 351.261711 -434.152343)
			(xy 351.214105 -434.181397) (xy 351.162776 -434.203209) (xy 351.108819 -434.217315) (xy 351.053382 -434.223415)
			(xy 350.997648 -434.221378) (xy 350.942805 -434.211248) (xy 350.890021 -434.193241) (xy 350.840421 -434.16774)
			(xy 350.795063 -434.135289) (xy 350.754914 -434.09658) (xy 350.720828 -434.052437) (xy 350.693532 -434.003802)
			(xy 350.673609 -433.951711) (xy 350.661483 -433.897274) (xy 350.657412 -433.841652) (xy 348.275656 -433.841652)
			(xy 348.275656 -434.857652) (xy 350.657412 -434.857652) (xy 350.661483 -434.80203) (xy 350.673609 -434.747593)
			(xy 350.693532 -434.695502) (xy 350.720828 -434.646867) (xy 350.754914 -434.602724) (xy 350.795063 -434.564015)
			(xy 350.840421 -434.531564) (xy 350.890021 -434.506063) (xy 350.942805 -434.488056) (xy 350.997648 -434.477926)
			(xy 351.053382 -434.475889) (xy 351.108819 -434.481989) (xy 351.162776 -434.496095) (xy 351.214105 -434.517907)
			(xy 351.261711 -434.546961) (xy 351.304579 -434.582636) (xy 351.341796 -434.624173) (xy 351.372569 -434.670686)
			(xy 351.396241 -434.721183) (xy 351.412309 -434.77459) (xy 351.420429 -434.829766) (xy 351.420938 -434.857652)
			(xy 351.420429 -434.885538) (xy 351.412309 -434.940714) (xy 351.396241 -434.994121) (xy 351.372569 -435.044618)
			(xy 351.341796 -435.091131) (xy 351.304579 -435.132668) (xy 351.261711 -435.168343) (xy 351.214105 -435.197397)
			(xy 351.162776 -435.219209) (xy 351.108819 -435.233315) (xy 351.053382 -435.239415) (xy 350.997648 -435.237378)
			(xy 350.942805 -435.227248) (xy 350.890021 -435.209241) (xy 350.840421 -435.18374) (xy 350.795063 -435.151289)
			(xy 350.754914 -435.11258) (xy 350.720828 -435.068437) (xy 350.693532 -435.019802) (xy 350.673609 -434.967711)
			(xy 350.661483 -434.913274) (xy 350.657412 -434.857652) (xy 348.275656 -434.857652) (xy 348.275656 -437.267453)
			(xy 351.42445 -437.267453) (xy 351.42445 -437.212947) (xy 351.432207 -437.158996) (xy 351.447563 -437.106698)
			(xy 351.470205 -437.057117) (xy 351.499673 -437.011264) (xy 351.535366 -436.970071) (xy 351.576559 -436.934377)
			(xy 351.622412 -436.904908) (xy 351.671992 -436.882265) (xy 351.72429 -436.866908) (xy 351.778241 -436.85915)
			(xy 351.805494 -436.858664) (xy 351.833652 -436.859176) (xy 351.889353 -436.867474) (xy 351.943227 -436.883877)
			(xy 351.994102 -436.908026) (xy 352.040871 -436.939397) (xy 352.062034 -436.957978) (xy 352.069146 -436.964328)
			(xy 352.086926 -436.971186) (xy 352.174048 -436.971186) (xy 352.191828 -436.964328) (xy 352.19894 -436.957978)
			(xy 352.220123 -436.939423) (xy 352.266895 -436.908066) (xy 352.317766 -436.88392) (xy 352.371632 -436.86751)
			(xy 352.427325 -436.859191) (xy 352.45548 -436.858664) (xy 352.482732 -436.859182) (xy 352.536681 -436.866936)
			(xy 352.588977 -436.882289) (xy 352.638556 -436.904929) (xy 352.684409 -436.934394) (xy 352.725601 -436.970085)
			(xy 352.761294 -437.011275) (xy 352.790762 -437.057126) (xy 352.813404 -437.106704) (xy 352.82876 -437.159)
			(xy 352.836517 -437.212948) (xy 352.836517 -437.267452) (xy 352.82876 -437.3214) (xy 352.813404 -437.373696)
			(xy 352.790762 -437.423274) (xy 352.761294 -437.469125) (xy 352.725601 -437.510315) (xy 352.684409 -437.546006)
			(xy 352.638556 -437.575471) (xy 352.588977 -437.598111) (xy 352.536681 -437.613464) (xy 352.482732 -437.621218)
			(xy 352.45548 -437.62168) (xy 352.427322 -437.621172) (xy 352.371621 -437.612871) (xy 352.317748 -437.596467)
			(xy 352.266873 -437.572317) (xy 352.220103 -437.540947) (xy 352.19894 -437.522366) (xy 352.191828 -437.516016)
			(xy 352.174048 -437.509158) (xy 352.086926 -437.509158) (xy 352.069146 -437.516016) (xy 352.062034 -437.522366)
			(xy 352.040868 -437.540941) (xy 351.994091 -437.572294) (xy 351.943215 -437.596435) (xy 351.889345 -437.612841)
			(xy 351.83365 -437.621156) (xy 351.805494 -437.62168) (xy 351.778241 -437.62125) (xy 351.72429 -437.613492)
			(xy 351.671992 -437.598135) (xy 351.622412 -437.575492) (xy 351.576559 -437.546023) (xy 351.535366 -437.510329)
			(xy 351.499673 -437.469136) (xy 351.470205 -437.423283) (xy 351.447563 -437.373702) (xy 351.432207 -437.321404)
			(xy 351.42445 -437.267453) (xy 348.275656 -437.267453) (xy 348.275656 -438.992772) (xy 351.307398 -438.992772)
			(xy 351.311469 -438.93715) (xy 351.323595 -438.882713) (xy 351.343518 -438.830622) (xy 351.370814 -438.781987)
			(xy 351.4049 -438.737844) (xy 351.445049 -438.699135) (xy 351.490407 -438.666684) (xy 351.540007 -438.641183)
			(xy 351.592791 -438.623176) (xy 351.647634 -438.613046) (xy 351.703368 -438.611009) (xy 351.758805 -438.617109)
			(xy 351.812762 -438.631215) (xy 351.864091 -438.653027) (xy 351.911697 -438.682081) (xy 351.954565 -438.717756)
			(xy 351.991782 -438.759293) (xy 352.022555 -438.805806) (xy 352.046227 -438.856303) (xy 352.062295 -438.90971)
			(xy 352.070415 -438.964886) (xy 352.070924 -438.992772) (xy 352.070415 -439.020658) (xy 352.062295 -439.075834)
			(xy 352.046227 -439.129241) (xy 352.022555 -439.179738) (xy 351.991782 -439.226251) (xy 351.954565 -439.267788)
			(xy 351.911697 -439.303463) (xy 351.864091 -439.332517) (xy 351.812762 -439.354329) (xy 351.758805 -439.368435)
			(xy 351.703368 -439.374535) (xy 351.647634 -439.372498) (xy 351.592791 -439.362368) (xy 351.540007 -439.344361)
			(xy 351.490407 -439.31886) (xy 351.445049 -439.286409) (xy 351.4049 -439.2477) (xy 351.370814 -439.203557)
			(xy 351.343518 -439.154922) (xy 351.323595 -439.102831) (xy 351.311469 -439.048394) (xy 351.307398 -438.992772)
			(xy 348.275656 -438.992772) (xy 348.275656 -440.408822) (xy 348.276116 -440.4187) (xy 348.283555 -440.437001)
			(xy 348.290134 -440.444382) (xy 348.290388 -440.444636) (xy 348.54896 -440.703208) (xy 348.549468 -440.703716)
			(xy 348.556848 -440.7103) (xy 348.575148 -440.71775) (xy 348.585028 -440.718194) (xy 352.649028 -440.718194)
		)
		(stroke
			(width 0)
			(type solid)
		)
		(fill yes)
		(layer "In15.Cu")
		(net "P3V3_AUX")
	)
	(gr_poly
		(pts
			(xy 188.134752 -366.186974) (xy 188.142166 -366.186725) (xy 188.156369 -366.18247) (xy 188.162692 -366.178592)
			(xy 188.1851 -366.16434) (xy 188.233173 -366.14178) (xy 188.284016 -366.126449) (xy 188.336547 -366.118671)
			(xy 188.363098 -366.11814) (xy 192.617344 -366.11814) (xy 192.627409 -366.117707) (xy 192.645996 -366.109975)
			(xy 192.653412 -366.103154) (xy 192.784222 -365.972344) (xy 192.791068 -365.964946) (xy 192.798795 -365.946347)
			(xy 192.799208 -365.936276) (xy 192.799208 -365.882428) (xy 192.799645 -365.872364) (xy 192.807378 -365.853779)
			(xy 192.814194 -365.84636) (xy 205.437232 -353.223322) (xy 205.444073 -353.215922) (xy 205.45179 -353.197323)
			(xy 205.452218 -353.187254) (xy 205.452218 -351.268284) (xy 205.452644 -351.258215) (xy 205.460365 -351.239617)
			(xy 205.467204 -351.232216) (xy 206.23022 -350.4692) (xy 206.237075 -350.461805) (xy 206.244822 -350.443206)
			(xy 206.245206 -350.433132) (xy 206.245206 -346.735654) (xy 206.245638 -346.725588) (xy 206.253365 -346.706996)
			(xy 206.260192 -346.699586) (xy 208.288382 -344.671396) (xy 208.29523 -344.663998) (xy 208.302965 -344.6454)
			(xy 208.303368 -344.635328) (xy 208.303368 -328.761598) (xy 208.302944 -328.751529) (xy 208.295225 -328.732928)
			(xy 208.288382 -328.72553) (xy 207.26654 -327.703688) (xy 207.259142 -327.696842) (xy 207.240543 -327.689115)
			(xy 207.230472 -327.688702) (xy 197.896734 -327.688702) (xy 197.886669 -327.689137) (xy 197.868082 -327.696869)
			(xy 197.860666 -327.703688) (xy 197.355714 -328.20864) (xy 199.140062 -328.20864) (xy 199.144133 -328.153018)
			(xy 199.156259 -328.098581) (xy 199.176182 -328.04649) (xy 199.203478 -327.997855) (xy 199.237564 -327.953712)
			(xy 199.277713 -327.915003) (xy 199.323071 -327.882552) (xy 199.372671 -327.857051) (xy 199.425455 -327.839044)
			(xy 199.480298 -327.828914) (xy 199.536032 -327.826877) (xy 199.591469 -327.832977) (xy 199.645426 -327.847083)
			(xy 199.696755 -327.868895) (xy 199.744361 -327.897949) (xy 199.787229 -327.933624) (xy 199.824446 -327.975161)
			(xy 199.855219 -328.021674) (xy 199.878891 -328.072171) (xy 199.894959 -328.125578) (xy 199.903079 -328.180754)
			(xy 199.903588 -328.20864) (xy 200.029062 -328.20864) (xy 200.033133 -328.153018) (xy 200.045259 -328.098581)
			(xy 200.065182 -328.04649) (xy 200.092478 -327.997855) (xy 200.126564 -327.953712) (xy 200.166713 -327.915003)
			(xy 200.212071 -327.882552) (xy 200.261671 -327.857051) (xy 200.314455 -327.839044) (xy 200.369298 -327.828914)
			(xy 200.425032 -327.826877) (xy 200.480469 -327.832977) (xy 200.534426 -327.847083) (xy 200.585755 -327.868895)
			(xy 200.633361 -327.897949) (xy 200.676229 -327.933624) (xy 200.713446 -327.975161) (xy 200.744219 -328.021674)
			(xy 200.767891 -328.072171) (xy 200.783959 -328.125578) (xy 200.792079 -328.180754) (xy 200.792588 -328.20864)
			(xy 200.918062 -328.20864) (xy 200.922133 -328.153018) (xy 200.934259 -328.098581) (xy 200.954182 -328.04649)
			(xy 200.981478 -327.997855) (xy 201.015564 -327.953712) (xy 201.055713 -327.915003) (xy 201.101071 -327.882552)
			(xy 201.150671 -327.857051) (xy 201.203455 -327.839044) (xy 201.258298 -327.828914) (xy 201.314032 -327.826877)
			(xy 201.369469 -327.832977) (xy 201.423426 -327.847083) (xy 201.474755 -327.868895) (xy 201.522361 -327.897949)
			(xy 201.565229 -327.933624) (xy 201.602446 -327.975161) (xy 201.633219 -328.021674) (xy 201.656891 -328.072171)
			(xy 201.672959 -328.125578) (xy 201.681079 -328.180754) (xy 201.681588 -328.20864) (xy 201.807062 -328.20864)
			(xy 201.811133 -328.153018) (xy 201.823259 -328.098581) (xy 201.843182 -328.04649) (xy 201.870478 -327.997855)
			(xy 201.904564 -327.953712) (xy 201.944713 -327.915003) (xy 201.990071 -327.882552) (xy 202.039671 -327.857051)
			(xy 202.092455 -327.839044) (xy 202.147298 -327.828914) (xy 202.203032 -327.826877) (xy 202.258469 -327.832977)
			(xy 202.312426 -327.847083) (xy 202.363755 -327.868895) (xy 202.411361 -327.897949) (xy 202.454229 -327.933624)
			(xy 202.491446 -327.975161) (xy 202.522219 -328.021674) (xy 202.545891 -328.072171) (xy 202.561959 -328.125578)
			(xy 202.570079 -328.180754) (xy 202.570588 -328.20864) (xy 202.570079 -328.236526) (xy 202.561959 -328.291702)
			(xy 202.545891 -328.345109) (xy 202.522219 -328.395606) (xy 202.491446 -328.442119) (xy 202.454229 -328.483656)
			(xy 202.411361 -328.519331) (xy 202.363755 -328.548385) (xy 202.312426 -328.570197) (xy 202.258469 -328.584303)
			(xy 202.203032 -328.590403) (xy 202.147298 -328.588366) (xy 202.092455 -328.578236) (xy 202.039671 -328.560229)
			(xy 201.990071 -328.534728) (xy 201.944713 -328.502277) (xy 201.904564 -328.463568) (xy 201.870478 -328.419425)
			(xy 201.843182 -328.37079) (xy 201.823259 -328.318699) (xy 201.811133 -328.264262) (xy 201.807062 -328.20864)
			(xy 201.681588 -328.20864) (xy 201.681079 -328.236526) (xy 201.672959 -328.291702) (xy 201.656891 -328.345109)
			(xy 201.633219 -328.395606) (xy 201.602446 -328.442119) (xy 201.565229 -328.483656) (xy 201.522361 -328.519331)
			(xy 201.474755 -328.548385) (xy 201.423426 -328.570197) (xy 201.369469 -328.584303) (xy 201.314032 -328.590403)
			(xy 201.258298 -328.588366) (xy 201.203455 -328.578236) (xy 201.150671 -328.560229) (xy 201.101071 -328.534728)
			(xy 201.055713 -328.502277) (xy 201.015564 -328.463568) (xy 200.981478 -328.419425) (xy 200.954182 -328.37079)
			(xy 200.934259 -328.318699) (xy 200.922133 -328.264262) (xy 200.918062 -328.20864) (xy 200.792588 -328.20864)
			(xy 200.792079 -328.236526) (xy 200.783959 -328.291702) (xy 200.767891 -328.345109) (xy 200.744219 -328.395606)
			(xy 200.713446 -328.442119) (xy 200.676229 -328.483656) (xy 200.633361 -328.519331) (xy 200.585755 -328.548385)
			(xy 200.534426 -328.570197) (xy 200.480469 -328.584303) (xy 200.425032 -328.590403) (xy 200.369298 -328.588366)
			(xy 200.314455 -328.578236) (xy 200.261671 -328.560229) (xy 200.212071 -328.534728) (xy 200.166713 -328.502277)
			(xy 200.126564 -328.463568) (xy 200.092478 -328.419425) (xy 200.065182 -328.37079) (xy 200.045259 -328.318699)
			(xy 200.033133 -328.264262) (xy 200.029062 -328.20864) (xy 199.903588 -328.20864) (xy 199.903079 -328.236526)
			(xy 199.894959 -328.291702) (xy 199.878891 -328.345109) (xy 199.855219 -328.395606) (xy 199.824446 -328.442119)
			(xy 199.787229 -328.483656) (xy 199.744361 -328.519331) (xy 199.696755 -328.548385) (xy 199.645426 -328.570197)
			(xy 199.591469 -328.584303) (xy 199.536032 -328.590403) (xy 199.480298 -328.588366) (xy 199.425455 -328.578236)
			(xy 199.372671 -328.560229) (xy 199.323071 -328.534728) (xy 199.277713 -328.502277) (xy 199.237564 -328.463568)
			(xy 199.203478 -328.419425) (xy 199.176182 -328.37079) (xy 199.156259 -328.318699) (xy 199.144133 -328.264262)
			(xy 199.140062 -328.20864) (xy 197.355714 -328.20864) (xy 196.976238 -328.588116) (xy 196.96939 -328.595514)
			(xy 196.961655 -328.614112) (xy 196.961252 -328.624184) (xy 196.961252 -329.277055) (xy 197.238541 -329.277055)
			(xy 197.238541 -329.222545) (xy 197.246299 -329.16859) (xy 197.261656 -329.116289) (xy 197.284301 -329.066706)
			(xy 197.313772 -329.02085) (xy 197.349469 -328.979655) (xy 197.390666 -328.94396) (xy 197.436523 -328.914492)
			(xy 197.486108 -328.891849) (xy 197.53841 -328.876494) (xy 197.592365 -328.86874) (xy 197.61962 -328.868278)
			(xy 197.646992 -328.868713) (xy 197.701173 -328.876536) (xy 197.753677 -328.892031) (xy 197.803423 -328.91488)
			(xy 197.849388 -328.944613) (xy 197.870318 -328.962258) (xy 197.870572 -328.962512) (xy 197.877661 -328.968094)
			(xy 197.894576 -328.974343) (xy 197.903592 -328.974704) (xy 197.970648 -328.974704) (xy 197.979662 -328.974321)
			(xy 197.996579 -328.968091) (xy 198.003668 -328.962512) (xy 198.003668 -328.962258) (xy 198.003922 -328.962258)
			(xy 198.024867 -328.944635) (xy 198.070837 -328.914922) (xy 198.120581 -328.892084) (xy 198.173079 -328.876589)
			(xy 198.227252 -328.868755) (xy 198.25462 -328.868278) (xy 198.282153 -328.868754) (xy 198.336646 -328.876679)
			(xy 198.389435 -328.892348) (xy 198.439428 -328.915436) (xy 198.485586 -328.945463) (xy 198.506588 -328.963274)
			(xy 198.514672 -328.969748) (xy 198.534341 -328.97617) (xy 198.544688 -328.97572) (xy 198.618602 -328.969116)
			(xy 198.628713 -328.967689) (xy 198.646665 -328.957995) (xy 198.6534 -328.95032) (xy 198.653908 -328.949812)
			(xy 198.672086 -328.927612) (xy 198.713978 -328.888406) (xy 198.761274 -328.855923) (xy 198.812905 -328.830897)
			(xy 198.867703 -328.813893) (xy 198.924432 -328.805295) (xy 198.95312 -328.804778) (xy 198.980371 -328.805259)
			(xy 199.034318 -328.813018) (xy 199.086612 -328.828375) (xy 199.136189 -328.851017) (xy 199.182038 -328.880484)
			(xy 199.223228 -328.916176) (xy 199.258919 -328.957367) (xy 199.288385 -329.003217) (xy 199.311027 -329.052793)
			(xy 199.326383 -329.105088) (xy 199.334141 -329.159035) (xy 199.334628 -329.186286) (xy 199.334171 -329.213657)
			(xy 199.326354 -329.267837) (xy 199.310864 -329.320341) (xy 199.288019 -329.370088) (xy 199.258291 -329.416053)
			(xy 199.240648 -329.436984) (xy 199.240394 -329.437238) (xy 199.234827 -329.444338) (xy 199.228569 -329.461244)
			(xy 199.228202 -329.470258) (xy 199.228202 -329.537314) (xy 199.228552 -329.546332) (xy 199.234804 -329.563248)
			(xy 199.240394 -329.570334) (xy 199.240648 -329.570334) (xy 199.240648 -329.570588) (xy 199.258276 -329.591531)
			(xy 199.288003 -329.637497) (xy 199.310851 -329.687241) (xy 199.326349 -329.739742) (xy 199.33418 -329.793919)
			(xy 199.334181 -329.84866) (xy 199.326354 -329.902838) (xy 199.310858 -329.955339) (xy 199.288013 -330.005085)
			(xy 199.258289 -330.051052) (xy 199.240648 -330.071984) (xy 199.240394 -330.072238) (xy 199.234827 -330.079338)
			(xy 199.228569 -330.096244) (xy 199.228202 -330.105258) (xy 199.228202 -330.172314) (xy 199.228552 -330.181332)
			(xy 199.234804 -330.198248) (xy 199.240394 -330.205334) (xy 199.240648 -330.205334) (xy 199.240648 -330.205588)
			(xy 199.258287 -330.22652) (xy 199.288001 -330.272492) (xy 199.310837 -330.32224) (xy 199.326328 -330.374741)
			(xy 199.334155 -330.428917) (xy 199.334628 -330.456286) (xy 202.635612 -330.456286) (xy 202.636067 -330.428915)
			(xy 202.643887 -330.374736) (xy 202.659379 -330.322232) (xy 202.682223 -330.272486) (xy 202.71195 -330.226519)
			(xy 202.729592 -330.205588) (xy 202.729846 -330.205334) (xy 202.73543 -330.198246) (xy 202.741677 -330.18133)
			(xy 202.742038 -330.172314) (xy 202.742038 -330.105258) (xy 202.741645 -330.096245) (xy 202.735422 -330.079328)
			(xy 202.729846 -330.072238) (xy 202.729592 -330.072238) (xy 202.729592 -330.071984) (xy 202.711939 -330.051062)
			(xy 202.682217 -330.005091) (xy 202.659375 -329.955343) (xy 202.643881 -329.90284) (xy 202.636055 -329.84866)
			(xy 202.636056 -329.793919) (xy 202.643886 -329.73974) (xy 202.659383 -329.687237) (xy 202.682228 -329.63749)
			(xy 202.711952 -329.591521) (xy 202.729592 -329.570588) (xy 202.729846 -329.570334) (xy 202.73543 -329.563246)
			(xy 202.741677 -329.54633) (xy 202.742038 -329.537314) (xy 202.742038 -329.470258) (xy 202.741645 -329.461245)
			(xy 202.735422 -329.444328) (xy 202.729846 -329.437238) (xy 202.729592 -329.437238) (xy 202.729592 -329.436984)
			(xy 202.711978 -329.416032) (xy 202.682262 -329.370065) (xy 202.659422 -329.320322) (xy 202.643925 -329.267826)
			(xy 202.63609 -329.213654) (xy 202.635612 -329.186286) (xy 202.636042 -329.159032) (xy 202.643801 -329.105079)
			(xy 202.65916 -329.052779) (xy 202.681806 -329.003197) (xy 202.711277 -328.957343) (xy 202.746974 -328.91615)
			(xy 202.788171 -328.880457) (xy 202.834027 -328.850989) (xy 202.883611 -328.828348) (xy 202.935912 -328.812994)
			(xy 202.989866 -328.805239) (xy 203.01712 -328.804778) (xy 203.04584 -328.805265) (xy 203.10263 -328.813885)
			(xy 203.157484 -328.830927) (xy 203.209161 -328.856004) (xy 203.256492 -328.88855) (xy 203.298404 -328.927828)
			(xy 203.316586 -328.950066) (xy 203.31684 -328.95032) (xy 203.323594 -328.957977) (xy 203.341531 -328.967685)
			(xy 203.351638 -328.969116) (xy 203.425552 -328.97572) (xy 203.435899 -328.976186) (xy 203.455567 -328.96975)
			(xy 203.463652 -328.963274) (xy 203.484661 -328.945471) (xy 203.530812 -328.915432) (xy 203.580802 -328.892339)
			(xy 203.633593 -328.876673) (xy 203.688087 -328.868759) (xy 203.71562 -328.868278) (xy 203.742992 -328.868713)
			(xy 203.797173 -328.876536) (xy 203.849677 -328.892031) (xy 203.899423 -328.91488) (xy 203.945388 -328.944613)
			(xy 203.966318 -328.962258) (xy 203.966572 -328.962512) (xy 203.973661 -328.968094) (xy 203.990576 -328.974343)
			(xy 203.999592 -328.974704) (xy 204.066648 -328.974704) (xy 204.075662 -328.974321) (xy 204.092579 -328.968091)
			(xy 204.099668 -328.962512) (xy 204.099668 -328.962258) (xy 204.099922 -328.962258) (xy 204.120867 -328.944635)
			(xy 204.166837 -328.914922) (xy 204.216581 -328.892084) (xy 204.269079 -328.876589) (xy 204.323252 -328.868755)
			(xy 204.35062 -328.868278) (xy 204.377869 -328.868794) (xy 204.431813 -328.876552) (xy 204.484103 -328.891908)
			(xy 204.533676 -328.91455) (xy 204.579522 -328.944016) (xy 204.620708 -328.979706) (xy 204.656396 -329.020894)
			(xy 204.68586 -329.066742) (xy 204.708499 -329.116316) (xy 204.723852 -329.168607) (xy 204.731608 -329.222551)
			(xy 204.731608 -329.277049) (xy 204.723852 -329.330993) (xy 204.708499 -329.383284) (xy 204.68586 -329.432858)
			(xy 204.656396 -329.478706) (xy 204.620708 -329.519894) (xy 204.579522 -329.555584) (xy 204.533676 -329.58505)
			(xy 204.484103 -329.607692) (xy 204.431813 -329.623048) (xy 204.377869 -329.630806) (xy 204.35062 -329.631294)
			(xy 204.32325 -329.630818) (xy 204.269071 -329.623003) (xy 204.216568 -329.607516) (xy 204.166821 -329.584676)
			(xy 204.120854 -329.554954) (xy 204.099922 -329.537314) (xy 204.099668 -329.53706) (xy 204.09257 -329.531491)
			(xy 204.075662 -329.525235) (xy 204.066648 -329.524868) (xy 203.999592 -329.524868) (xy 203.990576 -329.525228)
			(xy 203.973659 -329.531474) (xy 203.966572 -329.53706) (xy 203.966572 -329.537314) (xy 203.966318 -329.537314)
			(xy 203.945392 -329.55496) (xy 203.899417 -329.584671) (xy 203.849668 -329.607505) (xy 203.797166 -329.622994)
			(xy 203.74299 -329.630821) (xy 203.71562 -329.631294) (xy 203.689029 -329.630885) (xy 203.636363 -329.623503)
			(xy 203.585236 -329.608864) (xy 203.536643 -329.587255) (xy 203.491529 -329.559095) (xy 203.450772 -329.524932)
			(xy 203.415165 -329.48543) (xy 203.399898 -329.463654) (xy 203.393005 -329.454667) (xy 203.373511 -329.443195)
			(xy 203.362306 -329.441556) (xy 203.305156 -329.436476) (xy 203.304648 -329.436984) (xy 203.304394 -329.437238)
			(xy 203.298827 -329.444338) (xy 203.292569 -329.461244) (xy 203.292202 -329.470258) (xy 203.292202 -329.537314)
			(xy 203.292552 -329.546332) (xy 203.298804 -329.563248) (xy 203.304394 -329.570334) (xy 203.304648 -329.570334)
			(xy 203.304648 -329.570588) (xy 203.322276 -329.591531) (xy 203.352003 -329.637497) (xy 203.374851 -329.687241)
			(xy 203.390349 -329.739742) (xy 203.39818 -329.793919) (xy 203.398181 -329.84866) (xy 203.390354 -329.902838)
			(xy 203.374858 -329.955339) (xy 203.352013 -330.005085) (xy 203.350636 -330.007214) (xy 204.748636 -330.007214)
			(xy 204.752707 -329.951592) (xy 204.764833 -329.897155) (xy 204.784756 -329.845064) (xy 204.812052 -329.796429)
			(xy 204.846138 -329.752286) (xy 204.886287 -329.713577) (xy 204.931645 -329.681126) (xy 204.981245 -329.655625)
			(xy 205.034029 -329.637618) (xy 205.088872 -329.627488) (xy 205.144606 -329.625451) (xy 205.200043 -329.631551)
			(xy 205.254 -329.645657) (xy 205.305329 -329.667469) (xy 205.352935 -329.696523) (xy 205.395803 -329.732198)
			(xy 205.43302 -329.773735) (xy 205.463793 -329.820248) (xy 205.487465 -329.870745) (xy 205.503533 -329.924152)
			(xy 205.511653 -329.979328) (xy 205.512162 -330.007214) (xy 205.511653 -330.0351) (xy 205.503533 -330.090276)
			(xy 205.487465 -330.143683) (xy 205.463793 -330.19418) (xy 205.43302 -330.240693) (xy 205.395803 -330.28223)
			(xy 205.352935 -330.317905) (xy 205.305329 -330.346959) (xy 205.254 -330.368771) (xy 205.200043 -330.382877)
			(xy 205.144606 -330.388977) (xy 205.088872 -330.38694) (xy 205.034029 -330.37681) (xy 204.981245 -330.358803)
			(xy 204.931645 -330.333302) (xy 204.886287 -330.300851) (xy 204.846138 -330.262142) (xy 204.812052 -330.217999)
			(xy 204.784756 -330.169364) (xy 204.764833 -330.117273) (xy 204.752707 -330.062836) (xy 204.748636 -330.007214)
			(xy 203.350636 -330.007214) (xy 203.322289 -330.051052) (xy 203.304648 -330.071984) (xy 203.304394 -330.072238)
			(xy 203.298827 -330.079338) (xy 203.292569 -330.096244) (xy 203.292202 -330.105258) (xy 203.292202 -330.172314)
			(xy 203.292552 -330.181332) (xy 203.298804 -330.198248) (xy 203.304394 -330.205334) (xy 203.304648 -330.205334)
			(xy 203.304648 -330.205588) (xy 203.322287 -330.22652) (xy 203.352001 -330.272492) (xy 203.374837 -330.32224)
			(xy 203.390328 -330.374741) (xy 203.398155 -330.428917) (xy 203.398628 -330.456286) (xy 203.398142 -330.483537)
			(xy 203.390386 -330.537485) (xy 203.375031 -330.58978) (xy 203.352389 -330.639357) (xy 203.322923 -330.685207)
			(xy 203.287232 -330.726398) (xy 203.246041 -330.762089) (xy 203.200191 -330.791555) (xy 203.150614 -330.814197)
			(xy 203.098319 -330.829552) (xy 203.044371 -330.837308) (xy 202.989869 -330.837308) (xy 202.935921 -330.829552)
			(xy 202.883626 -330.814197) (xy 202.834049 -330.791555) (xy 202.788199 -330.762089) (xy 202.747008 -330.726398)
			(xy 202.711317 -330.685207) (xy 202.681851 -330.639357) (xy 202.659209 -330.58978) (xy 202.643854 -330.537485)
			(xy 202.636098 -330.483537) (xy 202.635612 -330.456286) (xy 199.334628 -330.456286) (xy 199.334142 -330.483537)
			(xy 199.326386 -330.537485) (xy 199.311031 -330.58978) (xy 199.288389 -330.639357) (xy 199.258923 -330.685207)
			(xy 199.223232 -330.726398) (xy 199.182041 -330.762089) (xy 199.136191 -330.791555) (xy 199.086614 -330.814197)
			(xy 199.034319 -330.829552) (xy 198.980371 -330.837308) (xy 198.925869 -330.837308) (xy 198.871921 -330.829552)
			(xy 198.819626 -330.814197) (xy 198.770049 -330.791555) (xy 198.724199 -330.762089) (xy 198.683008 -330.726398)
			(xy 198.647317 -330.685207) (xy 198.617851 -330.639357) (xy 198.595209 -330.58978) (xy 198.579854 -330.537485)
			(xy 198.572098 -330.483537) (xy 198.571612 -330.456286) (xy 198.572067 -330.428915) (xy 198.579887 -330.374736)
			(xy 198.595379 -330.322232) (xy 198.618223 -330.272486) (xy 198.64795 -330.226519) (xy 198.665592 -330.205588)
			(xy 198.665846 -330.205334) (xy 198.67143 -330.198246) (xy 198.677677 -330.18133) (xy 198.678038 -330.172314)
			(xy 198.678038 -330.105258) (xy 198.677645 -330.096245) (xy 198.671422 -330.079328) (xy 198.665846 -330.072238)
			(xy 198.665592 -330.072238) (xy 198.665592 -330.071984) (xy 198.647939 -330.051062) (xy 198.618217 -330.005091)
			(xy 198.595375 -329.955343) (xy 198.579881 -329.90284) (xy 198.572055 -329.84866) (xy 198.572056 -329.793919)
			(xy 198.579886 -329.73974) (xy 198.595383 -329.687237) (xy 198.618228 -329.63749) (xy 198.647952 -329.591521)
			(xy 198.665592 -329.570588) (xy 198.665846 -329.570334) (xy 198.67143 -329.563246) (xy 198.677677 -329.54633)
			(xy 198.678038 -329.537314) (xy 198.678038 -329.470258) (xy 198.677645 -329.461245) (xy 198.671422 -329.444328)
			(xy 198.665846 -329.437238) (xy 198.665592 -329.436984) (xy 198.665084 -329.436476) (xy 198.607934 -329.441556)
			(xy 198.596703 -329.443133) (xy 198.577176 -329.454604) (xy 198.570342 -329.463654) (xy 198.555076 -329.485426)
			(xy 198.519452 -329.524904) (xy 198.478688 -329.559048) (xy 198.433573 -329.587194) (xy 198.384985 -329.608797)
			(xy 198.333865 -329.623438) (xy 198.281207 -329.630831) (xy 198.25462 -329.631294) (xy 198.22725 -329.630818)
			(xy 198.173071 -329.623003) (xy 198.120568 -329.607516) (xy 198.070821 -329.584676) (xy 198.024854 -329.554954)
			(xy 198.003922 -329.537314) (xy 198.003668 -329.53706) (xy 197.99657 -329.531491) (xy 197.979662 -329.525235)
			(xy 197.970648 -329.524868) (xy 197.903592 -329.524868) (xy 197.894576 -329.525228) (xy 197.877659 -329.531474)
			(xy 197.870572 -329.53706) (xy 197.870572 -329.537314) (xy 197.870318 -329.537314) (xy 197.849392 -329.55496)
			(xy 197.803417 -329.584671) (xy 197.753668 -329.607505) (xy 197.701166 -329.622994) (xy 197.64699 -329.630821)
			(xy 197.61962 -329.631294) (xy 197.592365 -329.63086) (xy 197.53841 -329.623106) (xy 197.486108 -329.607751)
			(xy 197.436523 -329.585108) (xy 197.390666 -329.55564) (xy 197.349469 -329.519945) (xy 197.313772 -329.47875)
			(xy 197.284301 -329.432894) (xy 197.261656 -329.383311) (xy 197.246299 -329.33101) (xy 197.238541 -329.277055)
			(xy 196.961252 -329.277055) (xy 196.961252 -338.879942) (xy 198.275192 -338.879942) (xy 198.279263 -338.82432)
			(xy 198.291389 -338.769883) (xy 198.311312 -338.717792) (xy 198.338608 -338.669157) (xy 198.372694 -338.625014)
			(xy 198.412843 -338.586305) (xy 198.458201 -338.553854) (xy 198.507801 -338.528353) (xy 198.560585 -338.510346)
			(xy 198.615428 -338.500216) (xy 198.671162 -338.498179) (xy 198.726599 -338.504279) (xy 198.780556 -338.518385)
			(xy 198.831885 -338.540197) (xy 198.879491 -338.569251) (xy 198.922359 -338.604926) (xy 198.959576 -338.646463)
			(xy 198.990349 -338.692976) (xy 199.014021 -338.743473) (xy 199.030089 -338.79688) (xy 199.038209 -338.852056)
			(xy 199.038718 -338.879942) (xy 199.038209 -338.907828) (xy 199.030089 -338.963004) (xy 199.014021 -339.016411)
			(xy 198.990349 -339.066908) (xy 198.959576 -339.113421) (xy 198.922359 -339.154958) (xy 198.879491 -339.190633)
			(xy 198.831885 -339.219687) (xy 198.780556 -339.241499) (xy 198.726599 -339.255605) (xy 198.671162 -339.261705)
			(xy 198.615428 -339.259668) (xy 198.560585 -339.249538) (xy 198.507801 -339.231531) (xy 198.458201 -339.20603)
			(xy 198.412843 -339.173579) (xy 198.372694 -339.13487) (xy 198.338608 -339.090727) (xy 198.311312 -339.042092)
			(xy 198.291389 -338.990001) (xy 198.279263 -338.935564) (xy 198.275192 -338.879942) (xy 196.961252 -338.879942)
			(xy 196.961252 -340.121748) (xy 203.227938 -340.121748) (xy 203.232009 -340.066126) (xy 203.244135 -340.011689)
			(xy 203.264058 -339.959598) (xy 203.291354 -339.910963) (xy 203.32544 -339.86682) (xy 203.365589 -339.828111)
			(xy 203.410947 -339.79566) (xy 203.460547 -339.770159) (xy 203.513331 -339.752152) (xy 203.568174 -339.742022)
			(xy 203.623908 -339.739985) (xy 203.679345 -339.746085) (xy 203.733302 -339.760191) (xy 203.784631 -339.782003)
			(xy 203.832237 -339.811057) (xy 203.875105 -339.846732) (xy 203.912322 -339.888269) (xy 203.943095 -339.934782)
			(xy 203.966767 -339.985279) (xy 203.982835 -340.038686) (xy 203.990955 -340.093862) (xy 203.991464 -340.121748)
			(xy 203.990955 -340.149634) (xy 203.982835 -340.20481) (xy 203.966767 -340.258217) (xy 203.943095 -340.308714)
			(xy 203.912322 -340.355227) (xy 203.875105 -340.396764) (xy 203.832237 -340.432439) (xy 203.784631 -340.461493)
			(xy 203.733302 -340.483305) (xy 203.679345 -340.497411) (xy 203.623908 -340.503511) (xy 203.568174 -340.501474)
			(xy 203.513331 -340.491344) (xy 203.460547 -340.473337) (xy 203.410947 -340.447836) (xy 203.365589 -340.415385)
			(xy 203.32544 -340.376676) (xy 203.291354 -340.332533) (xy 203.264058 -340.283898) (xy 203.244135 -340.231807)
			(xy 203.232009 -340.17737) (xy 203.227938 -340.121748) (xy 196.961252 -340.121748) (xy 196.961252 -341.839042)
			(xy 196.96082 -341.849108) (xy 196.953089 -341.867697) (xy 196.946266 -341.87511) (xy 196.337682 -342.483694)
			(xy 196.330283 -342.490538) (xy 196.311685 -342.498267) (xy 196.301614 -342.49868) (xy 160.496504 -342.49868)
			(xy 160.486656 -342.499121) (xy 160.468407 -342.50653) (xy 160.454315 -342.520288) (xy 160.450022 -342.52916)
			(xy 160.406334 -342.628474) (xy 160.41116 -342.657938) (xy 160.421574 -342.669114) (xy 160.44047 -342.690362)
			(xy 160.472401 -342.737409) (xy 160.49699 -342.788677) (xy 160.513694 -342.843027) (xy 160.52214 -342.899256)
			(xy 160.522567 -342.922352) (xy 202.582016 -342.922352) (xy 202.586087 -342.86673) (xy 202.598213 -342.812293)
			(xy 202.618136 -342.760202) (xy 202.645432 -342.711567) (xy 202.679518 -342.667424) (xy 202.719667 -342.628715)
			(xy 202.765025 -342.596264) (xy 202.814625 -342.570763) (xy 202.867409 -342.552756) (xy 202.922252 -342.542626)
			(xy 202.977986 -342.540589) (xy 203.033423 -342.546689) (xy 203.08738 -342.560795) (xy 203.138709 -342.582607)
			(xy 203.186315 -342.611661) (xy 203.229183 -342.647336) (xy 203.2664 -342.688873) (xy 203.297173 -342.735386)
			(xy 203.320845 -342.785883) (xy 203.336913 -342.83929) (xy 203.345033 -342.894466) (xy 203.345542 -342.922352)
			(xy 203.345033 -342.950238) (xy 203.336913 -343.005414) (xy 203.320845 -343.058821) (xy 203.297173 -343.109318)
			(xy 203.2664 -343.155831) (xy 203.229183 -343.197368) (xy 203.186315 -343.233043) (xy 203.138709 -343.262097)
			(xy 203.08738 -343.283909) (xy 203.033423 -343.298015) (xy 202.977986 -343.304115) (xy 202.922252 -343.302078)
			(xy 202.867409 -343.291948) (xy 202.814625 -343.273941) (xy 202.765025 -343.24844) (xy 202.719667 -343.215989)
			(xy 202.679518 -343.17728) (xy 202.645432 -343.133137) (xy 202.618136 -343.084502) (xy 202.598213 -343.032411)
			(xy 202.586087 -342.977974) (xy 202.582016 -342.922352) (xy 160.522567 -342.922352) (xy 160.522666 -342.927686)
			(xy 160.522133 -342.956603) (xy 160.513407 -343.013774) (xy 160.496154 -343.068974) (xy 160.470767 -343.120938)
			(xy 160.437829 -343.168476) (xy 160.398095 -343.210499) (xy 160.3756 -343.228676) (xy 160.36677 -343.236266)
			(xy 160.356585 -343.257176) (xy 160.356042 -343.268808) (xy 160.356042 -343.348564) (xy 160.356613 -343.360186)
			(xy 160.366801 -343.381081) (xy 160.3756 -343.388696) (xy 160.398082 -343.406887) (xy 160.437816 -343.448906)
			(xy 160.470752 -343.496441) (xy 160.496134 -343.548403) (xy 160.513382 -343.603601) (xy 160.522099 -343.660771)
			(xy 160.522666 -343.689686) (xy 160.52218 -343.716937) (xy 160.514424 -343.770885) (xy 160.499069 -343.82318)
			(xy 160.486954 -343.849706) (xy 160.851086 -343.849706) (xy 160.855157 -343.794084) (xy 160.867283 -343.739647)
			(xy 160.887206 -343.687556) (xy 160.914502 -343.638921) (xy 160.948588 -343.594778) (xy 160.988737 -343.556069)
			(xy 161.034095 -343.523618) (xy 161.083695 -343.498117) (xy 161.136479 -343.48011) (xy 161.191322 -343.46998)
			(xy 161.247056 -343.467943) (xy 161.302493 -343.474043) (xy 161.35645 -343.488149) (xy 161.407779 -343.509961)
			(xy 161.455385 -343.539015) (xy 161.498253 -343.57469) (xy 161.53547 -343.616227) (xy 161.566243 -343.66274)
			(xy 161.589915 -343.713237) (xy 161.605983 -343.766644) (xy 161.614103 -343.82182) (xy 161.614612 -343.849706)
			(xy 161.614103 -343.877592) (xy 161.605983 -343.932768) (xy 161.589915 -343.986175) (xy 161.566243 -344.036672)
			(xy 161.53547 -344.083185) (xy 161.498253 -344.124722) (xy 161.455385 -344.160397) (xy 161.407779 -344.189451)
			(xy 161.35645 -344.211263) (xy 161.302493 -344.225369) (xy 161.247056 -344.231469) (xy 161.191322 -344.229432)
			(xy 161.136479 -344.219302) (xy 161.083695 -344.201295) (xy 161.034095 -344.175794) (xy 160.988737 -344.143343)
			(xy 160.948588 -344.104634) (xy 160.914502 -344.060491) (xy 160.887206 -344.011856) (xy 160.867283 -343.959765)
			(xy 160.855157 -343.905328) (xy 160.851086 -343.849706) (xy 160.486954 -343.849706) (xy 160.476427 -343.872757)
			(xy 160.446961 -343.918607) (xy 160.41127 -343.959798) (xy 160.370079 -343.995489) (xy 160.324229 -344.024955)
			(xy 160.274652 -344.047597) (xy 160.222357 -344.062952) (xy 160.168409 -344.070708) (xy 160.113907 -344.070708)
			(xy 160.059959 -344.062952) (xy 160.007664 -344.047597) (xy 159.958087 -344.024955) (xy 159.912237 -343.995489)
			(xy 159.871046 -343.959798) (xy 159.835355 -343.918607) (xy 159.805889 -343.872757) (xy 159.783247 -343.82318)
			(xy 159.767892 -343.770885) (xy 159.760136 -343.716937) (xy 159.75965 -343.689686) (xy 159.760185 -343.66077)
			(xy 159.768915 -343.603601) (xy 159.786172 -343.548405) (xy 159.811561 -343.496445) (xy 159.844502 -343.448911)
			(xy 159.884238 -343.406893) (xy 159.906716 -343.388696) (xy 159.915556 -343.38111) (xy 159.925767 -343.3602)
			(xy 159.926274 -343.348564) (xy 159.926274 -343.268808) (xy 159.925698 -343.257188) (xy 159.915505 -343.236301)
			(xy 159.906716 -343.228676) (xy 159.884229 -343.210487) (xy 159.844485 -343.168471) (xy 159.811539 -343.120938)
			(xy 159.786146 -343.068976) (xy 159.768888 -343.013776) (xy 159.760159 -342.956603) (xy 159.75965 -342.927686)
			(xy 159.760177 -342.899256) (xy 159.768623 -342.843028) (xy 159.785327 -342.788678) (xy 159.809917 -342.737411)
			(xy 159.841849 -342.690365) (xy 159.860742 -342.669114) (xy 159.871156 -342.657938) (xy 159.875982 -342.628474)
			(xy 159.832294 -342.52916) (xy 159.827937 -342.520327) (xy 159.813858 -342.506579) (xy 159.795649 -342.499119)
			(xy 159.785812 -342.49868) (xy 156.512768 -342.49868) (xy 156.5027 -342.499108) (xy 156.484102 -342.506829)
			(xy 156.4767 -342.513666) (xy 155.510738 -343.479628) (xy 155.503892 -343.487026) (xy 155.496161 -343.505625)
			(xy 155.495752 -343.515696) (xy 155.495752 -345.078304) (xy 160.503106 -345.078304) (xy 160.507177 -345.022682)
			(xy 160.519303 -344.968245) (xy 160.539226 -344.916154) (xy 160.566522 -344.867519) (xy 160.600608 -344.823376)
			(xy 160.640757 -344.784667) (xy 160.686115 -344.752216) (xy 160.735715 -344.726715) (xy 160.788499 -344.708708)
			(xy 160.843342 -344.698578) (xy 160.899076 -344.696541) (xy 160.954513 -344.702641) (xy 161.00847 -344.716747)
			(xy 161.059799 -344.738559) (xy 161.107405 -344.767613) (xy 161.150273 -344.803288) (xy 161.174565 -344.8304)
			(xy 201.363834 -344.8304) (xy 201.36434 -344.801482) (xy 201.373069 -344.74431) (xy 201.390329 -344.68911)
			(xy 201.415723 -344.637149) (xy 201.448669 -344.589615) (xy 201.488413 -344.547599) (xy 201.5109 -344.52941)
			(xy 201.519693 -344.521789) (xy 201.529884 -344.500899) (xy 201.530458 -344.489278) (xy 201.530458 -344.409522)
			(xy 201.529906 -344.397891) (xy 201.519728 -344.376981) (xy 201.5109 -344.36939) (xy 201.488412 -344.351205)
			(xy 201.448677 -344.309184) (xy 201.415738 -344.261648) (xy 201.390351 -344.209685) (xy 201.373096 -344.154487)
			(xy 201.364368 -344.097316) (xy 201.363834 -344.0684) (xy 201.36432 -344.041149) (xy 201.372076 -343.987201)
			(xy 201.387431 -343.934906) (xy 201.410073 -343.885329) (xy 201.439539 -343.839479) (xy 201.47523 -343.798288)
			(xy 201.516421 -343.762597) (xy 201.562271 -343.733131) (xy 201.611848 -343.710489) (xy 201.664143 -343.695134)
			(xy 201.718091 -343.687378) (xy 201.772593 -343.687378) (xy 201.826541 -343.695134) (xy 201.878836 -343.710489)
			(xy 201.928413 -343.733131) (xy 201.974263 -343.762597) (xy 202.015454 -343.798288) (xy 202.051145 -343.839479)
			(xy 202.080611 -343.885329) (xy 202.103253 -343.934906) (xy 202.118608 -343.987201) (xy 202.126364 -344.041149)
			(xy 202.12685 -344.0684) (xy 202.126351 -344.097318) (xy 202.11762 -344.154491) (xy 202.10036 -344.209691)
			(xy 202.074965 -344.261653) (xy 202.052577 -344.293952) (xy 205.807816 -344.293952) (xy 205.811887 -344.23833)
			(xy 205.824013 -344.183893) (xy 205.843936 -344.131802) (xy 205.871232 -344.083167) (xy 205.905318 -344.039024)
			(xy 205.945467 -344.000315) (xy 205.990825 -343.967864) (xy 206.040425 -343.942363) (xy 206.093209 -343.924356)
			(xy 206.148052 -343.914226) (xy 206.203786 -343.912189) (xy 206.259223 -343.918289) (xy 206.31318 -343.932395)
			(xy 206.364509 -343.954207) (xy 206.412115 -343.983261) (xy 206.454983 -344.018936) (xy 206.4922 -344.060473)
			(xy 206.522973 -344.106986) (xy 206.546645 -344.157483) (xy 206.562713 -344.21089) (xy 206.570833 -344.266066)
			(xy 206.571342 -344.293952) (xy 206.570833 -344.321838) (xy 206.562713 -344.377014) (xy 206.546645 -344.430421)
			(xy 206.522973 -344.480918) (xy 206.4922 -344.527431) (xy 206.454983 -344.568968) (xy 206.412115 -344.604643)
			(xy 206.364509 -344.633697) (xy 206.31318 -344.655509) (xy 206.259223 -344.669615) (xy 206.203786 -344.675715)
			(xy 206.148052 -344.673678) (xy 206.093209 -344.663548) (xy 206.040425 -344.645541) (xy 205.990825 -344.62004)
			(xy 205.945467 -344.587589) (xy 205.905318 -344.54888) (xy 205.871232 -344.504737) (xy 205.843936 -344.456102)
			(xy 205.824013 -344.404011) (xy 205.811887 -344.349574) (xy 205.807816 -344.293952) (xy 202.052577 -344.293952)
			(xy 202.042017 -344.309186) (xy 202.002272 -344.351201) (xy 201.979784 -344.36939) (xy 201.970988 -344.377008)
			(xy 201.960799 -344.397901) (xy 201.960226 -344.409522) (xy 201.960226 -344.489278) (xy 201.960783 -344.500908)
			(xy 201.970958 -344.521818) (xy 201.979784 -344.52941) (xy 202.002269 -344.547599) (xy 202.042005 -344.589619)
			(xy 202.074944 -344.637154) (xy 202.100332 -344.689116) (xy 202.117588 -344.744314) (xy 202.126316 -344.801484)
			(xy 202.12685 -344.8304) (xy 202.126364 -344.857651) (xy 202.118608 -344.911599) (xy 202.103253 -344.963894)
			(xy 202.080611 -345.013471) (xy 202.051145 -345.059321) (xy 202.015454 -345.100512) (xy 201.974263 -345.136203)
			(xy 201.928413 -345.165669) (xy 201.878836 -345.188311) (xy 201.826541 -345.203666) (xy 201.772593 -345.211422)
			(xy 201.718091 -345.211422) (xy 201.664143 -345.203666) (xy 201.611848 -345.188311) (xy 201.562271 -345.165669)
			(xy 201.516421 -345.136203) (xy 201.47523 -345.100512) (xy 201.439539 -345.059321) (xy 201.410073 -345.013471)
			(xy 201.387431 -344.963894) (xy 201.372076 -344.911599) (xy 201.36432 -344.857651) (xy 201.363834 -344.8304)
			(xy 161.174565 -344.8304) (xy 161.18749 -344.844825) (xy 161.218263 -344.891338) (xy 161.241935 -344.941835)
			(xy 161.258003 -344.995242) (xy 161.266123 -345.050418) (xy 161.266632 -345.078304) (xy 161.266123 -345.10619)
			(xy 161.258003 -345.161366) (xy 161.241935 -345.214773) (xy 161.218263 -345.26527) (xy 161.18749 -345.311783)
			(xy 161.150273 -345.35332) (xy 161.107405 -345.388995) (xy 161.059799 -345.418049) (xy 161.00847 -345.439861)
			(xy 160.954513 -345.453967) (xy 160.899076 -345.460067) (xy 160.843342 -345.45803) (xy 160.788499 -345.4479)
			(xy 160.735715 -345.429893) (xy 160.686115 -345.404392) (xy 160.640757 -345.371941) (xy 160.600608 -345.333232)
			(xy 160.566522 -345.289089) (xy 160.539226 -345.240454) (xy 160.519303 -345.188363) (xy 160.507177 -345.133926)
			(xy 160.503106 -345.078304) (xy 155.495752 -345.078304) (xy 155.495752 -346.211652) (xy 165.219634 -346.211652)
			(xy 165.22012 -346.184401) (xy 165.227876 -346.130453) (xy 165.243231 -346.078158) (xy 165.265873 -346.028581)
			(xy 165.295339 -345.982731) (xy 165.33103 -345.94154) (xy 165.372221 -345.905849) (xy 165.418071 -345.876383)
			(xy 165.467648 -345.853741) (xy 165.519943 -345.838386) (xy 165.573891 -345.83063) (xy 165.628393 -345.83063)
			(xy 165.682341 -345.838386) (xy 165.734636 -345.853741) (xy 165.784213 -345.876383) (xy 165.830063 -345.905849)
			(xy 165.871254 -345.94154) (xy 165.906945 -345.982731) (xy 165.936411 -346.028581) (xy 165.959053 -346.078158)
			(xy 165.974408 -346.130453) (xy 165.982164 -346.184401) (xy 165.98265 -346.211652) (xy 165.98265 -346.211906)
			(xy 165.982064 -346.242274) (xy 165.972446 -346.302076) (xy 167.694608 -346.302076) (xy 167.698679 -346.246454)
			(xy 167.710805 -346.192017) (xy 167.730728 -346.139926) (xy 167.758024 -346.091291) (xy 167.79211 -346.047148)
			(xy 167.832259 -346.008439) (xy 167.877617 -345.975988) (xy 167.927217 -345.950487) (xy 167.980001 -345.93248)
			(xy 168.034844 -345.92235) (xy 168.090578 -345.920313) (xy 168.146015 -345.926413) (xy 168.199972 -345.940519)
			(xy 168.251301 -345.962331) (xy 168.298907 -345.991385) (xy 168.341775 -346.02706) (xy 168.378992 -346.068597)
			(xy 168.409765 -346.11511) (xy 168.433437 -346.165607) (xy 168.449505 -346.219014) (xy 168.457625 -346.27419)
			(xy 168.458134 -346.302076) (xy 168.457625 -346.329962) (xy 168.449505 -346.385138) (xy 168.433437 -346.438545)
			(xy 168.409765 -346.489042) (xy 168.378992 -346.535555) (xy 168.341775 -346.577092) (xy 168.334676 -346.583)
			(xy 201.363834 -346.583) (xy 201.36434 -346.554082) (xy 201.373069 -346.49691) (xy 201.390329 -346.44171)
			(xy 201.415723 -346.389749) (xy 201.448669 -346.342215) (xy 201.488413 -346.300199) (xy 201.5109 -346.28201)
			(xy 201.519693 -346.274389) (xy 201.529884 -346.253499) (xy 201.530458 -346.241878) (xy 201.530458 -346.162122)
			(xy 201.529906 -346.150491) (xy 201.519728 -346.129581) (xy 201.5109 -346.12199) (xy 201.488412 -346.103805)
			(xy 201.448677 -346.061784) (xy 201.415738 -346.014248) (xy 201.390351 -345.962285) (xy 201.373096 -345.907087)
			(xy 201.364368 -345.849916) (xy 201.363834 -345.821) (xy 201.36432 -345.793749) (xy 201.372076 -345.739801)
			(xy 201.387431 -345.687506) (xy 201.410073 -345.637929) (xy 201.439539 -345.592079) (xy 201.47523 -345.550888)
			(xy 201.516421 -345.515197) (xy 201.562271 -345.485731) (xy 201.611848 -345.463089) (xy 201.664143 -345.447734)
			(xy 201.718091 -345.439978) (xy 201.772593 -345.439978) (xy 201.826541 -345.447734) (xy 201.878836 -345.463089)
			(xy 201.928413 -345.485731) (xy 201.974263 -345.515197) (xy 202.015454 -345.550888) (xy 202.051145 -345.592079)
			(xy 202.080611 -345.637929) (xy 202.103253 -345.687506) (xy 202.118608 -345.739801) (xy 202.126364 -345.793749)
			(xy 202.12685 -345.821) (xy 202.126351 -345.849918) (xy 202.11762 -345.907091) (xy 202.10036 -345.962291)
			(xy 202.074965 -346.014253) (xy 202.042017 -346.061786) (xy 202.002272 -346.103801) (xy 201.979784 -346.12199)
			(xy 201.970988 -346.129608) (xy 201.960799 -346.150501) (xy 201.960226 -346.162122) (xy 201.960226 -346.241878)
			(xy 201.960783 -346.253508) (xy 201.970958 -346.274418) (xy 201.979784 -346.28201) (xy 202.002269 -346.300199)
			(xy 202.042005 -346.342219) (xy 202.074944 -346.389754) (xy 202.100332 -346.441716) (xy 202.117588 -346.496914)
			(xy 202.126316 -346.554084) (xy 202.12685 -346.583) (xy 202.126364 -346.610251) (xy 202.118608 -346.664199)
			(xy 202.103253 -346.716494) (xy 202.080611 -346.766071) (xy 202.051145 -346.811921) (xy 202.015454 -346.853112)
			(xy 201.974263 -346.888803) (xy 201.928413 -346.918269) (xy 201.878836 -346.940911) (xy 201.826541 -346.956266)
			(xy 201.772593 -346.964022) (xy 201.718091 -346.964022) (xy 201.664143 -346.956266) (xy 201.611848 -346.940911)
			(xy 201.562271 -346.918269) (xy 201.516421 -346.888803) (xy 201.47523 -346.853112) (xy 201.439539 -346.811921)
			(xy 201.410073 -346.766071) (xy 201.387431 -346.716494) (xy 201.372076 -346.664199) (xy 201.36432 -346.610251)
			(xy 201.363834 -346.583) (xy 168.334676 -346.583) (xy 168.298907 -346.612767) (xy 168.251301 -346.641821)
			(xy 168.199972 -346.663633) (xy 168.146015 -346.677739) (xy 168.090578 -346.683839) (xy 168.034844 -346.681802)
			(xy 167.980001 -346.671672) (xy 167.927217 -346.653665) (xy 167.877617 -346.628164) (xy 167.832259 -346.595713)
			(xy 167.79211 -346.557004) (xy 167.758024 -346.512861) (xy 167.730728 -346.464226) (xy 167.710805 -346.412135)
			(xy 167.698679 -346.357698) (xy 167.694608 -346.302076) (xy 165.972446 -346.302076) (xy 165.97242 -346.302239)
			(xy 165.953408 -346.359923) (xy 165.939978 -346.387166) (xy 165.93403 -346.39961) (xy 165.928387 -346.426599)
			(xy 165.930175 -346.454113) (xy 165.939261 -346.480145) (xy 165.954984 -346.502794) (xy 165.976196 -346.520409)
			(xy 166.001348 -346.531704) (xy 166.014908 -346.534232) (xy 166.041624 -346.538778) (xy 166.093505 -346.554432)
			(xy 166.142648 -346.577269) (xy 166.188066 -346.60683) (xy 166.228844 -346.642521) (xy 166.264161 -346.683623)
			(xy 166.293307 -346.729308) (xy 166.315695 -346.778659) (xy 166.330874 -346.83068) (xy 166.338539 -346.884326)
			(xy 166.339012 -346.911422) (xy 166.338526 -346.938673) (xy 166.33077 -346.992621) (xy 166.315415 -347.044916)
			(xy 166.292773 -347.094493) (xy 166.263307 -347.140343) (xy 166.227616 -347.181534) (xy 166.186425 -347.217225)
			(xy 166.140575 -347.246691) (xy 166.09206 -347.268848) (xy 203.547 -347.268848) (xy 203.547 -347.214352)
			(xy 203.554755 -347.160411) (xy 203.570108 -347.108122) (xy 203.592745 -347.05855) (xy 203.622206 -347.012704)
			(xy 203.657892 -346.971517) (xy 203.699075 -346.935828) (xy 203.744918 -346.906362) (xy 203.794488 -346.88372)
			(xy 203.846775 -346.868363) (xy 203.900716 -346.860603) (xy 203.927964 -346.860114) (xy 203.955334 -346.860598)
			(xy 204.009512 -346.868411) (xy 204.062015 -346.883896) (xy 204.111762 -346.906733) (xy 204.15773 -346.936454)
			(xy 204.178662 -346.954094) (xy 204.178916 -346.954348) (xy 204.18599 -346.959953) (xy 204.202917 -346.966188)
			(xy 204.211936 -346.96654) (xy 204.278992 -346.96654) (xy 204.28801 -346.966192) (xy 204.304928 -346.95994)
			(xy 204.312012 -346.954348) (xy 204.312012 -346.954094) (xy 204.312266 -346.954094) (xy 204.333199 -346.936456)
			(xy 204.379172 -346.906745) (xy 204.428919 -346.883908) (xy 204.481419 -346.868417) (xy 204.535595 -346.860588)
			(xy 204.562964 -346.860114) (xy 204.589876 -346.860595) (xy 204.643163 -346.868196) (xy 204.694856 -346.883196)
			(xy 204.743935 -346.905299) (xy 204.766926 -346.919296) (xy 204.76718 -346.919296) (xy 204.775203 -346.923891)
			(xy 204.793311 -346.927542) (xy 204.802486 -346.926408) (xy 204.869288 -346.915486) (xy 204.878413 -346.913542)
			(xy 204.894436 -346.904011) (xy 204.90053 -346.896944) (xy 204.91875 -346.875108) (xy 204.960565 -346.836565)
			(xy 205.007637 -346.804656) (xy 205.058924 -346.780086) (xy 205.11329 -346.763401) (xy 205.16953 -346.75497)
			(xy 205.197964 -346.75445) (xy 205.225212 -346.755012) (xy 205.279155 -346.762762) (xy 205.331446 -346.778111)
			(xy 205.38102 -346.800744) (xy 205.426869 -346.830203) (xy 205.468058 -346.865887) (xy 205.50375 -346.907069)
			(xy 205.533218 -346.952911) (xy 205.555862 -347.002481) (xy 205.571221 -347.054768) (xy 205.578983 -347.10871)
			(xy 205.579472 -347.135958) (xy 205.578988 -347.163328) (xy 205.571176 -347.217506) (xy 205.555691 -347.270009)
			(xy 205.532853 -347.319757) (xy 205.503132 -347.365724) (xy 205.485492 -347.386656) (xy 205.485238 -347.38691)
			(xy 205.479634 -347.393984) (xy 205.473399 -347.410911) (xy 205.473046 -347.41993) (xy 205.473046 -347.486986)
			(xy 205.4734 -347.496003) (xy 205.479649 -347.512921) (xy 205.485238 -347.520006) (xy 205.485492 -347.520006)
			(xy 205.485492 -347.52026) (xy 205.503125 -347.541197) (xy 205.532838 -347.587169) (xy 205.555675 -347.636915)
			(xy 205.571168 -347.689414) (xy 205.578997 -347.743589) (xy 205.579472 -347.770958) (xy 205.578986 -347.798209)
			(xy 205.57123 -347.852157) (xy 205.555875 -347.904452) (xy 205.533233 -347.954029) (xy 205.503767 -347.999879)
			(xy 205.468076 -348.04107) (xy 205.426885 -348.076761) (xy 205.381035 -348.106227) (xy 205.331458 -348.128869)
			(xy 205.279163 -348.144224) (xy 205.225215 -348.15198) (xy 205.170713 -348.15198) (xy 205.116765 -348.144224)
			(xy 205.06447 -348.128869) (xy 205.014893 -348.106227) (xy 204.969043 -348.076761) (xy 204.927852 -348.04107)
			(xy 204.892161 -347.999879) (xy 204.862695 -347.954029) (xy 204.840053 -347.904452) (xy 204.824698 -347.852157)
			(xy 204.816942 -347.798209) (xy 204.816456 -347.770958) (xy 204.816456 -347.770704) (xy 204.816596 -347.756361)
			(xy 204.818759 -347.727756) (xy 204.820774 -347.713554) (xy 204.822806 -347.700346) (xy 204.813408 -347.675708)
			(xy 204.736446 -347.611192) (xy 204.729468 -347.605905) (xy 204.713039 -347.599903) (xy 204.695548 -347.599767)
			(xy 204.68717 -347.602302) (xy 204.657048 -347.612043) (xy 204.594616 -347.62251) (xy 204.562964 -347.62313)
			(xy 204.535592 -347.622702) (xy 204.481411 -347.614878) (xy 204.428907 -347.599381) (xy 204.37916 -347.57653)
			(xy 204.333196 -347.546796) (xy 204.312266 -347.52915) (xy 204.312012 -347.528896) (xy 204.304927 -347.523308)
			(xy 204.288009 -347.517062) (xy 204.278992 -347.516704) (xy 204.211936 -347.516704) (xy 204.202921 -347.517077)
			(xy 204.186004 -347.523313) (xy 204.178916 -347.528896) (xy 204.178916 -347.52915) (xy 204.178662 -347.52915)
			(xy 204.157711 -347.546766) (xy 204.111744 -347.576483) (xy 204.062002 -347.599324) (xy 204.009505 -347.61482)
			(xy 203.955332 -347.622654) (xy 203.927964 -347.62313) (xy 203.900716 -347.622597) (xy 203.846775 -347.614837)
			(xy 203.794488 -347.59948) (xy 203.744918 -347.576838) (xy 203.699075 -347.547372) (xy 203.657892 -347.511683)
			(xy 203.622206 -347.470496) (xy 203.592745 -347.42465) (xy 203.570108 -347.375078) (xy 203.554755 -347.322789)
			(xy 203.547 -347.268848) (xy 166.09206 -347.268848) (xy 166.090998 -347.269333) (xy 166.038703 -347.284688)
			(xy 165.984755 -347.292444) (xy 165.930253 -347.292444) (xy 165.876305 -347.284688) (xy 165.82401 -347.269333)
			(xy 165.774433 -347.246691) (xy 165.728583 -347.217225) (xy 165.687392 -347.181534) (xy 165.651701 -347.140343)
			(xy 165.622235 -347.094493) (xy 165.599593 -347.044916) (xy 165.584238 -346.992621) (xy 165.576482 -346.938673)
			(xy 165.575996 -346.911422) (xy 165.575996 -346.911168) (xy 165.576616 -346.880802) (xy 165.586247 -346.820838)
			(xy 165.605245 -346.763153) (xy 165.618668 -346.735908) (xy 165.624614 -346.723465) (xy 165.630247 -346.696478)
			(xy 165.628455 -346.668967) (xy 165.619367 -346.642939) (xy 165.603648 -346.620292) (xy 165.582442 -346.602675)
			(xy 165.557295 -346.591375) (xy 165.543738 -346.588842) (xy 165.517029 -346.584266) (xy 165.465153 -346.56861)
			(xy 165.416014 -346.545772) (xy 165.3706 -346.516212) (xy 165.329825 -346.480524) (xy 165.294508 -346.439427)
			(xy 165.265362 -346.393747) (xy 165.24297 -346.344402) (xy 165.227785 -346.292386) (xy 165.220112 -346.238745)
			(xy 165.219634 -346.211652) (xy 155.495752 -346.211652) (xy 155.495752 -347.260164) (xy 156.09138 -347.260164)
			(xy 156.095451 -347.204542) (xy 156.107577 -347.150105) (xy 156.1275 -347.098014) (xy 156.154796 -347.049379)
			(xy 156.188882 -347.005236) (xy 156.229031 -346.966527) (xy 156.274389 -346.934076) (xy 156.323989 -346.908575)
			(xy 156.376773 -346.890568) (xy 156.431616 -346.880438) (xy 156.48735 -346.878401) (xy 156.542787 -346.884501)
			(xy 156.596744 -346.898607) (xy 156.648073 -346.920419) (xy 156.695679 -346.949473) (xy 156.738547 -346.985148)
			(xy 156.775764 -347.026685) (xy 156.806537 -347.073198) (xy 156.830209 -347.123695) (xy 156.846277 -347.177102)
			(xy 156.854397 -347.232278) (xy 156.854906 -347.260164) (xy 156.854397 -347.28805) (xy 156.846277 -347.343226)
			(xy 156.830209 -347.396633) (xy 156.806537 -347.44713) (xy 156.775764 -347.493643) (xy 156.738547 -347.53518)
			(xy 156.695679 -347.570855) (xy 156.648073 -347.599909) (xy 156.596744 -347.621721) (xy 156.542787 -347.635827)
			(xy 156.48735 -347.641927) (xy 156.431616 -347.63989) (xy 156.376773 -347.62976) (xy 156.323989 -347.611753)
			(xy 156.274389 -347.586252) (xy 156.229031 -347.553801) (xy 156.188882 -347.515092) (xy 156.154796 -347.470949)
			(xy 156.1275 -347.422314) (xy 156.107577 -347.370223) (xy 156.095451 -347.315786) (xy 156.09138 -347.260164)
			(xy 155.495752 -347.260164) (xy 155.495752 -348.807278) (xy 158.315912 -348.807278) (xy 158.319983 -348.751656)
			(xy 158.332109 -348.697219) (xy 158.352032 -348.645128) (xy 158.379328 -348.596493) (xy 158.413414 -348.55235)
			(xy 158.453563 -348.513641) (xy 158.498921 -348.48119) (xy 158.548521 -348.455689) (xy 158.601305 -348.437682)
			(xy 158.656148 -348.427552) (xy 158.711882 -348.425515) (xy 158.767319 -348.431615) (xy 158.821276 -348.445721)
			(xy 158.872605 -348.467533) (xy 158.920211 -348.496587) (xy 158.963079 -348.532262) (xy 159.000296 -348.573799)
			(xy 159.031069 -348.620312) (xy 159.054741 -348.670809) (xy 159.070809 -348.724216) (xy 159.078929 -348.779392)
			(xy 159.079438 -348.807278) (xy 159.078929 -348.835164) (xy 159.070809 -348.89034) (xy 159.054741 -348.943747)
			(xy 159.031069 -348.994244) (xy 159.000296 -349.040757) (xy 158.963079 -349.082294) (xy 158.920211 -349.117969)
			(xy 158.872605 -349.147023) (xy 158.821276 -349.168835) (xy 158.767319 -349.182941) (xy 158.711882 -349.189041)
			(xy 158.656148 -349.187004) (xy 158.601305 -349.176874) (xy 158.548521 -349.158867) (xy 158.498921 -349.133366)
			(xy 158.453563 -349.100915) (xy 158.413414 -349.062206) (xy 158.379328 -349.018063) (xy 158.352032 -348.969428)
			(xy 158.332109 -348.917337) (xy 158.319983 -348.8629) (xy 158.315912 -348.807278) (xy 155.495752 -348.807278)
			(xy 155.495752 -349.270828) (xy 156.241748 -349.270828) (xy 156.245819 -349.215206) (xy 156.257945 -349.160769)
			(xy 156.277868 -349.108678) (xy 156.305164 -349.060043) (xy 156.33925 -349.0159) (xy 156.379399 -348.977191)
			(xy 156.424757 -348.94474) (xy 156.474357 -348.919239) (xy 156.527141 -348.901232) (xy 156.581984 -348.891102)
			(xy 156.637718 -348.889065) (xy 156.693155 -348.895165) (xy 156.747112 -348.909271) (xy 156.798441 -348.931083)
			(xy 156.846047 -348.960137) (xy 156.888915 -348.995812) (xy 156.926132 -349.037349) (xy 156.956905 -349.083862)
			(xy 156.980577 -349.134359) (xy 156.996645 -349.187766) (xy 157.004765 -349.242942) (xy 157.005274 -349.270828)
			(xy 157.004765 -349.298714) (xy 157.000421 -349.328232) (xy 165.391846 -349.328232) (xy 165.392346 -349.30034)
			(xy 165.400459 -349.245149) (xy 165.416529 -349.19173) (xy 165.440215 -349.141225) (xy 165.47101 -349.094712)
			(xy 165.508257 -349.053184) (xy 165.551158 -349.017529) (xy 165.574726 -349.002604) (xy 165.583715 -348.996529)
			(xy 165.595954 -348.978641) (xy 165.598348 -348.96806) (xy 165.611556 -348.892876) (xy 165.612903 -348.882232)
			(xy 165.60766 -348.861452) (xy 165.601396 -348.852744) (xy 165.601396 -348.85249) (xy 165.585731 -348.832176)
			(xy 165.55946 -348.788114) (xy 165.539321 -348.740933) (xy 165.525677 -348.691482) (xy 165.518773 -348.640649)
			(xy 165.518338 -348.615) (xy 165.518907 -348.586442) (xy 165.527415 -348.529964) (xy 165.544241 -348.475384)
			(xy 165.569009 -348.423918) (xy 165.601167 -348.376716) (xy 165.620192 -348.355412) (xy 165.62705 -348.348046)
			(xy 165.633908 -348.330012) (xy 165.632384 -348.239334) (xy 165.624764 -348.221554) (xy 165.617652 -348.214442)
			(xy 165.596896 -348.192852) (xy 165.561726 -348.14438) (xy 165.534565 -348.091007) (xy 165.516081 -348.034044)
			(xy 165.506728 -347.974892) (xy 165.506146 -347.944948) (xy 165.506632 -347.917697) (xy 165.514388 -347.863749)
			(xy 165.529743 -347.811454) (xy 165.552385 -347.761877) (xy 165.581851 -347.716027) (xy 165.617542 -347.674836)
			(xy 165.658733 -347.639145) (xy 165.704583 -347.609679) (xy 165.75416 -347.587037) (xy 165.806455 -347.571682)
			(xy 165.860403 -347.563926) (xy 165.914905 -347.563926) (xy 165.968853 -347.571682) (xy 166.021148 -347.587037)
			(xy 166.070725 -347.609679) (xy 166.116575 -347.639145) (xy 166.157766 -347.674836) (xy 166.193457 -347.716027)
			(xy 166.222923 -347.761877) (xy 166.245565 -347.811454) (xy 166.26092 -347.863749) (xy 166.268676 -347.917697)
			(xy 166.269162 -347.944948) (xy 166.268622 -347.973507) (xy 166.264541 -348.000574) (xy 167.718484 -348.000574)
			(xy 167.722555 -347.944952) (xy 167.734681 -347.890515) (xy 167.754604 -347.838424) (xy 167.7819 -347.789789)
			(xy 167.815986 -347.745646) (xy 167.856135 -347.706937) (xy 167.901493 -347.674486) (xy 167.951093 -347.648985)
			(xy 168.003877 -347.630978) (xy 168.05872 -347.620848) (xy 168.114454 -347.618811) (xy 168.169891 -347.624911)
			(xy 168.223848 -347.639017) (xy 168.275177 -347.660829) (xy 168.322783 -347.689883) (xy 168.365651 -347.725558)
			(xy 168.402868 -347.767095) (xy 168.433641 -347.813608) (xy 168.457313 -347.864105) (xy 168.473381 -347.917512)
			(xy 168.481501 -347.972688) (xy 168.48201 -348.000574) (xy 168.481501 -348.02846) (xy 168.473381 -348.083636)
			(xy 168.457313 -348.137043) (xy 168.433641 -348.18754) (xy 168.402868 -348.234053) (xy 168.365651 -348.27559)
			(xy 168.322783 -348.311265) (xy 168.275177 -348.340319) (xy 168.223848 -348.362131) (xy 168.169891 -348.376237)
			(xy 168.114454 -348.382337) (xy 168.05872 -348.3803) (xy 168.003877 -348.37017) (xy 167.951093 -348.352163)
			(xy 167.901493 -348.326662) (xy 167.856135 -348.294211) (xy 167.815986 -348.255502) (xy 167.7819 -348.211359)
			(xy 167.754604 -348.162724) (xy 167.734681 -348.110633) (xy 167.722555 -348.056196) (xy 167.718484 -348.000574)
			(xy 166.264541 -348.000574) (xy 166.260107 -348.029986) (xy 166.243274 -348.084567) (xy 166.2185 -348.136032)
			(xy 166.186336 -348.183232) (xy 166.167308 -348.204536) (xy 166.16045 -348.211902) (xy 166.153592 -348.229936)
			(xy 166.155116 -348.320614) (xy 166.162736 -348.338394) (xy 166.169848 -348.345506) (xy 166.190579 -348.367119)
			(xy 166.225752 -348.415585) (xy 166.252918 -348.468952) (xy 166.271408 -348.52591) (xy 166.280768 -348.585058)
			(xy 166.281354 -348.615) (xy 166.280879 -348.642893) (xy 166.272762 -348.698085) (xy 166.256687 -348.751504)
			(xy 166.232997 -348.80201) (xy 166.202198 -348.848523) (xy 166.164948 -348.89005) (xy 166.122043 -348.925703)
			(xy 166.098474 -348.940628) (xy 166.089474 -348.946689) (xy 166.077241 -348.964587) (xy 166.074852 -348.975172)
			(xy 166.061644 -349.050356) (xy 166.060279 -349.060999) (xy 166.065535 -349.081781) (xy 166.071804 -349.090488)
			(xy 166.071804 -349.090742) (xy 166.087438 -349.111079) (xy 166.113714 -349.155134) (xy 166.133859 -349.202309)
			(xy 166.14751 -349.251756) (xy 166.154423 -349.302584) (xy 166.154862 -349.328232) (xy 166.154275 -349.359057)
			(xy 166.144345 -349.419902) (xy 166.124751 -349.478355) (xy 166.096003 -349.532892) (xy 166.0779 -349.557848)
			(xy 166.072057 -349.566446) (xy 166.067217 -349.586646) (xy 166.068502 -349.596964) (xy 166.080948 -349.669862)
			(xy 166.083133 -349.680028) (xy 166.094427 -349.697465) (xy 166.102792 -349.703644) (xy 166.121171 -349.716344)
			(xy 168.5704 -349.716344) (xy 168.574471 -349.660722) (xy 168.586597 -349.606285) (xy 168.60652 -349.554194)
			(xy 168.633816 -349.505559) (xy 168.667902 -349.461416) (xy 168.708051 -349.422707) (xy 168.753409 -349.390256)
			(xy 168.803009 -349.364755) (xy 168.855793 -349.346748) (xy 168.910636 -349.336618) (xy 168.96637 -349.334581)
			(xy 169.021807 -349.340681) (xy 169.075764 -349.354787) (xy 169.127093 -349.376599) (xy 169.174699 -349.405653)
			(xy 169.217567 -349.441328) (xy 169.254784 -349.482865) (xy 169.285557 -349.529378) (xy 169.309229 -349.579875)
			(xy 169.325297 -349.633282) (xy 169.333417 -349.688458) (xy 169.333926 -349.716344) (xy 169.333417 -349.74423)
			(xy 169.325297 -349.799406) (xy 169.309229 -349.852813) (xy 169.285557 -349.90331) (xy 169.254784 -349.949823)
			(xy 169.217567 -349.99136) (xy 169.174699 -350.027035) (xy 169.127093 -350.056089) (xy 169.075764 -350.077901)
			(xy 169.021807 -350.092007) (xy 168.96637 -350.098107) (xy 168.910636 -350.09607) (xy 168.855793 -350.08594)
			(xy 168.803009 -350.067933) (xy 168.753409 -350.042432) (xy 168.708051 -350.009981) (xy 168.667902 -349.971272)
			(xy 168.633816 -349.927129) (xy 168.60652 -349.878494) (xy 168.586597 -349.826403) (xy 168.574471 -349.771966)
			(xy 168.5704 -349.716344) (xy 166.121171 -349.716344) (xy 166.124874 -349.718903) (xy 166.164991 -349.754562)
			(xy 166.199711 -349.795494) (xy 166.228348 -349.840891) (xy 166.250337 -349.889854) (xy 166.265242 -349.941417)
			(xy 166.272769 -349.994561) (xy 166.273226 -350.021398) (xy 166.27274 -350.048649) (xy 166.264984 -350.102597)
			(xy 166.249629 -350.154892) (xy 166.226987 -350.204469) (xy 166.197521 -350.250319) (xy 166.16183 -350.29151)
			(xy 166.120639 -350.327201) (xy 166.074789 -350.356667) (xy 166.025212 -350.379309) (xy 165.972917 -350.394664)
			(xy 165.918969 -350.40242) (xy 165.864467 -350.40242) (xy 165.810519 -350.394664) (xy 165.758224 -350.379309)
			(xy 165.708647 -350.356667) (xy 165.662797 -350.327201) (xy 165.621606 -350.29151) (xy 165.585915 -350.250319)
			(xy 165.556449 -350.204469) (xy 165.533807 -350.154892) (xy 165.518452 -350.102597) (xy 165.510696 -350.048649)
			(xy 165.51021 -350.021398) (xy 165.510819 -349.990574) (xy 165.520742 -349.92973) (xy 165.540331 -349.871277)
			(xy 165.569073 -349.81674) (xy 165.587172 -349.791782) (xy 165.592998 -349.783173) (xy 165.597849 -349.762982)
			(xy 165.59657 -349.752666) (xy 165.584124 -349.679768) (xy 165.581899 -349.669614) (xy 165.570631 -349.652173)
			(xy 165.56228 -349.645986) (xy 165.540159 -349.63078) (xy 165.500044 -349.595112) (xy 165.465328 -349.55417)
			(xy 165.436696 -349.508764) (xy 165.414714 -349.459792) (xy 165.399817 -349.408222) (xy 165.392299 -349.355072)
			(xy 165.391846 -349.328232) (xy 157.000421 -349.328232) (xy 156.996645 -349.35389) (xy 156.980577 -349.407297)
			(xy 156.956905 -349.457794) (xy 156.926132 -349.504307) (xy 156.888915 -349.545844) (xy 156.846047 -349.581519)
			(xy 156.798441 -349.610573) (xy 156.747112 -349.632385) (xy 156.693155 -349.646491) (xy 156.637718 -349.652591)
			(xy 156.581984 -349.650554) (xy 156.527141 -349.640424) (xy 156.474357 -349.622417) (xy 156.424757 -349.596916)
			(xy 156.379399 -349.564465) (xy 156.33925 -349.525756) (xy 156.305164 -349.481613) (xy 156.277868 -349.432978)
			(xy 156.257945 -349.380887) (xy 156.245819 -349.32645) (xy 156.241748 -349.270828) (xy 155.495752 -349.270828)
			(xy 155.495752 -350.091502) (xy 158.361886 -350.091502) (xy 158.365957 -350.03588) (xy 158.378083 -349.981443)
			(xy 158.398006 -349.929352) (xy 158.425302 -349.880717) (xy 158.459388 -349.836574) (xy 158.499537 -349.797865)
			(xy 158.544895 -349.765414) (xy 158.594495 -349.739913) (xy 158.647279 -349.721906) (xy 158.702122 -349.711776)
			(xy 158.757856 -349.709739) (xy 158.813293 -349.715839) (xy 158.86725 -349.729945) (xy 158.918579 -349.751757)
			(xy 158.966185 -349.780811) (xy 159.009053 -349.816486) (xy 159.04627 -349.858023) (xy 159.077043 -349.904536)
			(xy 159.100715 -349.955033) (xy 159.116783 -350.00844) (xy 159.124903 -350.063616) (xy 159.125412 -350.091502)
			(xy 159.124903 -350.119388) (xy 159.116783 -350.174564) (xy 159.100715 -350.227971) (xy 159.077043 -350.278468)
			(xy 159.04627 -350.324981) (xy 159.009053 -350.366518) (xy 158.966185 -350.402193) (xy 158.918579 -350.431247)
			(xy 158.86725 -350.453059) (xy 158.813293 -350.467165) (xy 158.757856 -350.473265) (xy 158.702122 -350.471228)
			(xy 158.647279 -350.461098) (xy 158.594495 -350.443091) (xy 158.544895 -350.41759) (xy 158.499537 -350.385139)
			(xy 158.459388 -350.34643) (xy 158.425302 -350.302287) (xy 158.398006 -350.253652) (xy 158.378083 -350.201561)
			(xy 158.365957 -350.147124) (xy 158.361886 -350.091502) (xy 155.495752 -350.091502) (xy 155.495752 -350.732344)
			(xy 168.5704 -350.732344) (xy 168.574471 -350.676722) (xy 168.586597 -350.622285) (xy 168.60652 -350.570194)
			(xy 168.633816 -350.521559) (xy 168.667902 -350.477416) (xy 168.708051 -350.438707) (xy 168.753409 -350.406256)
			(xy 168.803009 -350.380755) (xy 168.855793 -350.362748) (xy 168.910636 -350.352618) (xy 168.96637 -350.350581)
			(xy 169.021807 -350.356681) (xy 169.075764 -350.370787) (xy 169.127093 -350.392599) (xy 169.174699 -350.421653)
			(xy 169.217567 -350.457328) (xy 169.254784 -350.498865) (xy 169.285557 -350.545378) (xy 169.309229 -350.595875)
			(xy 169.325297 -350.649282) (xy 169.333417 -350.704458) (xy 169.333926 -350.732344) (xy 169.333417 -350.76023)
			(xy 169.325297 -350.815406) (xy 169.309229 -350.868813) (xy 169.285557 -350.91931) (xy 169.254784 -350.965823)
			(xy 169.217567 -351.00736) (xy 169.174699 -351.043035) (xy 169.127093 -351.072089) (xy 169.075764 -351.093901)
			(xy 169.021807 -351.108007) (xy 168.96637 -351.114107) (xy 168.910636 -351.11207) (xy 168.855793 -351.10194)
			(xy 168.803009 -351.083933) (xy 168.753409 -351.058432) (xy 168.708051 -351.025981) (xy 168.667902 -350.987272)
			(xy 168.633816 -350.943129) (xy 168.60652 -350.894494) (xy 168.586597 -350.842403) (xy 168.574471 -350.787966)
			(xy 168.5704 -350.732344) (xy 155.495752 -350.732344) (xy 155.495752 -351.398078) (xy 158.417512 -351.398078)
			(xy 158.421583 -351.342456) (xy 158.433709 -351.288019) (xy 158.453632 -351.235928) (xy 158.480928 -351.187293)
			(xy 158.515014 -351.14315) (xy 158.555163 -351.104441) (xy 158.600521 -351.07199) (xy 158.650121 -351.046489)
			(xy 158.702905 -351.028482) (xy 158.757748 -351.018352) (xy 158.813482 -351.016315) (xy 158.868919 -351.022415)
			(xy 158.922876 -351.036521) (xy 158.974205 -351.058333) (xy 159.021811 -351.087387) (xy 159.064679 -351.123062)
			(xy 159.101896 -351.164599) (xy 159.132669 -351.211112) (xy 159.156341 -351.261609) (xy 159.172409 -351.315016)
			(xy 159.180529 -351.370192) (xy 159.181038 -351.398078) (xy 159.180529 -351.425964) (xy 159.172409 -351.48114)
			(xy 159.156341 -351.534547) (xy 159.132669 -351.585044) (xy 159.12092 -351.602802) (xy 159.687512 -351.602802)
			(xy 159.691583 -351.54718) (xy 159.703709 -351.492743) (xy 159.723632 -351.440652) (xy 159.750928 -351.392017)
			(xy 159.785014 -351.347874) (xy 159.825163 -351.309165) (xy 159.870521 -351.276714) (xy 159.920121 -351.251213)
			(xy 159.972905 -351.233206) (xy 160.027748 -351.223076) (xy 160.083482 -351.221039) (xy 160.138919 -351.227139)
			(xy 160.192876 -351.241245) (xy 160.244205 -351.263057) (xy 160.291811 -351.292111) (xy 160.334679 -351.327786)
			(xy 160.371896 -351.369323) (xy 160.402669 -351.415836) (xy 160.426341 -351.466333) (xy 160.442409 -351.51974)
			(xy 160.450529 -351.574916) (xy 160.451038 -351.602802) (xy 160.450529 -351.630688) (xy 160.443367 -351.679356)
			(xy 160.907633 -351.679356) (xy 160.907633 -351.624844) (xy 160.915391 -351.570887) (xy 160.93075 -351.518584)
			(xy 160.953396 -351.468999) (xy 160.982868 -351.423142) (xy 161.018567 -351.381946) (xy 161.059766 -351.34625)
			(xy 161.105625 -351.316781) (xy 161.155212 -351.294139) (xy 161.207517 -351.278785) (xy 161.261474 -351.271031)
			(xy 161.28873 -351.27057) (xy 161.314483 -351.27099) (xy 161.36552 -351.277935) (xy 161.415158 -351.291681)
			(xy 161.462497 -351.311979) (xy 161.506676 -351.338459) (xy 161.546892 -351.37064) (xy 161.582414 -351.407938)
			(xy 161.597848 -351.428558) (xy 161.606183 -351.439287) (xy 161.627314 -351.456343) (xy 161.652198 -351.467214)
			(xy 161.679069 -351.471129) (xy 161.706021 -351.467811) (xy 161.73114 -351.457494) (xy 161.752644 -351.440912)
			(xy 161.76117 -351.430336) (xy 161.779334 -351.407289) (xy 161.8215 -351.366484) (xy 161.869419 -351.33262)
			(xy 161.921961 -351.306498) (xy 161.977885 -351.288733) (xy 162.035869 -351.279745) (xy 162.065208 -351.279206)
			(xy 162.065462 -351.279206) (xy 162.092718 -351.279638) (xy 162.146675 -351.287391) (xy 162.198979 -351.302744)
			(xy 162.248566 -351.325386) (xy 162.294426 -351.354854) (xy 162.335624 -351.390549) (xy 162.371323 -351.431744)
			(xy 162.400796 -351.477601) (xy 162.423442 -351.527185) (xy 162.437965 -351.57664) (xy 164.057836 -351.57664)
			(xy 164.061907 -351.521018) (xy 164.074033 -351.466581) (xy 164.093956 -351.41449) (xy 164.121252 -351.365855)
			(xy 164.155338 -351.321712) (xy 164.195487 -351.283003) (xy 164.240845 -351.250552) (xy 164.290445 -351.225051)
			(xy 164.343229 -351.207044) (xy 164.398072 -351.196914) (xy 164.453806 -351.194877) (xy 164.509243 -351.200977)
			(xy 164.5632 -351.215083) (xy 164.614529 -351.236895) (xy 164.662135 -351.265949) (xy 164.705003 -351.301624)
			(xy 164.74222 -351.343161) (xy 164.772993 -351.389674) (xy 164.796665 -351.440171) (xy 164.812733 -351.493578)
			(xy 164.820853 -351.548754) (xy 164.821362 -351.57664) (xy 164.820853 -351.604526) (xy 164.812733 -351.659702)
			(xy 164.796665 -351.713109) (xy 164.772993 -351.763606) (xy 164.74222 -351.810119) (xy 164.705003 -351.851656)
			(xy 164.662135 -351.887331) (xy 164.614529 -351.916385) (xy 164.5632 -351.938197) (xy 164.509243 -351.952303)
			(xy 164.453806 -351.958403) (xy 164.398072 -351.956366) (xy 164.343229 -351.946236) (xy 164.290445 -351.928229)
			(xy 164.240845 -351.902728) (xy 164.195487 -351.870277) (xy 164.155338 -351.831568) (xy 164.121252 -351.787425)
			(xy 164.093956 -351.73879) (xy 164.074033 -351.686699) (xy 164.061907 -351.632262) (xy 164.057836 -351.57664)
			(xy 162.437965 -351.57664) (xy 162.438801 -351.579488) (xy 162.446559 -351.633444) (xy 162.446559 -351.687956)
			(xy 162.438801 -351.741912) (xy 162.423442 -351.794215) (xy 162.400796 -351.843799) (xy 162.371323 -351.889656)
			(xy 162.335624 -351.930851) (xy 162.294426 -351.966546) (xy 162.248566 -351.996014) (xy 162.198979 -352.018656)
			(xy 162.146675 -352.034009) (xy 162.092718 -352.041762) (xy 162.065462 -352.042222) (xy 162.039708 -352.041811)
			(xy 161.988671 -352.034865) (xy 161.939033 -352.021117) (xy 161.891694 -352.000818) (xy 161.847515 -351.974337)
			(xy 161.807299 -351.942154) (xy 161.771778 -351.904855) (xy 161.756344 -351.884234) (xy 161.748018 -351.873497)
			(xy 161.726885 -351.856443) (xy 161.701999 -351.845574) (xy 161.675126 -351.84166) (xy 161.648173 -351.844979)
			(xy 161.623053 -351.855297) (xy 161.601548 -351.87188) (xy 161.593022 -351.882456) (xy 161.57486 -351.905505)
			(xy 161.532694 -351.94631) (xy 161.484774 -351.980174) (xy 161.432232 -352.006296) (xy 161.376308 -352.024061)
			(xy 161.318323 -352.033048) (xy 161.288984 -352.033586) (xy 161.28873 -352.033586) (xy 161.261474 -352.033169)
			(xy 161.207517 -352.025415) (xy 161.155212 -352.010061) (xy 161.105625 -351.987419) (xy 161.059766 -351.95795)
			(xy 161.018567 -351.922254) (xy 160.982868 -351.881058) (xy 160.953396 -351.835201) (xy 160.93075 -351.785616)
			(xy 160.915391 -351.733313) (xy 160.907633 -351.679356) (xy 160.443367 -351.679356) (xy 160.442409 -351.685864)
			(xy 160.426341 -351.739271) (xy 160.402669 -351.789768) (xy 160.371896 -351.836281) (xy 160.334679 -351.877818)
			(xy 160.291811 -351.913493) (xy 160.244205 -351.942547) (xy 160.192876 -351.964359) (xy 160.138919 -351.978465)
			(xy 160.083482 -351.984565) (xy 160.027748 -351.982528) (xy 159.972905 -351.972398) (xy 159.920121 -351.954391)
			(xy 159.870521 -351.92889) (xy 159.825163 -351.896439) (xy 159.785014 -351.85773) (xy 159.750928 -351.813587)
			(xy 159.723632 -351.764952) (xy 159.703709 -351.712861) (xy 159.691583 -351.658424) (xy 159.687512 -351.602802)
			(xy 159.12092 -351.602802) (xy 159.101896 -351.631557) (xy 159.064679 -351.673094) (xy 159.021811 -351.708769)
			(xy 158.974205 -351.737823) (xy 158.922876 -351.759635) (xy 158.868919 -351.773741) (xy 158.813482 -351.779841)
			(xy 158.757748 -351.777804) (xy 158.702905 -351.767674) (xy 158.650121 -351.749667) (xy 158.600521 -351.724166)
			(xy 158.555163 -351.691715) (xy 158.515014 -351.653006) (xy 158.480928 -351.608863) (xy 158.453632 -351.560228)
			(xy 158.433709 -351.508137) (xy 158.421583 -351.4537) (xy 158.417512 -351.398078) (xy 155.495752 -351.398078)
			(xy 155.495752 -352.102928) (xy 156.238192 -352.102928) (xy 156.242263 -352.047306) (xy 156.254389 -351.992869)
			(xy 156.274312 -351.940778) (xy 156.301608 -351.892143) (xy 156.335694 -351.848) (xy 156.375843 -351.809291)
			(xy 156.421201 -351.77684) (xy 156.470801 -351.751339) (xy 156.523585 -351.733332) (xy 156.578428 -351.723202)
			(xy 156.634162 -351.721165) (xy 156.689599 -351.727265) (xy 156.743556 -351.741371) (xy 156.794885 -351.763183)
			(xy 156.842491 -351.792237) (xy 156.885359 -351.827912) (xy 156.922576 -351.869449) (xy 156.953349 -351.915962)
			(xy 156.977021 -351.966459) (xy 156.993089 -352.019866) (xy 157.001209 -352.075042) (xy 157.001718 -352.102928)
			(xy 157.001209 -352.130814) (xy 156.993089 -352.18599) (xy 156.977021 -352.239397) (xy 156.953349 -352.289894)
			(xy 156.922576 -352.336407) (xy 156.885359 -352.377944) (xy 156.842491 -352.413619) (xy 156.794885 -352.442673)
			(xy 156.743556 -352.464485) (xy 156.689599 -352.478591) (xy 156.634162 -352.484691) (xy 156.578428 -352.482654)
			(xy 156.523585 -352.472524) (xy 156.470801 -352.454517) (xy 156.421201 -352.429016) (xy 156.375843 -352.396565)
			(xy 156.335694 -352.357856) (xy 156.301608 -352.313713) (xy 156.274312 -352.265078) (xy 156.254389 -352.212987)
			(xy 156.242263 -352.15855) (xy 156.238192 -352.102928) (xy 155.495752 -352.102928) (xy 155.495752 -352.818446)
			(xy 155.496185 -352.828511) (xy 155.503917 -352.847099) (xy 155.510738 -352.854514) (xy 155.606518 -352.950272)
			(xy 178.85537 -352.950272) (xy 178.855851 -352.922361) (xy 178.863989 -352.867135) (xy 178.880088 -352.813684)
			(xy 178.903803 -352.763149) (xy 178.934629 -352.71661) (xy 178.952906 -352.69551) (xy 178.958799 -352.68833)
			(xy 178.965452 -352.671007) (xy 178.96586 -352.661728) (xy 178.96586 -352.584004) (xy 178.959256 -352.566732)
			(xy 178.952906 -352.55962) (xy 178.934617 -352.538529) (xy 178.903791 -352.491989) (xy 178.880078 -352.441452)
			(xy 178.863984 -352.387998) (xy 178.855853 -352.33277) (xy 178.85537 -352.304858) (xy 178.855856 -352.277607)
			(xy 178.863612 -352.223659) (xy 178.878967 -352.171364) (xy 178.901609 -352.121787) (xy 178.931075 -352.075937)
			(xy 178.966766 -352.034746) (xy 179.007957 -351.999055) (xy 179.053807 -351.969589) (xy 179.103384 -351.946947)
			(xy 179.155679 -351.931592) (xy 179.209627 -351.923836) (xy 179.264129 -351.923836) (xy 179.318077 -351.931592)
			(xy 179.370372 -351.946947) (xy 179.419949 -351.969589) (xy 179.465799 -351.999055) (xy 179.50699 -352.034746)
			(xy 179.542681 -352.075937) (xy 179.572147 -352.121787) (xy 179.594789 -352.171364) (xy 179.610144 -352.223659)
			(xy 179.6179 -352.277607) (xy 179.618386 -352.304858) (xy 179.617909 -352.332769) (xy 179.609768 -352.387995)
			(xy 179.593667 -352.441445) (xy 179.569952 -352.491979) (xy 179.539127 -352.538519) (xy 179.52085 -352.55962)
			(xy 179.514939 -352.566787) (xy 179.508298 -352.58412) (xy 179.507896 -352.593402) (xy 179.507896 -352.671126)
			(xy 179.5145 -352.688398) (xy 179.52085 -352.69551) (xy 179.539115 -352.71662) (xy 179.569943 -352.763156)
			(xy 179.593659 -352.813688) (xy 179.609759 -352.867137) (xy 179.617898 -352.922362) (xy 179.618386 -352.950272)
			(xy 179.6179 -352.977523) (xy 179.610144 -353.031471) (xy 179.594789 -353.083766) (xy 179.572147 -353.133343)
			(xy 179.542681 -353.179193) (xy 179.50699 -353.220384) (xy 179.465799 -353.256075) (xy 179.419949 -353.285541)
			(xy 179.370372 -353.308183) (xy 179.318077 -353.323538) (xy 179.264129 -353.331294) (xy 179.209627 -353.331294)
			(xy 179.155679 -353.323538) (xy 179.103384 -353.308183) (xy 179.053807 -353.285541) (xy 179.007957 -353.256075)
			(xy 178.966766 -353.220384) (xy 178.931075 -353.179193) (xy 178.901609 -353.133343) (xy 178.878967 -353.083766)
			(xy 178.863612 -353.031471) (xy 178.855856 -352.977523) (xy 178.85537 -352.950272) (xy 155.606518 -352.950272)
			(xy 156.626052 -353.969574) (xy 156.633452 -353.976415) (xy 156.652051 -353.984134) (xy 156.66212 -353.98456)
			(xy 157.594554 -353.98456) (xy 157.604366 -353.984065) (xy 157.622531 -353.976624) (xy 157.62986 -353.970082)
			(xy 157.687772 -353.913694) (xy 157.6959 -353.895152) (xy 157.6959 -353.8855) (xy 157.697057 -353.857384)
			(xy 157.706615 -353.801932) (xy 157.724212 -353.748484) (xy 157.749467 -353.6982) (xy 157.781832 -353.652169)
			(xy 157.820606 -353.61139) (xy 157.864948 -353.576748) (xy 157.913896 -353.548992) (xy 157.96639 -353.528725)
			(xy 158.021291 -353.516386) (xy 158.077408 -353.512243) (xy 158.133525 -353.516386) (xy 158.188426 -353.528725)
			(xy 158.24092 -353.548992) (xy 158.289868 -353.576748) (xy 158.33421 -353.61139) (xy 158.372984 -353.652169)
			(xy 158.405349 -353.6982) (xy 158.430604 -353.748484) (xy 158.448201 -353.801932) (xy 158.457759 -353.857384)
			(xy 158.458916 -353.8855) (xy 158.458916 -353.895152) (xy 158.467044 -353.913694) (xy 158.524956 -353.970082)
			(xy 158.532285 -353.976625) (xy 158.550449 -353.984068) (xy 158.560262 -353.98456) (xy 159.702246 -353.98456)
			(xy 159.714728 -353.983988) (xy 159.736831 -353.972397) (xy 159.74441 -353.962462) (xy 159.798766 -353.882706)
			(xy 159.80156 -353.858322) (xy 159.796988 -353.846384) (xy 159.788882 -353.82439) (xy 159.777475 -353.778925)
			(xy 159.771706 -353.732407) (xy 159.771334 -353.70897) (xy 159.771334 -353.708716) (xy 159.77182 -353.681465)
			(xy 159.779576 -353.627517) (xy 159.794931 -353.575222) (xy 159.817573 -353.525645) (xy 159.847039 -353.479795)
			(xy 159.88273 -353.438604) (xy 159.923921 -353.402913) (xy 159.969771 -353.373447) (xy 160.019348 -353.350805)
			(xy 160.071643 -353.33545) (xy 160.125591 -353.327694) (xy 160.180093 -353.327694) (xy 160.215581 -353.332796)
			(xy 165.19474 -353.332796) (xy 165.198811 -353.277174) (xy 165.210937 -353.222737) (xy 165.23086 -353.170646)
			(xy 165.258156 -353.122011) (xy 165.292242 -353.077868) (xy 165.332391 -353.039159) (xy 165.377749 -353.006708)
			(xy 165.427349 -352.981207) (xy 165.480133 -352.9632) (xy 165.534976 -352.95307) (xy 165.59071 -352.951033)
			(xy 165.646147 -352.957133) (xy 165.700104 -352.971239) (xy 165.751433 -352.993051) (xy 165.799039 -353.022105)
			(xy 165.841907 -353.05778) (xy 165.879124 -353.099317) (xy 165.909897 -353.14583) (xy 165.933569 -353.196327)
			(xy 165.949637 -353.249734) (xy 165.957757 -353.30491) (xy 165.958266 -353.332796) (xy 165.957757 -353.360682)
			(xy 165.949637 -353.415858) (xy 165.933569 -353.469265) (xy 165.909897 -353.519762) (xy 165.894451 -353.543108)
			(xy 183.038496 -353.543108) (xy 183.038496 -351.813368) (xy 183.038989 -351.789365) (xy 183.046526 -351.741953)
			(xy 183.061394 -351.696305) (xy 183.083225 -351.653549) (xy 183.111482 -351.614739) (xy 183.128158 -351.597468)
			(xy 183.375808 -351.349818) (xy 183.393103 -351.333168) (xy 183.431911 -351.304916) (xy 183.474662 -351.283082)
			(xy 183.520302 -351.268205) (xy 183.567707 -351.26065) (xy 183.591708 -351.260156) (xy 185.070496 -351.260156)
			(xy 185.094502 -351.260591) (xy 185.141917 -351.26814) (xy 185.187566 -351.28302) (xy 185.230321 -351.304865)
			(xy 185.269128 -351.333135) (xy 185.286396 -351.349818) (xy 186.91225 -352.975672) (xy 187.181998 -352.975672)
			(xy 187.182472 -352.94776) (xy 187.190611 -352.892534) (xy 187.20671 -352.839083) (xy 187.230427 -352.788548)
			(xy 187.261255 -352.742009) (xy 187.279534 -352.72091) (xy 187.285431 -352.713733) (xy 187.292081 -352.696407)
			(xy 187.292488 -352.687128) (xy 187.292488 -352.609404) (xy 187.285884 -352.592132) (xy 187.279534 -352.58502)
			(xy 187.261234 -352.563939) (xy 187.230412 -352.517395) (xy 187.206702 -352.466855) (xy 187.19061 -352.4134)
			(xy 187.182481 -352.35817) (xy 187.181998 -352.330258) (xy 187.182484 -352.303007) (xy 187.19024 -352.249059)
			(xy 187.205595 -352.196764) (xy 187.228237 -352.147187) (xy 187.257703 -352.101337) (xy 187.293394 -352.060146)
			(xy 187.334585 -352.024455) (xy 187.380435 -351.994989) (xy 187.430012 -351.972347) (xy 187.482307 -351.956992)
			(xy 187.536255 -351.949236) (xy 187.590757 -351.949236) (xy 187.644705 -351.956992) (xy 187.697 -351.972347)
			(xy 187.746577 -351.994989) (xy 187.792427 -352.024455) (xy 187.833618 -352.060146) (xy 187.869309 -352.101337)
			(xy 187.898775 -352.147187) (xy 187.921417 -352.196764) (xy 187.936772 -352.249059) (xy 187.944528 -352.303007)
			(xy 187.945014 -352.330258) (xy 187.944555 -352.35817) (xy 187.936412 -352.413397) (xy 187.920309 -352.466848)
			(xy 187.896589 -352.517383) (xy 187.865758 -352.563921) (xy 187.847478 -352.58502) (xy 187.84157 -352.592189)
			(xy 187.834926 -352.609521) (xy 187.834524 -352.618802) (xy 187.834524 -352.696526) (xy 187.841128 -352.713798)
			(xy 187.847478 -352.72091) (xy 187.865731 -352.74203) (xy 187.896563 -352.788562) (xy 187.920284 -352.839092)
			(xy 187.936386 -352.892539) (xy 187.944526 -352.947762) (xy 187.945014 -352.975672) (xy 187.944528 -353.002923)
			(xy 187.936772 -353.056871) (xy 187.921417 -353.109166) (xy 187.898775 -353.158743) (xy 187.869309 -353.204593)
			(xy 187.833618 -353.245784) (xy 187.792427 -353.281475) (xy 187.746577 -353.310941) (xy 187.697 -353.333583)
			(xy 187.644705 -353.348938) (xy 187.590757 -353.356694) (xy 187.536255 -353.356694) (xy 187.482307 -353.348938)
			(xy 187.430012 -353.333583) (xy 187.380435 -353.310941) (xy 187.334585 -353.281475) (xy 187.293394 -353.245784)
			(xy 187.257703 -353.204593) (xy 187.228237 -353.158743) (xy 187.205595 -353.109166) (xy 187.19024 -353.056871)
			(xy 187.182484 -353.002923) (xy 187.181998 -352.975672) (xy 186.91225 -352.975672) (xy 187.002166 -353.065588)
			(xy 187.018822 -353.082878) (xy 187.047079 -353.121686) (xy 187.068918 -353.164437) (xy 187.083799 -353.210078)
			(xy 187.091357 -353.257486) (xy 187.091828 -353.281488) (xy 187.091828 -354.207318) (xy 188.13983 -354.207318)
			(xy 188.143901 -354.151696) (xy 188.156027 -354.097259) (xy 188.17595 -354.045168) (xy 188.203246 -353.996533)
			(xy 188.237332 -353.95239) (xy 188.277481 -353.913681) (xy 188.322839 -353.88123) (xy 188.372439 -353.855729)
			(xy 188.425223 -353.837722) (xy 188.480066 -353.827592) (xy 188.5358 -353.825555) (xy 188.591237 -353.831655)
			(xy 188.645194 -353.845761) (xy 188.696523 -353.867573) (xy 188.744129 -353.896627) (xy 188.786997 -353.932302)
			(xy 188.824214 -353.973839) (xy 188.854987 -354.020352) (xy 188.878659 -354.070849) (xy 188.894727 -354.124256)
			(xy 188.902847 -354.179432) (xy 188.903356 -354.207318) (xy 188.902847 -354.235204) (xy 188.894727 -354.29038)
			(xy 188.878659 -354.343787) (xy 188.854987 -354.394284) (xy 188.824214 -354.440797) (xy 188.786997 -354.482334)
			(xy 188.744129 -354.518009) (xy 188.696523 -354.547063) (xy 188.645194 -354.568875) (xy 188.591237 -354.582981)
			(xy 188.5358 -354.589081) (xy 188.480066 -354.587044) (xy 188.425223 -354.576914) (xy 188.372439 -354.558907)
			(xy 188.322839 -354.533406) (xy 188.277481 -354.500955) (xy 188.237332 -354.462246) (xy 188.203246 -354.418103)
			(xy 188.17595 -354.369468) (xy 188.156027 -354.317377) (xy 188.143901 -354.26294) (xy 188.13983 -354.207318)
			(xy 187.091828 -354.207318) (xy 187.091828 -355.102668) (xy 187.56071 -355.102668) (xy 187.564781 -355.047046)
			(xy 187.576907 -354.992609) (xy 187.59683 -354.940518) (xy 187.624126 -354.891883) (xy 187.658212 -354.84774)
			(xy 187.698361 -354.809031) (xy 187.743719 -354.77658) (xy 187.793319 -354.751079) (xy 187.846103 -354.733072)
			(xy 187.900946 -354.722942) (xy 187.95668 -354.720905) (xy 188.012117 -354.727005) (xy 188.066074 -354.741111)
			(xy 188.117403 -354.762923) (xy 188.165009 -354.791977) (xy 188.207877 -354.827652) (xy 188.245094 -354.869189)
			(xy 188.275867 -354.915702) (xy 188.299539 -354.966199) (xy 188.315607 -355.019606) (xy 188.323727 -355.074782)
			(xy 188.324236 -355.102668) (xy 188.323727 -355.130554) (xy 188.315607 -355.18573) (xy 188.299539 -355.239137)
			(xy 188.275867 -355.289634) (xy 188.245094 -355.336147) (xy 188.207877 -355.377684) (xy 188.165009 -355.413359)
			(xy 188.117403 -355.442413) (xy 188.066074 -355.464225) (xy 188.012117 -355.478331) (xy 187.95668 -355.484431)
			(xy 187.900946 -355.482394) (xy 187.846103 -355.472264) (xy 187.793319 -355.454257) (xy 187.743719 -355.428756)
			(xy 187.698361 -355.396305) (xy 187.658212 -355.357596) (xy 187.624126 -355.313453) (xy 187.59683 -355.264818)
			(xy 187.576907 -355.212727) (xy 187.564781 -355.15829) (xy 187.56071 -355.102668) (xy 187.091828 -355.102668)
			(xy 187.091828 -355.778308) (xy 188.899546 -355.778308) (xy 188.900026 -355.750833) (xy 188.907918 -355.696453)
			(xy 188.923539 -355.64377) (xy 188.946565 -355.593877) (xy 188.976519 -355.547809) (xy 188.994288 -355.526848)
			(xy 188.994542 -355.526594) (xy 189.000142 -355.519517) (xy 189.00638 -355.502593) (xy 189.006734 -355.493574)
			(xy 189.006734 -355.42601) (xy 189.006365 -355.416995) (xy 189.000125 -355.400078) (xy 188.994542 -355.39299)
			(xy 188.994034 -355.392482) (xy 188.976301 -355.371535) (xy 188.946418 -355.325503) (xy 188.923451 -355.275658)
			(xy 188.907876 -355.223033) (xy 188.900016 -355.168717) (xy 188.899546 -355.141276) (xy 188.900032 -355.114025)
			(xy 188.907788 -355.060077) (xy 188.923143 -355.007782) (xy 188.945785 -354.958205) (xy 188.975251 -354.912355)
			(xy 189.010942 -354.871164) (xy 189.052133 -354.835473) (xy 189.097983 -354.806007) (xy 189.14756 -354.783365)
			(xy 189.199855 -354.76801) (xy 189.253803 -354.760254) (xy 189.308305 -354.760254) (xy 189.362253 -354.76801)
			(xy 189.414548 -354.783365) (xy 189.464125 -354.806007) (xy 189.509975 -354.835473) (xy 189.551166 -354.871164)
			(xy 189.586857 -354.912355) (xy 189.616323 -354.958205) (xy 189.638965 -355.007782) (xy 189.65432 -355.060077)
			(xy 189.662076 -355.114025) (xy 189.662562 -355.141276) (xy 189.662071 -355.168751) (xy 189.654182 -355.22313)
			(xy 189.638563 -355.275813) (xy 189.635916 -355.281549) (xy 189.904384 -355.281549) (xy 189.904384 -355.227051)
			(xy 189.912139 -355.173106) (xy 189.927493 -355.120815) (xy 189.950131 -355.07124) (xy 189.979594 -355.025392)
			(xy 190.015282 -354.984203) (xy 190.056468 -354.948512) (xy 190.102314 -354.919046) (xy 190.151887 -354.896403)
			(xy 190.204177 -354.881046) (xy 190.258121 -354.873286) (xy 190.28537 -354.872798) (xy 190.285624 -354.872798)
			(xy 190.310828 -354.873179) (xy 190.360797 -354.879823) (xy 190.409452 -354.893005) (xy 190.455941 -354.912493)
			(xy 190.477902 -354.924868) (xy 190.487808 -354.93071) (xy 190.509652 -354.932742) (xy 190.604394 -354.899214)
			(xy 190.620142 -354.88372) (xy 190.624206 -354.873306) (xy 190.634884 -354.846522) (xy 190.663173 -354.796278)
			(xy 190.698704 -354.750867) (xy 190.740669 -354.711325) (xy 190.788109 -354.678551) (xy 190.839943 -354.653295)
			(xy 190.894989 -354.636132) (xy 190.951992 -354.627453) (xy 190.980822 -354.626926) (xy 191.008077 -354.627335)
			(xy 191.062032 -354.635095) (xy 191.114333 -354.650456) (xy 191.163915 -354.673103) (xy 191.20977 -354.702577)
			(xy 191.250963 -354.738276) (xy 191.286657 -354.779475) (xy 191.316123 -354.825334) (xy 191.338764 -354.87492)
			(xy 191.354117 -354.927223) (xy 191.361869 -354.981179) (xy 191.36233 -355.008434) (xy 191.361665 -355.039996)
			(xy 191.351279 -355.102261) (xy 191.330796 -355.161971) (xy 191.316356 -355.190044) (xy 191.31153 -355.198934)
			(xy 191.309498 -355.218492) (xy 191.332358 -355.296978) (xy 191.335594 -355.306404) (xy 191.348012 -355.321963)
			(xy 191.356488 -355.327204) (xy 191.381573 -355.34178) (xy 191.427455 -355.377278) (xy 191.467431 -355.419317)
			(xy 191.500578 -355.466927) (xy 191.526132 -355.519007) (xy 191.543502 -355.574357) (xy 191.552288 -355.6317)
			(xy 191.55283 -355.660706) (xy 191.552344 -355.687957) (xy 191.544588 -355.741905) (xy 191.529233 -355.7942)
			(xy 191.506591 -355.843777) (xy 191.477125 -355.889627) (xy 191.441434 -355.930818) (xy 191.400243 -355.966509)
			(xy 191.354393 -355.995975) (xy 191.304816 -356.018617) (xy 191.252521 -356.033972) (xy 191.198573 -356.041728)
			(xy 191.144071 -356.041728) (xy 191.090123 -356.033972) (xy 191.037828 -356.018617) (xy 190.988251 -355.995975)
			(xy 190.942401 -355.966509) (xy 190.90121 -355.930818) (xy 190.865519 -355.889627) (xy 190.836053 -355.843777)
			(xy 190.813411 -355.7942) (xy 190.798056 -355.741905) (xy 190.7903 -355.687957) (xy 190.789814 -355.660706)
			(xy 190.79045 -355.629142) (xy 190.800847 -355.566876) (xy 190.821342 -355.507168) (xy 190.835788 -355.479096)
			(xy 190.840614 -355.470206) (xy 190.842646 -355.450648) (xy 190.819786 -355.372162) (xy 190.816558 -355.362734)
			(xy 190.804133 -355.347177) (xy 190.795656 -355.341936) (xy 190.78829 -355.337872) (xy 190.778384 -355.33203)
			(xy 190.75654 -355.329998) (xy 190.661798 -355.363526) (xy 190.64605 -355.37902) (xy 190.641986 -355.389434)
			(xy 190.631336 -355.41623) (xy 190.603042 -355.466472) (xy 190.567505 -355.511882) (xy 190.525536 -355.551423)
			(xy 190.478092 -355.584194) (xy 190.426255 -355.609449) (xy 190.371206 -355.62661) (xy 190.314201 -355.635287)
			(xy 190.28537 -355.635814) (xy 190.258121 -355.635314) (xy 190.204177 -355.627554) (xy 190.151887 -355.612197)
			(xy 190.102314 -355.589554) (xy 190.056468 -355.560088) (xy 190.015282 -355.524397) (xy 189.979594 -355.483208)
			(xy 189.950131 -355.43736) (xy 189.927493 -355.387785) (xy 189.912139 -355.335494) (xy 189.904384 -355.281549)
			(xy 189.635916 -355.281549) (xy 189.615539 -355.325706) (xy 189.585588 -355.371774) (xy 189.56782 -355.392736)
			(xy 189.567566 -355.39299) (xy 189.561974 -355.400072) (xy 189.555732 -355.416993) (xy 189.555374 -355.42601)
			(xy 189.555374 -355.493574) (xy 189.555749 -355.502589) (xy 189.561985 -355.519506) (xy 189.567566 -355.526594)
			(xy 189.568074 -355.527102) (xy 189.5858 -355.548054) (xy 189.615685 -355.594085) (xy 189.638653 -355.643928)
			(xy 189.654229 -355.696553) (xy 189.662091 -355.750867) (xy 189.662562 -355.778308) (xy 189.662076 -355.805559)
			(xy 189.65432 -355.859507) (xy 189.638965 -355.911802) (xy 189.616323 -355.961379) (xy 189.586857 -356.007229)
			(xy 189.551166 -356.04842) (xy 189.509975 -356.084111) (xy 189.464125 -356.113577) (xy 189.414548 -356.136219)
			(xy 189.362253 -356.151574) (xy 189.308305 -356.15933) (xy 189.253803 -356.15933) (xy 189.199855 -356.151574)
			(xy 189.14756 -356.136219) (xy 189.097983 -356.113577) (xy 189.052133 -356.084111) (xy 189.010942 -356.04842)
			(xy 188.975251 -356.007229) (xy 188.945785 -355.961379) (xy 188.923143 -355.911802) (xy 188.907788 -355.859507)
			(xy 188.900032 -355.805559) (xy 188.899546 -355.778308) (xy 187.091828 -355.778308) (xy 187.091828 -356.289102)
			(xy 187.092245 -356.299172) (xy 187.099971 -356.31777) (xy 187.106814 -356.32517) (xy 188.025024 -357.243634)
			(xy 188.032418 -357.250482) (xy 188.051022 -357.258196) (xy 188.061092 -357.25862) (xy 191.623188 -357.25862)
			(xy 191.633259 -357.25821) (xy 191.651858 -357.250481) (xy 191.659256 -357.243634) (xy 192.226946 -356.67569)
			(xy 192.233789 -356.668293) (xy 192.241506 -356.649691) (xy 192.241932 -356.639622) (xy 192.241932 -354.582984)
			(xy 192.241533 -354.572911) (xy 192.233796 -354.554313) (xy 192.226946 -354.546916) (xy 191.60617 -353.92614)
			(xy 191.596518 -353.92614) (xy 191.454786 -353.784408) (xy 191.438138 -353.767112) (xy 191.409886 -353.728303)
			(xy 191.388053 -353.685553) (xy 191.373175 -353.639914) (xy 191.365619 -353.592509) (xy 191.365124 -353.568508)
			(xy 191.365124 -351.59823) (xy 191.365585 -351.574225) (xy 191.373129 -351.526811) (xy 191.388003 -351.481164)
			(xy 191.409842 -351.438408) (xy 191.438106 -351.399599) (xy 191.454786 -351.38233) (xy 191.461898 -351.375218)
			(xy 191.479197 -351.358573) (xy 191.518004 -351.33032) (xy 191.560754 -351.308485) (xy 191.606393 -351.293607)
			(xy 191.653797 -351.286051) (xy 191.677798 -351.285556) (xy 196.719444 -351.285556) (xy 196.743449 -351.286024)
			(xy 196.790863 -351.293564) (xy 196.836511 -351.308437) (xy 196.879267 -351.330274) (xy 196.918075 -351.358538)
			(xy 196.935344 -351.375218) (xy 197.413118 -351.852992) (xy 197.429767 -351.870287) (xy 197.458018 -351.909096)
			(xy 197.479851 -351.951847) (xy 197.494729 -351.997486) (xy 197.502285 -352.044891) (xy 197.50278 -352.068892)
			(xy 197.50278 -358.14) (xy 197.502337 -358.164006) (xy 197.494789 -358.21142) (xy 197.47991 -358.257068)
			(xy 197.458067 -358.299823) (xy 197.4298 -358.338631) (xy 197.413118 -358.3559) (xy 192.249552 -363.519466)
			(xy 192.232289 -363.536151) (xy 192.193473 -363.564404) (xy 192.150715 -363.586237) (xy 192.105068 -363.601112)
			(xy 192.057656 -363.608662) (xy 192.033652 -363.609128) (xy 184.831228 -363.609128) (xy 184.807224 -363.608653)
			(xy 184.759811 -363.601111) (xy 184.714164 -363.586238) (xy 184.671409 -363.564403) (xy 184.632598 -363.536144)
			(xy 184.615328 -363.519466) (xy 184.23509 -363.139228) (xy 184.218452 -363.121923) (xy 184.190199 -363.083116)
			(xy 184.168364 -363.040368) (xy 184.153483 -362.994731) (xy 184.145924 -362.947328) (xy 184.145428 -362.923328)
			(xy 184.145428 -354.79736) (xy 184.145043 -354.787286) (xy 184.137296 -354.768687) (xy 184.130442 -354.761292)
			(xy 183.128158 -353.759008) (xy 183.111504 -353.741716) (xy 183.083246 -353.702909) (xy 183.061407 -353.660158)
			(xy 183.046525 -353.614517) (xy 183.038966 -353.56711) (xy 183.038496 -353.543108) (xy 165.894451 -353.543108)
			(xy 165.879124 -353.566275) (xy 165.841907 -353.607812) (xy 165.799039 -353.643487) (xy 165.751433 -353.672541)
			(xy 165.700104 -353.694353) (xy 165.646147 -353.708459) (xy 165.59071 -353.714559) (xy 165.534976 -353.712522)
			(xy 165.480133 -353.702392) (xy 165.427349 -353.684385) (xy 165.377749 -353.658884) (xy 165.332391 -353.626433)
			(xy 165.292242 -353.587724) (xy 165.258156 -353.543581) (xy 165.23086 -353.494946) (xy 165.210937 -353.442855)
			(xy 165.198811 -353.388418) (xy 165.19474 -353.332796) (xy 160.215581 -353.332796) (xy 160.234041 -353.33545)
			(xy 160.286336 -353.350805) (xy 160.335913 -353.373447) (xy 160.381763 -353.402913) (xy 160.422954 -353.438604)
			(xy 160.458645 -353.479795) (xy 160.488111 -353.525645) (xy 160.510753 -353.575222) (xy 160.526108 -353.627517)
			(xy 160.533864 -353.681465) (xy 160.53435 -353.708716) (xy 160.53435 -353.70897) (xy 160.534012 -353.73241)
			(xy 160.528265 -353.778936) (xy 160.516842 -353.824402) (xy 160.508696 -353.846384) (xy 160.504124 -353.858322)
			(xy 160.506918 -353.882706) (xy 160.561274 -353.962462) (xy 160.568852 -353.972394) (xy 160.590958 -353.983971)
			(xy 160.603438 -353.98456) (xy 161.023808 -353.98456) (xy 161.033414 -353.98414) (xy 161.051285 -353.97708)
			(xy 161.058606 -353.970844) (xy 161.109152 -353.923854) (xy 161.115835 -353.917108) (xy 161.124074 -353.900013)
			(xy 161.125154 -353.89058) (xy 161.125154 -353.890326) (xy 161.127558 -353.863177) (xy 161.139139 -353.809919)
			(xy 161.158181 -353.758852) (xy 161.184298 -353.711014) (xy 161.216958 -353.667381) (xy 161.255495 -353.62884)
			(xy 161.299125 -353.596176) (xy 161.34696 -353.570055) (xy 161.398026 -353.551007) (xy 161.451282 -353.539421)
			(xy 161.505646 -353.535533) (xy 161.56001 -353.539421) (xy 161.613266 -353.551007) (xy 161.664332 -353.570055)
			(xy 161.712167 -353.596176) (xy 161.755797 -353.62884) (xy 161.794334 -353.667381) (xy 161.826994 -353.711014)
			(xy 161.853111 -353.758852) (xy 161.872153 -353.809919) (xy 161.883734 -353.863177) (xy 161.886138 -353.890326)
			(xy 161.886138 -353.89058) (xy 161.887238 -353.90001) (xy 161.89546 -353.917108) (xy 161.90214 -353.923854)
			(xy 161.952686 -353.970844) (xy 161.959975 -353.977132) (xy 161.977866 -353.984194) (xy 161.987484 -353.98456)
			(xy 165.553644 -353.98456) (xy 165.637107 -353.985064) (xy 165.803852 -353.992862) (xy 165.970053 -354.008402)
			(xy 166.135353 -354.031651) (xy 166.299393 -354.062557) (xy 166.46182 -354.101055) (xy 166.622281 -354.147061)
			(xy 166.725485 -354.181918) (xy 179.813202 -354.181918) (xy 179.817273 -354.126296) (xy 179.829399 -354.071859)
			(xy 179.849322 -354.019768) (xy 179.876618 -353.971133) (xy 179.910704 -353.92699) (xy 179.950853 -353.888281)
			(xy 179.996211 -353.85583) (xy 180.045811 -353.830329) (xy 180.098595 -353.812322) (xy 180.153438 -353.802192)
			(xy 180.209172 -353.800155) (xy 180.264609 -353.806255) (xy 180.318566 -353.820361) (xy 180.369895 -353.842173)
			(xy 180.417501 -353.871227) (xy 180.460369 -353.906902) (xy 180.497586 -353.948439) (xy 180.528359 -353.994952)
			(xy 180.552031 -354.045449) (xy 180.568099 -354.098856) (xy 180.576219 -354.154032) (xy 180.576728 -354.181918)
			(xy 180.576219 -354.209804) (xy 180.568099 -354.26498) (xy 180.552031 -354.318387) (xy 180.528359 -354.368884)
			(xy 180.497586 -354.415397) (xy 180.460369 -354.456934) (xy 180.417501 -354.492609) (xy 180.369895 -354.521663)
			(xy 180.318566 -354.543475) (xy 180.264609 -354.557581) (xy 180.209172 -354.563681) (xy 180.153438 -354.561644)
			(xy 180.098595 -354.551514) (xy 180.045811 -354.533507) (xy 179.996211 -354.508006) (xy 179.950853 -354.475555)
			(xy 179.910704 -354.436846) (xy 179.876618 -354.392703) (xy 179.849322 -354.344068) (xy 179.829399 -354.291977)
			(xy 179.817273 -354.23754) (xy 179.813202 -354.181918) (xy 166.725485 -354.181918) (xy 166.780431 -354.200476)
			(xy 166.935927 -354.261184) (xy 167.088434 -354.329054) (xy 167.163242 -354.366068) (xy 167.16375 -354.366068)
			(xy 167.16375 -354.366322) (xy 167.169029 -354.368699) (xy 167.180315 -354.371267) (xy 167.186102 -354.371402)
			(xy 168.95572 -354.371402) (xy 168.965789 -354.371829) (xy 168.984387 -354.379549) (xy 168.991788 -354.386388)
			(xy 169.573702 -354.968302) (xy 176.841656 -354.968302) (xy 176.845727 -354.91268) (xy 176.857853 -354.858243)
			(xy 176.877776 -354.806152) (xy 176.905072 -354.757517) (xy 176.939158 -354.713374) (xy 176.979307 -354.674665)
			(xy 177.024665 -354.642214) (xy 177.074265 -354.616713) (xy 177.127049 -354.598706) (xy 177.181892 -354.588576)
			(xy 177.237626 -354.586539) (xy 177.293063 -354.592639) (xy 177.34702 -354.606745) (xy 177.398349 -354.628557)
			(xy 177.445955 -354.657611) (xy 177.488823 -354.693286) (xy 177.52604 -354.734823) (xy 177.556813 -354.781336)
			(xy 177.580485 -354.831833) (xy 177.596553 -354.88524) (xy 177.604673 -354.940416) (xy 177.605182 -354.968302)
			(xy 177.604834 -354.987352) (xy 179.031136 -354.987352) (xy 179.035207 -354.93173) (xy 179.047333 -354.877293)
			(xy 179.067256 -354.825202) (xy 179.094552 -354.776567) (xy 179.128638 -354.732424) (xy 179.168787 -354.693715)
			(xy 179.214145 -354.661264) (xy 179.263745 -354.635763) (xy 179.316529 -354.617756) (xy 179.371372 -354.607626)
			(xy 179.427106 -354.605589) (xy 179.482543 -354.611689) (xy 179.5365 -354.625795) (xy 179.587829 -354.647607)
			(xy 179.635435 -354.676661) (xy 179.678303 -354.712336) (xy 179.71552 -354.753873) (xy 179.746293 -354.800386)
			(xy 179.769965 -354.850883) (xy 179.786033 -354.90429) (xy 179.794153 -354.959466) (xy 179.794662 -354.987352)
			(xy 179.794153 -355.015238) (xy 179.786033 -355.070414) (xy 179.769965 -355.123821) (xy 179.746293 -355.174318)
			(xy 179.71552 -355.220831) (xy 179.678303 -355.262368) (xy 179.635435 -355.298043) (xy 179.587829 -355.327097)
			(xy 179.5365 -355.348909) (xy 179.482543 -355.363015) (xy 179.427106 -355.369115) (xy 179.371372 -355.367078)
			(xy 179.316529 -355.356948) (xy 179.263745 -355.338941) (xy 179.214145 -355.31344) (xy 179.168787 -355.280989)
			(xy 179.128638 -355.24228) (xy 179.094552 -355.198137) (xy 179.067256 -355.149502) (xy 179.047333 -355.097411)
			(xy 179.035207 -355.042974) (xy 179.031136 -354.987352) (xy 177.604834 -354.987352) (xy 177.604673 -354.996188)
			(xy 177.596553 -355.051364) (xy 177.580485 -355.104771) (xy 177.556813 -355.155268) (xy 177.52604 -355.201781)
			(xy 177.488823 -355.243318) (xy 177.445955 -355.278993) (xy 177.398349 -355.308047) (xy 177.34702 -355.329859)
			(xy 177.293063 -355.343965) (xy 177.237626 -355.350065) (xy 177.181892 -355.348028) (xy 177.127049 -355.337898)
			(xy 177.074265 -355.319891) (xy 177.024665 -355.29439) (xy 176.979307 -355.261939) (xy 176.939158 -355.22323)
			(xy 176.905072 -355.179087) (xy 176.877776 -355.130452) (xy 176.857853 -355.078361) (xy 176.845727 -355.023924)
			(xy 176.841656 -354.968302) (xy 169.573702 -354.968302) (xy 170.08983 -355.48443) (xy 177.846988 -355.48443)
			(xy 177.851059 -355.428808) (xy 177.863185 -355.374371) (xy 177.883108 -355.32228) (xy 177.910404 -355.273645)
			(xy 177.94449 -355.229502) (xy 177.984639 -355.190793) (xy 178.029997 -355.158342) (xy 178.079597 -355.132841)
			(xy 178.132381 -355.114834) (xy 178.187224 -355.104704) (xy 178.242958 -355.102667) (xy 178.298395 -355.108767)
			(xy 178.352352 -355.122873) (xy 178.403681 -355.144685) (xy 178.451287 -355.173739) (xy 178.494155 -355.209414)
			(xy 178.531372 -355.250951) (xy 178.562145 -355.297464) (xy 178.585817 -355.347961) (xy 178.601885 -355.401368)
			(xy 178.610005 -355.456544) (xy 178.610514 -355.48443) (xy 178.610005 -355.512316) (xy 178.601885 -355.567492)
			(xy 178.585817 -355.620899) (xy 178.562145 -355.671396) (xy 178.531372 -355.717909) (xy 178.500013 -355.752908)
			(xy 180.572918 -355.752908) (xy 180.573405 -355.725433) (xy 180.581296 -355.671054) (xy 180.596916 -355.618371)
			(xy 180.61994 -355.568478) (xy 180.649892 -355.52241) (xy 180.66766 -355.501448) (xy 180.667914 -355.501194)
			(xy 180.673511 -355.494114) (xy 180.679751 -355.477192) (xy 180.680106 -355.468174) (xy 180.680106 -355.40061)
			(xy 180.679743 -355.391594) (xy 180.673499 -355.374677) (xy 180.667914 -355.36759) (xy 180.667406 -355.367082)
			(xy 180.649669 -355.346139) (xy 180.619787 -355.300105) (xy 180.596821 -355.250259) (xy 180.581247 -355.197633)
			(xy 180.573388 -355.143317) (xy 180.572918 -355.115876) (xy 180.573404 -355.088625) (xy 180.58116 -355.034677)
			(xy 180.596515 -354.982382) (xy 180.619157 -354.932805) (xy 180.648623 -354.886955) (xy 180.684314 -354.845764)
			(xy 180.725505 -354.810073) (xy 180.771355 -354.780607) (xy 180.820932 -354.757965) (xy 180.873227 -354.74261)
			(xy 180.927175 -354.734854) (xy 180.981677 -354.734854) (xy 181.035625 -354.74261) (xy 181.08792 -354.757965)
			(xy 181.137497 -354.780607) (xy 181.183347 -354.810073) (xy 181.224538 -354.845764) (xy 181.260229 -354.886955)
			(xy 181.289695 -354.932805) (xy 181.312337 -354.982382) (xy 181.327692 -355.034677) (xy 181.335448 -355.088625)
			(xy 181.335934 -355.115876) (xy 181.335425 -355.14335) (xy 181.327537 -355.197728) (xy 181.311922 -355.25041)
			(xy 181.309272 -355.256154) (xy 181.577661 -355.256154) (xy 181.577661 -355.201646) (xy 181.585419 -355.147692)
			(xy 181.600777 -355.095392) (xy 181.623423 -355.045809) (xy 181.652894 -354.999955) (xy 181.688592 -354.958762)
			(xy 181.729789 -354.923069) (xy 181.775646 -354.893602) (xy 181.825231 -354.870963) (xy 181.877533 -354.85561)
			(xy 181.931488 -354.847858) (xy 181.958742 -354.847398) (xy 181.958996 -354.847398) (xy 181.9842 -354.847791)
			(xy 182.034168 -354.854432) (xy 182.082823 -354.86761) (xy 182.129312 -354.887095) (xy 182.151274 -354.899468)
			(xy 182.16118 -354.90531) (xy 182.183024 -354.907342) (xy 182.277766 -354.873814) (xy 182.293514 -354.85832)
			(xy 182.297578 -354.847906) (xy 182.308279 -354.821132) (xy 182.336565 -354.770889) (xy 182.372094 -354.725479)
			(xy 182.414055 -354.685936) (xy 182.461492 -354.653162) (xy 182.513322 -354.627904) (xy 182.568365 -354.610738)
			(xy 182.625365 -354.602055) (xy 182.654194 -354.601526) (xy 182.681448 -354.601961) (xy 182.735402 -354.609718)
			(xy 182.787702 -354.625075) (xy 182.837285 -354.647719) (xy 182.88314 -354.67719) (xy 182.924333 -354.712887)
			(xy 182.960027 -354.754083) (xy 182.989494 -354.79994) (xy 183.012135 -354.849524) (xy 183.027488 -354.901825)
			(xy 183.035241 -354.95578) (xy 183.035702 -354.983034) (xy 183.03504 -355.014597) (xy 183.024654 -355.076862)
			(xy 183.004169 -355.136571) (xy 182.989728 -355.164644) (xy 182.984902 -355.173534) (xy 182.98287 -355.193092)
			(xy 183.00573 -355.271578) (xy 183.008976 -355.280999) (xy 183.021387 -355.29656) (xy 183.02986 -355.301804)
			(xy 183.054938 -355.31639) (xy 183.100822 -355.351886) (xy 183.140799 -355.393923) (xy 183.173948 -355.44153)
			(xy 183.199503 -355.493609) (xy 183.216874 -355.548959) (xy 183.22566 -355.6063) (xy 183.226202 -355.635306)
			(xy 183.225716 -355.662557) (xy 183.21796 -355.716505) (xy 183.202605 -355.7688) (xy 183.179963 -355.818377)
			(xy 183.150497 -355.864227) (xy 183.114806 -355.905418) (xy 183.073615 -355.941109) (xy 183.027765 -355.970575)
			(xy 182.978188 -355.993217) (xy 182.925893 -356.008572) (xy 182.871945 -356.016328) (xy 182.817443 -356.016328)
			(xy 182.763495 -356.008572) (xy 182.7112 -355.993217) (xy 182.661623 -355.970575) (xy 182.615773 -355.941109)
			(xy 182.574582 -355.905418) (xy 182.538891 -355.864227) (xy 182.509425 -355.818377) (xy 182.486783 -355.7688)
			(xy 182.471428 -355.716505) (xy 182.463672 -355.662557) (xy 182.463186 -355.635306) (xy 182.463826 -355.603742)
			(xy 182.474222 -355.541477) (xy 182.494715 -355.481768) (xy 182.50916 -355.453696) (xy 182.513986 -355.444806)
			(xy 182.516018 -355.425248) (xy 182.493158 -355.346762) (xy 182.48994 -355.337329) (xy 182.477508 -355.321774)
			(xy 182.469028 -355.316536) (xy 182.461662 -355.312472) (xy 182.451756 -355.30663) (xy 182.429912 -355.304598)
			(xy 182.33517 -355.338126) (xy 182.319422 -355.35362) (xy 182.315358 -355.364034) (xy 182.304648 -355.390804)
			(xy 182.276361 -355.441044) (xy 182.240832 -355.486452) (xy 182.198872 -355.525994) (xy 182.151437 -355.558768)
			(xy 182.099608 -355.584027) (xy 182.044568 -355.601196) (xy 181.98757 -355.609882) (xy 181.958742 -355.610414)
			(xy 181.931488 -355.609942) (xy 181.877533 -355.60219) (xy 181.825231 -355.586837) (xy 181.775646 -355.564198)
			(xy 181.729789 -355.534731) (xy 181.688592 -355.499038) (xy 181.652894 -355.457845) (xy 181.623423 -355.411991)
			(xy 181.600777 -355.362408) (xy 181.585419 -355.310108) (xy 181.577661 -355.256154) (xy 181.309272 -355.256154)
			(xy 181.288903 -355.300303) (xy 181.258957 -355.346373) (xy 181.241192 -355.367336) (xy 181.240938 -355.36759)
			(xy 181.235342 -355.37467) (xy 181.229103 -355.391592) (xy 181.228746 -355.40061) (xy 181.228746 -355.468174)
			(xy 181.229106 -355.477191) (xy 181.23535 -355.494108) (xy 181.240938 -355.501194) (xy 181.241446 -355.501702)
			(xy 181.259168 -355.522658) (xy 181.289054 -355.568687) (xy 181.312023 -355.61853) (xy 181.327601 -355.671153)
			(xy 181.335463 -355.725468) (xy 181.335934 -355.752908) (xy 181.335448 -355.780159) (xy 181.327692 -355.834107)
			(xy 181.312337 -355.886402) (xy 181.289695 -355.935979) (xy 181.260229 -355.981829) (xy 181.224538 -356.02302)
			(xy 181.183347 -356.058711) (xy 181.137497 -356.088177) (xy 181.08792 -356.110819) (xy 181.035625 -356.126174)
			(xy 180.981677 -356.13393) (xy 180.927175 -356.13393) (xy 180.873227 -356.126174) (xy 180.820932 -356.110819)
			(xy 180.771355 -356.088177) (xy 180.725505 -356.058711) (xy 180.684314 -356.02302) (xy 180.648623 -355.981829)
			(xy 180.619157 -355.935979) (xy 180.596515 -355.886402) (xy 180.58116 -355.834107) (xy 180.573404 -355.780159)
			(xy 180.572918 -355.752908) (xy 178.500013 -355.752908) (xy 178.494155 -355.759446) (xy 178.451287 -355.795121)
			(xy 178.403681 -355.824175) (xy 178.352352 -355.845987) (xy 178.298395 -355.860093) (xy 178.242958 -355.866193)
			(xy 178.187224 -355.864156) (xy 178.132381 -355.854026) (xy 178.079597 -355.836019) (xy 178.029997 -355.810518)
			(xy 177.984639 -355.778067) (xy 177.94449 -355.739358) (xy 177.910404 -355.695215) (xy 177.883108 -355.64658)
			(xy 177.863185 -355.594489) (xy 177.851059 -355.540052) (xy 177.846988 -355.48443) (xy 170.08983 -355.48443)
			(xy 178.529742 -363.924342) (xy 179.856638 -363.924342) (xy 179.857119 -363.896972) (xy 179.864932 -363.842793)
			(xy 179.880417 -363.79029) (xy 179.903256 -363.740543) (xy 179.932978 -363.694576) (xy 179.950618 -363.673644)
			(xy 179.950872 -363.67339) (xy 179.956477 -363.666317) (xy 179.962711 -363.649389) (xy 179.963064 -363.64037)
			(xy 179.963064 -363.573314) (xy 179.962708 -363.564297) (xy 179.95646 -363.54738) (xy 179.950872 -363.540294)
			(xy 179.950618 -363.540294) (xy 179.950618 -363.54004) (xy 179.932987 -363.519101) (xy 179.903273 -363.473131)
			(xy 179.880436 -363.423385) (xy 179.864943 -363.370886) (xy 179.857113 -363.316711) (xy 179.856638 -363.289342)
			(xy 179.857119 -363.261768) (xy 179.865067 -363.207195) (xy 179.880788 -363.154335) (xy 179.903955 -363.104289)
			(xy 179.934085 -363.058099) (xy 179.970551 -363.016728) (xy 179.991258 -362.998512) (xy 179.999337 -362.990961)
			(xy 180.008687 -362.970946) (xy 180.009292 -362.959904) (xy 180.009292 -362.88218) (xy 180.008682 -362.871136)
			(xy 179.999347 -362.851114) (xy 179.991258 -362.843572) (xy 179.970522 -362.825388) (xy 179.934055 -362.784013)
			(xy 179.903927 -362.737817) (xy 179.880766 -362.687764) (xy 179.865055 -362.634897) (xy 179.857121 -362.580318)
			(xy 179.856638 -362.552742) (xy 179.857119 -362.525372) (xy 179.864932 -362.471193) (xy 179.880417 -362.41869)
			(xy 179.903256 -362.368943) (xy 179.932978 -362.322976) (xy 179.950618 -362.302044) (xy 179.950872 -362.30179)
			(xy 179.956477 -362.294717) (xy 179.962711 -362.277789) (xy 179.963064 -362.26877) (xy 179.963064 -362.201714)
			(xy 179.962708 -362.192697) (xy 179.95646 -362.17578) (xy 179.950872 -362.168694) (xy 179.950618 -362.168694)
			(xy 179.950618 -362.16844) (xy 179.933019 -362.147474) (xy 179.903293 -362.101512) (xy 179.880446 -362.051771)
			(xy 179.864947 -361.999274) (xy 179.857114 -361.9451) (xy 179.85711 -361.890363) (xy 179.864933 -361.836188)
			(xy 179.880423 -361.783689) (xy 179.903263 -361.733944) (xy 179.932981 -361.687977) (xy 179.950618 -361.667044)
			(xy 179.950872 -361.66679) (xy 179.956477 -361.659717) (xy 179.962711 -361.642789) (xy 179.963064 -361.63377)
			(xy 179.963064 -361.566714) (xy 179.962708 -361.557697) (xy 179.95646 -361.54078) (xy 179.950872 -361.533694)
			(xy 179.950618 -361.533694) (xy 179.950618 -361.53344) (xy 179.933019 -361.512474) (xy 179.903293 -361.466512)
			(xy 179.880446 -361.416771) (xy 179.864947 -361.364274) (xy 179.857114 -361.3101) (xy 179.85711 -361.255363)
			(xy 179.864933 -361.201188) (xy 179.880423 -361.148689) (xy 179.903263 -361.098944) (xy 179.932981 -361.052977)
			(xy 179.950618 -361.032044) (xy 179.950872 -361.03179) (xy 179.956477 -361.024717) (xy 179.962711 -361.007789)
			(xy 179.963064 -360.99877) (xy 179.963064 -360.931714) (xy 179.962708 -360.922697) (xy 179.95646 -360.90578)
			(xy 179.950872 -360.898694) (xy 179.950618 -360.898694) (xy 179.950618 -360.89844) (xy 179.932987 -360.877501)
			(xy 179.903273 -360.831531) (xy 179.880436 -360.781785) (xy 179.864943 -360.729286) (xy 179.857113 -360.675111)
			(xy 179.856638 -360.647742) (xy 179.857119 -360.620168) (xy 179.865067 -360.565595) (xy 179.880788 -360.512735)
			(xy 179.903955 -360.462689) (xy 179.934085 -360.416499) (xy 179.970551 -360.375128) (xy 179.991258 -360.356912)
			(xy 179.999337 -360.349361) (xy 180.008687 -360.329346) (xy 180.009292 -360.318304) (xy 180.009292 -360.24058)
			(xy 180.008682 -360.229536) (xy 179.999347 -360.209514) (xy 179.991258 -360.201972) (xy 179.970522 -360.183788)
			(xy 179.934055 -360.142413) (xy 179.903927 -360.096217) (xy 179.880766 -360.046164) (xy 179.865055 -359.993297)
			(xy 179.857121 -359.938718) (xy 179.856638 -359.911142) (xy 179.857119 -359.883772) (xy 179.864932 -359.829593)
			(xy 179.880417 -359.77709) (xy 179.903256 -359.727343) (xy 179.932978 -359.681376) (xy 179.950618 -359.660444)
			(xy 179.950872 -359.66019) (xy 179.956477 -359.653117) (xy 179.962711 -359.636189) (xy 179.963064 -359.62717)
			(xy 179.963064 -359.560114) (xy 179.962708 -359.551097) (xy 179.95646 -359.53418) (xy 179.950872 -359.527094)
			(xy 179.950618 -359.527094) (xy 179.950618 -359.52684) (xy 179.932987 -359.505901) (xy 179.903273 -359.459931)
			(xy 179.880436 -359.410185) (xy 179.864943 -359.357686) (xy 179.857113 -359.303511) (xy 179.856638 -359.276142)
			(xy 179.857095 -359.248888) (xy 179.864847 -359.194935) (xy 179.8802 -359.142634) (xy 179.902841 -359.093051)
			(xy 179.932309 -359.047195) (xy 179.968004 -359.006001) (xy 180.009198 -358.970306) (xy 180.055054 -358.940839)
			(xy 180.104637 -358.918199) (xy 180.156938 -358.902846) (xy 180.210892 -358.895094) (xy 180.238146 -358.894634)
			(xy 180.265515 -358.895123) (xy 180.319694 -358.902934) (xy 180.372197 -358.918418) (xy 180.421944 -358.941254)
			(xy 180.467912 -358.970975) (xy 180.488844 -358.988614) (xy 180.489098 -358.988868) (xy 180.496175 -358.994468)
			(xy 180.513099 -359.000705) (xy 180.522118 -359.00106) (xy 180.589174 -359.00106) (xy 180.598191 -359.000699)
			(xy 180.615108 -358.994455) (xy 180.622194 -358.988868) (xy 180.622194 -358.988614) (xy 180.622448 -358.988614)
			(xy 180.643381 -358.970973) (xy 180.689349 -358.941249) (xy 180.739095 -358.918403) (xy 180.791597 -358.902907)
			(xy 180.845775 -358.895078) (xy 180.900517 -358.895078) (xy 180.954695 -358.902907) (xy 181.007197 -358.918403)
			(xy 181.056943 -358.941249) (xy 181.102911 -358.970973) (xy 181.123844 -358.988614) (xy 181.124098 -358.988868)
			(xy 181.131175 -358.994468) (xy 181.148099 -359.000705) (xy 181.157118 -359.00106) (xy 181.224174 -359.00106)
			(xy 181.233191 -359.000699) (xy 181.250108 -358.994455) (xy 181.257194 -358.988868) (xy 181.257194 -358.988614)
			(xy 181.257448 -358.988614) (xy 181.278381 -358.970973) (xy 181.324349 -358.941249) (xy 181.374095 -358.918403)
			(xy 181.426597 -358.902907) (xy 181.480775 -358.895078) (xy 181.535517 -358.895078) (xy 181.589695 -358.902907)
			(xy 181.642197 -358.918403) (xy 181.691943 -358.941249) (xy 181.737911 -358.970973) (xy 181.758844 -358.988614)
			(xy 181.759098 -358.988868) (xy 181.766175 -358.994468) (xy 181.783099 -359.000705) (xy 181.792118 -359.00106)
			(xy 181.859174 -359.00106) (xy 181.868191 -359.000699) (xy 181.885108 -358.994455) (xy 181.892194 -358.988868)
			(xy 181.892194 -358.988614) (xy 181.892448 -358.988614) (xy 181.913391 -358.970988) (xy 181.95936 -358.941274)
			(xy 182.009105 -358.918435) (xy 182.061604 -358.902941) (xy 182.115778 -358.89511) (xy 182.143146 -358.894634)
			(xy 182.1704 -358.895035) (xy 182.224353 -358.902799) (xy 182.276652 -358.918162) (xy 182.326232 -358.940812)
			(xy 182.372085 -358.970287) (xy 182.413275 -359.005987) (xy 182.448966 -359.047186) (xy 182.478431 -359.093045)
			(xy 182.501069 -359.14263) (xy 182.51642 -359.194933) (xy 182.524171 -359.248888) (xy 182.524654 -359.276142)
			(xy 182.524165 -359.303512) (xy 182.516355 -359.35769) (xy 182.500871 -359.410193) (xy 182.478034 -359.459941)
			(xy 182.448314 -359.505908) (xy 182.430674 -359.52684) (xy 182.43042 -359.527094) (xy 182.42482 -359.534171)
			(xy 182.418584 -359.551096) (xy 182.418228 -359.560114) (xy 182.418228 -359.62717) (xy 182.418593 -359.636186)
			(xy 182.424835 -359.653103) (xy 182.43042 -359.66019) (xy 182.430674 -359.66019) (xy 182.430674 -359.660444)
			(xy 182.448296 -359.68139) (xy 182.478012 -359.727358) (xy 182.500851 -359.777102) (xy 182.516346 -359.8296)
			(xy 182.524178 -359.883774) (xy 182.524654 -359.911142) (xy 182.524161 -359.938392) (xy 182.5164 -359.992337)
			(xy 182.501042 -360.044629) (xy 182.4784 -360.094203) (xy 182.448933 -360.140051) (xy 182.413243 -360.18124)
			(xy 182.372055 -360.216931) (xy 182.326207 -360.246398) (xy 182.276633 -360.269041) (xy 182.224341 -360.2844)
			(xy 182.170396 -360.292161) (xy 182.143146 -360.29265) (xy 182.115776 -360.292169) (xy 182.061597 -360.284357)
			(xy 182.009094 -360.268872) (xy 181.959347 -360.246033) (xy 181.91338 -360.216311) (xy 181.892448 -360.19867)
			(xy 181.892194 -360.198416) (xy 181.885112 -360.192823) (xy 181.868192 -360.186579) (xy 181.859174 -360.186224)
			(xy 181.792118 -360.186224) (xy 181.783101 -360.186585) (xy 181.766184 -360.192829) (xy 181.759098 -360.198416)
			(xy 181.759098 -360.19867) (xy 181.758844 -360.19867) (xy 181.737911 -360.216311) (xy 181.691943 -360.246035)
			(xy 181.642197 -360.268881) (xy 181.589695 -360.284377) (xy 181.535517 -360.292206) (xy 181.480775 -360.292206)
			(xy 181.426597 -360.284377) (xy 181.374095 -360.268881) (xy 181.324349 -360.246035) (xy 181.278381 -360.216311)
			(xy 181.257448 -360.19867) (xy 181.257194 -360.198416) (xy 181.250112 -360.192823) (xy 181.233192 -360.186579)
			(xy 181.224174 -360.186224) (xy 181.157118 -360.186224) (xy 181.148101 -360.186585) (xy 181.131184 -360.192829)
			(xy 181.124098 -360.198416) (xy 181.124098 -360.19867) (xy 181.123844 -360.19867) (xy 181.102911 -360.216311)
			(xy 181.056943 -360.246035) (xy 181.007197 -360.268881) (xy 180.954695 -360.284377) (xy 180.900517 -360.292206)
			(xy 180.845775 -360.292206) (xy 180.791597 -360.284377) (xy 180.739095 -360.268881) (xy 180.689349 -360.246035)
			(xy 180.643381 -360.216311) (xy 180.622448 -360.19867) (xy 180.622194 -360.198416) (xy 180.615112 -360.192823)
			(xy 180.598192 -360.186579) (xy 180.589174 -360.186224) (xy 180.522118 -360.186224) (xy 180.513101 -360.186585)
			(xy 180.496184 -360.192829) (xy 180.489098 -360.198416) (xy 180.488844 -360.19867) (xy 180.485034 -360.201972)
			(xy 180.476922 -360.20958) (xy 180.467567 -360.229728) (xy 180.467 -360.240834) (xy 180.467 -360.318304)
			(xy 180.467621 -360.329347) (xy 180.476949 -360.349368) (xy 180.485034 -360.356912) (xy 180.505761 -360.375106)
			(xy 180.542229 -360.416479) (xy 180.572358 -360.462673) (xy 180.595521 -360.512724) (xy 180.611234 -360.565589)
			(xy 180.61917 -360.620166) (xy 180.619654 -360.647742) (xy 180.619165 -360.675112) (xy 180.611355 -360.72929)
			(xy 180.595871 -360.781793) (xy 180.573034 -360.831541) (xy 180.543314 -360.877508) (xy 180.525674 -360.89844)
			(xy 180.52542 -360.898694) (xy 180.51982 -360.905771) (xy 180.513584 -360.922696) (xy 180.513228 -360.931714)
			(xy 180.513228 -360.99877) (xy 180.513593 -361.007786) (xy 180.519835 -361.024703) (xy 180.52542 -361.03179)
			(xy 180.525674 -361.03179) (xy 180.525674 -361.032044) (xy 180.543356 -361.052943) (xy 180.573079 -361.098917)
			(xy 180.595922 -361.148669) (xy 180.611415 -361.201176) (xy 180.619239 -361.255359) (xy 180.619235 -361.310104)
			(xy 180.611401 -361.364286) (xy 180.595899 -361.416791) (xy 180.573048 -361.466539) (xy 180.543318 -361.512507)
			(xy 180.525674 -361.53344) (xy 180.52542 -361.533694) (xy 180.51982 -361.540771) (xy 180.513584 -361.557696)
			(xy 180.513228 -361.566714) (xy 180.513228 -361.63377) (xy 180.513593 -361.642786) (xy 180.519835 -361.659703)
			(xy 180.52542 -361.66679) (xy 180.525674 -361.66679) (xy 180.525674 -361.667044) (xy 180.543356 -361.687943)
			(xy 180.573079 -361.733917) (xy 180.595922 -361.783669) (xy 180.611415 -361.836176) (xy 180.619239 -361.890359)
			(xy 180.619235 -361.945104) (xy 180.611401 -361.999286) (xy 180.595899 -362.051791) (xy 180.573048 -362.101539)
			(xy 180.543318 -362.147507) (xy 180.525674 -362.16844) (xy 180.52542 -362.168694) (xy 180.51982 -362.175771)
			(xy 180.513584 -362.192696) (xy 180.513228 -362.201714) (xy 180.513228 -362.26877) (xy 180.513593 -362.277786)
			(xy 180.519835 -362.294703) (xy 180.52542 -362.30179) (xy 180.525674 -362.30179) (xy 180.525674 -362.302044)
			(xy 180.543296 -362.32299) (xy 180.573012 -362.368958) (xy 180.595851 -362.418702) (xy 180.611346 -362.4712)
			(xy 180.619178 -362.525374) (xy 180.619654 -362.552742) (xy 180.619164 -362.580316) (xy 180.611219 -362.634888)
			(xy 180.5955 -362.687748) (xy 180.572334 -362.737795) (xy 180.542205 -362.783985) (xy 180.50574 -362.825356)
			(xy 180.485034 -362.843572) (xy 180.47696 -362.851128) (xy 180.467608 -362.871139) (xy 180.467 -362.88218)
			(xy 180.467 -362.95965) (xy 180.46758 -362.970758) (xy 180.47691 -362.990917) (xy 180.485034 -362.998512)
			(xy 180.488844 -363.001814) (xy 180.489098 -363.002068) (xy 180.496175 -363.007668) (xy 180.513099 -363.013905)
			(xy 180.522118 -363.01426) (xy 180.589174 -363.01426) (xy 180.598191 -363.013899) (xy 180.615108 -363.007655)
			(xy 180.622194 -363.002068) (xy 180.622194 -363.001814) (xy 180.622448 -363.001814) (xy 180.643381 -362.984173)
			(xy 180.689349 -362.954449) (xy 180.739095 -362.931603) (xy 180.791597 -362.916107) (xy 180.845775 -362.908278)
			(xy 180.900517 -362.908278) (xy 180.954695 -362.916107) (xy 181.007197 -362.931603) (xy 181.056943 -362.954449)
			(xy 181.102911 -362.984173) (xy 181.123844 -363.001814) (xy 181.124098 -363.002068) (xy 181.131175 -363.007668)
			(xy 181.148099 -363.013905) (xy 181.157118 -363.01426) (xy 181.224174 -363.01426) (xy 181.233191 -363.013899)
			(xy 181.250108 -363.007655) (xy 181.257194 -363.002068) (xy 181.257194 -363.001814) (xy 181.257448 -363.001814)
			(xy 181.278381 -362.984173) (xy 181.324349 -362.954449) (xy 181.374095 -362.931603) (xy 181.426597 -362.916107)
			(xy 181.480775 -362.908278) (xy 181.535517 -362.908278) (xy 181.589695 -362.916107) (xy 181.642197 -362.931603)
			(xy 181.691943 -362.954449) (xy 181.737911 -362.984173) (xy 181.758844 -363.001814) (xy 181.759098 -363.002068)
			(xy 181.766175 -363.007668) (xy 181.783099 -363.013905) (xy 181.792118 -363.01426) (xy 181.859174 -363.01426)
			(xy 181.868191 -363.013899) (xy 181.885108 -363.007655) (xy 181.892194 -363.002068) (xy 181.892194 -363.001814)
			(xy 181.892448 -363.001814) (xy 181.913391 -362.984188) (xy 181.95936 -362.954474) (xy 182.009105 -362.931635)
			(xy 182.061604 -362.916141) (xy 182.115778 -362.90831) (xy 182.143146 -362.907834) (xy 182.1704 -362.908235)
			(xy 182.224353 -362.915999) (xy 182.276652 -362.931362) (xy 182.326232 -362.954012) (xy 182.372085 -362.983487)
			(xy 182.413275 -363.019187) (xy 182.448966 -363.060386) (xy 182.478431 -363.106245) (xy 182.501069 -363.15583)
			(xy 182.51642 -363.208133) (xy 182.524171 -363.262088) (xy 182.524654 -363.289342) (xy 182.524165 -363.316712)
			(xy 182.516355 -363.37089) (xy 182.500871 -363.423393) (xy 182.478034 -363.473141) (xy 182.448314 -363.519108)
			(xy 182.430674 -363.54004) (xy 182.43042 -363.540294) (xy 182.42482 -363.547371) (xy 182.418584 -363.564296)
			(xy 182.418228 -363.573314) (xy 182.418228 -363.64037) (xy 182.418593 -363.649386) (xy 182.424835 -363.666303)
			(xy 182.43042 -363.67339) (xy 182.430674 -363.67339) (xy 182.430674 -363.673644) (xy 182.448296 -363.69459)
			(xy 182.478012 -363.740558) (xy 182.500851 -363.790302) (xy 182.516346 -363.8428) (xy 182.524178 -363.896974)
			(xy 182.524654 -363.924342) (xy 182.524161 -363.951592) (xy 182.5164 -364.005537) (xy 182.501042 -364.057829)
			(xy 182.4784 -364.107403) (xy 182.448933 -364.153251) (xy 182.413243 -364.19444) (xy 182.372055 -364.230131)
			(xy 182.326207 -364.259598) (xy 182.276633 -364.282241) (xy 182.224341 -364.2976) (xy 182.170396 -364.305361)
			(xy 182.143146 -364.30585) (xy 182.115776 -364.305369) (xy 182.061597 -364.297557) (xy 182.009094 -364.282072)
			(xy 181.959347 -364.259233) (xy 181.91338 -364.229511) (xy 181.892448 -364.21187) (xy 181.892194 -364.211616)
			(xy 181.885112 -364.206023) (xy 181.868192 -364.199779) (xy 181.859174 -364.199424) (xy 181.792118 -364.199424)
			(xy 181.783101 -364.199785) (xy 181.766184 -364.206029) (xy 181.759098 -364.211616) (xy 181.758844 -364.21187)
			(xy 181.737911 -364.229511) (xy 181.691943 -364.259235) (xy 181.642197 -364.282081) (xy 181.589695 -364.297577)
			(xy 181.535517 -364.305406) (xy 181.480775 -364.305406) (xy 181.426597 -364.297577) (xy 181.374095 -364.282081)
			(xy 181.324349 -364.259235) (xy 181.278381 -364.229511) (xy 181.257448 -364.21187) (xy 181.257194 -364.211616)
			(xy 181.250112 -364.206023) (xy 181.233192 -364.199779) (xy 181.224174 -364.199424) (xy 181.157118 -364.199424)
			(xy 181.148101 -364.199785) (xy 181.131184 -364.206029) (xy 181.124098 -364.211616) (xy 181.124098 -364.21187)
			(xy 181.123844 -364.21187) (xy 181.102911 -364.229511) (xy 181.056943 -364.259235) (xy 181.007197 -364.282081)
			(xy 180.954695 -364.297577) (xy 180.900517 -364.305406) (xy 180.845775 -364.305406) (xy 180.791597 -364.297577)
			(xy 180.739095 -364.282081) (xy 180.689349 -364.259235) (xy 180.643381 -364.229511) (xy 180.622448 -364.21187)
			(xy 180.622194 -364.211616) (xy 180.615112 -364.206023) (xy 180.598192 -364.199779) (xy 180.589174 -364.199424)
			(xy 180.522118 -364.199424) (xy 180.513101 -364.199785) (xy 180.496184 -364.206029) (xy 180.489098 -364.211616)
			(xy 180.489098 -364.21187) (xy 180.488844 -364.21187) (xy 180.467902 -364.229497) (xy 180.421933 -364.259212)
			(xy 180.372188 -364.282051) (xy 180.319689 -364.297544) (xy 180.265515 -364.305375) (xy 180.238146 -364.30585)
			(xy 180.210896 -364.305302) (xy 180.15695 -364.297552) (xy 180.104657 -364.282204) (xy 180.05508 -364.25957)
			(xy 180.009228 -364.230111) (xy 179.968036 -364.194426) (xy 179.932342 -364.153242) (xy 179.902872 -364.107398)
			(xy 179.880226 -364.057826) (xy 179.864866 -364.005536) (xy 179.857104 -363.951592) (xy 179.856638 -363.924342)
			(xy 178.529742 -363.924342) (xy 179.578438 -364.973038) (xy 190.790826 -364.973038) (xy 190.790826 -364.888342)
			(xy 190.798877 -364.804028) (xy 190.814906 -364.720862) (xy 190.838767 -364.639595) (xy 190.870246 -364.560965)
			(xy 190.909057 -364.485684) (xy 190.954847 -364.414432) (xy 191.007203 -364.347856) (xy 191.065651 -364.286558)
			(xy 191.129661 -364.231093) (xy 191.198653 -364.181964) (xy 191.272003 -364.139615) (xy 191.349046 -364.104431)
			(xy 191.429085 -364.076729) (xy 191.511394 -364.056761) (xy 191.595229 -364.044708) (xy 191.67983 -364.040678)
			(xy 191.764431 -364.044708) (xy 191.848266 -364.056761) (xy 191.930575 -364.076729) (xy 192.010614 -364.104431)
			(xy 192.087657 -364.139615) (xy 192.161007 -364.181964) (xy 192.229999 -364.231093) (xy 192.294009 -364.286558)
			(xy 192.352457 -364.347856) (xy 192.404813 -364.414432) (xy 192.450603 -364.485684) (xy 192.489414 -364.560965)
			(xy 192.520893 -364.639595) (xy 192.544754 -364.720862) (xy 192.560783 -364.804028) (xy 192.568834 -364.888342)
			(xy 192.569338 -364.93069) (xy 192.568834 -364.973038) (xy 192.560783 -365.057352) (xy 192.544754 -365.140518)
			(xy 192.520893 -365.221785) (xy 192.489414 -365.300415) (xy 192.450603 -365.375696) (xy 192.404813 -365.446948)
			(xy 192.352457 -365.513524) (xy 192.294009 -365.574822) (xy 192.229999 -365.630287) (xy 192.161007 -365.679416)
			(xy 192.087657 -365.721765) (xy 192.010614 -365.756949) (xy 191.930575 -365.784651) (xy 191.848266 -365.804619)
			(xy 191.764431 -365.816672) (xy 191.67983 -365.820703) (xy 191.595229 -365.816672) (xy 191.511394 -365.804619)
			(xy 191.429085 -365.784651) (xy 191.349046 -365.756949) (xy 191.272003 -365.721765) (xy 191.198653 -365.679416)
			(xy 191.129661 -365.630287) (xy 191.065651 -365.574822) (xy 191.007203 -365.513524) (xy 190.954847 -365.446948)
			(xy 190.909057 -365.375696) (xy 190.870246 -365.300415) (xy 190.838767 -365.221785) (xy 190.814906 -365.140518)
			(xy 190.798877 -365.057352) (xy 190.790826 -364.973038) (xy 179.578438 -364.973038) (xy 180.777388 -366.171988)
			(xy 180.784785 -366.178838) (xy 180.803383 -366.186578) (xy 180.813456 -366.186974)
		)
		(stroke
			(width 0)
			(type solid)
		)
		(fill yes)
		(layer "In15.Cu")
		(net "GND")
	)
	(gr_poly
		(pts
			(xy 395.187424 -403.198076) (xy 395.19635 -403.206133) (xy 395.219142 -403.213691) (xy 395.231112 -403.212554)
			(xy 395.78534 -403.128226) (xy 395.853676 -403.117425) (xy 395.989282 -403.089934) (xy 396.123366 -403.055777)
			(xy 396.255598 -403.015039) (xy 396.320772 -402.991828) (xy 396.32128 -402.991574) (xy 398.093692 -402.350986)
			(xy 398.101741 -402.34771) (xy 398.115172 -402.336699) (xy 398.12416 -402.321839) (xy 398.126204 -402.313394)
			(xy 398.14627 -402.21535) (xy 398.138396 -402.190458) (xy 398.128744 -402.181314) (xy 398.12341 -402.176234)
			(xy 398.11608 -402.169694) (xy 398.097916 -402.16226) (xy 398.088104 -402.161756) (xy 398.0561 -402.161756)
			(xy 398.046289 -402.162256) (xy 398.028129 -402.1697) (xy 398.020794 -402.176234) (xy 397.999296 -402.196411)
			(xy 397.95124 -402.230566) (xy 397.898501 -402.25692) (xy 397.842335 -402.274845) (xy 397.78408 -402.283917)
			(xy 397.754602 -402.284438) (xy 397.727232 -402.283966) (xy 397.673055 -402.276142) (xy 397.620552 -402.260653)
			(xy 397.570803 -402.237818) (xy 397.524829 -402.208106) (xy 397.503904 -402.190458) (xy 397.496792 -402.184362)
			(xy 397.479774 -402.178012) (xy 397.39443 -402.178012) (xy 397.377412 -402.184362) (xy 397.3703 -402.190458)
			(xy 397.349369 -402.208102) (xy 397.303404 -402.237831) (xy 397.253657 -402.260677) (xy 397.201153 -402.276169)
			(xy 397.146973 -402.283988) (xy 397.119602 -402.284438) (xy 397.09235 -402.283952) (xy 397.0384 -402.276196)
			(xy 396.986104 -402.260842) (xy 396.936524 -402.238201) (xy 396.890671 -402.208735) (xy 396.849479 -402.173044)
			(xy 396.813784 -402.131854) (xy 396.784314 -402.086004) (xy 396.76167 -402.036426) (xy 396.746311 -401.984131)
			(xy 396.73855 -401.930182) (xy 396.738094 -401.90293) (xy 396.738571 -401.875562) (xy 396.746403 -401.821388)
			(xy 396.761898 -401.76889) (xy 396.784736 -401.719146) (xy 396.814449 -401.673176) (xy 396.832074 -401.652232)
			(xy 396.83817 -401.64512) (xy 396.84452 -401.628102) (xy 396.84452 -401.542758) (xy 396.83817 -401.52574)
			(xy 396.832074 -401.518628) (xy 396.814429 -401.497696) (xy 396.784697 -401.451729) (xy 396.761844 -401.401981)
			(xy 396.746342 -401.349477) (xy 396.738509 -401.295295) (xy 396.738506 -401.24055) (xy 396.746332 -401.186367)
			(xy 396.761828 -401.133861) (xy 396.784675 -401.084111) (xy 396.814402 -401.03814) (xy 396.832074 -401.017232)
			(xy 396.83817 -401.01012) (xy 396.84452 -400.993102) (xy 396.84452 -400.907758) (xy 396.83817 -400.89074)
			(xy 396.832074 -400.883628) (xy 396.814429 -400.862696) (xy 396.784697 -400.816729) (xy 396.761844 -400.766981)
			(xy 396.746342 -400.714477) (xy 396.738509 -400.660295) (xy 396.738506 -400.60555) (xy 396.746332 -400.551367)
			(xy 396.761828 -400.498861) (xy 396.784675 -400.449111) (xy 396.814402 -400.40314) (xy 396.832074 -400.382232)
			(xy 396.83817 -400.37512) (xy 396.84452 -400.358102) (xy 396.84452 -400.272758) (xy 396.83817 -400.25574)
			(xy 396.832074 -400.248628) (xy 396.814432 -400.227697) (xy 396.784704 -400.18173) (xy 396.761859 -400.131984)
			(xy 396.746366 -400.079481) (xy 396.738544 -400.025301) (xy 396.738094 -399.99793) (xy 396.738582 -399.969973)
			(xy 396.746744 -399.914657) (xy 396.762896 -399.861126) (xy 396.786693 -399.810529) (xy 396.817624 -399.763948)
			(xy 396.855026 -399.722385) (xy 396.898097 -399.686729) (xy 396.921736 -399.671794) (xy 396.930372 -399.66646)
			(xy 396.942056 -399.650712) (xy 396.964916 -399.562828) (xy 396.962122 -399.543016) (xy 396.957296 -399.53438)
			(xy 396.945361 -399.512683) (xy 396.92657 -399.466868) (xy 396.913854 -399.419009) (xy 396.907426 -399.369909)
			(xy 396.907004 -399.34515) (xy 396.907591 -399.31525) (xy 396.916911 -399.25618) (xy 396.925546 -399.227548)
			(xy 396.929102 -399.21688) (xy 396.926308 -399.195036) (xy 396.874492 -399.109946) (xy 396.856204 -399.097754)
			(xy 396.845028 -399.095976) (xy 396.818516 -399.091235) (xy 396.767079 -399.075274) (xy 396.718398 -399.052237)
			(xy 396.673442 -399.022581) (xy 396.633104 -398.986895) (xy 396.598187 -398.945891) (xy 396.569385 -398.900383)
			(xy 396.547271 -398.851276) (xy 396.532285 -398.799546) (xy 396.524724 -398.746223) (xy 396.524226 -398.719294)
			(xy 396.524712 -398.692043) (xy 396.532468 -398.638095) (xy 396.547823 -398.5858) (xy 396.570465 -398.536223)
			(xy 396.599931 -398.490373) (xy 396.635622 -398.449182) (xy 396.676813 -398.413491) (xy 396.722663 -398.384025)
			(xy 396.77224 -398.361383) (xy 396.824535 -398.346028) (xy 396.878483 -398.338272) (xy 396.932985 -398.338272)
			(xy 396.986933 -398.346028) (xy 397.039228 -398.361383) (xy 397.088805 -398.384025) (xy 397.134655 -398.413491)
			(xy 397.175846 -398.449182) (xy 397.211537 -398.490373) (xy 397.241003 -398.536223) (xy 397.263645 -398.5858)
			(xy 397.279 -398.638095) (xy 397.286756 -398.692043) (xy 397.287242 -398.719294) (xy 397.286659 -398.749195)
			(xy 397.277346 -398.808267) (xy 397.2687 -398.836896) (xy 397.265144 -398.847564) (xy 397.267938 -398.869408)
			(xy 397.319754 -398.954498) (xy 397.338042 -398.96669) (xy 397.349218 -398.968468) (xy 397.375729 -398.973211)
			(xy 397.427165 -398.989176) (xy 397.467133 -399.008092) (xy 400.39036 -399.008092) (xy 400.39078 -398.984859)
			(xy 400.397273 -398.938849) (xy 400.410145 -398.894202) (xy 400.429141 -398.851797) (xy 400.453888 -398.81247)
			(xy 400.468592 -398.794478) (xy 400.474688 -398.787366) (xy 400.480784 -398.770856) (xy 400.480784 -398.686528)
			(xy 400.474688 -398.670018) (xy 400.468592 -398.662906) (xy 400.453871 -398.644927) (xy 400.429127 -398.605594)
			(xy 400.41013 -398.563187) (xy 400.397254 -398.518538) (xy 400.390753 -398.472526) (xy 400.39036 -398.449292)
			(xy 400.39087 -398.423305) (xy 400.399 -398.37197) (xy 400.415061 -398.32254) (xy 400.438657 -398.27623)
			(xy 400.469207 -398.234182) (xy 400.505958 -398.197431) (xy 400.548006 -398.166881) (xy 400.594316 -398.143285)
			(xy 400.643746 -398.127224) (xy 400.695081 -398.119094) (xy 400.747055 -398.119094) (xy 400.79839 -398.127224)
			(xy 400.84782 -398.143285) (xy 400.89413 -398.166881) (xy 400.936178 -398.197431) (xy 400.972929 -398.234182)
			(xy 401.003479 -398.27623) (xy 401.027075 -398.32254) (xy 401.043136 -398.37197) (xy 401.051266 -398.423305)
			(xy 401.051776 -398.449292) (xy 401.051396 -398.472526) (xy 401.044892 -398.518537) (xy 401.038122 -398.542002)
			(xy 402.712948 -398.542002) (xy 402.716908 -398.492948) (xy 402.728685 -398.445164) (xy 402.747976 -398.399888)
			(xy 402.774279 -398.358292) (xy 402.806914 -398.321455) (xy 402.845035 -398.29033) (xy 402.887656 -398.265723)
			(xy 402.933672 -398.248271) (xy 402.981891 -398.238427) (xy 403.031066 -398.236446) (xy 403.079921 -398.242378)
			(xy 403.127192 -398.25607) (xy 403.171654 -398.277168) (xy 403.212157 -398.305124) (xy 403.24765 -398.339216)
			(xy 403.277215 -398.37856) (xy 403.300086 -398.422137) (xy 403.31567 -398.468818) (xy 403.323565 -398.517395)
			(xy 403.32406 -398.542002) (xy 403.913098 -398.542002) (xy 403.917058 -398.492948) (xy 403.928835 -398.445164)
			(xy 403.948126 -398.399888) (xy 403.974429 -398.358292) (xy 404.007064 -398.321455) (xy 404.045185 -398.29033)
			(xy 404.087806 -398.265723) (xy 404.133822 -398.248271) (xy 404.182041 -398.238427) (xy 404.231216 -398.236446)
			(xy 404.280071 -398.242378) (xy 404.327342 -398.25607) (xy 404.371804 -398.277168) (xy 404.412307 -398.305124)
			(xy 404.4478 -398.339216) (xy 404.477365 -398.37856) (xy 404.500236 -398.422137) (xy 404.51582 -398.468818)
			(xy 404.523715 -398.517395) (xy 404.52421 -398.542002) (xy 405.113248 -398.542002) (xy 405.117208 -398.492948)
			(xy 405.128985 -398.445164) (xy 405.148276 -398.399888) (xy 405.174579 -398.358292) (xy 405.207214 -398.321455)
			(xy 405.245335 -398.29033) (xy 405.287956 -398.265723) (xy 405.333972 -398.248271) (xy 405.382191 -398.238427)
			(xy 405.431366 -398.236446) (xy 405.480221 -398.242378) (xy 405.527492 -398.25607) (xy 405.571954 -398.277168)
			(xy 405.612457 -398.305124) (xy 405.64795 -398.339216) (xy 405.677515 -398.37856) (xy 405.700386 -398.422137)
			(xy 405.71597 -398.468818) (xy 405.723865 -398.517395) (xy 405.72436 -398.542002) (xy 406.313144 -398.542002)
			(xy 406.317104 -398.492948) (xy 406.328881 -398.445164) (xy 406.348172 -398.399888) (xy 406.374475 -398.358292)
			(xy 406.40711 -398.321455) (xy 406.445231 -398.29033) (xy 406.487852 -398.265723) (xy 406.533868 -398.248271)
			(xy 406.582087 -398.238427) (xy 406.631262 -398.236446) (xy 406.680117 -398.242378) (xy 406.727388 -398.25607)
			(xy 406.77185 -398.277168) (xy 406.812353 -398.305124) (xy 406.847846 -398.339216) (xy 406.877411 -398.37856)
			(xy 406.900282 -398.422137) (xy 406.915866 -398.468818) (xy 406.923761 -398.517395) (xy 406.924256 -398.542002)
			(xy 407.513294 -398.542002) (xy 407.517254 -398.492948) (xy 407.529031 -398.445164) (xy 407.548322 -398.399888)
			(xy 407.574625 -398.358292) (xy 407.60726 -398.321455) (xy 407.645381 -398.29033) (xy 407.688002 -398.265723)
			(xy 407.734018 -398.248271) (xy 407.782237 -398.238427) (xy 407.831412 -398.236446) (xy 407.880267 -398.242378)
			(xy 407.927538 -398.25607) (xy 407.972 -398.277168) (xy 408.012503 -398.305124) (xy 408.047996 -398.339216)
			(xy 408.077561 -398.37856) (xy 408.100432 -398.422137) (xy 408.116016 -398.468818) (xy 408.123911 -398.517395)
			(xy 408.124406 -398.542002) (xy 408.71319 -398.542002) (xy 408.71715 -398.492948) (xy 408.728927 -398.445164)
			(xy 408.748218 -398.399888) (xy 408.774521 -398.358292) (xy 408.807156 -398.321455) (xy 408.845277 -398.29033)
			(xy 408.887898 -398.265723) (xy 408.933914 -398.248271) (xy 408.982133 -398.238427) (xy 409.031308 -398.236446)
			(xy 409.080163 -398.242378) (xy 409.127434 -398.25607) (xy 409.171896 -398.277168) (xy 409.212399 -398.305124)
			(xy 409.247892 -398.339216) (xy 409.277457 -398.37856) (xy 409.300328 -398.422137) (xy 409.315912 -398.468818)
			(xy 409.323807 -398.517395) (xy 409.324302 -398.542002) (xy 409.913086 -398.542002) (xy 409.917046 -398.492948)
			(xy 409.928823 -398.445164) (xy 409.948114 -398.399888) (xy 409.974417 -398.358292) (xy 410.007052 -398.321455)
			(xy 410.045173 -398.29033) (xy 410.087794 -398.265723) (xy 410.13381 -398.248271) (xy 410.182029 -398.238427)
			(xy 410.231204 -398.236446) (xy 410.280059 -398.242378) (xy 410.32733 -398.25607) (xy 410.371792 -398.277168)
			(xy 410.412295 -398.305124) (xy 410.447788 -398.339216) (xy 410.477353 -398.37856) (xy 410.500224 -398.422137)
			(xy 410.515808 -398.468818) (xy 410.523703 -398.517395) (xy 410.524198 -398.542002) (xy 411.113236 -398.542002)
			(xy 411.117196 -398.492948) (xy 411.128973 -398.445164) (xy 411.148264 -398.399888) (xy 411.174567 -398.358292)
			(xy 411.207202 -398.321455) (xy 411.245323 -398.29033) (xy 411.287944 -398.265723) (xy 411.33396 -398.248271)
			(xy 411.382179 -398.238427) (xy 411.431354 -398.236446) (xy 411.480209 -398.242378) (xy 411.52748 -398.25607)
			(xy 411.571942 -398.277168) (xy 411.612445 -398.305124) (xy 411.647938 -398.339216) (xy 411.677503 -398.37856)
			(xy 411.700374 -398.422137) (xy 411.715958 -398.468818) (xy 411.723853 -398.517395) (xy 411.724348 -398.542002)
			(xy 412.313132 -398.542002) (xy 412.317092 -398.492948) (xy 412.328869 -398.445164) (xy 412.34816 -398.399888)
			(xy 412.374463 -398.358292) (xy 412.407098 -398.321455) (xy 412.445219 -398.29033) (xy 412.48784 -398.265723)
			(xy 412.533856 -398.248271) (xy 412.582075 -398.238427) (xy 412.63125 -398.236446) (xy 412.680105 -398.242378)
			(xy 412.727376 -398.25607) (xy 412.771838 -398.277168) (xy 412.812341 -398.305124) (xy 412.847834 -398.339216)
			(xy 412.877399 -398.37856) (xy 412.90027 -398.422137) (xy 412.915854 -398.468818) (xy 412.923749 -398.517395)
			(xy 412.924244 -398.542002) (xy 413.513282 -398.542002) (xy 413.517242 -398.492948) (xy 413.529019 -398.445164)
			(xy 413.54831 -398.399888) (xy 413.574613 -398.358292) (xy 413.607248 -398.321455) (xy 413.645369 -398.29033)
			(xy 413.68799 -398.265723) (xy 413.734006 -398.248271) (xy 413.782225 -398.238427) (xy 413.8314 -398.236446)
			(xy 413.880255 -398.242378) (xy 413.927526 -398.25607) (xy 413.971988 -398.277168) (xy 414.012491 -398.305124)
			(xy 414.047984 -398.339216) (xy 414.077549 -398.37856) (xy 414.10042 -398.422137) (xy 414.116004 -398.468818)
			(xy 414.123899 -398.517395) (xy 414.124394 -398.542002) (xy 414.713178 -398.542002) (xy 414.717138 -398.492948)
			(xy 414.728915 -398.445164) (xy 414.748206 -398.399888) (xy 414.774509 -398.358292) (xy 414.807144 -398.321455)
			(xy 414.845265 -398.29033) (xy 414.887886 -398.265723) (xy 414.933902 -398.248271) (xy 414.982121 -398.238427)
			(xy 415.031296 -398.236446) (xy 415.080151 -398.242378) (xy 415.127422 -398.25607) (xy 415.171884 -398.277168)
			(xy 415.212387 -398.305124) (xy 415.24788 -398.339216) (xy 415.277445 -398.37856) (xy 415.300316 -398.422137)
			(xy 415.3159 -398.468818) (xy 415.323795 -398.517395) (xy 415.32429 -398.542002) (xy 415.913074 -398.542002)
			(xy 415.917034 -398.492948) (xy 415.928811 -398.445164) (xy 415.948102 -398.399888) (xy 415.974405 -398.358292)
			(xy 416.00704 -398.321455) (xy 416.045161 -398.29033) (xy 416.087782 -398.265723) (xy 416.133798 -398.248271)
			(xy 416.182017 -398.238427) (xy 416.231192 -398.236446) (xy 416.280047 -398.242378) (xy 416.327318 -398.25607)
			(xy 416.37178 -398.277168) (xy 416.412283 -398.305124) (xy 416.447776 -398.339216) (xy 416.477341 -398.37856)
			(xy 416.500212 -398.422137) (xy 416.515796 -398.468818) (xy 416.523691 -398.517395) (xy 416.524186 -398.542002)
			(xy 417.113224 -398.542002) (xy 417.117184 -398.492948) (xy 417.128961 -398.445164) (xy 417.148252 -398.399888)
			(xy 417.174555 -398.358292) (xy 417.20719 -398.321455) (xy 417.245311 -398.29033) (xy 417.287932 -398.265723)
			(xy 417.333948 -398.248271) (xy 417.382167 -398.238427) (xy 417.431342 -398.236446) (xy 417.480197 -398.242378)
			(xy 417.527468 -398.25607) (xy 417.57193 -398.277168) (xy 417.612433 -398.305124) (xy 417.647926 -398.339216)
			(xy 417.677491 -398.37856) (xy 417.700362 -398.422137) (xy 417.715946 -398.468818) (xy 417.723841 -398.517395)
			(xy 417.724336 -398.542002) (xy 418.31312 -398.542002) (xy 418.31708 -398.492948) (xy 418.328857 -398.445164)
			(xy 418.348148 -398.399888) (xy 418.374451 -398.358292) (xy 418.407086 -398.321455) (xy 418.445207 -398.29033)
			(xy 418.487828 -398.265723) (xy 418.533844 -398.248271) (xy 418.582063 -398.238427) (xy 418.631238 -398.236446)
			(xy 418.680093 -398.242378) (xy 418.727364 -398.25607) (xy 418.771826 -398.277168) (xy 418.812329 -398.305124)
			(xy 418.847822 -398.339216) (xy 418.877387 -398.37856) (xy 418.900258 -398.422137) (xy 418.915842 -398.468818)
			(xy 418.923737 -398.517395) (xy 418.924232 -398.542002) (xy 419.51327 -398.542002) (xy 419.51723 -398.492948)
			(xy 419.529007 -398.445164) (xy 419.548298 -398.399888) (xy 419.574601 -398.358292) (xy 419.607236 -398.321455)
			(xy 419.645357 -398.29033) (xy 419.687978 -398.265723) (xy 419.733994 -398.248271) (xy 419.782213 -398.238427)
			(xy 419.831388 -398.236446) (xy 419.880243 -398.242378) (xy 419.927514 -398.25607) (xy 419.971976 -398.277168)
			(xy 420.012479 -398.305124) (xy 420.047972 -398.339216) (xy 420.077537 -398.37856) (xy 420.100408 -398.422137)
			(xy 420.115992 -398.468818) (xy 420.123887 -398.517395) (xy 420.124382 -398.542002) (xy 420.713166 -398.542002)
			(xy 420.717126 -398.492948) (xy 420.728903 -398.445164) (xy 420.748194 -398.399888) (xy 420.774497 -398.358292)
			(xy 420.807132 -398.321455) (xy 420.845253 -398.29033) (xy 420.887874 -398.265723) (xy 420.93389 -398.248271)
			(xy 420.982109 -398.238427) (xy 421.031284 -398.236446) (xy 421.080139 -398.242378) (xy 421.12741 -398.25607)
			(xy 421.171872 -398.277168) (xy 421.212375 -398.305124) (xy 421.247868 -398.339216) (xy 421.277433 -398.37856)
			(xy 421.300304 -398.422137) (xy 421.315888 -398.468818) (xy 421.323783 -398.517395) (xy 421.324278 -398.542002)
			(xy 421.323783 -398.566609) (xy 421.315888 -398.615186) (xy 421.300304 -398.661867) (xy 421.277433 -398.705444)
			(xy 421.247868 -398.744788) (xy 421.212375 -398.77888) (xy 421.171872 -398.806836) (xy 421.12741 -398.827934)
			(xy 421.080139 -398.841626) (xy 421.031284 -398.847558) (xy 420.982109 -398.845577) (xy 420.93389 -398.835733)
			(xy 420.887874 -398.818281) (xy 420.845253 -398.793674) (xy 420.807132 -398.762549) (xy 420.774497 -398.725712)
			(xy 420.748194 -398.684116) (xy 420.728903 -398.63884) (xy 420.717126 -398.591056) (xy 420.713166 -398.542002)
			(xy 420.124382 -398.542002) (xy 420.123887 -398.566609) (xy 420.115992 -398.615186) (xy 420.100408 -398.661867)
			(xy 420.077537 -398.705444) (xy 420.047972 -398.744788) (xy 420.012479 -398.77888) (xy 419.971976 -398.806836)
			(xy 419.927514 -398.827934) (xy 419.880243 -398.841626) (xy 419.831388 -398.847558) (xy 419.782213 -398.845577)
			(xy 419.733994 -398.835733) (xy 419.687978 -398.818281) (xy 419.645357 -398.793674) (xy 419.607236 -398.762549)
			(xy 419.574601 -398.725712) (xy 419.548298 -398.684116) (xy 419.529007 -398.63884) (xy 419.51723 -398.591056)
			(xy 419.51327 -398.542002) (xy 418.924232 -398.542002) (xy 418.923737 -398.566609) (xy 418.915842 -398.615186)
			(xy 418.900258 -398.661867) (xy 418.877387 -398.705444) (xy 418.847822 -398.744788) (xy 418.812329 -398.77888)
			(xy 418.771826 -398.806836) (xy 418.727364 -398.827934) (xy 418.680093 -398.841626) (xy 418.631238 -398.847558)
			(xy 418.582063 -398.845577) (xy 418.533844 -398.835733) (xy 418.487828 -398.818281) (xy 418.445207 -398.793674)
			(xy 418.407086 -398.762549) (xy 418.374451 -398.725712) (xy 418.348148 -398.684116) (xy 418.328857 -398.63884)
			(xy 418.31708 -398.591056) (xy 418.31312 -398.542002) (xy 417.724336 -398.542002) (xy 417.723841 -398.566609)
			(xy 417.715946 -398.615186) (xy 417.700362 -398.661867) (xy 417.677491 -398.705444) (xy 417.647926 -398.744788)
			(xy 417.612433 -398.77888) (xy 417.57193 -398.806836) (xy 417.527468 -398.827934) (xy 417.480197 -398.841626)
			(xy 417.431342 -398.847558) (xy 417.382167 -398.845577) (xy 417.333948 -398.835733) (xy 417.287932 -398.818281)
			(xy 417.245311 -398.793674) (xy 417.20719 -398.762549) (xy 417.174555 -398.725712) (xy 417.148252 -398.684116)
			(xy 417.128961 -398.63884) (xy 417.117184 -398.591056) (xy 417.113224 -398.542002) (xy 416.524186 -398.542002)
			(xy 416.523691 -398.566609) (xy 416.515796 -398.615186) (xy 416.500212 -398.661867) (xy 416.477341 -398.705444)
			(xy 416.447776 -398.744788) (xy 416.412283 -398.77888) (xy 416.37178 -398.806836) (xy 416.327318 -398.827934)
			(xy 416.280047 -398.841626) (xy 416.231192 -398.847558) (xy 416.182017 -398.845577) (xy 416.133798 -398.835733)
			(xy 416.087782 -398.818281) (xy 416.045161 -398.793674) (xy 416.00704 -398.762549) (xy 415.974405 -398.725712)
			(xy 415.948102 -398.684116) (xy 415.928811 -398.63884) (xy 415.917034 -398.591056) (xy 415.913074 -398.542002)
			(xy 415.32429 -398.542002) (xy 415.323795 -398.566609) (xy 415.3159 -398.615186) (xy 415.300316 -398.661867)
			(xy 415.277445 -398.705444) (xy 415.24788 -398.744788) (xy 415.212387 -398.77888) (xy 415.171884 -398.806836)
			(xy 415.127422 -398.827934) (xy 415.080151 -398.841626) (xy 415.031296 -398.847558) (xy 414.982121 -398.845577)
			(xy 414.933902 -398.835733) (xy 414.887886 -398.818281) (xy 414.845265 -398.793674) (xy 414.807144 -398.762549)
			(xy 414.774509 -398.725712) (xy 414.748206 -398.684116) (xy 414.728915 -398.63884) (xy 414.717138 -398.591056)
			(xy 414.713178 -398.542002) (xy 414.124394 -398.542002) (xy 414.123899 -398.566609) (xy 414.116004 -398.615186)
			(xy 414.10042 -398.661867) (xy 414.077549 -398.705444) (xy 414.047984 -398.744788) (xy 414.012491 -398.77888)
			(xy 413.971988 -398.806836) (xy 413.927526 -398.827934) (xy 413.880255 -398.841626) (xy 413.8314 -398.847558)
			(xy 413.782225 -398.845577) (xy 413.734006 -398.835733) (xy 413.68799 -398.818281) (xy 413.645369 -398.793674)
			(xy 413.607248 -398.762549) (xy 413.574613 -398.725712) (xy 413.54831 -398.684116) (xy 413.529019 -398.63884)
			(xy 413.517242 -398.591056) (xy 413.513282 -398.542002) (xy 412.924244 -398.542002) (xy 412.923749 -398.566609)
			(xy 412.915854 -398.615186) (xy 412.90027 -398.661867) (xy 412.877399 -398.705444) (xy 412.847834 -398.744788)
			(xy 412.812341 -398.77888) (xy 412.771838 -398.806836) (xy 412.727376 -398.827934) (xy 412.680105 -398.841626)
			(xy 412.63125 -398.847558) (xy 412.582075 -398.845577) (xy 412.533856 -398.835733) (xy 412.48784 -398.818281)
			(xy 412.445219 -398.793674) (xy 412.407098 -398.762549) (xy 412.374463 -398.725712) (xy 412.34816 -398.684116)
			(xy 412.328869 -398.63884) (xy 412.317092 -398.591056) (xy 412.313132 -398.542002) (xy 411.724348 -398.542002)
			(xy 411.723853 -398.566609) (xy 411.715958 -398.615186) (xy 411.700374 -398.661867) (xy 411.677503 -398.705444)
			(xy 411.647938 -398.744788) (xy 411.612445 -398.77888) (xy 411.571942 -398.806836) (xy 411.52748 -398.827934)
			(xy 411.480209 -398.841626) (xy 411.431354 -398.847558) (xy 411.382179 -398.845577) (xy 411.33396 -398.835733)
			(xy 411.287944 -398.818281) (xy 411.245323 -398.793674) (xy 411.207202 -398.762549) (xy 411.174567 -398.725712)
			(xy 411.148264 -398.684116) (xy 411.128973 -398.63884) (xy 411.117196 -398.591056) (xy 411.113236 -398.542002)
			(xy 410.524198 -398.542002) (xy 410.523703 -398.566609) (xy 410.515808 -398.615186) (xy 410.500224 -398.661867)
			(xy 410.477353 -398.705444) (xy 410.447788 -398.744788) (xy 410.412295 -398.77888) (xy 410.371792 -398.806836)
			(xy 410.32733 -398.827934) (xy 410.280059 -398.841626) (xy 410.231204 -398.847558) (xy 410.182029 -398.845577)
			(xy 410.13381 -398.835733) (xy 410.087794 -398.818281) (xy 410.045173 -398.793674) (xy 410.007052 -398.762549)
			(xy 409.974417 -398.725712) (xy 409.948114 -398.684116) (xy 409.928823 -398.63884) (xy 409.917046 -398.591056)
			(xy 409.913086 -398.542002) (xy 409.324302 -398.542002) (xy 409.323807 -398.566609) (xy 409.315912 -398.615186)
			(xy 409.300328 -398.661867) (xy 409.277457 -398.705444) (xy 409.247892 -398.744788) (xy 409.212399 -398.77888)
			(xy 409.171896 -398.806836) (xy 409.127434 -398.827934) (xy 409.080163 -398.841626) (xy 409.031308 -398.847558)
			(xy 408.982133 -398.845577) (xy 408.933914 -398.835733) (xy 408.887898 -398.818281) (xy 408.845277 -398.793674)
			(xy 408.807156 -398.762549) (xy 408.774521 -398.725712) (xy 408.748218 -398.684116) (xy 408.728927 -398.63884)
			(xy 408.71715 -398.591056) (xy 408.71319 -398.542002) (xy 408.124406 -398.542002) (xy 408.123911 -398.566609)
			(xy 408.116016 -398.615186) (xy 408.100432 -398.661867) (xy 408.077561 -398.705444) (xy 408.047996 -398.744788)
			(xy 408.012503 -398.77888) (xy 407.972 -398.806836) (xy 407.927538 -398.827934) (xy 407.880267 -398.841626)
			(xy 407.831412 -398.847558) (xy 407.782237 -398.845577) (xy 407.734018 -398.835733) (xy 407.688002 -398.818281)
			(xy 407.645381 -398.793674) (xy 407.60726 -398.762549) (xy 407.574625 -398.725712) (xy 407.548322 -398.684116)
			(xy 407.529031 -398.63884) (xy 407.517254 -398.591056) (xy 407.513294 -398.542002) (xy 406.924256 -398.542002)
			(xy 406.923761 -398.566609) (xy 406.915866 -398.615186) (xy 406.900282 -398.661867) (xy 406.877411 -398.705444)
			(xy 406.847846 -398.744788) (xy 406.812353 -398.77888) (xy 406.77185 -398.806836) (xy 406.727388 -398.827934)
			(xy 406.680117 -398.841626) (xy 406.631262 -398.847558) (xy 406.582087 -398.845577) (xy 406.533868 -398.835733)
			(xy 406.487852 -398.818281) (xy 406.445231 -398.793674) (xy 406.40711 -398.762549) (xy 406.374475 -398.725712)
			(xy 406.348172 -398.684116) (xy 406.328881 -398.63884) (xy 406.317104 -398.591056) (xy 406.313144 -398.542002)
			(xy 405.72436 -398.542002) (xy 405.723865 -398.566609) (xy 405.71597 -398.615186) (xy 405.700386 -398.661867)
			(xy 405.677515 -398.705444) (xy 405.64795 -398.744788) (xy 405.612457 -398.77888) (xy 405.571954 -398.806836)
			(xy 405.527492 -398.827934) (xy 405.480221 -398.841626) (xy 405.431366 -398.847558) (xy 405.382191 -398.845577)
			(xy 405.333972 -398.835733) (xy 405.287956 -398.818281) (xy 405.245335 -398.793674) (xy 405.207214 -398.762549)
			(xy 405.174579 -398.725712) (xy 405.148276 -398.684116) (xy 405.128985 -398.63884) (xy 405.117208 -398.591056)
			(xy 405.113248 -398.542002) (xy 404.52421 -398.542002) (xy 404.523715 -398.566609) (xy 404.51582 -398.615186)
			(xy 404.500236 -398.661867) (xy 404.477365 -398.705444) (xy 404.4478 -398.744788) (xy 404.412307 -398.77888)
			(xy 404.371804 -398.806836) (xy 404.327342 -398.827934) (xy 404.280071 -398.841626) (xy 404.231216 -398.847558)
			(xy 404.182041 -398.845577) (xy 404.133822 -398.835733) (xy 404.087806 -398.818281) (xy 404.045185 -398.793674)
			(xy 404.007064 -398.762549) (xy 403.974429 -398.725712) (xy 403.948126 -398.684116) (xy 403.928835 -398.63884)
			(xy 403.917058 -398.591056) (xy 403.913098 -398.542002) (xy 403.32406 -398.542002) (xy 403.323565 -398.566609)
			(xy 403.31567 -398.615186) (xy 403.300086 -398.661867) (xy 403.277215 -398.705444) (xy 403.24765 -398.744788)
			(xy 403.212157 -398.77888) (xy 403.171654 -398.806836) (xy 403.127192 -398.827934) (xy 403.079921 -398.841626)
			(xy 403.031066 -398.847558) (xy 402.981891 -398.845577) (xy 402.933672 -398.835733) (xy 402.887656 -398.818281)
			(xy 402.845035 -398.793674) (xy 402.806914 -398.762549) (xy 402.774279 -398.725712) (xy 402.747976 -398.684116)
			(xy 402.728685 -398.63884) (xy 402.716908 -398.591056) (xy 402.712948 -398.542002) (xy 401.038122 -398.542002)
			(xy 401.032011 -398.563185) (xy 401.013006 -398.605589) (xy 400.988251 -398.644915) (xy 400.973544 -398.662906)
			(xy 400.967448 -398.670018) (xy 400.961352 -398.686528) (xy 400.961352 -398.770856) (xy 400.967448 -398.787366)
			(xy 400.973544 -398.794478) (xy 400.988248 -398.812471) (xy 401.012997 -398.851798) (xy 401.031998 -398.894203)
			(xy 401.044878 -398.938849) (xy 401.051382 -398.984859) (xy 401.051776 -399.008092) (xy 401.051365 -399.032185)
			(xy 401.044385 -399.079862) (xy 401.030573 -399.126025) (xy 401.020788 -399.148046) (xy 401.015454 -399.159476)
			(xy 401.016724 -399.184622) (xy 401.072858 -399.278602) (xy 401.094448 -399.291556) (xy 401.107148 -399.292318)
			(xy 401.132143 -399.294174) (xy 401.181187 -399.304504) (xy 401.228111 -399.322116) (xy 401.27184 -399.346607)
			(xy 401.311373 -399.377416) (xy 401.345804 -399.413838) (xy 401.374345 -399.455038) (xy 401.396342 -399.500073)
			(xy 401.411292 -399.547911) (xy 401.418852 -399.597458) (xy 401.419314 -399.622518) (xy 401.418804 -399.648505)
			(xy 401.410674 -399.69984) (xy 401.394613 -399.74927) (xy 401.371017 -399.79558) (xy 401.340467 -399.837628)
			(xy 401.303716 -399.874379) (xy 401.261668 -399.904929) (xy 401.215358 -399.928525) (xy 401.165928 -399.944586)
			(xy 401.114593 -399.952716) (xy 401.062619 -399.952716) (xy 401.011284 -399.944586) (xy 400.961854 -399.928525)
			(xy 400.915544 -399.904929) (xy 400.873496 -399.874379) (xy 400.836745 -399.837628) (xy 400.806195 -399.79558)
			(xy 400.782599 -399.74927) (xy 400.766538 -399.69984) (xy 400.758408 -399.648505) (xy 400.757898 -399.622518)
			(xy 400.758315 -399.598426) (xy 400.765293 -399.550748) (xy 400.779103 -399.504585) (xy 400.788886 -399.482564)
			(xy 400.79422 -399.471134) (xy 400.79295 -399.445988) (xy 400.736816 -399.352008) (xy 400.715226 -399.339054)
			(xy 400.702526 -399.338292) (xy 400.67753 -399.336448) (xy 400.628486 -399.326115) (xy 400.581563 -399.3085)
			(xy 400.537835 -399.284007) (xy 400.498303 -399.253197) (xy 400.463872 -399.216774) (xy 400.435331 -399.175573)
			(xy 400.413334 -399.130538) (xy 400.398383 -399.082699) (xy 400.390822 -399.033152) (xy 400.39036 -399.008092)
			(xy 397.467133 -399.008092) (xy 397.475844 -399.012215) (xy 397.5208 -399.041872) (xy 397.561137 -399.077557)
			(xy 397.596055 -399.11856) (xy 397.624859 -399.164067) (xy 397.646976 -399.213172) (xy 397.661968 -399.2649)
			(xy 397.669535 -399.318222) (xy 397.67002 -399.34515) (xy 397.669295 -399.379439) (xy 397.657021 -399.44691)
			(xy 397.645636 -399.479262) (xy 397.641064 -399.491454) (xy 397.644366 -399.516346) (xy 397.708374 -399.605754)
			(xy 397.730726 -399.61693) (xy 397.74368 -399.616676) (xy 397.754602 -399.616422) (xy 397.781972 -399.616894)
			(xy 397.83615 -399.624718) (xy 397.888653 -399.640206) (xy 397.938403 -399.66304) (xy 397.984379 -399.69275)
			(xy 398.0053 -399.710402) (xy 398.012412 -399.716498) (xy 398.02943 -399.722848) (xy 398.114774 -399.722848)
			(xy 398.131792 -399.716498) (xy 398.138904 -399.710402) (xy 398.159837 -399.692761) (xy 398.205805 -399.663037)
			(xy 398.255551 -399.640191) (xy 398.308053 -399.624695) (xy 398.362231 -399.616866) (xy 398.416973 -399.616866)
			(xy 398.471151 -399.624695) (xy 398.523653 -399.640191) (xy 398.573399 -399.663037) (xy 398.619367 -399.692761)
			(xy 398.6403 -399.710402) (xy 398.647412 -399.716498) (xy 398.66443 -399.722848) (xy 398.749774 -399.722848)
			(xy 398.766792 -399.716498) (xy 398.773904 -399.710402) (xy 398.794835 -399.69276) (xy 398.840802 -399.663034)
			(xy 398.890549 -399.640192) (xy 398.943052 -399.624702) (xy 398.997232 -399.616884) (xy 399.024602 -399.616422)
			(xy 399.051854 -399.616885) (xy 399.105803 -399.624643) (xy 399.158099 -399.639999) (xy 399.207677 -399.662642)
			(xy 399.253528 -399.692111) (xy 399.294718 -399.727805) (xy 399.330408 -399.768998) (xy 399.359873 -399.814851)
			(xy 399.382512 -399.864431) (xy 399.397864 -399.916728) (xy 399.405617 -399.970678) (xy 399.40611 -399.99793)
			(xy 399.405636 -400.025299) (xy 399.397809 -400.079476) (xy 399.382319 -400.131977) (xy 399.359484 -400.181726)
			(xy 399.329774 -400.2277) (xy 399.31213 -400.248628) (xy 399.306034 -400.25574) (xy 399.299684 -400.272758)
			(xy 399.299684 -400.358102) (xy 399.306034 -400.37512) (xy 399.31213 -400.382232) (xy 399.32977 -400.403164)
			(xy 399.359494 -400.44913) (xy 399.382338 -400.498875) (xy 399.397832 -400.551376) (xy 399.405658 -400.605553)
			(xy 399.405655 -400.660292) (xy 399.397823 -400.714468) (xy 399.382322 -400.766967) (xy 399.359472 -400.81671)
			(xy 399.329743 -400.862672) (xy 399.31213 -400.883628) (xy 399.306034 -400.89074) (xy 399.299684 -400.907758)
			(xy 399.299684 -400.993102) (xy 399.306034 -401.01012) (xy 399.31213 -401.017232) (xy 399.32977 -401.038164)
			(xy 399.359494 -401.08413) (xy 399.382338 -401.133875) (xy 399.397832 -401.186376) (xy 399.405658 -401.240553)
			(xy 399.405655 -401.295292) (xy 399.397823 -401.349468) (xy 399.382322 -401.401967) (xy 399.359472 -401.45171)
			(xy 399.329743 -401.497672) (xy 399.31213 -401.518628) (xy 399.306034 -401.52574) (xy 399.299684 -401.542758)
			(xy 399.299684 -401.628102) (xy 399.306034 -401.64512) (xy 399.31213 -401.652232) (xy 399.327603 -401.670554)
			(xy 399.354345 -401.710362) (xy 399.375903 -401.7532) (xy 399.384266 -401.775676) (xy 399.387568 -401.785074)
			(xy 399.40103 -401.80006) (xy 399.475452 -401.835366) (xy 399.484789 -401.839197) (xy 399.504928 -401.840127)
			(xy 399.514568 -401.837144) (xy 400.061684 -401.639278) (xy 400.061938 -401.639278) (xy 400.073164 -401.635077)
			(xy 400.09527 -401.625801) (xy 400.106134 -401.620736) (xy 400.10715 -401.620482) (xy 400.175476 -401.588478)
			(xy 400.186486 -401.582734) (xy 400.201541 -401.563021) (xy 400.204178 -401.550886) (xy 400.22018 -401.45589)
			(xy 400.21256 -401.432522) (xy 400.203416 -401.423632) (xy 400.185553 -401.405615) (xy 400.154262 -401.365678)
			(xy 400.12854 -401.321947) (xy 400.108842 -401.275191) (xy 400.095514 -401.226238) (xy 400.088792 -401.17595)
			(xy 400.088354 -401.150582) (xy 400.088637 -401.130294) (xy 400.092964 -401.08995) (xy 400.09699 -401.070064)
			(xy 400.099276 -401.059396) (xy 400.094704 -401.038314) (xy 400.036538 -400.95932) (xy 400.017742 -400.948652)
			(xy 400.00682 -400.947636) (xy 399.978729 -400.944573) (xy 399.923824 -400.931222) (xy 399.871489 -400.909918)
			(xy 399.822869 -400.881127) (xy 399.779027 -400.84548) (xy 399.740923 -400.803756) (xy 399.70939 -400.756868)
			(xy 399.685118 -400.705841) (xy 399.668638 -400.651793) (xy 399.66031 -400.595905) (xy 399.659856 -400.567652)
			(xy 399.660342 -400.540401) (xy 399.668098 -400.486453) (xy 399.683453 -400.434158) (xy 399.706095 -400.384581)
			(xy 399.735561 -400.338731) (xy 399.771252 -400.29754) (xy 399.812443 -400.261849) (xy 399.858293 -400.232383)
			(xy 399.90787 -400.209741) (xy 399.960165 -400.194386) (xy 400.014113 -400.18663) (xy 400.068615 -400.18663)
			(xy 400.122563 -400.194386) (xy 400.174858 -400.209741) (xy 400.224435 -400.232383) (xy 400.270285 -400.261849)
			(xy 400.311476 -400.29754) (xy 400.347167 -400.338731) (xy 400.376633 -400.384581) (xy 400.399275 -400.434158)
			(xy 400.41463 -400.486453) (xy 400.422386 -400.540401) (xy 400.422872 -400.567652) (xy 400.422587 -400.587939)
			(xy 400.418257 -400.628283) (xy 400.414236 -400.64817) (xy 400.41195 -400.658838) (xy 400.416522 -400.67992)
			(xy 400.474688 -400.758914) (xy 400.493484 -400.769582) (xy 400.504406 -400.770598) (xy 400.531016 -400.773463)
			(xy 400.583119 -400.7857) (xy 400.632998 -400.805103) (xy 400.679673 -400.831292) (xy 400.722227 -400.863751)
			(xy 400.759823 -400.901842) (xy 400.791723 -400.944817) (xy 400.817299 -400.99183) (xy 400.836048 -401.041959)
			(xy 400.847603 -401.094217) (xy 400.8501 -401.120864) (xy 400.851116 -401.133564) (xy 400.864324 -401.154392)
			(xy 400.947382 -401.202906) (xy 400.958392 -401.208634) (xy 400.98316 -401.209691) (xy 400.994626 -401.204938)
			(xy 401.355052 -401.036282) (xy 401.372223 -401.028211) (xy 401.406137 -401.01119) (xy 401.42287 -401.002246)
			(xy 401.423124 -401.001992) (xy 401.488833 -400.967206) (xy 401.624482 -400.906311) (xy 401.694142 -400.880326)
			(xy 401.694904 -400.880072) (xy 401.78736 -400.846798) (xy 401.805648 -400.812762) (xy 401.801076 -400.793712)
			(xy 401.796814 -400.774757) (xy 401.792235 -400.736176) (xy 401.791932 -400.71675) (xy 401.792398 -400.691679)
			(xy 401.79997 -400.642111) (xy 401.814931 -400.594253) (xy 401.836941 -400.549199) (xy 401.865495 -400.507981)
			(xy 401.882356 -400.48942) (xy 401.889214 -400.482308) (xy 401.896326 -400.464274) (xy 401.896326 -400.410426)
			(xy 401.889214 -400.392392) (xy 401.882356 -400.38528) (xy 401.865474 -400.366739) (xy 401.836929 -400.325514)
			(xy 401.814931 -400.280454) (xy 401.799982 -400.232592) (xy 401.792424 -400.183021) (xy 401.791932 -400.15795)
			(xy 401.792411 -400.131959) (xy 401.800537 -400.080617) (xy 401.816595 -400.031178) (xy 401.840191 -399.984861)
			(xy 401.870743 -399.942806) (xy 401.907499 -399.906049) (xy 401.949553 -399.875496) (xy 401.995869 -399.851899)
			(xy 402.045307 -399.835839) (xy 402.096649 -399.827712) (xy 402.12264 -399.827242) (xy 402.149552 -399.827774)
			(xy 402.202664 -399.836501) (xy 402.253661 -399.853717) (xy 402.301194 -399.878968) (xy 402.344009 -399.911586)
			(xy 402.380974 -399.95071) (xy 402.411112 -399.995305) (xy 402.422868 -400.01952) (xy 402.429218 -400.032982)
			(xy 402.45411 -400.048984) (xy 403.159976 -400.048984) (xy 403.1718 -400.048437) (xy 403.193002 -400.03798)
			(xy 403.200616 -400.028918) (xy 403.216486 -400.008744) (xy 403.253807 -399.973509) (xy 403.296498 -399.945018)
			(xy 403.343356 -399.924072) (xy 403.393058 -399.911264) (xy 403.444202 -399.906954) (xy 403.495346 -399.911264)
			(xy 403.545048 -399.924072) (xy 403.591906 -399.945018) (xy 403.634597 -399.973509) (xy 403.671918 -400.008744)
			(xy 403.687788 -400.028918) (xy 403.695433 -400.03794) (xy 403.716616 -400.048388) (xy 403.728428 -400.048984)
			(xy 404.360126 -400.048984) (xy 404.371945 -400.048427) (xy 404.39313 -400.037957) (xy 404.400766 -400.028918)
			(xy 404.416636 -400.008744) (xy 404.453957 -399.973509) (xy 404.496648 -399.945018) (xy 404.543506 -399.924072)
			(xy 404.593208 -399.911264) (xy 404.644352 -399.906954) (xy 404.695496 -399.911264) (xy 404.745198 -399.924072)
			(xy 404.792056 -399.945018) (xy 404.834747 -399.973509) (xy 404.872068 -400.008744) (xy 404.887938 -400.028918)
			(xy 404.89558 -400.037948) (xy 404.916763 -400.048417) (xy 404.928578 -400.048984) (xy 405.560022 -400.048984)
			(xy 405.571841 -400.048428) (xy 405.593027 -400.037959) (xy 405.600662 -400.028918) (xy 405.616532 -400.008744)
			(xy 405.653853 -399.973509) (xy 405.696544 -399.945018) (xy 405.743402 -399.924072) (xy 405.793104 -399.911264)
			(xy 405.844248 -399.906954) (xy 405.895392 -399.911264) (xy 405.945094 -399.924072) (xy 405.991952 -399.945018)
			(xy 406.034643 -399.973509) (xy 406.071964 -400.008744) (xy 406.087834 -400.028918) (xy 406.095475 -400.037949)
			(xy 406.116659 -400.048419) (xy 406.128474 -400.048984) (xy 406.759918 -400.048984) (xy 406.771738 -400.048429)
			(xy 406.792925 -400.037961) (xy 406.800558 -400.028918) (xy 406.816428 -400.008744) (xy 406.853749 -399.973509)
			(xy 406.89644 -399.945018) (xy 406.943298 -399.924072) (xy 406.993 -399.911264) (xy 407.044144 -399.906954)
			(xy 407.095288 -399.911264) (xy 407.14499 -399.924072) (xy 407.191848 -399.945018) (xy 407.234539 -399.973509)
			(xy 407.27186 -400.008744) (xy 407.28773 -400.028918) (xy 407.295371 -400.03795) (xy 407.316554 -400.048422)
			(xy 407.32837 -400.048984) (xy 407.960068 -400.048984) (xy 407.971893 -400.048439) (xy 407.993098 -400.037984)
			(xy 408.000708 -400.028918) (xy 408.016578 -400.008744) (xy 408.053899 -399.973509) (xy 408.09659 -399.945018)
			(xy 408.143448 -399.924072) (xy 408.19315 -399.911264) (xy 408.244294 -399.906954) (xy 408.295438 -399.911264)
			(xy 408.34514 -399.924072) (xy 408.391998 -399.945018) (xy 408.434689 -399.973509) (xy 408.47201 -400.008744)
			(xy 408.48788 -400.028918) (xy 408.495524 -400.037941) (xy 408.516708 -400.048392) (xy 408.52852 -400.048984)
			(xy 409.159964 -400.048984) (xy 409.17179 -400.04844) (xy 409.192996 -400.037985) (xy 409.200604 -400.028918)
			(xy 409.216474 -400.008744) (xy 409.253795 -399.973509) (xy 409.296486 -399.945018) (xy 409.343344 -399.924072)
			(xy 409.393046 -399.911264) (xy 409.44419 -399.906954) (xy 409.495334 -399.911264) (xy 409.545036 -399.924072)
			(xy 409.591894 -399.945018) (xy 409.634585 -399.973509) (xy 409.671906 -400.008744) (xy 409.687776 -400.028918)
			(xy 409.69542 -400.037942) (xy 409.716604 -400.048395) (xy 409.728416 -400.048984) (xy 410.360114 -400.048984)
			(xy 410.371934 -400.048429) (xy 410.393123 -400.037962) (xy 410.400754 -400.028918) (xy 410.416624 -400.008744)
			(xy 410.453945 -399.973509) (xy 410.496636 -399.945018) (xy 410.543494 -399.924072) (xy 410.593196 -399.911264)
			(xy 410.64434 -399.906954) (xy 410.695484 -399.911264) (xy 410.745186 -399.924072) (xy 410.792044 -399.945018)
			(xy 410.834735 -399.973509) (xy 410.872056 -400.008744) (xy 410.887926 -400.028918) (xy 410.895567 -400.037951)
			(xy 410.91675 -400.048424) (xy 410.928566 -400.048984) (xy 411.56001 -400.048984) (xy 411.57183 -400.04843)
			(xy 411.593021 -400.037964) (xy 411.60065 -400.028918) (xy 411.61652 -400.008744) (xy 411.653841 -399.973509)
			(xy 411.696532 -399.945018) (xy 411.74339 -399.924072) (xy 411.793092 -399.911264) (xy 411.844236 -399.906954)
			(xy 411.89538 -399.911264) (xy 411.945082 -399.924072) (xy 411.99194 -399.945018) (xy 412.034631 -399.973509)
			(xy 412.071952 -400.008744) (xy 412.087822 -400.028918) (xy 412.095462 -400.037951) (xy 412.116646 -400.048426)
			(xy 412.128462 -400.048984) (xy 412.759906 -400.048984) (xy 412.771727 -400.048431) (xy 412.792919 -400.037966)
			(xy 412.800546 -400.028918) (xy 412.816416 -400.008744) (xy 412.853737 -399.973509) (xy 412.896428 -399.945018)
			(xy 412.943286 -399.924072) (xy 412.992988 -399.911264) (xy 413.044132 -399.906954) (xy 413.095276 -399.911264)
			(xy 413.144978 -399.924072) (xy 413.191836 -399.945018) (xy 413.234527 -399.973509) (xy 413.271848 -400.008744)
			(xy 413.287718 -400.028918) (xy 413.295358 -400.037952) (xy 413.316541 -400.048429) (xy 413.328358 -400.048984)
			(xy 413.960056 -400.048984) (xy 413.971882 -400.048442) (xy 413.993091 -400.037989) (xy 414.000696 -400.028918)
			(xy 414.016566 -400.008744) (xy 414.053887 -399.973509) (xy 414.096578 -399.945018) (xy 414.143436 -399.924072)
			(xy 414.193138 -399.911264) (xy 414.244282 -399.906954) (xy 414.295426 -399.911264) (xy 414.345128 -399.924072)
			(xy 414.391986 -399.945018) (xy 414.434677 -399.973509) (xy 414.471998 -400.008744) (xy 414.487868 -400.028918)
			(xy 414.495511 -400.037944) (xy 414.516695 -400.0484) (xy 414.528508 -400.048984) (xy 415.159952 -400.048984)
			(xy 415.171779 -400.048443) (xy 415.192989 -400.037991) (xy 415.200592 -400.028918) (xy 415.216462 -400.008744)
			(xy 415.253783 -399.973509) (xy 415.296474 -399.945018) (xy 415.343332 -399.924072) (xy 415.393034 -399.911264)
			(xy 415.444178 -399.906954) (xy 415.495322 -399.911264) (xy 415.545024 -399.924072) (xy 415.591882 -399.945018)
			(xy 415.634573 -399.973509) (xy 415.671894 -400.008744) (xy 415.687764 -400.028918) (xy 415.695407 -400.037944)
			(xy 415.716591 -400.048402) (xy 415.728404 -400.048984) (xy 416.360102 -400.048984) (xy 416.371923 -400.048432)
			(xy 416.393117 -400.037968) (xy 416.400742 -400.028918) (xy 416.415252 -400.010401) (xy 416.449007 -399.977636)
			(xy 416.487392 -399.950441) (xy 416.529496 -399.929461) (xy 416.574322 -399.915194) (xy 416.620807 -399.907976)
			(xy 416.644328 -399.907506) (xy 416.667386 -399.907921) (xy 416.712978 -399.914844) (xy 416.757011 -399.928543)
			(xy 416.798484 -399.948706) (xy 416.836455 -399.974876) (xy 416.870058 -400.006457) (xy 416.884612 -400.024346)
			(xy 416.892151 -400.03314) (xy 416.912922 -400.043338) (xy 416.92449 -400.043904) (xy 417.564062 -400.043904)
			(xy 417.575616 -400.043283) (xy 417.596364 -400.033093) (xy 417.60394 -400.024346) (xy 417.619878 -400.004882)
			(xy 417.657011 -399.970944) (xy 417.699201 -399.943548) (xy 417.745309 -399.923433) (xy 417.794089 -399.911143)
			(xy 417.844224 -399.907009) (xy 417.894359 -399.911143) (xy 417.943139 -399.923433) (xy 417.989247 -399.943548)
			(xy 418.031437 -399.970944) (xy 418.06857 -400.004882) (xy 418.084508 -400.024346) (xy 418.092047 -400.033141)
			(xy 418.112817 -400.04334) (xy 418.124386 -400.043904) (xy 418.763958 -400.043904) (xy 418.775512 -400.043283)
			(xy 418.796262 -400.033095) (xy 418.803836 -400.024346) (xy 418.819774 -400.004882) (xy 418.856907 -399.970944)
			(xy 418.899097 -399.943548) (xy 418.945205 -399.923433) (xy 418.993985 -399.911143) (xy 419.04412 -399.907009)
			(xy 419.094255 -399.911143) (xy 419.143035 -399.923433) (xy 419.189143 -399.943548) (xy 419.231333 -399.970944)
			(xy 419.268466 -400.004882) (xy 419.284404 -400.024346) (xy 419.291942 -400.033141) (xy 419.312713 -400.043342)
			(xy 419.324282 -400.043904) (xy 419.964108 -400.043904) (xy 419.975667 -400.043294) (xy 419.996434 -400.033117)
			(xy 420.003986 -400.024346) (xy 420.019924 -400.004882) (xy 420.057057 -399.970944) (xy 420.099247 -399.943548)
			(xy 420.145355 -399.923433) (xy 420.194135 -399.911143) (xy 420.24427 -399.907009) (xy 420.294405 -399.911143)
			(xy 420.343185 -399.923433) (xy 420.389293 -399.943548) (xy 420.431483 -399.970944) (xy 420.468616 -400.004882)
			(xy 420.484554 -400.024346) (xy 420.492096 -400.033133) (xy 420.512867 -400.043314) (xy 420.524432 -400.043904)
			(xy 421.164004 -400.043904) (xy 421.175564 -400.043294) (xy 421.196331 -400.033119) (xy 421.203882 -400.024346)
			(xy 421.21982 -400.004882) (xy 421.256953 -399.970944) (xy 421.299143 -399.943548) (xy 421.345251 -399.923433)
			(xy 421.394031 -399.911143) (xy 421.444166 -399.907009) (xy 421.494301 -399.911143) (xy 421.543081 -399.923433)
			(xy 421.589189 -399.943548) (xy 421.631379 -399.970944) (xy 421.668512 -400.004882) (xy 421.68445 -400.024346)
			(xy 421.691991 -400.033134) (xy 421.712763 -400.043316) (xy 421.724328 -400.043904) (xy 421.818054 -400.043904)
			(xy 421.82812 -400.043471) (xy 421.84671 -400.035743) (xy 421.854122 -400.028918) (xy 422.277794 -399.605246)
			(xy 422.284633 -399.597845) (xy 422.292348 -399.579247) (xy 422.29278 -399.569178) (xy 422.29278 -398.88414)
			(xy 422.274746 -398.858232) (xy 422.259506 -398.852644) (xy 422.235961 -398.843534) (xy 422.191728 -398.819206)
			(xy 422.151706 -398.788438) (xy 422.116824 -398.751945) (xy 422.087894 -398.710574) (xy 422.065587 -398.665288)
			(xy 422.050421 -398.617138) (xy 422.042749 -398.567242) (xy 422.042749 -398.51676) (xy 422.050421 -398.466864)
			(xy 422.065587 -398.418713) (xy 422.087894 -398.373427) (xy 422.116824 -398.332057) (xy 422.151705 -398.295563)
			(xy 422.191727 -398.264795) (xy 422.23596 -398.240466) (xy 422.259506 -398.23136) (xy 422.274746 -398.225772)
			(xy 422.29278 -398.199864) (xy 422.29278 -397.805402) (xy 422.292357 -397.795332) (xy 422.284641 -397.776729)
			(xy 422.277794 -397.769334) (xy 422.200832 -397.692372) (xy 422.193398 -397.685656) (xy 422.174898 -397.67802)
			(xy 422.154884 -397.67802) (xy 422.136384 -397.685656) (xy 422.12895 -397.692372) (xy 422.118536 -397.702786)
			(xy 422.112186 -397.731234) (xy 422.117012 -397.74495) (xy 422.125291 -397.770252) (xy 422.134225 -397.822728)
			(xy 422.134792 -397.849344) (xy 422.134327 -397.874147) (xy 422.126557 -397.92314) (xy 422.111216 -397.970314)
			(xy 422.088681 -398.014505) (xy 422.059509 -398.054626) (xy 422.024417 -398.089687) (xy 421.984271 -398.118825)
			(xy 421.94006 -398.141321) (xy 421.892873 -398.156621) (xy 421.843873 -398.164348) (xy 421.81907 -398.164812)
			(xy 421.793678 -398.164302) (xy 421.743548 -398.156168) (xy 421.695368 -398.140114) (xy 421.650379 -398.116554)
			(xy 421.609741 -398.086096) (xy 421.574503 -398.049526) (xy 421.545573 -398.007787) (xy 421.523698 -397.961955)
			(xy 421.516048 -397.937736) (xy 421.514524 -397.931894) (xy 421.19423 -397.378174) (xy 421.190166 -397.373856)
			(xy 421.173979 -397.356146) (xy 421.146606 -397.316742) (xy 421.125519 -397.273647) (xy 421.111204 -397.227854)
			(xy 421.103991 -397.180422) (xy 421.103552 -397.156432) (xy 421.103638 -397.144384) (xy 421.105421 -397.120355)
			(xy 421.107108 -397.108426) (xy 421.108378 -397.099536) (xy 421.10533 -397.082518) (xy 421.063166 -397.011652)
			(xy 421.049958 -397.000476) (xy 421.041576 -396.997428) (xy 421.018518 -396.988495) (xy 420.975411 -396.96427)
			(xy 420.936766 -396.933423) (xy 420.903589 -396.896758) (xy 420.876746 -396.855231) (xy 420.856937 -396.809925)
			(xy 420.850314 -396.7861) (xy 420.845996 -396.769082) (xy 420.818818 -396.748) (xy 420.501826 -396.748)
			(xy 420.491649 -396.748448) (xy 420.472897 -396.756358) (xy 420.458699 -396.770941) (xy 420.454582 -396.780258)
			(xy 420.414196 -396.883382) (xy 420.421308 -396.913608) (xy 420.432992 -396.924276) (xy 420.453672 -396.944185)
			(xy 420.488168 -396.990061) (xy 420.513818 -397.041409) (xy 420.5224 -397.068802) (xy 420.523924 -397.074644)
			(xy 420.84371 -397.627602) (xy 420.847774 -397.63192) (xy 420.863966 -397.649628) (xy 420.891346 -397.68903)
			(xy 420.91244 -397.732125) (xy 420.926762 -397.777918) (xy 420.93398 -397.825353) (xy 420.934388 -397.849344)
			(xy 420.933899 -397.874132) (xy 420.926138 -397.923097) (xy 420.910813 -397.970245) (xy 420.888303 -398.014415)
			(xy 420.85916 -398.054522) (xy 420.824103 -398.089576) (xy 420.783995 -398.118715) (xy 420.739822 -398.141222)
			(xy 420.692673 -398.156543) (xy 420.643708 -398.164301) (xy 420.61892 -398.164812) (xy 420.593525 -398.164306)
			(xy 420.543391 -398.156178) (xy 420.495204 -398.140129) (xy 420.450208 -398.116572) (xy 420.409563 -398.086116)
			(xy 420.374319 -398.049546) (xy 420.345383 -398.007805) (xy 420.323504 -397.96197) (xy 420.315898 -397.937736)
			(xy 420.314374 -397.931894) (xy 419.993826 -397.377412) (xy 419.989762 -397.373094) (xy 419.973683 -397.355416)
			(xy 419.946496 -397.316118) (xy 419.925538 -397.273173) (xy 419.911288 -397.227562) (xy 419.90407 -397.180325)
			(xy 419.903656 -397.156432) (xy 419.903742 -397.144384) (xy 419.905525 -397.120355) (xy 419.907212 -397.108426)
			(xy 419.908482 -397.099536) (xy 419.905434 -397.082518) (xy 419.86327 -397.011652) (xy 419.850062 -397.000476)
			(xy 419.84168 -396.997428) (xy 419.818621 -396.988496) (xy 419.775515 -396.964271) (xy 419.736869 -396.933424)
			(xy 419.703692 -396.896759) (xy 419.676848 -396.855232) (xy 419.657038 -396.809926) (xy 419.650418 -396.7861)
			(xy 419.6461 -396.769082) (xy 419.618922 -396.748) (xy 419.301676 -396.748) (xy 419.291494 -396.748439)
			(xy 419.272725 -396.756339) (xy 419.258512 -396.770921) (xy 419.254432 -396.780258) (xy 419.214046 -396.883382)
			(xy 419.221158 -396.913608) (xy 419.232842 -396.924276) (xy 419.253433 -396.944084) (xy 419.287802 -396.989719)
			(xy 419.313401 -397.040792) (xy 419.321996 -397.06804) (xy 419.32352 -397.073882) (xy 419.643814 -397.627602)
			(xy 419.647878 -397.63192) (xy 419.664069 -397.649628) (xy 419.691449 -397.68903) (xy 419.712543 -397.732125)
			(xy 419.726865 -397.777918) (xy 419.734083 -397.825353) (xy 419.734492 -397.849344) (xy 419.734003 -397.874132)
			(xy 419.726242 -397.923097) (xy 419.710917 -397.970245) (xy 419.688407 -398.014416) (xy 419.659264 -398.054523)
			(xy 419.624208 -398.089577) (xy 419.584099 -398.118717) (xy 419.539927 -398.141225) (xy 419.492778 -398.156546)
			(xy 419.443812 -398.164304) (xy 419.419024 -398.164812) (xy 419.393629 -398.164306) (xy 419.343494 -398.156179)
			(xy 419.295306 -398.14013) (xy 419.25031 -398.116574) (xy 419.209665 -398.086118) (xy 419.17442 -398.049547)
			(xy 419.145484 -398.007806) (xy 419.123604 -397.961971) (xy 419.116002 -397.937736) (xy 419.114478 -397.931894)
			(xy 418.794184 -397.378174) (xy 418.79012 -397.373856) (xy 418.773904 -397.356158) (xy 418.746472 -397.316769)
			(xy 418.725327 -397.273677) (xy 418.710956 -397.227879) (xy 418.703692 -397.180432) (xy 418.703252 -397.156432)
			(xy 418.70341 -397.14438) (xy 418.705319 -397.120352) (xy 418.707062 -397.108426) (xy 418.708332 -397.099536)
			(xy 418.705284 -397.082518) (xy 418.66312 -397.011652) (xy 418.649912 -397.000476) (xy 418.64153 -396.997428)
			(xy 418.619792 -396.98902) (xy 418.578954 -396.966563) (xy 418.542002 -396.938161) (xy 418.509795 -396.904474)
			(xy 418.483081 -396.866284) (xy 418.462481 -396.824479) (xy 418.448472 -396.780028) (xy 418.441381 -396.733965)
			(xy 418.44087 -396.710662) (xy 418.440963 -396.700406) (xy 418.442364 -396.679942) (xy 418.443664 -396.669768)
			(xy 418.445188 -396.658084) (xy 418.437568 -396.635478) (xy 418.002974 -396.200884) (xy 417.993969 -396.192854)
			(xy 417.97104 -396.185456) (xy 417.959032 -396.18666) (xy 417.865814 -396.201392) (xy 417.846256 -396.215362)
			(xy 417.840668 -396.226284) (xy 417.830035 -396.246298) (xy 417.804111 -396.283474) (xy 417.773353 -396.31676)
			(xy 417.756086 -396.33144) (xy 417.747196 -396.338552) (xy 417.737798 -396.35811) (xy 417.735004 -396.457424)
			(xy 417.74364 -396.47749) (xy 417.752022 -396.48511) (xy 417.770443 -396.502599) (xy 417.801782 -396.542567)
			(xy 417.826077 -396.58717) (xy 417.842658 -396.635178) (xy 417.851067 -396.685267) (xy 417.85159 -396.710662)
			(xy 417.851518 -396.72002) (xy 417.850372 -396.738702) (xy 417.849304 -396.748) (xy 417.848288 -396.75689)
			(xy 417.852098 -396.773654) (xy 417.89604 -396.843504) (xy 417.909756 -396.853918) (xy 417.918138 -396.856712)
			(xy 417.942232 -396.865198) (xy 417.987514 -396.888832) (xy 418.028401 -396.919447) (xy 418.063828 -396.956244)
			(xy 418.092869 -396.998263) (xy 418.114768 -397.04441) (xy 418.122354 -397.068802) (xy 418.123878 -397.074644)
			(xy 418.443664 -397.627602) (xy 418.447728 -397.63192) (xy 418.463944 -397.649619) (xy 418.491374 -397.689009)
			(xy 418.512519 -397.7321) (xy 418.526891 -397.777898) (xy 418.534157 -397.825344) (xy 418.534596 -397.849344)
			(xy 418.534131 -397.874147) (xy 418.526361 -397.92314) (xy 418.51102 -397.970314) (xy 418.488486 -398.014506)
			(xy 418.459313 -398.054627) (xy 418.424222 -398.089689) (xy 418.384076 -398.118827) (xy 418.339864 -398.141323)
			(xy 418.292677 -398.156624) (xy 418.243677 -398.164352) (xy 418.218874 -398.164812) (xy 418.193481 -398.164302)
			(xy 418.143352 -398.156168) (xy 418.095171 -398.140115) (xy 418.050181 -398.116555) (xy 418.009543 -398.086098)
			(xy 417.974304 -398.049528) (xy 417.945374 -398.007788) (xy 417.923498 -397.961956) (xy 417.915852 -397.937736)
			(xy 417.914328 -397.931894) (xy 417.59378 -397.377412) (xy 417.589716 -397.373094) (xy 417.573613 -397.355425)
			(xy 417.546375 -397.316139) (xy 417.525366 -397.273198) (xy 417.511065 -397.227583) (xy 417.5038 -397.180334)
			(xy 417.503356 -397.156432) (xy 417.503514 -397.14438) (xy 417.505423 -397.120352) (xy 417.507166 -397.108426)
			(xy 417.508436 -397.099536) (xy 417.505388 -397.082518) (xy 417.463224 -397.011652) (xy 417.450016 -397.000476)
			(xy 417.441634 -396.997428) (xy 417.419896 -396.98902) (xy 417.379057 -396.966564) (xy 417.342105 -396.938162)
			(xy 417.309897 -396.904475) (xy 417.283183 -396.866285) (xy 417.262582 -396.824479) (xy 417.248573 -396.780028)
			(xy 417.241482 -396.733965) (xy 417.240974 -396.710662) (xy 417.241473 -396.685264) (xy 417.249873 -396.635167)
			(xy 417.266449 -396.587151) (xy 417.290746 -396.542542) (xy 417.322092 -396.502571) (xy 417.340542 -396.48511)
			(xy 417.348924 -396.47749) (xy 417.35756 -396.457424) (xy 417.354766 -396.35811) (xy 417.345368 -396.338552)
			(xy 417.336478 -396.33144) (xy 417.317918 -396.315637) (xy 417.285193 -396.279509) (xy 417.258122 -396.238972)
			(xy 417.237291 -396.194902) (xy 417.22315 -396.148253) (xy 417.216004 -396.100035) (xy 417.215574 -396.075662)
			(xy 417.216013 -396.051546) (xy 417.223018 -396.003825) (xy 417.236874 -395.957627) (xy 417.257289 -395.913928)
			(xy 417.270184 -395.893544) (xy 417.276026 -395.884654) (xy 417.279582 -395.864588) (xy 417.2585 -395.772386)
			(xy 417.246308 -395.755622) (xy 417.237418 -395.750288) (xy 417.216613 -395.737435) (xy 417.178688 -395.70656)
			(xy 417.145731 -395.670431) (xy 417.118462 -395.629838) (xy 417.097475 -395.585667) (xy 417.083231 -395.538885)
			(xy 417.076041 -395.490514) (xy 417.07562 -395.466062) (xy 417.076388 -395.434132) (xy 417.088665 -395.371461)
			(xy 417.100004 -395.341602) (xy 417.105592 -395.327378) (xy 417.09975 -395.29766) (xy 417.063682 -395.261592)
			(xy 417.056282 -395.25475) (xy 417.037684 -395.247023) (xy 417.027614 -395.246606) (xy 415.553144 -395.246606)
			(xy 415.541723 -395.247061) (xy 415.521088 -395.256838) (xy 415.51352 -395.265402) (xy 415.456624 -395.336014)
			(xy 415.45129 -395.358366) (xy 415.45383 -395.369542) (xy 415.458627 -395.393382) (xy 415.463714 -395.441746)
			(xy 415.46399 -395.466062) (xy 415.463386 -395.499382) (xy 415.453717 -395.565317) (xy 415.434592 -395.629154)
			(xy 415.421064 -395.65961) (xy 415.416802 -395.670079) (xy 415.416877 -395.692653) (xy 415.426631 -395.713011)
			(xy 415.435034 -395.72057) (xy 415.457281 -395.739244) (xy 415.497345 -395.7813) (xy 415.531766 -395.828086)
			(xy 415.559993 -395.878851) (xy 415.58157 -395.932779) (xy 415.596153 -395.989003) (xy 415.603505 -396.04662)
			(xy 415.603944 -396.075662) (xy 415.603493 -396.104666) (xy 415.596163 -396.16221) (xy 415.581627 -396.218368)
			(xy 415.560119 -396.272242) (xy 415.531982 -396.32297) (xy 415.497666 -396.36974) (xy 415.457721 -396.411804)
			(xy 415.435542 -396.4305) (xy 415.42843 -396.436088) (xy 415.419286 -396.451328) (xy 415.404046 -396.534132)
			(xy 415.40684 -396.551404) (xy 415.411412 -396.559532) (xy 415.424005 -396.582711) (xy 415.441891 -396.632331)
			(xy 415.450973 -396.684289) (xy 415.451544 -396.710662) (xy 416.040824 -396.710662) (xy 416.041346 -396.685407)
			(xy 416.049659 -396.635585) (xy 416.06606 -396.587811) (xy 416.090101 -396.543388) (xy 416.121125 -396.503528)
			(xy 416.158287 -396.469318) (xy 416.200573 -396.441692) (xy 416.246829 -396.421402) (xy 416.295794 -396.409002)
			(xy 416.346132 -396.404831) (xy 416.39647 -396.409002) (xy 416.445435 -396.421402) (xy 416.491691 -396.441692)
			(xy 416.533977 -396.469318) (xy 416.571139 -396.503528) (xy 416.602163 -396.543388) (xy 416.626204 -396.587811)
			(xy 416.642605 -396.635585) (xy 416.650918 -396.685407) (xy 416.65144 -396.710662) (xy 416.651371 -396.720021)
			(xy 416.650228 -396.738703) (xy 416.649154 -396.748) (xy 416.648138 -396.75689) (xy 416.651948 -396.773654)
			(xy 416.69589 -396.843504) (xy 416.709606 -396.853918) (xy 416.717988 -396.856712) (xy 416.742006 -396.865208)
			(xy 416.78718 -396.888753) (xy 416.827986 -396.919246) (xy 416.863368 -396.955896) (xy 416.892405 -396.997751)
			(xy 416.914346 -397.043726) (xy 416.92195 -397.06804) (xy 416.923474 -397.073882) (xy 417.243768 -397.627602)
			(xy 417.247832 -397.63192) (xy 417.264029 -397.649634) (xy 417.291453 -397.689024) (xy 417.312597 -397.732112)
			(xy 417.326972 -397.777905) (xy 417.334248 -397.825346) (xy 417.3347 -397.849344) (xy 417.334247 -397.874148)
			(xy 417.326477 -397.923143) (xy 417.311135 -397.970319) (xy 417.2886 -398.014513) (xy 417.259427 -398.054636)
			(xy 417.224334 -398.0897) (xy 417.184186 -398.118839) (xy 417.139973 -398.141337) (xy 417.092784 -398.156639)
			(xy 417.043782 -398.164368) (xy 417.018978 -398.164812) (xy 416.993583 -398.164331) (xy 416.943448 -398.156197)
			(xy 416.895263 -398.140142) (xy 416.850268 -398.116581) (xy 416.809626 -398.086121) (xy 416.774383 -398.049547)
			(xy 416.74545 -398.007804) (xy 416.723572 -397.961967) (xy 416.715956 -397.937736) (xy 416.714432 -397.931894)
			(xy 416.394138 -397.378174) (xy 416.390074 -397.373856) (xy 416.373918 -397.356119) (xy 416.346549 -397.316718)
			(xy 416.325457 -397.273629) (xy 416.311129 -397.227845) (xy 416.303894 -397.180419) (xy 416.30346 -397.156432)
			(xy 416.303541 -397.144384) (xy 416.305323 -397.120355) (xy 416.307016 -397.108426) (xy 416.308286 -397.099536)
			(xy 416.305238 -397.082518) (xy 416.263074 -397.011652) (xy 416.249866 -397.000476) (xy 416.241484 -396.997428)
			(xy 416.219739 -396.989025) (xy 416.17888 -396.966586) (xy 416.141909 -396.938194) (xy 416.109686 -396.90451)
			(xy 416.08296 -396.866317) (xy 416.062354 -396.824504) (xy 416.048346 -396.780043) (xy 416.041262 -396.73397)
			(xy 416.040824 -396.710662) (xy 415.451544 -396.710662) (xy 415.451472 -396.72002) (xy 415.450326 -396.738702)
			(xy 415.449258 -396.748) (xy 415.448242 -396.75689) (xy 415.452052 -396.773654) (xy 415.495994 -396.843504)
			(xy 415.50971 -396.853918) (xy 415.518092 -396.856712) (xy 415.542129 -396.865165) (xy 415.587312 -396.888708)
			(xy 415.628127 -396.919204) (xy 415.663514 -396.955861) (xy 415.692553 -396.997725) (xy 415.71449 -397.04371)
			(xy 415.722054 -397.06804) (xy 415.723578 -397.073882) (xy 416.043872 -397.627602) (xy 416.047936 -397.63192)
			(xy 416.064151 -397.649619) (xy 416.091581 -397.689009) (xy 416.112726 -397.7321) (xy 416.127097 -397.777898)
			(xy 416.134363 -397.825344) (xy 416.134804 -397.849344) (xy 416.134339 -397.874147) (xy 416.126569 -397.923141)
			(xy 416.111228 -397.970315) (xy 416.088694 -398.014508) (xy 416.059522 -398.05463) (xy 416.02443 -398.089692)
			(xy 415.984284 -398.118831) (xy 415.940073 -398.141328) (xy 415.892886 -398.15663) (xy 415.843885 -398.164359)
			(xy 415.819082 -398.164812) (xy 415.793689 -398.164303) (xy 415.743559 -398.15617) (xy 415.695376 -398.140117)
			(xy 415.650386 -398.116558) (xy 415.609746 -398.086101) (xy 415.574506 -398.049531) (xy 415.545575 -398.007791)
			(xy 415.523699 -397.961958) (xy 415.51606 -397.937736) (xy 415.514536 -397.931894) (xy 415.194242 -397.378174)
			(xy 415.190178 -397.373856) (xy 415.17399 -397.356146) (xy 415.146617 -397.316743) (xy 415.125529 -397.273647)
			(xy 415.111213 -397.227855) (xy 415.104 -397.180422) (xy 415.103564 -397.156432) (xy 415.10365 -397.144384)
			(xy 415.105433 -397.120355) (xy 415.10712 -397.108426) (xy 415.10839 -397.099536) (xy 415.105342 -397.082518)
			(xy 415.063178 -397.011652) (xy 415.04997 -397.000476) (xy 415.041588 -396.997428) (xy 415.018677 -396.988545)
			(xy 414.975811 -396.964525) (xy 414.937346 -396.933949) (xy 414.904278 -396.897605) (xy 414.890458 -396.877286)
			(xy 414.884108 -396.867634) (xy 414.86455 -396.855696) (xy 414.774634 -396.846298) (xy 414.763287 -396.845781)
			(xy 414.741934 -396.853436) (xy 414.733486 -396.86103) (xy 414.66262 -396.931896) (xy 414.655217 -396.93873)
			(xy 414.636619 -396.946436) (xy 414.626552 -396.946882) (xy 414.549082 -396.946882) (xy 414.539075 -396.947373)
			(xy 414.520587 -396.955035) (xy 414.506435 -396.969187) (xy 414.498773 -396.987675) (xy 414.498282 -396.997682)
			(xy 414.498282 -397.009366) (xy 414.503362 -397.01978) (xy 414.508853 -397.031499) (xy 414.518136 -397.055659)
			(xy 414.521904 -397.06804) (xy 414.523428 -397.073882) (xy 414.843722 -397.627602) (xy 414.847786 -397.63192)
			(xy 414.863977 -397.649628) (xy 414.891356 -397.68903) (xy 414.91245 -397.732125) (xy 414.926771 -397.777919)
			(xy 414.933988 -397.825353) (xy 414.9344 -397.849344) (xy 414.933911 -397.874132) (xy 414.92615 -397.923098)
			(xy 414.910825 -397.970247) (xy 414.888315 -398.014418) (xy 414.859173 -398.054525) (xy 414.824116 -398.089581)
			(xy 414.784008 -398.118721) (xy 414.739835 -398.14123) (xy 414.692686 -398.156552) (xy 414.64372 -398.164312)
			(xy 414.618932 -398.164812) (xy 414.593537 -398.164307) (xy 414.543401 -398.15618) (xy 414.495212 -398.140132)
			(xy 414.450215 -398.116577) (xy 414.409568 -398.086121) (xy 414.374323 -398.049551) (xy 414.345386 -398.007809)
			(xy 414.323505 -397.961974) (xy 414.31591 -397.937736) (xy 414.314386 -397.931894) (xy 413.994092 -397.378174)
			(xy 413.990028 -397.373856) (xy 413.973811 -397.356158) (xy 413.946379 -397.316769) (xy 413.925233 -397.273678)
			(xy 413.910862 -397.227879) (xy 413.903598 -397.180432) (xy 413.90316 -397.156432) (xy 413.903318 -397.14438)
			(xy 413.905227 -397.120352) (xy 413.90697 -397.108426) (xy 413.90824 -397.099536) (xy 413.905192 -397.082518)
			(xy 413.863028 -397.011652) (xy 413.84982 -397.000476) (xy 413.841438 -396.997428) (xy 413.821262 -396.989664)
			(xy 413.783146 -396.969267) (xy 413.765492 -396.956788) (xy 413.758796 -396.952199) (xy 413.743379 -396.947143)
			(xy 413.735266 -396.946882) (xy 413.349186 -396.946882) (xy 413.339179 -396.947372) (xy 413.320689 -396.955033)
			(xy 413.306536 -396.969185) (xy 413.298873 -396.987675) (xy 413.298386 -396.997682) (xy 413.298386 -397.009366)
			(xy 413.303466 -397.01978) (xy 413.308957 -397.031499) (xy 413.318239 -397.055659) (xy 413.322008 -397.06804)
			(xy 413.323532 -397.073882) (xy 413.643826 -397.627602) (xy 413.64789 -397.63192) (xy 413.664081 -397.649628)
			(xy 413.69146 -397.68903) (xy 413.712553 -397.732125) (xy 413.726874 -397.777919) (xy 413.734091 -397.825353)
			(xy 413.734504 -397.849344) (xy 413.734015 -397.874132) (xy 413.726254 -397.923098) (xy 413.710929 -397.970247)
			(xy 413.688419 -398.014419) (xy 413.659277 -398.054526) (xy 413.62422 -398.089582) (xy 413.584112 -398.118723)
			(xy 413.53994 -398.141232) (xy 413.49279 -398.156556) (xy 413.443824 -398.164315) (xy 413.419036 -398.164812)
			(xy 413.393641 -398.164307) (xy 413.343504 -398.156181) (xy 413.295315 -398.140134) (xy 413.250317 -398.116578)
			(xy 413.20967 -398.086122) (xy 413.174424 -398.049552) (xy 413.145487 -398.007811) (xy 413.123606 -397.961975)
			(xy 413.116014 -397.937736) (xy 413.11449 -397.931894) (xy 412.794196 -397.378174) (xy 412.790132 -397.373856)
			(xy 412.773915 -397.356158) (xy 412.746483 -397.316769) (xy 412.725337 -397.273678) (xy 412.710965 -397.22788)
			(xy 412.703701 -397.180432) (xy 412.703264 -397.156432) (xy 412.703422 -397.14438) (xy 412.705331 -397.120352)
			(xy 412.707074 -397.108426) (xy 412.708344 -397.099536) (xy 412.705296 -397.082518) (xy 412.663132 -397.011652)
			(xy 412.649924 -397.000476) (xy 412.641542 -396.997428) (xy 412.621365 -396.989665) (xy 412.583249 -396.969267)
			(xy 412.565596 -396.956788) (xy 412.5589 -396.952198) (xy 412.543484 -396.947141) (xy 412.53537 -396.946882)
			(xy 412.14929 -396.946882) (xy 412.139282 -396.947371) (xy 412.120791 -396.955032) (xy 412.106637 -396.969184)
			(xy 412.098973 -396.987674) (xy 412.09849 -396.997682) (xy 412.09849 -397.009366) (xy 412.10357 -397.01978)
			(xy 412.109163 -397.031674) (xy 412.118577 -397.056217) (xy 412.122366 -397.068802) (xy 412.12389 -397.074644)
			(xy 412.443676 -397.627602) (xy 412.44774 -397.63192) (xy 412.463955 -397.649619) (xy 412.491384 -397.689009)
			(xy 412.512529 -397.7321) (xy 412.5269 -397.777898) (xy 412.534166 -397.825344) (xy 412.534608 -397.849344)
			(xy 412.534143 -397.874147) (xy 412.526373 -397.923141) (xy 412.511032 -397.970316) (xy 412.488498 -398.014509)
			(xy 412.459326 -398.054631) (xy 412.424234 -398.089694) (xy 412.384089 -398.118833) (xy 412.339877 -398.141331)
			(xy 412.29269 -398.156633) (xy 412.24369 -398.164363) (xy 412.218886 -398.164812) (xy 412.193493 -398.164303)
			(xy 412.143362 -398.156171) (xy 412.095179 -398.140118) (xy 412.050188 -398.11656) (xy 412.009548 -398.086103)
			(xy 411.974308 -398.049533) (xy 411.945376 -398.007793) (xy 411.9235 -397.96196) (xy 411.915864 -397.937736)
			(xy 411.91434 -397.931894) (xy 411.593792 -397.377412) (xy 411.589728 -397.373094) (xy 411.573624 -397.355425)
			(xy 411.546385 -397.31614) (xy 411.525376 -397.273199) (xy 411.511074 -397.227583) (xy 411.503808 -397.180334)
			(xy 411.503368 -397.156432) (xy 411.503526 -397.14438) (xy 411.505435 -397.120352) (xy 411.507178 -397.108426)
			(xy 411.508448 -397.099536) (xy 411.5054 -397.082518) (xy 411.463236 -397.011652) (xy 411.450028 -397.000476)
			(xy 411.441646 -396.997428) (xy 411.421469 -396.989665) (xy 411.383353 -396.969268) (xy 411.3657 -396.956788)
			(xy 411.359004 -396.952198) (xy 411.343588 -396.947139) (xy 411.335474 -396.946882) (xy 410.94914 -396.946882)
			(xy 410.939112 -396.947295) (xy 410.920578 -396.954957) (xy 410.906389 -396.96913) (xy 410.898706 -396.987655)
			(xy 410.89834 -396.997682) (xy 410.89834 -397.009366) (xy 410.90342 -397.01978) (xy 410.908911 -397.031499)
			(xy 410.918195 -397.055659) (xy 410.921962 -397.06804) (xy 410.923486 -397.073882) (xy 411.24378 -397.627602)
			(xy 411.247844 -397.63192) (xy 411.264063 -397.649617) (xy 411.291501 -397.689004) (xy 411.312652 -397.732095)
			(xy 411.327028 -397.777894) (xy 411.334296 -397.825343) (xy 411.334712 -397.849344) (xy 411.334247 -397.874147)
			(xy 411.326477 -397.923142) (xy 411.311136 -397.970317) (xy 411.288602 -398.01451) (xy 411.25943 -398.054632)
			(xy 411.224339 -398.089695) (xy 411.184193 -398.118835) (xy 411.139982 -398.141334) (xy 411.092794 -398.156636)
			(xy 411.043794 -398.164367) (xy 411.01899 -398.164812) (xy 410.993597 -398.164303) (xy 410.943465 -398.156172)
			(xy 410.895282 -398.14012) (xy 410.85029 -398.116561) (xy 410.80965 -398.086104) (xy 410.774409 -398.049534)
			(xy 410.745477 -398.007794) (xy 410.7236 -397.961961) (xy 410.715968 -397.937736) (xy 410.714444 -397.931894)
			(xy 410.39415 -397.378174) (xy 410.390086 -397.373856) (xy 410.373898 -397.356147) (xy 410.346524 -397.316743)
			(xy 410.325435 -397.273648) (xy 410.311119 -397.227855) (xy 410.303906 -397.180422) (xy 410.303472 -397.156432)
			(xy 410.303558 -397.144384) (xy 410.305341 -397.120355) (xy 410.307028 -397.108426) (xy 410.308298 -397.099536)
			(xy 410.30525 -397.082518) (xy 410.263086 -397.011652) (xy 410.249878 -397.000476) (xy 410.241496 -396.997428)
			(xy 410.221318 -396.989668) (xy 410.183197 -396.969276) (xy 410.16555 -396.956788) (xy 410.158852 -396.952205)
			(xy 410.143436 -396.947161) (xy 410.135324 -396.946882) (xy 409.749244 -396.946882) (xy 409.739216 -396.947294)
			(xy 409.720681 -396.954955) (xy 409.70649 -396.969128) (xy 409.698806 -396.987654) (xy 409.698444 -396.997682)
			(xy 409.698444 -397.009366) (xy 409.703524 -397.01978) (xy 409.709015 -397.031499) (xy 409.718299 -397.055659)
			(xy 409.722066 -397.06804) (xy 409.72359 -397.073882) (xy 410.043884 -397.627602) (xy 410.047948 -397.63192)
			(xy 410.064167 -397.649617) (xy 410.091604 -397.689005) (xy 410.112755 -397.732096) (xy 410.127131 -397.777894)
			(xy 410.134399 -397.825343) (xy 410.134816 -397.849344) (xy 410.134351 -397.874147) (xy 410.126581 -397.923142)
			(xy 410.11124 -397.970317) (xy 410.088706 -398.014511) (xy 410.059534 -398.054633) (xy 410.024443 -398.089697)
			(xy 409.984297 -398.118837) (xy 409.940086 -398.141336) (xy 409.892899 -398.15664) (xy 409.843898 -398.16437)
			(xy 409.819094 -398.164812) (xy 409.793701 -398.164304) (xy 409.743569 -398.156173) (xy 409.695385 -398.140121)
			(xy 409.650392 -398.116563) (xy 409.609751 -398.086106) (xy 409.57451 -398.049536) (xy 409.545578 -398.007796)
			(xy 409.523701 -397.961962) (xy 409.516072 -397.937736) (xy 409.514548 -397.931894) (xy 409.194254 -397.378174)
			(xy 409.19019 -397.373856) (xy 409.174001 -397.356147) (xy 409.146627 -397.316744) (xy 409.125539 -397.273648)
			(xy 409.111222 -397.227855) (xy 409.104009 -397.180422) (xy 409.103576 -397.156432) (xy 409.103662 -397.144384)
			(xy 409.105445 -397.120355) (xy 409.107132 -397.108426) (xy 409.108402 -397.099536) (xy 409.105354 -397.082518)
			(xy 409.06319 -397.011652) (xy 409.049982 -397.000476) (xy 409.0416 -396.997428) (xy 409.019859 -396.989024)
			(xy 408.979012 -396.966572) (xy 408.942052 -396.938174) (xy 408.909837 -396.904488) (xy 408.883116 -396.866297)
			(xy 408.862511 -396.824489) (xy 408.848498 -396.780035) (xy 408.841405 -396.733967) (xy 408.84094 -396.710662)
			(xy 408.841443 -396.685654) (xy 408.849595 -396.636305) (xy 408.865675 -396.588943) (xy 408.877008 -396.566644)
			(xy 408.884882 -396.551658) (xy 408.880056 -396.518638) (xy 408.756612 -396.395194) (xy 408.749765 -396.387796)
			(xy 408.742031 -396.369198) (xy 408.741626 -396.359126) (xy 408.741626 -396.29588) (xy 408.739086 -396.284704)
			(xy 408.736292 -396.27937) (xy 408.721222 -396.24755) (xy 408.69994 -396.180439) (xy 408.689168 -396.110864)
			(xy 408.68854 -396.075662) (xy 408.689162 -396.040458) (xy 408.699908 -395.970876) (xy 408.721203 -395.903766)
			(xy 408.736292 -395.871954) (xy 408.738753 -395.866628) (xy 408.741445 -395.855212) (xy 408.741626 -395.849348)
			(xy 408.741626 -395.839442) (xy 408.716472 -395.820965) (xy 408.670928 -395.77829) (xy 408.631603 -395.729824)
			(xy 408.599225 -395.676466) (xy 408.574397 -395.619204) (xy 408.557576 -395.5591) (xy 408.549076 -395.497268)
			(xy 408.548586 -395.466062) (xy 408.549068 -395.435934) (xy 408.556979 -395.3762) (xy 408.57266 -395.318021)
			(xy 408.595839 -395.262402) (xy 408.626116 -395.210305) (xy 408.662966 -395.162631) (xy 408.705754 -395.120205)
			(xy 408.729434 -395.101572) (xy 408.739086 -395.094206) (xy 408.7495 -395.073124) (xy 408.7495 -395.048486)
			(xy 408.74442 -395.033246) (xy 408.739594 -395.026642) (xy 408.724519 -395.005242) (xy 408.700604 -394.958679)
			(xy 408.684329 -394.908929) (xy 408.676099 -394.857235) (xy 408.675586 -394.831062) (xy 408.67584 -394.81887)
			(xy 408.676094 -394.809218) (xy 408.669998 -394.791184) (xy 408.611324 -394.723874) (xy 408.59456 -394.715238)
			(xy 408.584654 -394.714222) (xy 408.557741 -394.710871) (xy 408.505442 -394.696525) (xy 408.456185 -394.673836)
			(xy 408.411292 -394.643413) (xy 408.371966 -394.60607) (xy 408.339262 -394.56281) (xy 408.314057 -394.514793)
			(xy 408.297027 -394.463306) (xy 408.2923 -394.4366) (xy 408.290776 -394.427202) (xy 408.01798 -393.95527)
			(xy 408.010614 -393.949428) (xy 407.991837 -393.933624) (xy 407.958705 -393.897416) (xy 407.931287 -393.856711)
			(xy 407.910184 -393.812402) (xy 407.895858 -393.765461) (xy 407.888625 -393.716919) (xy 407.888186 -393.69238)
			(xy 407.888697 -393.666394) (xy 407.89683 -393.615061) (xy 407.912893 -393.565633) (xy 407.93649 -393.519326)
			(xy 407.96704 -393.47728) (xy 408.003791 -393.44053) (xy 408.045838 -393.409982) (xy 408.092146 -393.386387)
			(xy 408.141575 -393.370327) (xy 408.192908 -393.362196) (xy 408.218894 -393.361672) (xy 408.244905 -393.362157)
			(xy 408.296285 -393.370302) (xy 408.345756 -393.386394) (xy 408.392097 -393.410034) (xy 408.434163 -393.44064)
			(xy 408.470918 -393.477456) (xy 408.501453 -393.519573) (xy 408.525017 -393.565953) (xy 408.541026 -393.615451)
			(xy 408.545538 -393.641072) (xy 408.547062 -393.65047) (xy 408.654758 -393.836906) (xy 408.660822 -393.84626)
			(xy 408.679073 -393.859016) (xy 408.701006 -393.862859) (xy 408.711908 -393.860528) (xy 408.728672 -393.855956)
			(xy 408.7495 -393.828778) (xy 408.7495 -391.963402) (xy 408.749077 -391.953332) (xy 408.741363 -391.934727)
			(xy 408.734514 -391.927334) (xy 408.36596 -391.55878) (xy 408.340052 -391.551668) (xy 408.326844 -391.555224)
			(xy 408.306557 -391.560108) (xy 408.265158 -391.565332) (xy 408.244294 -391.565638) (xy 408.216289 -391.56505)
			(xy 408.16108 -391.555618) (xy 408.108247 -391.537024) (xy 408.0593 -391.509799) (xy 408.015635 -391.474721)
			(xy 407.996644 -391.454132) (xy 407.989107 -391.446339) (xy 407.969373 -391.437404) (xy 407.958544 -391.43686)
			(xy 407.329894 -391.43686) (xy 407.319051 -391.437351) (xy 407.299297 -391.446291) (xy 407.291794 -391.454132)
			(xy 407.27457 -391.472885) (xy 407.235379 -391.505388) (xy 407.19167 -391.531502) (xy 407.144475 -391.550608)
			(xy 407.094909 -391.562255) (xy 407.044144 -391.566168) (xy 406.993379 -391.562255) (xy 406.943813 -391.550608)
			(xy 406.896618 -391.531502) (xy 406.852909 -391.505388) (xy 406.813718 -391.472885) (xy 406.796494 -391.454132)
			(xy 406.78896 -391.446331) (xy 406.769227 -391.437377) (xy 406.758394 -391.43686) (xy 406.129998 -391.43686)
			(xy 406.119155 -391.43735) (xy 406.099399 -391.446289) (xy 406.091898 -391.454132) (xy 406.074674 -391.472885)
			(xy 406.035483 -391.505388) (xy 405.991774 -391.531502) (xy 405.944579 -391.550608) (xy 405.895013 -391.562255)
			(xy 405.844248 -391.566168) (xy 405.793483 -391.562255) (xy 405.743917 -391.550608) (xy 405.696722 -391.531502)
			(xy 405.653013 -391.505388) (xy 405.613822 -391.472885) (xy 405.596598 -391.454132) (xy 405.589064 -391.44633)
			(xy 405.569331 -391.437375) (xy 405.558498 -391.43686) (xy 404.930102 -391.43686) (xy 404.919259 -391.43735)
			(xy 404.899501 -391.446287) (xy 404.892002 -391.454132) (xy 404.874778 -391.472885) (xy 404.835587 -391.505388)
			(xy 404.791878 -391.531502) (xy 404.744683 -391.550608) (xy 404.695117 -391.562255) (xy 404.644352 -391.566168)
			(xy 404.593587 -391.562255) (xy 404.544021 -391.550608) (xy 404.496826 -391.531502) (xy 404.453117 -391.505388)
			(xy 404.413926 -391.472885) (xy 404.396702 -391.454132) (xy 404.389168 -391.446329) (xy 404.369435 -391.437373)
			(xy 404.358602 -391.43686) (xy 403.729952 -391.43686) (xy 403.719113 -391.437359) (xy 403.699371 -391.44631)
			(xy 403.691852 -391.454132) (xy 403.674628 -391.472885) (xy 403.635437 -391.505388) (xy 403.591728 -391.531502)
			(xy 403.544533 -391.550608) (xy 403.494967 -391.562255) (xy 403.444202 -391.566168) (xy 403.393437 -391.562255)
			(xy 403.343871 -391.550608) (xy 403.296676 -391.531502) (xy 403.252967 -391.505388) (xy 403.213776 -391.472885)
			(xy 403.196552 -391.454132) (xy 403.189015 -391.446337) (xy 403.169282 -391.4374) (xy 403.158452 -391.43686)
			(xy 402.609812 -391.43686) (xy 402.599742 -391.437283) (xy 402.58114 -391.445001) (xy 402.573744 -391.451846)
			(xy 401.362926 -392.662664) (xy 401.355306 -392.684762) (xy 401.35683 -392.6967) (xy 401.358137 -392.70732)
			(xy 401.359538 -392.728673) (xy 401.359624 -392.739372) (xy 401.359143 -392.765363) (xy 401.351015 -392.816706)
			(xy 401.334956 -392.866145) (xy 401.31136 -392.912464) (xy 401.280808 -392.95452) (xy 401.244054 -392.99128)
			(xy 401.202001 -393.021837) (xy 401.194403 -393.025709) (xy 402.759928 -393.025709) (xy 402.759928 -392.973735)
			(xy 402.768058 -392.9224) (xy 402.784119 -392.87297) (xy 402.807715 -392.82666) (xy 402.838265 -392.784612)
			(xy 402.875016 -392.747861) (xy 402.917064 -392.717311) (xy 402.963374 -392.693715) (xy 403.012804 -392.677654)
			(xy 403.064139 -392.669524) (xy 403.116113 -392.669524) (xy 403.167448 -392.677654) (xy 403.216878 -392.693715)
			(xy 403.263188 -392.717311) (xy 403.305236 -392.747861) (xy 403.341987 -392.784612) (xy 403.372537 -392.82666)
			(xy 403.396133 -392.87297) (xy 403.412194 -392.9224) (xy 403.420324 -392.973735) (xy 403.420834 -392.999722)
			(xy 403.420324 -393.025709) (xy 403.959824 -393.025709) (xy 403.959824 -392.973735) (xy 403.967954 -392.9224)
			(xy 403.984015 -392.87297) (xy 404.007611 -392.82666) (xy 404.038161 -392.784612) (xy 404.074912 -392.747861)
			(xy 404.11696 -392.717311) (xy 404.16327 -392.693715) (xy 404.2127 -392.677654) (xy 404.264035 -392.669524)
			(xy 404.316009 -392.669524) (xy 404.367344 -392.677654) (xy 404.416774 -392.693715) (xy 404.463084 -392.717311)
			(xy 404.505132 -392.747861) (xy 404.541883 -392.784612) (xy 404.572433 -392.82666) (xy 404.596029 -392.87297)
			(xy 404.61209 -392.9224) (xy 404.62022 -392.973735) (xy 404.62073 -392.999722) (xy 404.62022 -393.025709)
			(xy 405.159974 -393.025709) (xy 405.159974 -392.973735) (xy 405.168104 -392.9224) (xy 405.184165 -392.87297)
			(xy 405.207761 -392.82666) (xy 405.238311 -392.784612) (xy 405.275062 -392.747861) (xy 405.31711 -392.717311)
			(xy 405.36342 -392.693715) (xy 405.41285 -392.677654) (xy 405.464185 -392.669524) (xy 405.516159 -392.669524)
			(xy 405.567494 -392.677654) (xy 405.616924 -392.693715) (xy 405.663234 -392.717311) (xy 405.705282 -392.747861)
			(xy 405.742033 -392.784612) (xy 405.772583 -392.82666) (xy 405.796179 -392.87297) (xy 405.81224 -392.9224)
			(xy 405.82037 -392.973735) (xy 405.82088 -392.999722) (xy 405.82037 -393.025709) (xy 406.35987 -393.025709)
			(xy 406.35987 -392.973735) (xy 406.368 -392.9224) (xy 406.384061 -392.87297) (xy 406.407657 -392.82666)
			(xy 406.438207 -392.784612) (xy 406.474958 -392.747861) (xy 406.517006 -392.717311) (xy 406.563316 -392.693715)
			(xy 406.612746 -392.677654) (xy 406.664081 -392.669524) (xy 406.716055 -392.669524) (xy 406.76739 -392.677654)
			(xy 406.81682 -392.693715) (xy 406.86313 -392.717311) (xy 406.905178 -392.747861) (xy 406.941929 -392.784612)
			(xy 406.972479 -392.82666) (xy 406.996075 -392.87297) (xy 407.012136 -392.9224) (xy 407.020266 -392.973735)
			(xy 407.020776 -392.999722) (xy 407.020266 -393.025709) (xy 407.56002 -393.025709) (xy 407.56002 -392.973735)
			(xy 407.56815 -392.9224) (xy 407.584211 -392.87297) (xy 407.607807 -392.82666) (xy 407.638357 -392.784612)
			(xy 407.675108 -392.747861) (xy 407.717156 -392.717311) (xy 407.763466 -392.693715) (xy 407.812896 -392.677654)
			(xy 407.864231 -392.669524) (xy 407.916205 -392.669524) (xy 407.96754 -392.677654) (xy 408.01697 -392.693715)
			(xy 408.06328 -392.717311) (xy 408.105328 -392.747861) (xy 408.142079 -392.784612) (xy 408.172629 -392.82666)
			(xy 408.196225 -392.87297) (xy 408.212286 -392.9224) (xy 408.220416 -392.973735) (xy 408.220926 -392.999722)
			(xy 408.220416 -393.025709) (xy 408.212286 -393.077044) (xy 408.196225 -393.126474) (xy 408.172629 -393.172784)
			(xy 408.142079 -393.214832) (xy 408.105328 -393.251583) (xy 408.06328 -393.282133) (xy 408.01697 -393.305729)
			(xy 407.96754 -393.32179) (xy 407.916205 -393.32992) (xy 407.864231 -393.32992) (xy 407.812896 -393.32179)
			(xy 407.763466 -393.305729) (xy 407.717156 -393.282133) (xy 407.675108 -393.251583) (xy 407.638357 -393.214832)
			(xy 407.607807 -393.172784) (xy 407.584211 -393.126474) (xy 407.56815 -393.077044) (xy 407.56002 -393.025709)
			(xy 407.020266 -393.025709) (xy 407.012136 -393.077044) (xy 406.996075 -393.126474) (xy 406.972479 -393.172784)
			(xy 406.941929 -393.214832) (xy 406.905178 -393.251583) (xy 406.86313 -393.282133) (xy 406.81682 -393.305729)
			(xy 406.76739 -393.32179) (xy 406.716055 -393.32992) (xy 406.664081 -393.32992) (xy 406.612746 -393.32179)
			(xy 406.563316 -393.305729) (xy 406.517006 -393.282133) (xy 406.474958 -393.251583) (xy 406.438207 -393.214832)
			(xy 406.407657 -393.172784) (xy 406.384061 -393.126474) (xy 406.368 -393.077044) (xy 406.35987 -393.025709)
			(xy 405.82037 -393.025709) (xy 405.81224 -393.077044) (xy 405.796179 -393.126474) (xy 405.772583 -393.172784)
			(xy 405.742033 -393.214832) (xy 405.705282 -393.251583) (xy 405.663234 -393.282133) (xy 405.616924 -393.305729)
			(xy 405.567494 -393.32179) (xy 405.516159 -393.32992) (xy 405.464185 -393.32992) (xy 405.41285 -393.32179)
			(xy 405.36342 -393.305729) (xy 405.31711 -393.282133) (xy 405.275062 -393.251583) (xy 405.238311 -393.214832)
			(xy 405.207761 -393.172784) (xy 405.184165 -393.126474) (xy 405.168104 -393.077044) (xy 405.159974 -393.025709)
			(xy 404.62022 -393.025709) (xy 404.61209 -393.077044) (xy 404.596029 -393.126474) (xy 404.572433 -393.172784)
			(xy 404.541883 -393.214832) (xy 404.505132 -393.251583) (xy 404.463084 -393.282133) (xy 404.416774 -393.305729)
			(xy 404.367344 -393.32179) (xy 404.316009 -393.32992) (xy 404.264035 -393.32992) (xy 404.2127 -393.32179)
			(xy 404.16327 -393.305729) (xy 404.11696 -393.282133) (xy 404.074912 -393.251583) (xy 404.038161 -393.214832)
			(xy 404.007611 -393.172784) (xy 403.984015 -393.126474) (xy 403.967954 -393.077044) (xy 403.959824 -393.025709)
			(xy 403.420324 -393.025709) (xy 403.412194 -393.077044) (xy 403.396133 -393.126474) (xy 403.372537 -393.172784)
			(xy 403.341987 -393.214832) (xy 403.305236 -393.251583) (xy 403.263188 -393.282133) (xy 403.216878 -393.305729)
			(xy 403.167448 -393.32179) (xy 403.116113 -393.32992) (xy 403.064139 -393.32992) (xy 403.012804 -393.32179)
			(xy 402.963374 -393.305729) (xy 402.917064 -393.282133) (xy 402.875016 -393.251583) (xy 402.838265 -393.214832)
			(xy 402.807715 -393.172784) (xy 402.784119 -393.126474) (xy 402.768058 -393.077044) (xy 402.759928 -393.025709)
			(xy 401.194403 -393.025709) (xy 401.155686 -393.045439) (xy 401.106249 -393.061505) (xy 401.054907 -393.06964)
			(xy 401.028916 -393.07008) (xy 401.018217 -393.069985) (xy 400.996864 -393.068586) (xy 400.986244 -393.067286)
			(xy 400.974306 -393.065762) (xy 400.952208 -393.073382) (xy 400.544792 -393.480798) (xy 400.538149 -393.488166)
			(xy 400.530539 -393.506467) (xy 400.530374 -393.526287) (xy 400.533616 -393.535662) (xy 400.574256 -393.6365)
			(xy 400.599402 -393.653772) (xy 400.614642 -393.654026) (xy 400.640264 -393.655055) (xy 400.690744 -393.664047)
			(xy 400.739231 -393.680725) (xy 400.76128 -393.69238) (xy 403.088348 -393.69238) (xy 403.088883 -393.666394)
			(xy 403.097015 -393.615064) (xy 403.113076 -393.565636) (xy 403.136671 -393.51933) (xy 403.167218 -393.477284)
			(xy 403.203966 -393.440533) (xy 403.246009 -393.409983) (xy 403.292314 -393.386385) (xy 403.34174 -393.370321)
			(xy 403.393071 -393.362185) (xy 403.419056 -393.361672) (xy 403.445068 -393.362091) (xy 403.496447 -393.370258)
			(xy 403.545914 -393.386366) (xy 403.59225 -393.410019) (xy 403.634313 -393.440633) (xy 403.671065 -393.477454)
			(xy 403.701601 -393.519573) (xy 403.725168 -393.565953) (xy 403.741185 -393.61545) (xy 403.7457 -393.641072)
			(xy 403.747224 -393.65047) (xy 403.77145 -393.69238) (xy 404.288244 -393.69238) (xy 404.288783 -393.666395)
			(xy 404.296915 -393.615064) (xy 404.312976 -393.565637) (xy 404.33657 -393.519331) (xy 404.367117 -393.477285)
			(xy 404.403864 -393.440535) (xy 404.445907 -393.409985) (xy 404.492211 -393.386386) (xy 404.541637 -393.370322)
			(xy 404.592967 -393.362185) (xy 404.618952 -393.361672) (xy 404.644964 -393.362094) (xy 404.696342 -393.370261)
			(xy 404.74581 -393.386369) (xy 404.792146 -393.410021) (xy 404.834208 -393.440635) (xy 404.870961 -393.477455)
			(xy 404.901497 -393.519574) (xy 404.925064 -393.565954) (xy 404.941081 -393.61545) (xy 404.945596 -393.641072)
			(xy 404.94712 -393.65047) (xy 404.971346 -393.69238) (xy 405.488394 -393.69238) (xy 405.488883 -393.666392)
			(xy 405.497017 -393.615057) (xy 405.513081 -393.565626) (xy 405.536679 -393.519316) (xy 405.567231 -393.477268)
			(xy 405.603985 -393.440517) (xy 405.646035 -393.409968) (xy 405.692346 -393.386372) (xy 405.741778 -393.370312)
			(xy 405.793114 -393.362181) (xy 405.819102 -393.361672) (xy 405.845146 -393.362131) (xy 405.896587 -393.370319)
			(xy 405.946111 -393.386462) (xy 405.992496 -393.41016) (xy 406.034598 -393.440829) (xy 406.071378 -393.477713)
			(xy 406.101929 -393.519902) (xy 406.125496 -393.566354) (xy 406.141499 -393.615923) (xy 406.146 -393.64158)
			(xy 406.14727 -393.650978) (xy 406.171206 -393.69238) (xy 406.68829 -393.69238) (xy 406.688783 -393.666392)
			(xy 406.696917 -393.615057) (xy 406.71298 -393.565627) (xy 406.736578 -393.519317) (xy 406.76713 -393.477269)
			(xy 406.803883 -393.440518) (xy 406.845933 -393.409969) (xy 406.892243 -393.386373) (xy 406.941675 -393.370312)
			(xy 406.99301 -393.362182) (xy 407.018998 -393.361672) (xy 407.045008 -393.362143) (xy 407.096385 -393.370302)
			(xy 407.145851 -393.386402) (xy 407.192187 -393.410048) (xy 407.23425 -393.440655) (xy 407.271003 -393.47747)
			(xy 407.301541 -393.519584) (xy 407.325109 -393.565959) (xy 407.341127 -393.615452) (xy 407.345642 -393.641072)
			(xy 407.347166 -393.65047) (xy 407.619962 -394.122402) (xy 407.627328 -394.128244) (xy 407.646115 -394.144035)
			(xy 407.679231 -394.180255) (xy 407.706639 -394.220966) (xy 407.727738 -394.265276) (xy 407.742067 -394.312214)
			(xy 407.749311 -394.360754) (xy 407.749756 -394.385292) (xy 407.749502 -394.397484) (xy 407.749248 -394.407136)
			(xy 407.755344 -394.42517) (xy 407.814018 -394.49248) (xy 407.830782 -394.501116) (xy 407.840434 -394.502132)
			(xy 407.8672 -394.505464) (xy 407.919223 -394.519691) (xy 407.968249 -394.542171) (xy 408.012978 -394.572307)
			(xy 408.052225 -394.609301) (xy 408.084949 -394.652172) (xy 408.110285 -394.699785) (xy 408.12756 -394.750877)
			(xy 408.136317 -394.804095) (xy 408.136852 -394.831062) (xy 408.136342 -394.857049) (xy 408.128212 -394.908384)
			(xy 408.112151 -394.957814) (xy 408.088555 -395.004124) (xy 408.058005 -395.046172) (xy 408.021254 -395.082923)
			(xy 407.979206 -395.113473) (xy 407.932896 -395.137069) (xy 407.883466 -395.15313) (xy 407.832131 -395.16126)
			(xy 407.780157 -395.16126) (xy 407.728822 -395.15313) (xy 407.679392 -395.137069) (xy 407.633082 -395.113473)
			(xy 407.591034 -395.082923) (xy 407.554283 -395.046172) (xy 407.523733 -395.004124) (xy 407.500137 -394.957814)
			(xy 407.484076 -394.908384) (xy 407.475946 -394.857049) (xy 407.475436 -394.831062) (xy 407.47569 -394.81887)
			(xy 407.475944 -394.809218) (xy 407.469848 -394.791184) (xy 407.411174 -394.723874) (xy 407.39441 -394.715238)
			(xy 407.384758 -394.714222) (xy 407.357851 -394.710852) (xy 407.305565 -394.696488) (xy 407.256322 -394.673789)
			(xy 407.211439 -394.643364) (xy 407.172119 -394.606026) (xy 407.139415 -394.562776) (xy 407.114201 -394.514771)
			(xy 407.097154 -394.463298) (xy 407.092404 -394.4366) (xy 407.09088 -394.427202) (xy 406.818084 -393.95527)
			(xy 406.810718 -393.949428) (xy 406.791975 -393.933587) (xy 406.758854 -393.897379) (xy 406.73144 -393.856679)
			(xy 406.710333 -393.812378) (xy 406.695995 -393.765448) (xy 406.688741 -393.716916) (xy 406.68829 -393.69238)
			(xy 406.171206 -393.69238) (xy 406.419812 -394.122402) (xy 406.427178 -394.128244) (xy 406.445955 -394.144047)
			(xy 406.479073 -394.180263) (xy 406.506484 -394.220971) (xy 406.527585 -394.265279) (xy 406.541915 -394.312216)
			(xy 406.54916 -394.360754) (xy 406.549606 -394.385292) (xy 406.549352 -394.397484) (xy 406.549098 -394.407136)
			(xy 406.555194 -394.42517) (xy 406.613868 -394.49248) (xy 406.630632 -394.501116) (xy 406.640538 -394.502132)
			(xy 406.667304 -394.50546) (xy 406.719328 -394.519689) (xy 406.768353 -394.542169) (xy 406.813082 -394.572305)
			(xy 406.852329 -394.609299) (xy 406.885054 -394.652171) (xy 406.910389 -394.699784) (xy 406.927664 -394.750877)
			(xy 406.936421 -394.804095) (xy 406.936956 -394.831062) (xy 406.936407 -394.858346) (xy 406.927454 -394.912175)
			(xy 406.909784 -394.963804) (xy 406.883878 -395.011831) (xy 406.850438 -395.054952) (xy 406.830784 -395.073886)
			(xy 406.823384 -395.081409) (xy 406.814859 -395.100688) (xy 406.814274 -395.111224) (xy 406.814274 -395.1859)
			(xy 406.814797 -395.19645) (xy 406.823337 -395.215745) (xy 406.830784 -395.223238) (xy 406.850433 -395.242175)
			(xy 406.883864 -395.285301) (xy 406.909765 -395.333327) (xy 406.927435 -395.384953) (xy 406.936395 -395.438779)
			(xy 406.936956 -395.466062) (xy 406.936505 -395.490178) (xy 406.929509 -395.5379) (xy 406.91566 -395.584101)
			(xy 406.89525 -395.627802) (xy 406.882346 -395.64818) (xy 406.876504 -395.65707) (xy 406.872948 -395.677136)
			(xy 406.89403 -395.769338) (xy 406.906222 -395.786102) (xy 406.915112 -395.791436) (xy 406.935908 -395.804299)
			(xy 406.973814 -395.835186) (xy 407.006758 -395.87132) (xy 407.034021 -395.911912) (xy 407.055007 -395.956076)
			(xy 407.069259 -396.00285) (xy 407.076467 -396.051213) (xy 407.07691 -396.075662) (xy 407.076485 -396.100035)
			(xy 407.06934 -396.148254) (xy 407.055198 -396.194904) (xy 407.034365 -396.238974) (xy 407.007293 -396.279511)
			(xy 406.974567 -396.315637) (xy 406.956006 -396.33144) (xy 406.947116 -396.338552) (xy 406.937718 -396.35811)
			(xy 406.934924 -396.457424) (xy 406.94356 -396.47749) (xy 406.951942 -396.48511) (xy 406.970388 -396.502575)
			(xy 407.001736 -396.542544) (xy 407.026033 -396.587152) (xy 407.042611 -396.635167) (xy 407.05101 -396.685264)
			(xy 407.05151 -396.710662) (xy 407.64079 -396.710662) (xy 407.641312 -396.685407) (xy 407.649625 -396.635585)
			(xy 407.666026 -396.587811) (xy 407.690067 -396.543388) (xy 407.721091 -396.503528) (xy 407.758253 -396.469318)
			(xy 407.800539 -396.441692) (xy 407.846795 -396.421402) (xy 407.89576 -396.409002) (xy 407.946098 -396.404831)
			(xy 407.996436 -396.409002) (xy 408.045401 -396.421402) (xy 408.091657 -396.441692) (xy 408.133943 -396.469318)
			(xy 408.171105 -396.503528) (xy 408.202129 -396.543388) (xy 408.22617 -396.587811) (xy 408.242571 -396.635585)
			(xy 408.250884 -396.685407) (xy 408.251406 -396.710662) (xy 408.251337 -396.720021) (xy 408.250194 -396.738703)
			(xy 408.24912 -396.748) (xy 408.248104 -396.75689) (xy 408.251914 -396.773654) (xy 408.295856 -396.843504)
			(xy 408.309572 -396.853918) (xy 408.317954 -396.856712) (xy 408.341985 -396.865172) (xy 408.387157 -396.888727)
			(xy 408.427962 -396.919228) (xy 408.46334 -396.955885) (xy 408.492375 -396.997745) (xy 408.514313 -397.043724)
			(xy 408.521916 -397.06804) (xy 408.52344 -397.073882) (xy 408.843734 -397.627602) (xy 408.847798 -397.63192)
			(xy 408.863986 -397.64963) (xy 408.891352 -397.689037) (xy 408.912438 -397.732133) (xy 408.926758 -397.777924)
			(xy 408.933983 -397.825355) (xy 408.934412 -397.849344) (xy 408.933923 -397.874133) (xy 408.926162 -397.923099)
			(xy 408.910838 -397.970248) (xy 408.888327 -398.014421) (xy 408.859185 -398.054529) (xy 408.824129 -398.089585)
			(xy 408.784021 -398.118727) (xy 408.739848 -398.141238) (xy 408.692699 -398.156562) (xy 408.643733 -398.164323)
			(xy 408.618944 -398.164812) (xy 408.593551 -398.164273) (xy 408.543419 -398.156149) (xy 408.495234 -398.140104)
			(xy 408.45024 -398.116552) (xy 408.409597 -398.086099) (xy 408.374353 -398.049533) (xy 408.345419 -398.007796)
			(xy 408.323539 -397.961965) (xy 408.315922 -397.937736) (xy 408.314398 -397.931894) (xy 407.994104 -397.378174)
			(xy 407.99004 -397.373856) (xy 407.973827 -397.356156) (xy 407.946406 -397.316762) (xy 407.925266 -397.27367)
			(xy 407.910894 -397.227875) (xy 407.903622 -397.180431) (xy 407.903172 -397.156432) (xy 407.903314 -397.14438)
			(xy 407.90522 -397.12035) (xy 407.906982 -397.108426) (xy 407.908252 -397.099536) (xy 407.905204 -397.082518)
			(xy 407.86304 -397.011652) (xy 407.849832 -397.000476) (xy 407.84145 -396.997428) (xy 407.819698 -396.989044)
			(xy 407.77884 -396.9666) (xy 407.74187 -396.938205) (xy 407.709648 -396.904518) (xy 407.682924 -396.866322)
			(xy 407.662318 -396.824507) (xy 407.648311 -396.780045) (xy 407.641228 -396.73397) (xy 407.64079 -396.710662)
			(xy 407.05151 -396.710662) (xy 407.051441 -396.720021) (xy 407.050298 -396.738703) (xy 407.049224 -396.748)
			(xy 407.048208 -396.75689) (xy 407.052018 -396.773654) (xy 407.09596 -396.843504) (xy 407.109676 -396.853918)
			(xy 407.118058 -396.856712) (xy 407.14209 -396.86517) (xy 407.187262 -396.888725) (xy 407.228066 -396.919227)
			(xy 407.263445 -396.955884) (xy 407.292479 -396.997745) (xy 407.314417 -397.043724) (xy 407.32202 -397.06804)
			(xy 407.323544 -397.073882) (xy 407.643838 -397.627602) (xy 407.647902 -397.63192) (xy 407.66409 -397.649629)
			(xy 407.691456 -397.689037) (xy 407.712542 -397.732133) (xy 407.726862 -397.777924) (xy 407.734087 -397.825355)
			(xy 407.734516 -397.849344) (xy 407.734023 -397.874132) (xy 407.726262 -397.923098) (xy 407.710938 -397.970247)
			(xy 407.688428 -398.01442) (xy 407.659287 -398.054528) (xy 407.624231 -398.089584) (xy 407.584123 -398.118726)
			(xy 407.539951 -398.141236) (xy 407.492802 -398.156561) (xy 407.443836 -398.164322) (xy 407.419048 -398.164812)
			(xy 407.393655 -398.164269) (xy 407.343523 -398.156146) (xy 407.295339 -398.140102) (xy 407.250345 -398.11655)
			(xy 407.209701 -398.086098) (xy 407.174458 -398.049532) (xy 407.145523 -398.007796) (xy 407.123643 -397.961965)
			(xy 407.116026 -397.937736) (xy 407.114502 -397.931894) (xy 406.794208 -397.378174) (xy 406.790144 -397.373856)
			(xy 406.773931 -397.356156) (xy 406.746511 -397.316762) (xy 406.72537 -397.27367) (xy 406.710999 -397.227875)
			(xy 406.703726 -397.180431) (xy 406.703276 -397.156432) (xy 406.703418 -397.14438) (xy 406.705324 -397.12035)
			(xy 406.707086 -397.108426) (xy 406.708356 -397.099536) (xy 406.705308 -397.082518) (xy 406.663144 -397.011652)
			(xy 406.649936 -397.000476) (xy 406.641554 -396.997428) (xy 406.619803 -396.989042) (xy 406.578945 -396.966599)
			(xy 406.541975 -396.938203) (xy 406.509753 -396.904517) (xy 406.483028 -396.866322) (xy 406.462422 -396.824507)
			(xy 406.448415 -396.780045) (xy 406.441332 -396.73397) (xy 406.440894 -396.710662) (xy 406.441422 -396.685267)
			(xy 406.449831 -396.635178) (xy 406.46641 -396.587171) (xy 406.490704 -396.542568) (xy 406.522042 -396.502599)
			(xy 406.540462 -396.48511) (xy 406.548844 -396.47749) (xy 406.55748 -396.457424) (xy 406.554686 -396.35811)
			(xy 406.545288 -396.338552) (xy 406.536398 -396.33144) (xy 406.51787 -396.315601) (xy 406.485147 -396.279479)
			(xy 406.458074 -396.238949) (xy 406.437238 -396.194886) (xy 406.423088 -396.148245) (xy 406.415932 -396.100032)
			(xy 406.415494 -396.075662) (xy 406.415901 -396.051544) (xy 406.422909 -396.00382) (xy 406.436771 -395.957619)
			(xy 406.457193 -395.91392) (xy 406.470104 -395.893544) (xy 406.475946 -395.884654) (xy 406.479502 -395.864588)
			(xy 406.45842 -395.772386) (xy 406.446228 -395.755622) (xy 406.437338 -395.750288) (xy 406.416541 -395.737427)
			(xy 406.378637 -395.706537) (xy 406.345696 -395.670402) (xy 406.318434 -395.62981) (xy 406.297448 -395.585646)
			(xy 406.283195 -395.538873) (xy 406.275985 -395.49051) (xy 406.27554 -395.466062) (xy 406.276106 -395.438778)
			(xy 406.285055 -395.38495) (xy 406.302721 -395.333322) (xy 406.328623 -395.285295) (xy 406.36206 -395.242172)
			(xy 406.381712 -395.223238) (xy 406.389101 -395.215706) (xy 406.397632 -395.196434) (xy 406.398222 -395.1859)
			(xy 406.398222 -395.111224) (xy 406.397687 -395.100675) (xy 406.389155 -395.08138) (xy 406.381712 -395.073886)
			(xy 406.362074 -395.054939) (xy 406.328642 -395.011816) (xy 406.302738 -394.963791) (xy 406.285066 -394.912168)
			(xy 406.276103 -394.858344) (xy 406.27554 -394.831062) (xy 406.275794 -394.81887) (xy 406.276048 -394.809218)
			(xy 406.269952 -394.791184) (xy 406.211278 -394.723874) (xy 406.194514 -394.715238) (xy 406.184608 -394.714222)
			(xy 406.157707 -394.710812) (xy 406.105421 -394.696456) (xy 406.056178 -394.673764) (xy 406.011295 -394.643345)
			(xy 405.971973 -394.606013) (xy 405.939268 -394.562767) (xy 405.914053 -394.514767) (xy 405.897004 -394.463296)
			(xy 405.892254 -394.4366) (xy 405.89073 -394.427202) (xy 405.61768 -393.954762) (xy 405.610568 -393.94892)
			(xy 405.59183 -393.933147) (xy 405.558777 -393.897003) (xy 405.531422 -393.856376) (xy 405.510364 -393.812156)
			(xy 405.496064 -393.765311) (xy 405.488837 -393.716869) (xy 405.488394 -393.69238) (xy 404.971346 -393.69238)
			(xy 405.219916 -394.122402) (xy 405.227282 -394.128244) (xy 405.24606 -394.144046) (xy 405.279178 -394.180262)
			(xy 405.306588 -394.22097) (xy 405.327689 -394.265278) (xy 405.342019 -394.312216) (xy 405.349264 -394.360754)
			(xy 405.34971 -394.385292) (xy 405.349456 -394.397484) (xy 405.349202 -394.407136) (xy 405.355298 -394.42517)
			(xy 405.413972 -394.49248) (xy 405.430736 -394.501116) (xy 405.440642 -394.502132) (xy 405.467409 -394.505457)
			(xy 405.519432 -394.519686) (xy 405.568458 -394.542167) (xy 405.613187 -394.572304) (xy 405.652433 -394.609298)
			(xy 405.685158 -394.65217) (xy 405.710493 -394.699783) (xy 405.727768 -394.750876) (xy 405.736525 -394.804095)
			(xy 405.73706 -394.831062) (xy 405.73651 -394.858346) (xy 405.727557 -394.912175) (xy 405.709887 -394.963804)
			(xy 405.683981 -395.011831) (xy 405.650541 -395.054952) (xy 405.630888 -395.073886) (xy 405.623489 -395.081409)
			(xy 405.614963 -395.100688) (xy 405.614378 -395.111224) (xy 405.614378 -395.1859) (xy 405.6149 -395.19645)
			(xy 405.623441 -395.215745) (xy 405.630888 -395.223238) (xy 405.650538 -395.242174) (xy 405.683968 -395.2853)
			(xy 405.70987 -395.333327) (xy 405.727539 -395.384953) (xy 405.736499 -395.438779) (xy 405.73706 -395.466062)
			(xy 405.736608 -395.490178) (xy 405.729612 -395.5379) (xy 405.715763 -395.584101) (xy 405.695354 -395.627802)
			(xy 405.68245 -395.64818) (xy 405.676608 -395.65707) (xy 405.673052 -395.677136) (xy 405.694134 -395.769338)
			(xy 405.706326 -395.786102) (xy 405.715216 -395.791436) (xy 405.736013 -395.804298) (xy 405.773919 -395.835185)
			(xy 405.806863 -395.871319) (xy 405.834125 -395.911911) (xy 405.855111 -395.956076) (xy 405.869363 -396.00285)
			(xy 405.876571 -396.051213) (xy 405.877014 -396.075662) (xy 405.876588 -396.100035) (xy 405.869442 -396.148254)
			(xy 405.855301 -396.194903) (xy 405.834468 -396.238973) (xy 405.807396 -396.27951) (xy 405.774671 -396.315637)
			(xy 405.75611 -396.33144) (xy 405.74722 -396.338552) (xy 405.737822 -396.35811) (xy 405.735028 -396.457424)
			(xy 405.743664 -396.47749) (xy 405.752046 -396.48511) (xy 405.770493 -396.502574) (xy 405.801841 -396.542544)
			(xy 405.826138 -396.587152) (xy 405.842715 -396.635167) (xy 405.851115 -396.685264) (xy 405.851614 -396.710662)
			(xy 405.851545 -396.720021) (xy 405.850402 -396.738703) (xy 405.849328 -396.748) (xy 405.848312 -396.75689)
			(xy 405.852122 -396.773654) (xy 405.896064 -396.843504) (xy 405.90978 -396.853918) (xy 405.918162 -396.856712)
			(xy 405.942252 -396.865212) (xy 405.987544 -396.888832) (xy 406.02844 -396.919439) (xy 406.063873 -396.956232)
			(xy 406.092918 -396.998253) (xy 406.114815 -397.044402) (xy 406.122378 -397.068802) (xy 406.123902 -397.074644)
			(xy 406.443688 -397.627602) (xy 406.447752 -397.63192) (xy 406.463952 -397.649631) (xy 406.491375 -397.689022)
			(xy 406.512518 -397.732111) (xy 406.526892 -397.777904) (xy 406.534168 -397.825346) (xy 406.53462 -397.849344)
			(xy 406.534246 -397.874152) (xy 406.526474 -397.923155) (xy 406.511128 -397.970338) (xy 406.488585 -398.014537)
			(xy 406.459403 -398.054664) (xy 406.4243 -398.089728) (xy 406.384142 -398.118866) (xy 406.339918 -398.14136)
			(xy 406.292718 -398.156655) (xy 406.243706 -398.164374) (xy 406.218898 -398.164812) (xy 406.193504 -398.164313)
			(xy 406.14337 -398.156182) (xy 406.095184 -398.140131) (xy 406.05019 -398.116572) (xy 406.009547 -398.086114)
			(xy 405.974304 -398.049543) (xy 405.945371 -398.007802) (xy 405.923493 -397.961967) (xy 405.915876 -397.937736)
			(xy 405.914352 -397.931894) (xy 405.593804 -397.377412) (xy 405.58974 -397.373094) (xy 405.573635 -397.355426)
			(xy 405.546387 -397.316147) (xy 405.525377 -397.273206) (xy 405.511085 -397.227587) (xy 405.503838 -397.180334)
			(xy 405.50338 -397.156432) (xy 405.503522 -397.14438) (xy 405.505428 -397.12035) (xy 405.50719 -397.108426)
			(xy 405.50846 -397.099536) (xy 405.505412 -397.082518) (xy 405.463248 -397.011652) (xy 405.45004 -397.000476)
			(xy 405.441658 -396.997428) (xy 405.419908 -396.989039) (xy 405.379049 -396.966597) (xy 405.342079 -396.938202)
			(xy 405.309857 -396.904516) (xy 405.283132 -396.866321) (xy 405.262527 -396.824507) (xy 405.248519 -396.780045)
			(xy 405.241436 -396.73397) (xy 405.240998 -396.710662) (xy 405.241524 -396.685267) (xy 405.249934 -396.635178)
			(xy 405.266514 -396.587171) (xy 405.290808 -396.542568) (xy 405.322146 -396.502599) (xy 405.340566 -396.48511)
			(xy 405.348948 -396.47749) (xy 405.357584 -396.457424) (xy 405.35479 -396.35811) (xy 405.345392 -396.338552)
			(xy 405.336502 -396.33144) (xy 405.317975 -396.315601) (xy 405.285251 -396.279479) (xy 405.258178 -396.238948)
			(xy 405.237342 -396.194886) (xy 405.223192 -396.148244) (xy 405.216036 -396.100032) (xy 405.215598 -396.075662)
			(xy 405.216004 -396.051544) (xy 405.223012 -396.00382) (xy 405.236874 -395.957619) (xy 405.257297 -395.91392)
			(xy 405.270208 -395.893544) (xy 405.27605 -395.884654) (xy 405.279606 -395.864588) (xy 405.258524 -395.772386)
			(xy 405.246332 -395.755622) (xy 405.237442 -395.750288) (xy 405.216646 -395.737425) (xy 405.178742 -395.706536)
			(xy 405.1458 -395.670401) (xy 405.118539 -395.629809) (xy 405.097552 -395.585645) (xy 405.083299 -395.538872)
			(xy 405.076089 -395.49051) (xy 405.075644 -395.466062) (xy 405.076209 -395.438778) (xy 405.085158 -395.38495)
			(xy 405.102824 -395.333322) (xy 405.128727 -395.285294) (xy 405.162164 -395.242172) (xy 405.181816 -395.223238)
			(xy 405.189205 -395.215706) (xy 405.197736 -395.196434) (xy 405.198326 -395.1859) (xy 405.198326 -395.111224)
			(xy 405.19779 -395.100675) (xy 405.189259 -395.08138) (xy 405.181816 -395.073886) (xy 405.162179 -395.054938)
			(xy 405.128746 -395.011815) (xy 405.102843 -394.963791) (xy 405.08517 -394.912168) (xy 405.076207 -394.858344)
			(xy 405.075644 -394.831062) (xy 405.075898 -394.81887) (xy 405.076152 -394.809218) (xy 405.070056 -394.791184)
			(xy 405.011382 -394.723874) (xy 404.994618 -394.715238) (xy 404.984712 -394.714222) (xy 404.957811 -394.710809)
			(xy 404.905526 -394.696453) (xy 404.856282 -394.673762) (xy 404.811399 -394.643343) (xy 404.772078 -394.606012)
			(xy 404.739372 -394.562766) (xy 404.714157 -394.514766) (xy 404.697108 -394.463296) (xy 404.692358 -394.4366)
			(xy 404.690834 -394.427202) (xy 404.418038 -393.95527) (xy 404.410672 -393.949428) (xy 404.391919 -393.933598)
			(xy 404.358801 -393.897386) (xy 404.331389 -393.856684) (xy 404.310284 -393.812381) (xy 404.295948 -393.76545)
			(xy 404.288694 -393.716916) (xy 404.288244 -393.69238) (xy 403.77145 -393.69238) (xy 404.02002 -394.122402)
			(xy 404.027386 -394.128244) (xy 404.046164 -394.144045) (xy 404.079283 -394.180262) (xy 404.106692 -394.22097)
			(xy 404.127793 -394.265278) (xy 404.142123 -394.312216) (xy 404.149368 -394.360754) (xy 404.149814 -394.385292)
			(xy 404.14956 -394.397484) (xy 404.149306 -394.407136) (xy 404.155402 -394.42517) (xy 404.214076 -394.49248)
			(xy 404.23084 -394.501116) (xy 404.240492 -394.502132) (xy 404.267253 -394.505498) (xy 404.319276 -394.519719)
			(xy 404.368302 -394.542193) (xy 404.413031 -394.572324) (xy 404.452279 -394.609314) (xy 404.485005 -394.652181)
			(xy 404.510341 -394.699791) (xy 404.527617 -394.75088) (xy 404.536374 -394.804096) (xy 404.53691 -394.831062)
			(xy 404.536376 -394.858347) (xy 404.527421 -394.912178) (xy 404.509749 -394.963807) (xy 404.483839 -395.011834)
			(xy 404.450394 -395.054954) (xy 404.430738 -395.073886) (xy 404.423346 -395.081416) (xy 404.414815 -395.100689)
			(xy 404.414228 -395.111224) (xy 404.414228 -395.1859) (xy 404.414735 -395.196452) (xy 404.423285 -395.215748)
			(xy 404.430738 -395.223238) (xy 404.450379 -395.242183) (xy 404.483812 -395.285306) (xy 404.509716 -395.33333)
			(xy 404.527388 -395.384955) (xy 404.536349 -395.438779) (xy 404.53691 -395.466062) (xy 404.536466 -395.490178)
			(xy 404.529469 -395.537901) (xy 404.515618 -395.584102) (xy 404.495206 -395.627803) (xy 404.4823 -395.64818)
			(xy 404.476458 -395.65707) (xy 404.472902 -395.677136) (xy 404.493984 -395.769338) (xy 404.506176 -395.786102)
			(xy 404.515066 -395.791436) (xy 404.535874 -395.804279) (xy 404.573778 -395.835172) (xy 404.606719 -395.87131)
			(xy 404.633979 -395.911905) (xy 404.654963 -395.956072) (xy 404.669214 -396.002848) (xy 404.676421 -396.051213)
			(xy 404.676864 -396.075662) (xy 404.676456 -396.100036) (xy 404.669309 -396.148257) (xy 404.655165 -396.194907)
			(xy 404.63433 -396.238977) (xy 404.607254 -396.279514) (xy 404.574523 -396.315639) (xy 404.55596 -396.33144)
			(xy 404.54707 -396.338552) (xy 404.537672 -396.35811) (xy 404.534878 -396.457424) (xy 404.543514 -396.47749)
			(xy 404.551896 -396.48511) (xy 404.570334 -396.502584) (xy 404.601684 -396.54255) (xy 404.625984 -396.587155)
			(xy 404.642564 -396.635169) (xy 404.650964 -396.685264) (xy 404.651464 -396.710662) (xy 404.651395 -396.720021)
			(xy 404.650252 -396.738703) (xy 404.649178 -396.748) (xy 404.648162 -396.75689) (xy 404.651972 -396.773654)
			(xy 404.695914 -396.843504) (xy 404.70963 -396.853918) (xy 404.718012 -396.856712) (xy 404.742035 -396.865195)
			(xy 404.787208 -396.888744) (xy 404.828014 -396.91924) (xy 404.863394 -396.955892) (xy 404.892431 -396.997749)
			(xy 404.91437 -397.043725) (xy 404.921974 -397.06804) (xy 404.923498 -397.073882) (xy 405.243792 -397.627602)
			(xy 405.247856 -397.63192) (xy 405.264057 -397.64963) (xy 405.29148 -397.689021) (xy 405.312622 -397.732111)
			(xy 405.326997 -397.777904) (xy 405.334272 -397.825346) (xy 405.334724 -397.849344) (xy 405.334346 -397.874152)
			(xy 405.326574 -397.923155) (xy 405.311228 -397.970337) (xy 405.288686 -398.014536) (xy 405.259504 -398.054662)
			(xy 405.224402 -398.089727) (xy 405.184244 -398.118865) (xy 405.140021 -398.141359) (xy 405.092821 -398.156654)
			(xy 405.04381 -398.164373) (xy 405.019002 -398.164812) (xy 404.993608 -398.16431) (xy 404.943474 -398.156179)
			(xy 404.895289 -398.140128) (xy 404.850294 -398.11657) (xy 404.809651 -398.086113) (xy 404.774409 -398.049542)
			(xy 404.745475 -398.007801) (xy 404.723597 -397.961966) (xy 404.71598 -397.937736) (xy 404.714456 -397.931894)
			(xy 404.394162 -397.378174) (xy 404.390098 -397.373856) (xy 404.373946 -397.356115) (xy 404.346575 -397.316716)
			(xy 404.325482 -397.273628) (xy 404.311153 -397.227844) (xy 404.303918 -397.180419) (xy 404.303484 -397.156432)
			(xy 404.303564 -397.144384) (xy 404.305347 -397.120355) (xy 404.30704 -397.108426) (xy 404.30831 -397.099536)
			(xy 404.305262 -397.082518) (xy 404.263098 -397.011652) (xy 404.24989 -397.000476) (xy 404.241508 -396.997428)
			(xy 404.219768 -396.989012) (xy 404.178909 -396.966576) (xy 404.141937 -396.938187) (xy 404.109713 -396.904505)
			(xy 404.082986 -396.866313) (xy 404.062378 -396.824502) (xy 404.04837 -396.780042) (xy 404.041286 -396.733969)
			(xy 404.040848 -396.710662) (xy 404.041358 -396.685266) (xy 404.049769 -396.635176) (xy 404.066352 -396.587167)
			(xy 404.09065 -396.542565) (xy 404.121993 -396.502597) (xy 404.140416 -396.48511) (xy 404.148798 -396.47749)
			(xy 404.157434 -396.457424) (xy 404.15464 -396.35811) (xy 404.145242 -396.338552) (xy 404.136352 -396.33144)
			(xy 404.117815 -396.315612) (xy 404.085094 -396.279486) (xy 404.058024 -396.238953) (xy 404.037189 -396.194889)
			(xy 404.023041 -396.148246) (xy 404.015886 -396.100033) (xy 404.015448 -396.075662) (xy 404.015862 -396.051544)
			(xy 404.022869 -396.003821) (xy 404.036729 -395.95762) (xy 404.057149 -395.91392) (xy 404.070058 -395.893544)
			(xy 404.0759 -395.884654) (xy 404.079456 -395.864588) (xy 404.058374 -395.772386) (xy 404.046182 -395.755622)
			(xy 404.037292 -395.750288) (xy 404.016508 -395.737407) (xy 403.978601 -395.706523) (xy 403.945656 -395.670392)
			(xy 403.918393 -395.629803) (xy 403.897405 -395.585642) (xy 403.88315 -395.53887) (xy 403.875939 -395.49051)
			(xy 403.875494 -395.466062) (xy 403.876043 -395.438777) (xy 403.884993 -395.384948) (xy 403.902662 -395.333318)
			(xy 403.928569 -395.285291) (xy 403.962011 -395.242171) (xy 403.981666 -395.223238) (xy 403.989048 -395.2157)
			(xy 403.997585 -395.196433) (xy 403.998176 -395.1859) (xy 403.998176 -395.111224) (xy 403.997655 -395.100673)
			(xy 403.989115 -395.081377) (xy 403.981666 -395.073886) (xy 403.962038 -395.054929) (xy 403.928602 -395.011809)
			(xy 403.902696 -394.963788) (xy 403.885021 -394.912166) (xy 403.876057 -394.858344) (xy 403.875494 -394.831062)
			(xy 403.875748 -394.81887) (xy 403.876002 -394.809218) (xy 403.869906 -394.791184) (xy 403.811232 -394.723874)
			(xy 403.794468 -394.715238) (xy 403.784816 -394.714222) (xy 403.757915 -394.710806) (xy 403.70563 -394.696451)
			(xy 403.656387 -394.67376) (xy 403.611503 -394.643342) (xy 403.572182 -394.60601) (xy 403.539476 -394.562766)
			(xy 403.514261 -394.514766) (xy 403.497212 -394.463296) (xy 403.492462 -394.4366) (xy 403.490938 -394.427202)
			(xy 403.218142 -393.95527) (xy 403.210776 -393.949428) (xy 403.192024 -393.933597) (xy 403.158906 -393.897386)
			(xy 403.131494 -393.856683) (xy 403.110388 -393.812381) (xy 403.096052 -393.76545) (xy 403.088798 -393.716916)
			(xy 403.088348 -393.69238) (xy 400.76128 -393.69238) (xy 400.784563 -393.704687) (xy 400.825652 -393.73536)
			(xy 400.861513 -393.772009) (xy 400.891287 -393.813754) (xy 400.91426 -393.859595) (xy 400.929882 -393.908432)
			(xy 400.937776 -393.959096) (xy 400.938238 -393.984734) (xy 400.937726 -394.01072) (xy 400.929591 -394.062052)
			(xy 400.913528 -394.11148) (xy 400.889931 -394.157787) (xy 400.859381 -394.199833) (xy 400.82263 -394.236583)
			(xy 400.793801 -394.25753) (xy 402.46173 -394.25753) (xy 402.46224 -394.231543) (xy 402.47037 -394.180208)
			(xy 402.486431 -394.130778) (xy 402.510027 -394.084468) (xy 402.540577 -394.04242) (xy 402.577328 -394.005669)
			(xy 402.619376 -393.975119) (xy 402.665686 -393.951523) (xy 402.715116 -393.935462) (xy 402.766451 -393.927332)
			(xy 402.818425 -393.927332) (xy 402.86976 -393.935462) (xy 402.91919 -393.951523) (xy 402.9655 -393.975119)
			(xy 403.007548 -394.005669) (xy 403.044299 -394.04242) (xy 403.074849 -394.084468) (xy 403.098445 -394.130778)
			(xy 403.114506 -394.180208) (xy 403.122636 -394.231543) (xy 403.123146 -394.25753) (xy 403.122763 -394.281206)
			(xy 403.11603 -394.328077) (xy 403.102665 -394.373504) (xy 403.093174 -394.395198) (xy 403.088856 -394.404596)
			(xy 403.088094 -394.424662) (xy 403.120352 -394.511022) (xy 403.134068 -394.525754) (xy 403.143466 -394.530072)
			(xy 403.167838 -394.541755) (xy 403.212708 -394.571884) (xy 403.252085 -394.608904) (xy 403.284922 -394.65183)
			(xy 403.310348 -394.699522) (xy 403.327686 -394.750712) (xy 403.336475 -394.804039) (xy 403.337014 -394.831062)
			(xy 403.336478 -394.858347) (xy 403.327524 -394.912177) (xy 403.309852 -394.963807) (xy 403.283942 -395.011833)
			(xy 403.250498 -395.054954) (xy 403.230842 -395.073886) (xy 403.223451 -395.081417) (xy 403.214919 -395.10069)
			(xy 403.214332 -395.111224) (xy 403.214332 -395.1859) (xy 403.214838 -395.196453) (xy 403.223388 -395.215748)
			(xy 403.230842 -395.223238) (xy 403.250483 -395.242182) (xy 403.283917 -395.285305) (xy 403.309821 -395.33333)
			(xy 403.327492 -395.384955) (xy 403.336453 -395.438779) (xy 403.337014 -395.466062) (xy 403.33657 -395.490178)
			(xy 403.329573 -395.537901) (xy 403.315722 -395.584102) (xy 403.29531 -395.627803) (xy 403.282404 -395.64818)
			(xy 403.276562 -395.65707) (xy 403.273006 -395.677136) (xy 403.294088 -395.769338) (xy 403.30628 -395.786102)
			(xy 403.31517 -395.791436) (xy 403.335979 -395.804278) (xy 403.373883 -395.835171) (xy 403.406824 -395.871309)
			(xy 403.434083 -395.911905) (xy 403.455067 -395.956072) (xy 403.469318 -396.002848) (xy 403.476525 -396.051213)
			(xy 403.476968 -396.075662) (xy 403.476559 -396.100036) (xy 403.469412 -396.148256) (xy 403.455268 -396.194907)
			(xy 403.434433 -396.238977) (xy 403.407357 -396.279513) (xy 403.374627 -396.315639) (xy 403.356064 -396.33144)
			(xy 403.347174 -396.338552) (xy 403.337776 -396.35811) (xy 403.334982 -396.457424) (xy 403.343618 -396.47749)
			(xy 403.352 -396.48511) (xy 403.370439 -396.502583) (xy 403.401789 -396.542549) (xy 403.426089 -396.587155)
			(xy 403.442668 -396.635168) (xy 403.451068 -396.685264) (xy 403.451568 -396.710662) (xy 403.451499 -396.720021)
			(xy 403.450356 -396.738703) (xy 403.449282 -396.748) (xy 403.448266 -396.75689) (xy 403.452076 -396.773654)
			(xy 403.496018 -396.843504) (xy 403.509734 -396.853918) (xy 403.518116 -396.856712) (xy 403.54214 -396.865193)
			(xy 403.587312 -396.888742) (xy 403.628118 -396.919239) (xy 403.663498 -396.955891) (xy 403.692535 -396.997749)
			(xy 403.714474 -397.043725) (xy 403.722078 -397.06804) (xy 403.723602 -397.073882) (xy 404.043896 -397.627602)
			(xy 404.04796 -397.63192) (xy 404.064162 -397.64963) (xy 404.091584 -397.689021) (xy 404.112726 -397.73211)
			(xy 404.127101 -397.777904) (xy 404.134376 -397.825346) (xy 404.134828 -397.849344) (xy 404.134446 -397.874151)
			(xy 404.126674 -397.923154) (xy 404.111328 -397.970336) (xy 404.088787 -398.014535) (xy 404.059606 -398.054661)
			(xy 404.024504 -398.089725) (xy 403.984346 -398.118864) (xy 403.940123 -398.141358) (xy 403.892925 -398.156653)
			(xy 403.843914 -398.164373) (xy 403.819106 -398.164812) (xy 403.793712 -398.164306) (xy 403.743578 -398.156177)
			(xy 403.695393 -398.140126) (xy 403.650399 -398.116568) (xy 403.609756 -398.086112) (xy 403.574513 -398.049541)
			(xy 403.545579 -398.007801) (xy 403.523701 -397.961966) (xy 403.516084 -397.937736) (xy 403.51456 -397.931894)
			(xy 403.194266 -397.378174) (xy 403.190202 -397.373856) (xy 403.174051 -397.356115) (xy 403.14668 -397.316716)
			(xy 403.125587 -397.273628) (xy 403.111257 -397.227844) (xy 403.104022 -397.180419) (xy 403.103588 -397.156432)
			(xy 403.103669 -397.144384) (xy 403.105452 -397.120355) (xy 403.107144 -397.108426) (xy 403.108414 -397.099536)
			(xy 403.105366 -397.082518) (xy 403.063202 -397.011652) (xy 403.049994 -397.000476) (xy 403.041612 -396.997428)
			(xy 403.019873 -396.98901) (xy 402.979014 -396.966574) (xy 402.942041 -396.938185) (xy 402.909817 -396.904504)
			(xy 402.88309 -396.866313) (xy 402.862483 -396.824501) (xy 402.848474 -396.780042) (xy 402.84139 -396.733969)
			(xy 402.840952 -396.710662) (xy 402.841461 -396.685266) (xy 402.849872 -396.635176) (xy 402.866455 -396.587167)
			(xy 402.890753 -396.542564) (xy 402.922097 -396.502597) (xy 402.94052 -396.48511) (xy 402.948902 -396.47749)
			(xy 402.957538 -396.457424) (xy 402.954744 -396.35811) (xy 402.945346 -396.338552) (xy 402.936456 -396.33144)
			(xy 402.91792 -396.315611) (xy 402.885198 -396.279486) (xy 402.858128 -396.238953) (xy 402.837294 -396.194889)
			(xy 402.823146 -396.148246) (xy 402.81599 -396.100033) (xy 402.815552 -396.075662) (xy 402.815965 -396.051544)
			(xy 402.822973 -396.003821) (xy 402.836833 -395.95762) (xy 402.857253 -395.91392) (xy 402.870162 -395.893544)
			(xy 402.876004 -395.884654) (xy 402.87956 -395.864588) (xy 402.858478 -395.772386) (xy 402.846286 -395.755622)
			(xy 402.837396 -395.750288) (xy 402.816613 -395.737406) (xy 402.778706 -395.706522) (xy 402.745761 -395.670391)
			(xy 402.718497 -395.629803) (xy 402.697509 -395.585641) (xy 402.683254 -395.53887) (xy 402.676043 -395.49051)
			(xy 402.675598 -395.466062) (xy 402.676145 -395.438777) (xy 402.685096 -395.384947) (xy 402.702765 -395.333318)
			(xy 402.728673 -395.285291) (xy 402.762115 -395.242171) (xy 402.78177 -395.223238) (xy 402.789153 -395.2157)
			(xy 402.797689 -395.196433) (xy 402.79828 -395.1859) (xy 402.79828 -395.111224) (xy 402.797757 -395.100673)
			(xy 402.789218 -395.081378) (xy 402.78177 -395.073886) (xy 402.762143 -395.054928) (xy 402.728707 -395.011809)
			(xy 402.7028 -394.963788) (xy 402.685125 -394.912166) (xy 402.676161 -394.858344) (xy 402.675598 -394.831062)
			(xy 402.675983 -394.807386) (xy 402.682716 -394.760515) (xy 402.69608 -394.715089) (xy 402.70557 -394.693394)
			(xy 402.709888 -394.683996) (xy 402.71065 -394.66393) (xy 402.678392 -394.57757) (xy 402.664676 -394.562838)
			(xy 402.655278 -394.55852) (xy 402.630912 -394.546823) (xy 402.586041 -394.516698) (xy 402.546662 -394.479682)
			(xy 402.513822 -394.436758) (xy 402.488395 -394.389068) (xy 402.471057 -394.337879) (xy 402.462269 -394.284553)
			(xy 402.46173 -394.25753) (xy 400.793801 -394.25753) (xy 400.780584 -394.267133) (xy 400.734277 -394.290729)
			(xy 400.684849 -394.306792) (xy 400.633516 -394.314926) (xy 400.60753 -394.315442) (xy 400.581898 -394.314955)
			(xy 400.531248 -394.307037) (xy 400.482426 -394.291401) (xy 400.4366 -394.268421) (xy 400.394867 -394.238647)
			(xy 400.358227 -394.202793) (xy 400.327555 -394.161716) (xy 400.303586 -394.116399) (xy 400.286895 -394.067927)
			(xy 400.27788 -394.017461) (xy 400.276822 -393.991846) (xy 400.276568 -393.976606) (xy 400.259296 -393.95146)
			(xy 400.158458 -393.91082) (xy 400.149083 -393.907524) (xy 400.12923 -393.907621) (xy 400.110913 -393.915276)
			(xy 400.103594 -393.921996) (xy 400.082766 -393.942824) (xy 400.075146 -393.960604) (xy 400.075146 -393.970764)
			(xy 400.074244 -393.997411) (xy 400.065915 -394.050073) (xy 400.050337 -394.101063) (xy 400.027813 -394.149388)
			(xy 399.998781 -394.194108) (xy 399.963806 -394.23435) (xy 399.923571 -394.269333) (xy 399.878858 -394.298374)
			(xy 399.830537 -394.320908) (xy 399.77955 -394.336497) (xy 399.72689 -394.344837) (xy 399.700242 -394.345668)
			(xy 399.690082 -394.345668) (xy 399.672302 -394.353288) (xy 399.154142 -394.871448) (xy 400.378676 -394.871448)
			(xy 400.379186 -394.845461) (xy 400.387316 -394.794126) (xy 400.403377 -394.744696) (xy 400.426973 -394.698386)
			(xy 400.457523 -394.656338) (xy 400.494274 -394.619587) (xy 400.536322 -394.589037) (xy 400.582632 -394.565441)
			(xy 400.632062 -394.54938) (xy 400.683397 -394.54125) (xy 400.735371 -394.54125) (xy 400.786706 -394.54938)
			(xy 400.836136 -394.565441) (xy 400.882446 -394.589037) (xy 400.924494 -394.619587) (xy 400.961245 -394.656338)
			(xy 400.991795 -394.698386) (xy 401.015391 -394.744696) (xy 401.031452 -394.794126) (xy 401.039582 -394.845461)
			(xy 401.040092 -394.871448) (xy 401.039556 -394.898777) (xy 401.030561 -394.952691) (xy 401.012823 -395.004392)
			(xy 400.986826 -395.052473) (xy 400.970496 -395.074394) (xy 400.964908 -395.08176) (xy 400.95932 -395.098524)
			(xy 400.962876 -395.182598) (xy 400.969734 -395.198854) (xy 400.97583 -395.205712) (xy 400.992214 -395.22411)
			(xy 401.019865 -395.264883) (xy 401.041166 -395.309305) (xy 401.055647 -395.356393) (xy 401.062988 -395.405108)
			(xy 401.06346 -395.42974) (xy 401.06295 -395.455727) (xy 401.05482 -395.507062) (xy 401.038759 -395.556492)
			(xy 401.015163 -395.602802) (xy 400.984613 -395.64485) (xy 400.947862 -395.681601) (xy 400.905814 -395.712151)
			(xy 400.859504 -395.735747) (xy 400.810074 -395.751808) (xy 400.758739 -395.759938) (xy 400.706765 -395.759938)
			(xy 400.65543 -395.751808) (xy 400.606 -395.735747) (xy 400.55969 -395.712151) (xy 400.517642 -395.681601)
			(xy 400.480891 -395.64485) (xy 400.450341 -395.602802) (xy 400.426745 -395.556492) (xy 400.410684 -395.507062)
			(xy 400.402554 -395.455727) (xy 400.402044 -395.42974) (xy 400.40264 -395.402413) (xy 400.411619 -395.348503)
			(xy 400.429339 -395.296802) (xy 400.455318 -395.248718) (xy 400.47164 -395.226794) (xy 400.477228 -395.219428)
			(xy 400.482816 -395.202664) (xy 400.47926 -395.11859) (xy 400.472402 -395.102334) (xy 400.466306 -395.095476)
			(xy 400.44997 -395.077037) (xy 400.422311 -395.036276) (xy 400.401 -394.991865) (xy 400.386508 -394.944785)
			(xy 400.379154 -394.896077) (xy 400.378676 -394.871448) (xy 399.154142 -394.871448) (xy 397.640556 -396.385034)
			(xy 397.633497 -396.392891) (xy 397.62589 -396.412571) (xy 397.625824 -396.423134) (xy 397.629634 -396.508986)
			(xy 397.639286 -396.528036) (xy 397.647414 -396.534894) (xy 397.672482 -396.556698) (xy 397.715405 -396.607401)
			(xy 397.732758 -396.635732) (xy 397.737584 -396.643606) (xy 397.7513 -396.654782) (xy 397.830802 -396.682722)
			(xy 397.848582 -396.682468) (xy 397.857218 -396.679166) (xy 397.886561 -396.668312) (xy 397.947234 -396.653046)
			(xy 398.009324 -396.645348) (xy 398.040606 -396.644876) (xy 398.072568 -396.645378) (xy 398.135987 -396.653391)
			(xy 398.197902 -396.669289) (xy 398.224131 -396.679674) (xy 399.436588 -396.679674) (xy 399.440659 -396.624052)
			(xy 399.452785 -396.569615) (xy 399.472708 -396.517524) (xy 399.500004 -396.468889) (xy 399.53409 -396.424746)
			(xy 399.574239 -396.386037) (xy 399.619597 -396.353586) (xy 399.669197 -396.328085) (xy 399.721981 -396.310078)
			(xy 399.776824 -396.299948) (xy 399.832558 -396.297911) (xy 399.887995 -396.304011) (xy 399.941952 -396.318117)
			(xy 399.993281 -396.339929) (xy 400.040887 -396.368983) (xy 400.083755 -396.404658) (xy 400.120972 -396.446195)
			(xy 400.151745 -396.492708) (xy 400.175417 -396.543205) (xy 400.191485 -396.596612) (xy 400.199605 -396.651788)
			(xy 400.200114 -396.679674) (xy 400.199667 -396.704137) (xy 400.402554 -396.704137) (xy 400.402554 -396.652163)
			(xy 400.410684 -396.600828) (xy 400.426745 -396.551398) (xy 400.450341 -396.505088) (xy 400.480891 -396.46304)
			(xy 400.517642 -396.426289) (xy 400.55969 -396.395739) (xy 400.606 -396.372143) (xy 400.65543 -396.356082)
			(xy 400.706765 -396.347952) (xy 400.758739 -396.347952) (xy 400.810074 -396.356082) (xy 400.859504 -396.372143)
			(xy 400.905814 -396.395739) (xy 400.947862 -396.426289) (xy 400.984613 -396.46304) (xy 401.015163 -396.505088)
			(xy 401.038759 -396.551398) (xy 401.05482 -396.600828) (xy 401.06295 -396.652163) (xy 401.06346 -396.67815)
			(xy 401.06295 -396.704137) (xy 401.05482 -396.755472) (xy 401.038759 -396.804902) (xy 401.015163 -396.851212)
			(xy 400.984613 -396.89326) (xy 400.947862 -396.930011) (xy 400.905814 -396.960561) (xy 400.859504 -396.984157)
			(xy 400.810074 -397.000218) (xy 400.758739 -397.008348) (xy 400.706765 -397.008348) (xy 400.65543 -397.000218)
			(xy 400.606 -396.984157) (xy 400.55969 -396.960561) (xy 400.517642 -396.930011) (xy 400.480891 -396.89326)
			(xy 400.450341 -396.851212) (xy 400.426745 -396.804902) (xy 400.410684 -396.755472) (xy 400.402554 -396.704137)
			(xy 400.199667 -396.704137) (xy 400.199605 -396.70756) (xy 400.191485 -396.762736) (xy 400.175417 -396.816143)
			(xy 400.151745 -396.86664) (xy 400.120972 -396.913153) (xy 400.083755 -396.95469) (xy 400.040887 -396.990365)
			(xy 399.993281 -397.019419) (xy 399.941952 -397.041231) (xy 399.887995 -397.055337) (xy 399.832558 -397.061437)
			(xy 399.776824 -397.0594) (xy 399.721981 -397.04927) (xy 399.669197 -397.031263) (xy 399.619597 -397.005762)
			(xy 399.574239 -396.973311) (xy 399.53409 -396.934602) (xy 399.500004 -396.890459) (xy 399.472708 -396.841824)
			(xy 399.452785 -396.789733) (xy 399.440659 -396.735296) (xy 399.436588 -396.679674) (xy 398.224131 -396.679674)
			(xy 398.257337 -396.692821) (xy 398.313353 -396.723617) (xy 398.365068 -396.76119) (xy 398.411666 -396.804949)
			(xy 398.452413 -396.854204) (xy 398.486664 -396.908176) (xy 398.513881 -396.966016) (xy 398.533635 -397.026811)
			(xy 398.545613 -397.089603) (xy 398.549627 -397.1534) (xy 398.545613 -397.217197) (xy 398.533635 -397.279989)
			(xy 398.513881 -397.340784) (xy 398.486664 -397.398624) (xy 398.452413 -397.452596) (xy 398.411666 -397.501851)
			(xy 398.365068 -397.54561) (xy 398.313353 -397.583183) (xy 398.257337 -397.613979) (xy 398.197902 -397.637511)
			(xy 398.135987 -397.653409) (xy 398.072568 -397.661422) (xy 398.040606 -397.661892) (xy 398.007216 -397.66136)
			(xy 397.941012 -397.652609) (xy 397.876522 -397.635272) (xy 397.814855 -397.609644) (xy 397.757072 -397.576169)
			(xy 397.704166 -397.53542) (xy 397.657046 -397.488099) (xy 397.616524 -397.435019) (xy 397.583295 -397.377093)
			(xy 397.557932 -397.315317) (xy 397.548862 -397.283178) (xy 397.546576 -397.274034) (xy 397.536416 -397.25981)
			(xy 397.467074 -397.21155) (xy 397.450056 -397.206978) (xy 397.440912 -397.207994) (xy 397.403574 -397.209772)
			(xy 397.370554 -397.208248) (xy 397.3576 -397.207232) (xy 397.334232 -397.217392) (xy 397.265652 -397.304514)
			(xy 397.261334 -397.32966) (xy 397.265398 -397.341852) (xy 397.274671 -397.371344) (xy 397.284632 -397.432354)
			(xy 397.28521 -397.463264) (xy 397.284749 -397.490519) (xy 397.276996 -397.544474) (xy 397.261643 -397.596776)
			(xy 397.239003 -397.646361) (xy 397.209536 -397.692218) (xy 397.173842 -397.733415) (xy 397.132649 -397.769113)
			(xy 397.086794 -397.798585) (xy 397.037211 -397.82123) (xy 396.984911 -397.836588) (xy 396.930957 -397.844346)
			(xy 396.903702 -397.844772) (xy 396.87428 -397.844227) (xy 396.816134 -397.835189) (xy 396.760067 -397.817327)
			(xy 396.707408 -397.791065) (xy 396.659408 -397.757026) (xy 396.617206 -397.716018) (xy 396.581804 -397.669015)
			(xy 396.567406 -397.64335) (xy 396.561818 -397.632682) (xy 396.542006 -397.618966) (xy 396.449296 -397.60525)
			(xy 396.437477 -397.604139) (xy 396.414955 -397.611551) (xy 396.406116 -397.619474) (xy 395.43736 -398.58823)
			(xy 395.429273 -398.597286) (xy 395.421826 -398.620358) (xy 395.423136 -398.632426) (xy 395.43863 -398.726152)
			(xy 395.453108 -398.74571) (xy 395.464284 -398.751298) (xy 395.480738 -398.759611) (xy 395.51252 -398.778298)
			(xy 395.527784 -398.788636) (xy 395.536536 -398.794107) (xy 395.55674 -398.798235) (xy 395.576944 -398.794107)
			(xy 395.585696 -398.788636) (xy 395.611223 -398.77158) (xy 395.665585 -398.74305) (xy 395.722989 -398.721279)
			(xy 395.782598 -398.706584) (xy 395.843543 -398.699178) (xy 395.87424 -398.69872) (xy 395.904969 -398.699186)
			(xy 395.965978 -398.706599) (xy 396.025649 -398.721311) (xy 396.083111 -398.743109) (xy 396.137527 -398.771673)
			(xy 396.188103 -398.806589) (xy 396.234102 -398.847346) (xy 396.274853 -398.89335) (xy 396.309762 -398.943931)
			(xy 396.338319 -398.998351) (xy 396.360109 -399.055816) (xy 396.374813 -399.115489) (xy 396.382218 -399.176499)
			(xy 396.382748 -399.207228) (xy 396.382174 -399.242074) (xy 396.372657 -399.311112) (xy 396.353806 -399.378206)
			(xy 396.325973 -399.442098) (xy 396.308326 -399.47215) (xy 396.3035 -399.480024) (xy 396.299944 -399.497804)
			(xy 396.314422 -399.582132) (xy 396.323566 -399.59788) (xy 396.330932 -399.603722) (xy 396.355586 -399.62448)
			(xy 396.399977 -399.671207) (xy 396.438112 -399.723165) (xy 396.469382 -399.779522) (xy 396.493286 -399.839377)
			(xy 396.50944 -399.90177) (xy 396.517587 -399.965705) (xy 396.51813 -399.99793) (xy 396.517649 -400.028624)
			(xy 396.510225 -400.089563) (xy 396.495524 -400.149166) (xy 396.47376 -400.206568) (xy 396.445248 -400.260935)
			(xy 396.428214 -400.286474) (xy 396.422747 -400.295225) (xy 396.418628 -400.315425) (xy 396.422766 -400.335621)
			(xy 396.428214 -400.344386) (xy 396.445268 -400.369913) (xy 396.473797 -400.424276) (xy 396.495567 -400.48168)
			(xy 396.510262 -400.541288) (xy 396.517668 -400.602233) (xy 396.51813 -400.63293) (xy 396.517664 -400.66366)
			(xy 396.510253 -400.724672) (xy 396.495542 -400.784347) (xy 396.473745 -400.841812) (xy 396.445182 -400.896232)
			(xy 396.410267 -400.946813) (xy 396.369511 -400.992816) (xy 396.323507 -401.033572) (xy 396.272926 -401.068486)
			(xy 396.218505 -401.097049) (xy 396.161039 -401.118844) (xy 396.101365 -401.133554) (xy 396.040352 -401.140965)
			(xy 396.009622 -401.141438) (xy 395.98854 -401.14093) (xy 395.977618 -401.140422) (xy 395.95806 -401.148042)
			(xy 395.889734 -401.216368) (xy 395.882114 -401.235926) (xy 395.882622 -401.246848) (xy 395.88313 -401.26793)
			(xy 395.882649 -401.298624) (xy 395.875225 -401.359563) (xy 395.860524 -401.419166) (xy 395.83876 -401.476568)
			(xy 395.810248 -401.530935) (xy 395.793214 -401.556474) (xy 395.787747 -401.565225) (xy 395.783628 -401.585425)
			(xy 395.787766 -401.605621) (xy 395.793214 -401.614386) (xy 395.810268 -401.639913) (xy 395.838797 -401.694276)
			(xy 395.860567 -401.75168) (xy 395.875262 -401.811288) (xy 395.882668 -401.872233) (xy 395.88313 -401.90293)
			(xy 395.882664 -401.93366) (xy 395.875253 -401.994672) (xy 395.860542 -402.054347) (xy 395.838745 -402.111812)
			(xy 395.810182 -402.166232) (xy 395.775267 -402.216813) (xy 395.734511 -402.262816) (xy 395.688507 -402.303572)
			(xy 395.637926 -402.338486) (xy 395.583505 -402.367049) (xy 395.526039 -402.388844) (xy 395.466365 -402.403554)
			(xy 395.405352 -402.410965) (xy 395.374622 -402.411438) (xy 395.337037 -402.410745) (xy 395.262688 -402.399656)
			(xy 395.22654 -402.38934) (xy 395.21511 -402.385784) (xy 395.191234 -402.390102) (xy 395.11605 -402.445728)
			(xy 395.106819 -402.453338) (xy 395.096071 -402.474675) (xy 395.095476 -402.486622) (xy 395.095476 -403.085046)
			(xy 395.095907 -403.095113) (xy 395.10363 -403.113708) (xy 395.110462 -403.121114)
		)
		(stroke
			(width 0)
			(type solid)
		)
		(fill yes)
		(layer "In15.Cu")
		(net "P0V9_CPU0_RT2_2A_2D")
	)
	(gr_poly
		(pts
			(xy 139.187428 -394.816076) (xy 139.196354 -394.824132) (xy 139.219146 -394.831688) (xy 139.231116 -394.830554)
			(xy 139.785344 -394.746226) (xy 139.85368 -394.735425) (xy 139.989286 -394.707934) (xy 140.12337 -394.673777)
			(xy 140.255602 -394.633038) (xy 140.320776 -394.609828) (xy 140.321284 -394.609574) (xy 142.093696 -393.968986)
			(xy 142.101745 -393.965709) (xy 142.115175 -393.954698) (xy 142.124162 -393.939838) (xy 142.126208 -393.931394)
			(xy 142.146274 -393.83335) (xy 142.1384 -393.808458) (xy 142.128748 -393.799314) (xy 142.123414 -393.794234)
			(xy 142.116084 -393.787693) (xy 142.09792 -393.780258) (xy 142.088108 -393.779756) (xy 142.056104 -393.779756)
			(xy 142.046293 -393.780256) (xy 142.028131 -393.787698) (xy 142.020798 -393.794234) (xy 141.9993 -393.814412)
			(xy 141.951244 -393.848566) (xy 141.898505 -393.874921) (xy 141.84234 -393.892847) (xy 141.784085 -393.901919)
			(xy 141.754606 -393.902438) (xy 141.727236 -393.901967) (xy 141.673058 -393.894142) (xy 141.620556 -393.878654)
			(xy 141.570806 -393.855819) (xy 141.524832 -393.826108) (xy 141.503908 -393.808458) (xy 141.496796 -393.802362)
			(xy 141.479778 -393.796012) (xy 141.394434 -393.796012) (xy 141.377416 -393.802362) (xy 141.370304 -393.808458)
			(xy 141.349374 -393.826102) (xy 141.303408 -393.855832) (xy 141.253661 -393.878678) (xy 141.201158 -393.894171)
			(xy 141.146977 -393.901991) (xy 141.119606 -393.902438) (xy 141.092354 -393.901953) (xy 141.038404 -393.894197)
			(xy 140.986107 -393.878843) (xy 140.936527 -393.856202) (xy 140.890673 -393.826737) (xy 140.84948 -393.791046)
			(xy 140.813785 -393.749856) (xy 140.784315 -393.704005) (xy 140.76167 -393.654427) (xy 140.746311 -393.602132)
			(xy 140.73855 -393.548182) (xy 140.738098 -393.52093) (xy 140.738575 -393.493562) (xy 140.746407 -393.439388)
			(xy 140.761902 -393.38689) (xy 140.784741 -393.337146) (xy 140.814454 -393.291176) (xy 140.832078 -393.270232)
			(xy 140.838174 -393.26312) (xy 140.844524 -393.246102) (xy 140.844524 -393.160758) (xy 140.838174 -393.14374)
			(xy 140.832078 -393.136628) (xy 140.814437 -393.115694) (xy 140.784712 -393.069725) (xy 140.761865 -393.019977)
			(xy 140.746367 -392.967474) (xy 140.738536 -392.913294) (xy 140.738533 -392.858551) (xy 140.746358 -392.80437)
			(xy 140.76185 -392.751865) (xy 140.78469 -392.702115) (xy 140.81441 -392.656142) (xy 140.832078 -392.635232)
			(xy 140.838174 -392.62812) (xy 140.844524 -392.611102) (xy 140.844524 -392.525758) (xy 140.838174 -392.50874)
			(xy 140.832078 -392.501628) (xy 140.814437 -392.480694) (xy 140.784712 -392.434725) (xy 140.761865 -392.384977)
			(xy 140.746367 -392.332474) (xy 140.738536 -392.278294) (xy 140.738533 -392.223551) (xy 140.746358 -392.16937)
			(xy 140.76185 -392.116865) (xy 140.78469 -392.067115) (xy 140.81441 -392.021142) (xy 140.832078 -392.000232)
			(xy 140.838174 -391.99312) (xy 140.844524 -391.976102) (xy 140.844524 -391.890758) (xy 140.838174 -391.87374)
			(xy 140.832078 -391.866628) (xy 140.814435 -391.845697) (xy 140.784708 -391.79973) (xy 140.761862 -391.749984)
			(xy 140.746369 -391.697481) (xy 140.738547 -391.643301) (xy 140.738098 -391.61593) (xy 140.738586 -391.588397)
			(xy 140.746511 -391.533904) (xy 140.762186 -391.481116) (xy 140.785286 -391.431129) (xy 140.815331 -391.384982)
			(xy 140.851697 -391.343632) (xy 140.893629 -391.307939) (xy 140.91666 -391.292842) (xy 140.925296 -391.287508)
			(xy 140.936726 -391.271252) (xy 140.957808 -391.181844) (xy 140.954506 -391.162286) (xy 140.949172 -391.15365)
			(xy 140.935721 -391.130989) (xy 140.914508 -391.08275) (xy 140.90015 -391.032046) (xy 140.892924 -390.979847)
			(xy 140.89253 -390.953498) (xy 140.893002 -390.926128) (xy 140.900827 -390.871951) (xy 140.916315 -390.819448)
			(xy 140.939149 -390.769698) (xy 140.968859 -390.723723) (xy 140.98651 -390.7028) (xy 140.992606 -390.695688)
			(xy 140.998956 -390.67867) (xy 140.998956 -390.593326) (xy 140.992606 -390.576308) (xy 140.98651 -390.569196)
			(xy 140.968868 -390.548265) (xy 140.939142 -390.502298) (xy 140.916298 -390.452552) (xy 140.900808 -390.400048)
			(xy 140.89299 -390.345869) (xy 140.89253 -390.318498) (xy 140.893016 -390.291247) (xy 140.900772 -390.237299)
			(xy 140.916127 -390.185004) (xy 140.938769 -390.135427) (xy 140.968235 -390.089577) (xy 141.003926 -390.048386)
			(xy 141.045117 -390.012695) (xy 141.090967 -389.983229) (xy 141.140544 -389.960587) (xy 141.192839 -389.945232)
			(xy 141.246787 -389.937476) (xy 141.301289 -389.937476) (xy 141.355237 -389.945232) (xy 141.407532 -389.960587)
			(xy 141.457109 -389.983229) (xy 141.502959 -390.012695) (xy 141.54415 -390.048386) (xy 141.579841 -390.089577)
			(xy 141.609307 -390.135427) (xy 141.631949 -390.185004) (xy 141.647304 -390.237299) (xy 141.65506 -390.291247)
			(xy 141.655546 -390.318498) (xy 141.655074 -390.345868) (xy 141.64725 -390.400045) (xy 141.631761 -390.452548)
			(xy 141.608927 -390.502297) (xy 141.579215 -390.548272) (xy 141.561566 -390.569196) (xy 141.55547 -390.576308)
			(xy 141.54912 -390.593326) (xy 141.54912 -390.626092) (xy 144.390364 -390.626092) (xy 144.390783 -390.602859)
			(xy 144.397277 -390.556849) (xy 144.410148 -390.512202) (xy 144.429145 -390.469797) (xy 144.453892 -390.43047)
			(xy 144.468596 -390.412478) (xy 144.474692 -390.405366) (xy 144.480788 -390.388856) (xy 144.480788 -390.304528)
			(xy 144.474692 -390.288018) (xy 144.468596 -390.280906) (xy 144.453875 -390.262926) (xy 144.429131 -390.223594)
			(xy 144.410134 -390.181186) (xy 144.397258 -390.136538) (xy 144.390757 -390.090526) (xy 144.390364 -390.067292)
			(xy 144.390874 -390.041305) (xy 144.399004 -389.98997) (xy 144.415065 -389.94054) (xy 144.438661 -389.89423)
			(xy 144.469211 -389.852182) (xy 144.505962 -389.815431) (xy 144.54801 -389.784881) (xy 144.59432 -389.761285)
			(xy 144.64375 -389.745224) (xy 144.695085 -389.737094) (xy 144.747059 -389.737094) (xy 144.798394 -389.745224)
			(xy 144.847824 -389.761285) (xy 144.894134 -389.784881) (xy 144.936182 -389.815431) (xy 144.972933 -389.852182)
			(xy 145.003483 -389.89423) (xy 145.027079 -389.94054) (xy 145.04314 -389.98997) (xy 145.05127 -390.041305)
			(xy 145.05178 -390.067292) (xy 145.051423 -390.090527) (xy 145.044917 -390.13654) (xy 145.038146 -390.160002)
			(xy 146.712952 -390.160002) (xy 146.716912 -390.110948) (xy 146.728689 -390.063164) (xy 146.74798 -390.017888)
			(xy 146.774283 -389.976292) (xy 146.806918 -389.939455) (xy 146.845039 -389.90833) (xy 146.88766 -389.883723)
			(xy 146.933676 -389.866271) (xy 146.981895 -389.856427) (xy 147.03107 -389.854446) (xy 147.079925 -389.860378)
			(xy 147.127196 -389.87407) (xy 147.171658 -389.895168) (xy 147.212161 -389.923124) (xy 147.247654 -389.957216)
			(xy 147.277219 -389.99656) (xy 147.30009 -390.040137) (xy 147.315674 -390.086818) (xy 147.323569 -390.135395)
			(xy 147.324064 -390.160002) (xy 147.913102 -390.160002) (xy 147.917062 -390.110948) (xy 147.928839 -390.063164)
			(xy 147.94813 -390.017888) (xy 147.974433 -389.976292) (xy 148.007068 -389.939455) (xy 148.045189 -389.90833)
			(xy 148.08781 -389.883723) (xy 148.133826 -389.866271) (xy 148.182045 -389.856427) (xy 148.23122 -389.854446)
			(xy 148.280075 -389.860378) (xy 148.327346 -389.87407) (xy 148.371808 -389.895168) (xy 148.412311 -389.923124)
			(xy 148.447804 -389.957216) (xy 148.477369 -389.99656) (xy 148.50024 -390.040137) (xy 148.515824 -390.086818)
			(xy 148.523719 -390.135395) (xy 148.524214 -390.160002) (xy 149.113252 -390.160002) (xy 149.117212 -390.110948)
			(xy 149.128989 -390.063164) (xy 149.14828 -390.017888) (xy 149.174583 -389.976292) (xy 149.207218 -389.939455)
			(xy 149.245339 -389.90833) (xy 149.28796 -389.883723) (xy 149.333976 -389.866271) (xy 149.382195 -389.856427)
			(xy 149.43137 -389.854446) (xy 149.480225 -389.860378) (xy 149.527496 -389.87407) (xy 149.571958 -389.895168)
			(xy 149.612461 -389.923124) (xy 149.647954 -389.957216) (xy 149.677519 -389.99656) (xy 149.70039 -390.040137)
			(xy 149.715974 -390.086818) (xy 149.723869 -390.135395) (xy 149.724364 -390.160002) (xy 150.313148 -390.160002)
			(xy 150.317108 -390.110948) (xy 150.328885 -390.063164) (xy 150.348176 -390.017888) (xy 150.374479 -389.976292)
			(xy 150.407114 -389.939455) (xy 150.445235 -389.90833) (xy 150.487856 -389.883723) (xy 150.533872 -389.866271)
			(xy 150.582091 -389.856427) (xy 150.631266 -389.854446) (xy 150.680121 -389.860378) (xy 150.727392 -389.87407)
			(xy 150.771854 -389.895168) (xy 150.812357 -389.923124) (xy 150.84785 -389.957216) (xy 150.877415 -389.99656)
			(xy 150.900286 -390.040137) (xy 150.91587 -390.086818) (xy 150.923765 -390.135395) (xy 150.92426 -390.160002)
			(xy 151.513298 -390.160002) (xy 151.517258 -390.110948) (xy 151.529035 -390.063164) (xy 151.548326 -390.017888)
			(xy 151.574629 -389.976292) (xy 151.607264 -389.939455) (xy 151.645385 -389.90833) (xy 151.688006 -389.883723)
			(xy 151.734022 -389.866271) (xy 151.782241 -389.856427) (xy 151.831416 -389.854446) (xy 151.880271 -389.860378)
			(xy 151.927542 -389.87407) (xy 151.972004 -389.895168) (xy 152.012507 -389.923124) (xy 152.048 -389.957216)
			(xy 152.077565 -389.99656) (xy 152.100436 -390.040137) (xy 152.11602 -390.086818) (xy 152.123915 -390.135395)
			(xy 152.12441 -390.160002) (xy 152.713194 -390.160002) (xy 152.717154 -390.110948) (xy 152.728931 -390.063164)
			(xy 152.748222 -390.017888) (xy 152.774525 -389.976292) (xy 152.80716 -389.939455) (xy 152.845281 -389.90833)
			(xy 152.887902 -389.883723) (xy 152.933918 -389.866271) (xy 152.982137 -389.856427) (xy 153.031312 -389.854446)
			(xy 153.080167 -389.860378) (xy 153.127438 -389.87407) (xy 153.1719 -389.895168) (xy 153.212403 -389.923124)
			(xy 153.247896 -389.957216) (xy 153.277461 -389.99656) (xy 153.300332 -390.040137) (xy 153.315916 -390.086818)
			(xy 153.323811 -390.135395) (xy 153.324306 -390.160002) (xy 153.91309 -390.160002) (xy 153.91705 -390.110948)
			(xy 153.928827 -390.063164) (xy 153.948118 -390.017888) (xy 153.974421 -389.976292) (xy 154.007056 -389.939455)
			(xy 154.045177 -389.90833) (xy 154.087798 -389.883723) (xy 154.133814 -389.866271) (xy 154.182033 -389.856427)
			(xy 154.231208 -389.854446) (xy 154.280063 -389.860378) (xy 154.327334 -389.87407) (xy 154.371796 -389.895168)
			(xy 154.412299 -389.923124) (xy 154.447792 -389.957216) (xy 154.477357 -389.99656) (xy 154.500228 -390.040137)
			(xy 154.515812 -390.086818) (xy 154.523707 -390.135395) (xy 154.524202 -390.160002) (xy 155.11324 -390.160002)
			(xy 155.1172 -390.110948) (xy 155.128977 -390.063164) (xy 155.148268 -390.017888) (xy 155.174571 -389.976292)
			(xy 155.207206 -389.939455) (xy 155.245327 -389.90833) (xy 155.287948 -389.883723) (xy 155.333964 -389.866271)
			(xy 155.382183 -389.856427) (xy 155.431358 -389.854446) (xy 155.480213 -389.860378) (xy 155.527484 -389.87407)
			(xy 155.571946 -389.895168) (xy 155.612449 -389.923124) (xy 155.647942 -389.957216) (xy 155.677507 -389.99656)
			(xy 155.700378 -390.040137) (xy 155.715962 -390.086818) (xy 155.723857 -390.135395) (xy 155.724352 -390.160002)
			(xy 156.313136 -390.160002) (xy 156.317096 -390.110948) (xy 156.328873 -390.063164) (xy 156.348164 -390.017888)
			(xy 156.374467 -389.976292) (xy 156.407102 -389.939455) (xy 156.445223 -389.90833) (xy 156.487844 -389.883723)
			(xy 156.53386 -389.866271) (xy 156.582079 -389.856427) (xy 156.631254 -389.854446) (xy 156.680109 -389.860378)
			(xy 156.72738 -389.87407) (xy 156.771842 -389.895168) (xy 156.812345 -389.923124) (xy 156.847838 -389.957216)
			(xy 156.877403 -389.99656) (xy 156.900274 -390.040137) (xy 156.915858 -390.086818) (xy 156.923753 -390.135395)
			(xy 156.924248 -390.160002) (xy 157.513286 -390.160002) (xy 157.517246 -390.110948) (xy 157.529023 -390.063164)
			(xy 157.548314 -390.017888) (xy 157.574617 -389.976292) (xy 157.607252 -389.939455) (xy 157.645373 -389.90833)
			(xy 157.687994 -389.883723) (xy 157.73401 -389.866271) (xy 157.782229 -389.856427) (xy 157.831404 -389.854446)
			(xy 157.880259 -389.860378) (xy 157.92753 -389.87407) (xy 157.971992 -389.895168) (xy 158.012495 -389.923124)
			(xy 158.047988 -389.957216) (xy 158.077553 -389.99656) (xy 158.100424 -390.040137) (xy 158.116008 -390.086818)
			(xy 158.123903 -390.135395) (xy 158.124398 -390.160002) (xy 158.713182 -390.160002) (xy 158.717142 -390.110948)
			(xy 158.728919 -390.063164) (xy 158.74821 -390.017888) (xy 158.774513 -389.976292) (xy 158.807148 -389.939455)
			(xy 158.845269 -389.90833) (xy 158.88789 -389.883723) (xy 158.933906 -389.866271) (xy 158.982125 -389.856427)
			(xy 159.0313 -389.854446) (xy 159.080155 -389.860378) (xy 159.127426 -389.87407) (xy 159.171888 -389.895168)
			(xy 159.212391 -389.923124) (xy 159.247884 -389.957216) (xy 159.277449 -389.99656) (xy 159.30032 -390.040137)
			(xy 159.315904 -390.086818) (xy 159.323799 -390.135395) (xy 159.324294 -390.160002) (xy 159.913078 -390.160002)
			(xy 159.917038 -390.110948) (xy 159.928815 -390.063164) (xy 159.948106 -390.017888) (xy 159.974409 -389.976292)
			(xy 160.007044 -389.939455) (xy 160.045165 -389.90833) (xy 160.087786 -389.883723) (xy 160.133802 -389.866271)
			(xy 160.182021 -389.856427) (xy 160.231196 -389.854446) (xy 160.280051 -389.860378) (xy 160.327322 -389.87407)
			(xy 160.371784 -389.895168) (xy 160.412287 -389.923124) (xy 160.44778 -389.957216) (xy 160.477345 -389.99656)
			(xy 160.500216 -390.040137) (xy 160.5158 -390.086818) (xy 160.523695 -390.135395) (xy 160.52419 -390.160002)
			(xy 161.113228 -390.160002) (xy 161.117188 -390.110948) (xy 161.128965 -390.063164) (xy 161.148256 -390.017888)
			(xy 161.174559 -389.976292) (xy 161.207194 -389.939455) (xy 161.245315 -389.90833) (xy 161.287936 -389.883723)
			(xy 161.333952 -389.866271) (xy 161.382171 -389.856427) (xy 161.431346 -389.854446) (xy 161.480201 -389.860378)
			(xy 161.527472 -389.87407) (xy 161.571934 -389.895168) (xy 161.612437 -389.923124) (xy 161.64793 -389.957216)
			(xy 161.677495 -389.99656) (xy 161.700366 -390.040137) (xy 161.71595 -390.086818) (xy 161.723845 -390.135395)
			(xy 161.72434 -390.160002) (xy 162.313124 -390.160002) (xy 162.317084 -390.110948) (xy 162.328861 -390.063164)
			(xy 162.348152 -390.017888) (xy 162.374455 -389.976292) (xy 162.40709 -389.939455) (xy 162.445211 -389.90833)
			(xy 162.487832 -389.883723) (xy 162.533848 -389.866271) (xy 162.582067 -389.856427) (xy 162.631242 -389.854446)
			(xy 162.680097 -389.860378) (xy 162.727368 -389.87407) (xy 162.77183 -389.895168) (xy 162.812333 -389.923124)
			(xy 162.847826 -389.957216) (xy 162.877391 -389.99656) (xy 162.900262 -390.040137) (xy 162.915846 -390.086818)
			(xy 162.923741 -390.135395) (xy 162.924236 -390.160002) (xy 163.513274 -390.160002) (xy 163.517234 -390.110948)
			(xy 163.529011 -390.063164) (xy 163.548302 -390.017888) (xy 163.574605 -389.976292) (xy 163.60724 -389.939455)
			(xy 163.645361 -389.90833) (xy 163.687982 -389.883723) (xy 163.733998 -389.866271) (xy 163.782217 -389.856427)
			(xy 163.831392 -389.854446) (xy 163.880247 -389.860378) (xy 163.927518 -389.87407) (xy 163.97198 -389.895168)
			(xy 164.012483 -389.923124) (xy 164.047976 -389.957216) (xy 164.077541 -389.99656) (xy 164.100412 -390.040137)
			(xy 164.115996 -390.086818) (xy 164.123891 -390.135395) (xy 164.124386 -390.160002) (xy 164.71317 -390.160002)
			(xy 164.71713 -390.110948) (xy 164.728907 -390.063164) (xy 164.748198 -390.017888) (xy 164.774501 -389.976292)
			(xy 164.807136 -389.939455) (xy 164.845257 -389.90833) (xy 164.887878 -389.883723) (xy 164.933894 -389.866271)
			(xy 164.982113 -389.856427) (xy 165.031288 -389.854446) (xy 165.080143 -389.860378) (xy 165.127414 -389.87407)
			(xy 165.171876 -389.895168) (xy 165.212379 -389.923124) (xy 165.247872 -389.957216) (xy 165.277437 -389.99656)
			(xy 165.300308 -390.040137) (xy 165.315892 -390.086818) (xy 165.323787 -390.135395) (xy 165.324282 -390.160002)
			(xy 165.323787 -390.184609) (xy 165.315892 -390.233186) (xy 165.300308 -390.279867) (xy 165.277437 -390.323444)
			(xy 165.247872 -390.362788) (xy 165.212379 -390.39688) (xy 165.171876 -390.424836) (xy 165.127414 -390.445934)
			(xy 165.080143 -390.459626) (xy 165.031288 -390.465558) (xy 164.982113 -390.463577) (xy 164.933894 -390.453733)
			(xy 164.887878 -390.436281) (xy 164.845257 -390.411674) (xy 164.807136 -390.380549) (xy 164.774501 -390.343712)
			(xy 164.748198 -390.302116) (xy 164.728907 -390.25684) (xy 164.71713 -390.209056) (xy 164.71317 -390.160002)
			(xy 164.124386 -390.160002) (xy 164.123891 -390.184609) (xy 164.115996 -390.233186) (xy 164.100412 -390.279867)
			(xy 164.077541 -390.323444) (xy 164.047976 -390.362788) (xy 164.012483 -390.39688) (xy 163.97198 -390.424836)
			(xy 163.927518 -390.445934) (xy 163.880247 -390.459626) (xy 163.831392 -390.465558) (xy 163.782217 -390.463577)
			(xy 163.733998 -390.453733) (xy 163.687982 -390.436281) (xy 163.645361 -390.411674) (xy 163.60724 -390.380549)
			(xy 163.574605 -390.343712) (xy 163.548302 -390.302116) (xy 163.529011 -390.25684) (xy 163.517234 -390.209056)
			(xy 163.513274 -390.160002) (xy 162.924236 -390.160002) (xy 162.923741 -390.184609) (xy 162.915846 -390.233186)
			(xy 162.900262 -390.279867) (xy 162.877391 -390.323444) (xy 162.847826 -390.362788) (xy 162.812333 -390.39688)
			(xy 162.77183 -390.424836) (xy 162.727368 -390.445934) (xy 162.680097 -390.459626) (xy 162.631242 -390.465558)
			(xy 162.582067 -390.463577) (xy 162.533848 -390.453733) (xy 162.487832 -390.436281) (xy 162.445211 -390.411674)
			(xy 162.40709 -390.380549) (xy 162.374455 -390.343712) (xy 162.348152 -390.302116) (xy 162.328861 -390.25684)
			(xy 162.317084 -390.209056) (xy 162.313124 -390.160002) (xy 161.72434 -390.160002) (xy 161.723845 -390.184609)
			(xy 161.71595 -390.233186) (xy 161.700366 -390.279867) (xy 161.677495 -390.323444) (xy 161.64793 -390.362788)
			(xy 161.612437 -390.39688) (xy 161.571934 -390.424836) (xy 161.527472 -390.445934) (xy 161.480201 -390.459626)
			(xy 161.431346 -390.465558) (xy 161.382171 -390.463577) (xy 161.333952 -390.453733) (xy 161.287936 -390.436281)
			(xy 161.245315 -390.411674) (xy 161.207194 -390.380549) (xy 161.174559 -390.343712) (xy 161.148256 -390.302116)
			(xy 161.128965 -390.25684) (xy 161.117188 -390.209056) (xy 161.113228 -390.160002) (xy 160.52419 -390.160002)
			(xy 160.523695 -390.184609) (xy 160.5158 -390.233186) (xy 160.500216 -390.279867) (xy 160.477345 -390.323444)
			(xy 160.44778 -390.362788) (xy 160.412287 -390.39688) (xy 160.371784 -390.424836) (xy 160.327322 -390.445934)
			(xy 160.280051 -390.459626) (xy 160.231196 -390.465558) (xy 160.182021 -390.463577) (xy 160.133802 -390.453733)
			(xy 160.087786 -390.436281) (xy 160.045165 -390.411674) (xy 160.007044 -390.380549) (xy 159.974409 -390.343712)
			(xy 159.948106 -390.302116) (xy 159.928815 -390.25684) (xy 159.917038 -390.209056) (xy 159.913078 -390.160002)
			(xy 159.324294 -390.160002) (xy 159.323799 -390.184609) (xy 159.315904 -390.233186) (xy 159.30032 -390.279867)
			(xy 159.277449 -390.323444) (xy 159.247884 -390.362788) (xy 159.212391 -390.39688) (xy 159.171888 -390.424836)
			(xy 159.127426 -390.445934) (xy 159.080155 -390.459626) (xy 159.0313 -390.465558) (xy 158.982125 -390.463577)
			(xy 158.933906 -390.453733) (xy 158.88789 -390.436281) (xy 158.845269 -390.411674) (xy 158.807148 -390.380549)
			(xy 158.774513 -390.343712) (xy 158.74821 -390.302116) (xy 158.728919 -390.25684) (xy 158.717142 -390.209056)
			(xy 158.713182 -390.160002) (xy 158.124398 -390.160002) (xy 158.123903 -390.184609) (xy 158.116008 -390.233186)
			(xy 158.100424 -390.279867) (xy 158.077553 -390.323444) (xy 158.047988 -390.362788) (xy 158.012495 -390.39688)
			(xy 157.971992 -390.424836) (xy 157.92753 -390.445934) (xy 157.880259 -390.459626) (xy 157.831404 -390.465558)
			(xy 157.782229 -390.463577) (xy 157.73401 -390.453733) (xy 157.687994 -390.436281) (xy 157.645373 -390.411674)
			(xy 157.607252 -390.380549) (xy 157.574617 -390.343712) (xy 157.548314 -390.302116) (xy 157.529023 -390.25684)
			(xy 157.517246 -390.209056) (xy 157.513286 -390.160002) (xy 156.924248 -390.160002) (xy 156.923753 -390.184609)
			(xy 156.915858 -390.233186) (xy 156.900274 -390.279867) (xy 156.877403 -390.323444) (xy 156.847838 -390.362788)
			(xy 156.812345 -390.39688) (xy 156.771842 -390.424836) (xy 156.72738 -390.445934) (xy 156.680109 -390.459626)
			(xy 156.631254 -390.465558) (xy 156.582079 -390.463577) (xy 156.53386 -390.453733) (xy 156.487844 -390.436281)
			(xy 156.445223 -390.411674) (xy 156.407102 -390.380549) (xy 156.374467 -390.343712) (xy 156.348164 -390.302116)
			(xy 156.328873 -390.25684) (xy 156.317096 -390.209056) (xy 156.313136 -390.160002) (xy 155.724352 -390.160002)
			(xy 155.723857 -390.184609) (xy 155.715962 -390.233186) (xy 155.700378 -390.279867) (xy 155.677507 -390.323444)
			(xy 155.647942 -390.362788) (xy 155.612449 -390.39688) (xy 155.571946 -390.424836) (xy 155.527484 -390.445934)
			(xy 155.480213 -390.459626) (xy 155.431358 -390.465558) (xy 155.382183 -390.463577) (xy 155.333964 -390.453733)
			(xy 155.287948 -390.436281) (xy 155.245327 -390.411674) (xy 155.207206 -390.380549) (xy 155.174571 -390.343712)
			(xy 155.148268 -390.302116) (xy 155.128977 -390.25684) (xy 155.1172 -390.209056) (xy 155.11324 -390.160002)
			(xy 154.524202 -390.160002) (xy 154.523707 -390.184609) (xy 154.515812 -390.233186) (xy 154.500228 -390.279867)
			(xy 154.477357 -390.323444) (xy 154.447792 -390.362788) (xy 154.412299 -390.39688) (xy 154.371796 -390.424836)
			(xy 154.327334 -390.445934) (xy 154.280063 -390.459626) (xy 154.231208 -390.465558) (xy 154.182033 -390.463577)
			(xy 154.133814 -390.453733) (xy 154.087798 -390.436281) (xy 154.045177 -390.411674) (xy 154.007056 -390.380549)
			(xy 153.974421 -390.343712) (xy 153.948118 -390.302116) (xy 153.928827 -390.25684) (xy 153.91705 -390.209056)
			(xy 153.91309 -390.160002) (xy 153.324306 -390.160002) (xy 153.323811 -390.184609) (xy 153.315916 -390.233186)
			(xy 153.300332 -390.279867) (xy 153.277461 -390.323444) (xy 153.247896 -390.362788) (xy 153.212403 -390.39688)
			(xy 153.1719 -390.424836) (xy 153.127438 -390.445934) (xy 153.080167 -390.459626) (xy 153.031312 -390.465558)
			(xy 152.982137 -390.463577) (xy 152.933918 -390.453733) (xy 152.887902 -390.436281) (xy 152.845281 -390.411674)
			(xy 152.80716 -390.380549) (xy 152.774525 -390.343712) (xy 152.748222 -390.302116) (xy 152.728931 -390.25684)
			(xy 152.717154 -390.209056) (xy 152.713194 -390.160002) (xy 152.12441 -390.160002) (xy 152.123915 -390.184609)
			(xy 152.11602 -390.233186) (xy 152.100436 -390.279867) (xy 152.077565 -390.323444) (xy 152.048 -390.362788)
			(xy 152.012507 -390.39688) (xy 151.972004 -390.424836) (xy 151.927542 -390.445934) (xy 151.880271 -390.459626)
			(xy 151.831416 -390.465558) (xy 151.782241 -390.463577) (xy 151.734022 -390.453733) (xy 151.688006 -390.436281)
			(xy 151.645385 -390.411674) (xy 151.607264 -390.380549) (xy 151.574629 -390.343712) (xy 151.548326 -390.302116)
			(xy 151.529035 -390.25684) (xy 151.517258 -390.209056) (xy 151.513298 -390.160002) (xy 150.92426 -390.160002)
			(xy 150.923765 -390.184609) (xy 150.91587 -390.233186) (xy 150.900286 -390.279867) (xy 150.877415 -390.323444)
			(xy 150.84785 -390.362788) (xy 150.812357 -390.39688) (xy 150.771854 -390.424836) (xy 150.727392 -390.445934)
			(xy 150.680121 -390.459626) (xy 150.631266 -390.465558) (xy 150.582091 -390.463577) (xy 150.533872 -390.453733)
			(xy 150.487856 -390.436281) (xy 150.445235 -390.411674) (xy 150.407114 -390.380549) (xy 150.374479 -390.343712)
			(xy 150.348176 -390.302116) (xy 150.328885 -390.25684) (xy 150.317108 -390.209056) (xy 150.313148 -390.160002)
			(xy 149.724364 -390.160002) (xy 149.723869 -390.184609) (xy 149.715974 -390.233186) (xy 149.70039 -390.279867)
			(xy 149.677519 -390.323444) (xy 149.647954 -390.362788) (xy 149.612461 -390.39688) (xy 149.571958 -390.424836)
			(xy 149.527496 -390.445934) (xy 149.480225 -390.459626) (xy 149.43137 -390.465558) (xy 149.382195 -390.463577)
			(xy 149.333976 -390.453733) (xy 149.28796 -390.436281) (xy 149.245339 -390.411674) (xy 149.207218 -390.380549)
			(xy 149.174583 -390.343712) (xy 149.14828 -390.302116) (xy 149.128989 -390.25684) (xy 149.117212 -390.209056)
			(xy 149.113252 -390.160002) (xy 148.524214 -390.160002) (xy 148.523719 -390.184609) (xy 148.515824 -390.233186)
			(xy 148.50024 -390.279867) (xy 148.477369 -390.323444) (xy 148.447804 -390.362788) (xy 148.412311 -390.39688)
			(xy 148.371808 -390.424836) (xy 148.327346 -390.445934) (xy 148.280075 -390.459626) (xy 148.23122 -390.465558)
			(xy 148.182045 -390.463577) (xy 148.133826 -390.453733) (xy 148.08781 -390.436281) (xy 148.045189 -390.411674)
			(xy 148.007068 -390.380549) (xy 147.974433 -390.343712) (xy 147.94813 -390.302116) (xy 147.928839 -390.25684)
			(xy 147.917062 -390.209056) (xy 147.913102 -390.160002) (xy 147.324064 -390.160002) (xy 147.323569 -390.184609)
			(xy 147.315674 -390.233186) (xy 147.30009 -390.279867) (xy 147.277219 -390.323444) (xy 147.247654 -390.362788)
			(xy 147.212161 -390.39688) (xy 147.171658 -390.424836) (xy 147.127196 -390.445934) (xy 147.079925 -390.459626)
			(xy 147.03107 -390.465558) (xy 146.981895 -390.463577) (xy 146.933676 -390.453733) (xy 146.88766 -390.436281)
			(xy 146.845039 -390.411674) (xy 146.806918 -390.380549) (xy 146.774283 -390.343712) (xy 146.74798 -390.302116)
			(xy 146.728689 -390.25684) (xy 146.716912 -390.209056) (xy 146.712952 -390.160002) (xy 145.038146 -390.160002)
			(xy 145.032031 -390.181188) (xy 145.013021 -390.223593) (xy 144.988259 -390.262917) (xy 144.973548 -390.280906)
			(xy 144.967452 -390.288018) (xy 144.961356 -390.304528) (xy 144.961356 -390.388856) (xy 144.967452 -390.405366)
			(xy 144.973548 -390.412478) (xy 144.988253 -390.43047) (xy 145.013001 -390.469798) (xy 145.032002 -390.512203)
			(xy 145.044882 -390.556849) (xy 145.051386 -390.602859) (xy 145.05178 -390.626092) (xy 145.051368 -390.650185)
			(xy 145.044389 -390.697862) (xy 145.030577 -390.744025) (xy 145.020792 -390.766046) (xy 145.015458 -390.777476)
			(xy 145.016728 -390.802622) (xy 145.072862 -390.896602) (xy 145.094452 -390.909556) (xy 145.107152 -390.910318)
			(xy 145.132148 -390.912171) (xy 145.181192 -390.922501) (xy 145.228116 -390.940114) (xy 145.271845 -390.964605)
			(xy 145.311377 -390.995415) (xy 145.345808 -391.031837) (xy 145.374349 -391.073037) (xy 145.396346 -391.118072)
			(xy 145.411296 -391.165911) (xy 145.418856 -391.215458) (xy 145.419318 -391.240518) (xy 145.418808 -391.266505)
			(xy 145.410678 -391.31784) (xy 145.394617 -391.36727) (xy 145.371021 -391.41358) (xy 145.340471 -391.455628)
			(xy 145.30372 -391.492379) (xy 145.261672 -391.522929) (xy 145.215362 -391.546525) (xy 145.165932 -391.562586)
			(xy 145.114597 -391.570716) (xy 145.062623 -391.570716) (xy 145.011288 -391.562586) (xy 144.961858 -391.546525)
			(xy 144.915548 -391.522929) (xy 144.8735 -391.492379) (xy 144.836749 -391.455628) (xy 144.806199 -391.41358)
			(xy 144.782603 -391.36727) (xy 144.766542 -391.31784) (xy 144.758412 -391.266505) (xy 144.757902 -391.240518)
			(xy 144.758319 -391.216425) (xy 144.765296 -391.168748) (xy 144.779107 -391.122585) (xy 144.78889 -391.100564)
			(xy 144.794224 -391.089134) (xy 144.792954 -391.063988) (xy 144.73682 -390.970008) (xy 144.71523 -390.957054)
			(xy 144.70253 -390.956292) (xy 144.677534 -390.954445) (xy 144.62849 -390.944112) (xy 144.581567 -390.926498)
			(xy 144.537839 -390.902005) (xy 144.498307 -390.871195) (xy 144.463876 -390.834773) (xy 144.435336 -390.793573)
			(xy 144.413338 -390.748537) (xy 144.398388 -390.700699) (xy 144.390826 -390.651152) (xy 144.390364 -390.626092)
			(xy 141.54912 -390.626092) (xy 141.54912 -390.67867) (xy 141.55547 -390.695688) (xy 141.561566 -390.7028)
			(xy 141.579209 -390.723731) (xy 141.608938 -390.769696) (xy 141.631783 -390.819443) (xy 141.647275 -390.871947)
			(xy 141.655094 -390.926127) (xy 141.655546 -390.953498) (xy 141.655145 -390.977847) (xy 141.64892 -391.026147)
			(xy 141.636609 -391.073265) (xy 141.62786 -391.095992) (xy 141.623034 -391.108438) (xy 141.626082 -391.133838)
			(xy 141.692376 -391.225278) (xy 141.715744 -391.2362) (xy 141.728952 -391.235184) (xy 141.754606 -391.234422)
			(xy 141.781976 -391.234894) (xy 141.836153 -391.242719) (xy 141.888656 -391.258208) (xy 141.938406 -391.281041)
			(xy 141.984381 -391.310752) (xy 142.005304 -391.328402) (xy 142.012416 -391.334498) (xy 142.029434 -391.340848)
			(xy 142.114778 -391.340848) (xy 142.131796 -391.334498) (xy 142.138908 -391.328402) (xy 142.159841 -391.310761)
			(xy 142.205809 -391.281037) (xy 142.255555 -391.258191) (xy 142.308057 -391.242695) (xy 142.362235 -391.234866)
			(xy 142.416977 -391.234866) (xy 142.471155 -391.242695) (xy 142.523657 -391.258191) (xy 142.573403 -391.281037)
			(xy 142.619371 -391.310761) (xy 142.640304 -391.328402) (xy 142.647416 -391.334498) (xy 142.664434 -391.340848)
			(xy 142.749778 -391.340848) (xy 142.766796 -391.334498) (xy 142.773908 -391.328402) (xy 142.794839 -391.31076)
			(xy 142.840806 -391.281035) (xy 142.890553 -391.258193) (xy 142.943056 -391.242704) (xy 142.997236 -391.234886)
			(xy 143.024606 -391.234422) (xy 143.051858 -391.234886) (xy 143.105806 -391.242644) (xy 143.158102 -391.258)
			(xy 143.207679 -391.280644) (xy 143.25353 -391.310112) (xy 143.294719 -391.345806) (xy 143.330409 -391.386999)
			(xy 143.359874 -391.432852) (xy 143.382512 -391.482432) (xy 143.397864 -391.534729) (xy 143.405617 -391.588678)
			(xy 143.406114 -391.61593) (xy 143.40564 -391.643299) (xy 143.397813 -391.697476) (xy 143.382323 -391.749977)
			(xy 143.359489 -391.799726) (xy 143.329779 -391.845701) (xy 143.312134 -391.866628) (xy 143.306038 -391.87374)
			(xy 143.299688 -391.890758) (xy 143.299688 -391.976102) (xy 143.306038 -391.99312) (xy 143.312134 -392.000232)
			(xy 143.329774 -392.021164) (xy 143.359498 -392.06713) (xy 143.382341 -392.116875) (xy 143.397835 -392.169376)
			(xy 143.405661 -392.223553) (xy 143.405658 -392.278292) (xy 143.397826 -392.332468) (xy 143.382325 -392.384967)
			(xy 143.359476 -392.434709) (xy 143.329747 -392.480672) (xy 143.312134 -392.501628) (xy 143.306038 -392.50874)
			(xy 143.299688 -392.525758) (xy 143.299688 -392.611102) (xy 143.306038 -392.62812) (xy 143.312134 -392.635232)
			(xy 143.329774 -392.656164) (xy 143.359498 -392.70213) (xy 143.382341 -392.751875) (xy 143.397835 -392.804376)
			(xy 143.405661 -392.858553) (xy 143.405658 -392.913292) (xy 143.397826 -392.967468) (xy 143.382325 -393.019967)
			(xy 143.359476 -393.069709) (xy 143.329747 -393.115672) (xy 143.312134 -393.136628) (xy 143.306038 -393.14374)
			(xy 143.299688 -393.160758) (xy 143.299688 -393.246102) (xy 143.306038 -393.26312) (xy 143.312134 -393.270232)
			(xy 143.327606 -393.288554) (xy 143.354349 -393.328362) (xy 143.375907 -393.371201) (xy 143.38427 -393.393676)
			(xy 143.387572 -393.403074) (xy 143.401034 -393.41806) (xy 143.475456 -393.453366) (xy 143.484793 -393.457197)
			(xy 143.504931 -393.458124) (xy 143.514572 -393.455144) (xy 144.061688 -393.257278) (xy 144.061942 -393.257278)
			(xy 144.073169 -393.253079) (xy 144.095276 -393.243806) (xy 144.106138 -393.238736) (xy 144.107154 -393.238482)
			(xy 144.17548 -393.206478) (xy 144.18649 -393.200733) (xy 144.201543 -393.18102) (xy 144.204182 -393.168886)
			(xy 144.220184 -393.07389) (xy 144.212564 -393.050522) (xy 144.20342 -393.041632) (xy 144.185557 -393.023615)
			(xy 144.154265 -392.983679) (xy 144.128543 -392.939947) (xy 144.108845 -392.893192) (xy 144.095517 -392.844238)
			(xy 144.088794 -392.79395) (xy 144.088358 -392.768582) (xy 144.089628 -392.736324) (xy 144.090644 -392.726672)
			(xy 144.08531 -392.708638) (xy 144.031716 -392.639042) (xy 144.01546 -392.62939) (xy 144.006062 -392.627612)
			(xy 143.979909 -392.622523) (xy 143.929241 -392.606049) (xy 143.881358 -392.582685) (xy 143.837191 -392.552886)
			(xy 143.7976 -392.517232) (xy 143.763355 -392.476416) (xy 143.735123 -392.431232) (xy 143.713451 -392.38256)
			(xy 143.698763 -392.331345) (xy 143.691344 -392.278585) (xy 143.690848 -392.251946) (xy 143.691334 -392.224695)
			(xy 143.69909 -392.170747) (xy 143.714445 -392.118452) (xy 143.737087 -392.068875) (xy 143.766553 -392.023025)
			(xy 143.802244 -391.981834) (xy 143.843435 -391.946143) (xy 143.889285 -391.916677) (xy 143.938862 -391.894035)
			(xy 143.991157 -391.87868) (xy 144.045105 -391.870924) (xy 144.099607 -391.870924) (xy 144.153555 -391.87868)
			(xy 144.20585 -391.894035) (xy 144.255427 -391.916677) (xy 144.301277 -391.946143) (xy 144.342468 -391.981834)
			(xy 144.378159 -392.023025) (xy 144.407625 -392.068875) (xy 144.430267 -392.118452) (xy 144.445622 -392.170747)
			(xy 144.453378 -392.224695) (xy 144.453864 -392.251946) (xy 144.452594 -392.284204) (xy 144.451578 -392.293856)
			(xy 144.456912 -392.31189) (xy 144.510506 -392.381486) (xy 144.526762 -392.391138) (xy 144.53616 -392.392916)
			(xy 144.5636 -392.398248) (xy 144.616644 -392.415882) (xy 144.666545 -392.441072) (xy 144.712233 -392.473279)
			(xy 144.752728 -392.511811) (xy 144.787164 -392.555843) (xy 144.814801 -392.604432) (xy 144.835047 -392.656535)
			(xy 144.847469 -392.711035) (xy 144.850104 -392.738864) (xy 144.85112 -392.751564) (xy 144.864328 -392.772392)
			(xy 144.947386 -392.820906) (xy 144.958396 -392.826633) (xy 144.983163 -392.827688) (xy 144.99463 -392.822938)
			(xy 145.355056 -392.654282) (xy 145.372227 -392.646211) (xy 145.406141 -392.629189) (xy 145.422874 -392.620246)
			(xy 145.423128 -392.619992) (xy 145.488837 -392.585206) (xy 145.624486 -392.524311) (xy 145.694146 -392.498326)
			(xy 145.694908 -392.498072) (xy 145.787364 -392.464798) (xy 145.805652 -392.430762) (xy 145.80108 -392.411712)
			(xy 145.796818 -392.392757) (xy 145.792238 -392.354176) (xy 145.791936 -392.33475) (xy 145.792402 -392.309679)
			(xy 145.799974 -392.260111) (xy 145.814936 -392.212253) (xy 145.836946 -392.1672) (xy 145.8655 -392.125982)
			(xy 145.88236 -392.10742) (xy 145.889218 -392.100308) (xy 145.89633 -392.082274) (xy 145.89633 -392.028426)
			(xy 145.889218 -392.010392) (xy 145.88236 -392.00328) (xy 145.865478 -391.984739) (xy 145.836933 -391.943514)
			(xy 145.814934 -391.898454) (xy 145.799985 -391.850592) (xy 145.792427 -391.801022) (xy 145.791936 -391.77595)
			(xy 145.792415 -391.749959) (xy 145.800541 -391.698617) (xy 145.816599 -391.649179) (xy 145.840195 -391.602862)
			(xy 145.870747 -391.560807) (xy 145.907503 -391.524051) (xy 145.949557 -391.493498) (xy 145.995873 -391.469901)
			(xy 146.045312 -391.453842) (xy 146.096653 -391.445716) (xy 146.122644 -391.445242) (xy 146.149556 -391.445775)
			(xy 146.202668 -391.454502) (xy 146.253664 -391.471718) (xy 146.301197 -391.496969) (xy 146.344011 -391.529588)
			(xy 146.380975 -391.568711) (xy 146.411112 -391.613307) (xy 146.422872 -391.63752) (xy 146.429222 -391.650982)
			(xy 146.454114 -391.666984) (xy 147.15998 -391.666984) (xy 147.171804 -391.666437) (xy 147.193005 -391.655978)
			(xy 147.20062 -391.646918) (xy 147.21649 -391.626744) (xy 147.253811 -391.591509) (xy 147.296502 -391.563018)
			(xy 147.34336 -391.542072) (xy 147.393062 -391.529264) (xy 147.444206 -391.524954) (xy 147.49535 -391.529264)
			(xy 147.545052 -391.542072) (xy 147.59191 -391.563018) (xy 147.634601 -391.591509) (xy 147.671922 -391.626744)
			(xy 147.687792 -391.646918) (xy 147.695437 -391.655939) (xy 147.716621 -391.666386) (xy 147.728432 -391.666984)
			(xy 148.36013 -391.666984) (xy 148.371948 -391.666426) (xy 148.393132 -391.655955) (xy 148.40077 -391.646918)
			(xy 148.41664 -391.626744) (xy 148.453961 -391.591509) (xy 148.496652 -391.563018) (xy 148.54351 -391.542072)
			(xy 148.593212 -391.529264) (xy 148.644356 -391.524954) (xy 148.6955 -391.529264) (xy 148.745202 -391.542072)
			(xy 148.79206 -391.563018) (xy 148.834751 -391.591509) (xy 148.872072 -391.626744) (xy 148.887942 -391.646918)
			(xy 148.895584 -391.655948) (xy 148.916767 -391.666414) (xy 148.928582 -391.666984) (xy 149.560026 -391.666984)
			(xy 149.571845 -391.666427) (xy 149.59303 -391.655957) (xy 149.600666 -391.646918) (xy 149.616536 -391.626744)
			(xy 149.653857 -391.591509) (xy 149.696548 -391.563018) (xy 149.743406 -391.542072) (xy 149.793108 -391.529264)
			(xy 149.844252 -391.524954) (xy 149.895396 -391.529264) (xy 149.945098 -391.542072) (xy 149.991956 -391.563018)
			(xy 150.034647 -391.591509) (xy 150.071968 -391.626744) (xy 150.087838 -391.646918) (xy 150.09548 -391.655948)
			(xy 150.116663 -391.666417) (xy 150.128478 -391.666984) (xy 150.759922 -391.666984) (xy 150.771741 -391.666428)
			(xy 150.792927 -391.655959) (xy 150.800562 -391.646918) (xy 150.816432 -391.626744) (xy 150.853753 -391.591509)
			(xy 150.896444 -391.563018) (xy 150.943302 -391.542072) (xy 150.993004 -391.529264) (xy 151.044148 -391.524954)
			(xy 151.095292 -391.529264) (xy 151.144994 -391.542072) (xy 151.191852 -391.563018) (xy 151.234543 -391.591509)
			(xy 151.271864 -391.626744) (xy 151.287734 -391.646918) (xy 151.295375 -391.655949) (xy 151.316559 -391.666419)
			(xy 151.328374 -391.666984) (xy 151.960072 -391.666984) (xy 151.971897 -391.666438) (xy 151.9931 -391.655982)
			(xy 152.000712 -391.646918) (xy 152.016582 -391.626744) (xy 152.053903 -391.591509) (xy 152.096594 -391.563018)
			(xy 152.143452 -391.542072) (xy 152.193154 -391.529264) (xy 152.244298 -391.524954) (xy 152.295442 -391.529264)
			(xy 152.345144 -391.542072) (xy 152.392002 -391.563018) (xy 152.434693 -391.591509) (xy 152.472014 -391.626744)
			(xy 152.487884 -391.646918) (xy 152.495529 -391.655941) (xy 152.516712 -391.66639) (xy 152.528524 -391.666984)
			(xy 153.159968 -391.666984) (xy 153.171793 -391.666439) (xy 153.192998 -391.655984) (xy 153.200608 -391.646918)
			(xy 153.216478 -391.626744) (xy 153.253799 -391.591509) (xy 153.29649 -391.563018) (xy 153.343348 -391.542072)
			(xy 153.39305 -391.529264) (xy 153.444194 -391.524954) (xy 153.495338 -391.529264) (xy 153.54504 -391.542072)
			(xy 153.591898 -391.563018) (xy 153.634589 -391.591509) (xy 153.67191 -391.626744) (xy 153.68778 -391.646918)
			(xy 153.695424 -391.655941) (xy 153.716608 -391.666392) (xy 153.72842 -391.666984) (xy 154.360118 -391.666984)
			(xy 154.371938 -391.666429) (xy 154.393125 -391.655961) (xy 154.400758 -391.646918) (xy 154.416628 -391.626744)
			(xy 154.453949 -391.591509) (xy 154.49664 -391.563018) (xy 154.543498 -391.542072) (xy 154.5932 -391.529264)
			(xy 154.644344 -391.524954) (xy 154.695488 -391.529264) (xy 154.74519 -391.542072) (xy 154.792048 -391.563018)
			(xy 154.834739 -391.591509) (xy 154.87206 -391.626744) (xy 154.88793 -391.646918) (xy 154.895571 -391.65595)
			(xy 154.916754 -391.666422) (xy 154.92857 -391.666984) (xy 155.560014 -391.666984) (xy 155.571834 -391.666429)
			(xy 155.593023 -391.655962) (xy 155.600654 -391.646918) (xy 155.616524 -391.626744) (xy 155.653845 -391.591509)
			(xy 155.696536 -391.563018) (xy 155.743394 -391.542072) (xy 155.793096 -391.529264) (xy 155.84424 -391.524954)
			(xy 155.895384 -391.529264) (xy 155.945086 -391.542072) (xy 155.991944 -391.563018) (xy 156.034635 -391.591509)
			(xy 156.071956 -391.626744) (xy 156.087826 -391.646918) (xy 156.095467 -391.655951) (xy 156.11665 -391.666424)
			(xy 156.128466 -391.666984) (xy 156.75991 -391.666984) (xy 156.77173 -391.66643) (xy 156.792921 -391.655964)
			(xy 156.80055 -391.646918) (xy 156.81642 -391.626744) (xy 156.853741 -391.591509) (xy 156.896432 -391.563018)
			(xy 156.94329 -391.542072) (xy 156.992992 -391.529264) (xy 157.044136 -391.524954) (xy 157.09528 -391.529264)
			(xy 157.144982 -391.542072) (xy 157.19184 -391.563018) (xy 157.234531 -391.591509) (xy 157.271852 -391.626744)
			(xy 157.287722 -391.646918) (xy 157.295362 -391.655951) (xy 157.316546 -391.666426) (xy 157.328362 -391.666984)
			(xy 157.96006 -391.666984) (xy 157.971886 -391.666441) (xy 157.993094 -391.655987) (xy 158.0007 -391.646918)
			(xy 158.01657 -391.626744) (xy 158.053891 -391.591509) (xy 158.096582 -391.563018) (xy 158.14344 -391.542072)
			(xy 158.193142 -391.529264) (xy 158.244286 -391.524954) (xy 158.29543 -391.529264) (xy 158.345132 -391.542072)
			(xy 158.39199 -391.563018) (xy 158.434681 -391.591509) (xy 158.472002 -391.626744) (xy 158.487872 -391.646918)
			(xy 158.495516 -391.655943) (xy 158.516699 -391.666397) (xy 158.528512 -391.666984) (xy 159.159956 -391.666984)
			(xy 159.171782 -391.666442) (xy 159.192991 -391.655989) (xy 159.200596 -391.646918) (xy 159.216466 -391.626744)
			(xy 159.253787 -391.591509) (xy 159.296478 -391.563018) (xy 159.343336 -391.542072) (xy 159.393038 -391.529264)
			(xy 159.444182 -391.524954) (xy 159.495326 -391.529264) (xy 159.545028 -391.542072) (xy 159.591886 -391.563018)
			(xy 159.634577 -391.591509) (xy 159.671898 -391.626744) (xy 159.687768 -391.646918) (xy 159.695411 -391.655944)
			(xy 159.716595 -391.6664) (xy 159.728408 -391.666984) (xy 160.360106 -391.666984) (xy 160.371927 -391.666431)
			(xy 160.393119 -391.655966) (xy 160.400746 -391.646918) (xy 160.416616 -391.626744) (xy 160.453937 -391.591509)
			(xy 160.496628 -391.563018) (xy 160.543486 -391.542072) (xy 160.593188 -391.529264) (xy 160.644332 -391.524954)
			(xy 160.695476 -391.529264) (xy 160.745178 -391.542072) (xy 160.792036 -391.563018) (xy 160.834727 -391.591509)
			(xy 160.872048 -391.626744) (xy 160.887918 -391.646918) (xy 160.895558 -391.655952) (xy 160.916741 -391.666429)
			(xy 160.928558 -391.666984) (xy 161.560002 -391.666984) (xy 161.571823 -391.666432) (xy 161.593017 -391.655968)
			(xy 161.600642 -391.646918) (xy 161.616512 -391.626744) (xy 161.653833 -391.591509) (xy 161.696524 -391.563018)
			(xy 161.743382 -391.542072) (xy 161.793084 -391.529264) (xy 161.844228 -391.524954) (xy 161.895372 -391.529264)
			(xy 161.945074 -391.542072) (xy 161.991932 -391.563018) (xy 162.034623 -391.591509) (xy 162.071944 -391.626744)
			(xy 162.087814 -391.646918) (xy 162.095454 -391.655952) (xy 162.116637 -391.666431) (xy 162.128454 -391.666984)
			(xy 162.759898 -391.666984) (xy 162.77172 -391.666433) (xy 162.792914 -391.65597) (xy 162.800538 -391.646918)
			(xy 162.816408 -391.626744) (xy 162.853729 -391.591509) (xy 162.89642 -391.563018) (xy 162.943278 -391.542072)
			(xy 162.99298 -391.529264) (xy 163.044124 -391.524954) (xy 163.095268 -391.529264) (xy 163.14497 -391.542072)
			(xy 163.191828 -391.563018) (xy 163.234519 -391.591509) (xy 163.27184 -391.626744) (xy 163.28771 -391.646918)
			(xy 163.29535 -391.655953) (xy 163.316533 -391.666433) (xy 163.32835 -391.666984) (xy 163.960048 -391.666984)
			(xy 163.971875 -391.666443) (xy 163.993087 -391.655993) (xy 164.000688 -391.646918) (xy 164.016558 -391.626744)
			(xy 164.053879 -391.591509) (xy 164.09657 -391.563018) (xy 164.143428 -391.542072) (xy 164.19313 -391.529264)
			(xy 164.244274 -391.524954) (xy 164.295418 -391.529264) (xy 164.34512 -391.542072) (xy 164.391978 -391.563018)
			(xy 164.434669 -391.591509) (xy 164.47199 -391.626744) (xy 164.48786 -391.646918) (xy 164.495503 -391.655945)
			(xy 164.516686 -391.666404) (xy 164.5285 -391.666984) (xy 165.159944 -391.666984) (xy 165.171772 -391.666444)
			(xy 165.192985 -391.655995) (xy 165.200584 -391.646918) (xy 165.215093 -391.628398) (xy 165.248846 -391.595626)
			(xy 165.28723 -391.568424) (xy 165.329334 -391.547437) (xy 165.374161 -391.533161) (xy 165.420647 -391.525935)
			(xy 165.44417 -391.525506) (xy 165.466432 -391.525892) (xy 165.51049 -391.532322) (xy 165.553147 -391.54508)
			(xy 165.593501 -391.563895) (xy 165.612318 -391.575798) (xy 165.627558 -391.585958) (xy 165.663118 -391.582402)
			(xy 166.073074 -391.172446) (xy 166.079915 -391.165046) (xy 166.087633 -391.146447) (xy 166.08806 -391.136378)
			(xy 166.08806 -390.3345) (xy 166.085012 -390.322562) (xy 166.081964 -390.316974) (xy 166.069507 -390.292702)
			(xy 166.051842 -390.24109) (xy 166.042888 -390.187278) (xy 166.042888 -390.132726) (xy 166.051842 -390.078914)
			(xy 166.069506 -390.027301) (xy 166.081964 -390.00303) (xy 166.085012 -389.997442) (xy 166.08806 -389.985504)
			(xy 166.08806 -389.84936) (xy 166.087308 -389.836695) (xy 166.075175 -389.814449) (xy 166.064946 -389.806942)
			(xy 165.982904 -389.753348) (xy 165.957504 -389.751316) (xy 165.94582 -389.756396) (xy 165.925756 -389.764781)
			(xy 165.883899 -389.776569) (xy 165.840817 -389.782476) (xy 165.819074 -389.782812) (xy 165.793681 -389.782302)
			(xy 165.743552 -389.774168) (xy 165.695371 -389.758115) (xy 165.650381 -389.734555) (xy 165.609743 -389.704098)
			(xy 165.574504 -389.667528) (xy 165.545574 -389.625788) (xy 165.523698 -389.579956) (xy 165.516052 -389.555736)
			(xy 165.514528 -389.549894) (xy 165.194234 -388.996174) (xy 165.19017 -388.991856) (xy 165.173982 -388.974146)
			(xy 165.14661 -388.934743) (xy 165.125523 -388.891647) (xy 165.111207 -388.845854) (xy 165.103994 -388.798422)
			(xy 165.103556 -388.774432) (xy 165.103642 -388.762384) (xy 165.105425 -388.738355) (xy 165.107112 -388.726426)
			(xy 165.108382 -388.717536) (xy 165.105334 -388.700518) (xy 165.06317 -388.629652) (xy 165.049962 -388.618476)
			(xy 165.04158 -388.615428) (xy 165.019746 -388.606975) (xy 164.978736 -388.584388) (xy 164.941654 -388.555808)
			(xy 164.909367 -388.521903) (xy 164.882631 -388.48347) (xy 164.862073 -388.441406) (xy 164.848174 -388.396699)
			(xy 164.844222 -388.37362) (xy 164.841428 -388.355078) (xy 164.81298 -388.33044) (xy 164.27958 -388.33044)
			(xy 164.251132 -388.355078) (xy 164.248338 -388.37362) (xy 164.24656 -388.384288) (xy 164.245182 -388.393693)
			(xy 164.248701 -388.412358) (xy 164.253418 -388.42061) (xy 164.27069 -388.447534) (xy 164.276087 -388.455329)
			(xy 164.291361 -388.466539) (xy 164.300408 -388.469378) (xy 164.326446 -388.47689) (xy 164.375662 -388.499566)
			(xy 164.420284 -388.530311) (xy 164.459002 -388.568223) (xy 164.49068 -388.612188) (xy 164.514387 -388.660916)
			(xy 164.522404 -388.686802) (xy 164.523928 -388.692644) (xy 164.843714 -389.245602) (xy 164.847778 -389.24992)
			(xy 164.863969 -389.267628) (xy 164.891349 -389.30703) (xy 164.912443 -389.350125) (xy 164.926765 -389.395918)
			(xy 164.933983 -389.443353) (xy 164.934392 -389.467344) (xy 164.933903 -389.492132) (xy 164.926142 -389.541097)
			(xy 164.910817 -389.588245) (xy 164.888307 -389.632416) (xy 164.859164 -389.672523) (xy 164.824108 -389.707577)
			(xy 164.783999 -389.736717) (xy 164.739827 -389.759225) (xy 164.692678 -389.774546) (xy 164.643712 -389.782304)
			(xy 164.618924 -389.782812) (xy 164.593529 -389.782306) (xy 164.543394 -389.774179) (xy 164.495206 -389.75813)
			(xy 164.45021 -389.734574) (xy 164.409565 -389.704118) (xy 164.37432 -389.667547) (xy 164.345384 -389.625806)
			(xy 164.323504 -389.579971) (xy 164.315902 -389.555736) (xy 164.314378 -389.549894) (xy 163.99383 -388.995412)
			(xy 163.989766 -388.991094) (xy 163.973687 -388.973416) (xy 163.946499 -388.934118) (xy 163.925541 -388.891174)
			(xy 163.911291 -388.845562) (xy 163.904073 -388.798325) (xy 163.90366 -388.774432) (xy 163.903746 -388.762384)
			(xy 163.905529 -388.738355) (xy 163.907216 -388.726426) (xy 163.908486 -388.717536) (xy 163.905438 -388.700518)
			(xy 163.863274 -388.629652) (xy 163.850066 -388.618476) (xy 163.841684 -388.615428) (xy 163.819849 -388.606975)
			(xy 163.77884 -388.584388) (xy 163.741757 -388.555808) (xy 163.709469 -388.521904) (xy 163.682733 -388.48347)
			(xy 163.662175 -388.441407) (xy 163.648276 -388.396699) (xy 163.644326 -388.37362) (xy 163.641532 -388.355078)
			(xy 163.613084 -388.33044) (xy 163.07943 -388.33044) (xy 163.050982 -388.355078) (xy 163.048188 -388.37362)
			(xy 163.04641 -388.384288) (xy 163.045032 -388.393693) (xy 163.048549 -388.41236) (xy 163.053268 -388.42061)
			(xy 163.07054 -388.447534) (xy 163.075934 -388.455334) (xy 163.091203 -388.466558) (xy 163.100258 -388.469378)
			(xy 163.126233 -388.476866) (xy 163.175336 -388.499464) (xy 163.219872 -388.530097) (xy 163.258538 -388.567868)
			(xy 163.290205 -388.611675) (xy 163.313946 -388.660236) (xy 163.322 -388.68604) (xy 163.323524 -388.691882)
			(xy 163.643818 -389.245602) (xy 163.647882 -389.24992) (xy 163.664073 -389.267628) (xy 163.691453 -389.30703)
			(xy 163.712547 -389.350125) (xy 163.726868 -389.395919) (xy 163.734085 -389.443353) (xy 163.734496 -389.467344)
			(xy 163.734007 -389.492132) (xy 163.726246 -389.541097) (xy 163.710921 -389.588246) (xy 163.688411 -389.632417)
			(xy 163.659269 -389.672524) (xy 163.624212 -389.707579) (xy 163.584104 -389.736719) (xy 163.539931 -389.759227)
			(xy 163.492782 -389.774549) (xy 163.443816 -389.782308) (xy 163.419028 -389.782812) (xy 163.393633 -389.782306)
			(xy 163.343497 -389.77418) (xy 163.295309 -389.758131) (xy 163.250312 -389.734575) (xy 163.209667 -389.704119)
			(xy 163.174421 -389.667549) (xy 163.145485 -389.625808) (xy 163.123605 -389.579972) (xy 163.116006 -389.555736)
			(xy 163.114482 -389.549894) (xy 162.794188 -388.996174) (xy 162.790124 -388.991856) (xy 162.773907 -388.974158)
			(xy 162.746476 -388.934769) (xy 162.72533 -388.891677) (xy 162.710959 -388.845879) (xy 162.703695 -388.798432)
			(xy 162.703256 -388.774432) (xy 162.703414 -388.76238) (xy 162.705323 -388.738352) (xy 162.707066 -388.726426)
			(xy 162.708336 -388.717536) (xy 162.705288 -388.700518) (xy 162.663124 -388.629652) (xy 162.649916 -388.618476)
			(xy 162.641534 -388.615428) (xy 162.619796 -388.60702) (xy 162.578957 -388.584564) (xy 162.542005 -388.556162)
			(xy 162.509797 -388.522475) (xy 162.483083 -388.484285) (xy 162.462482 -388.442479) (xy 162.448473 -388.398028)
			(xy 162.441382 -388.351965) (xy 162.440874 -388.328662) (xy 162.440967 -388.318406) (xy 162.442368 -388.297942)
			(xy 162.443668 -388.287768) (xy 162.445192 -388.276084) (xy 162.437572 -388.253478) (xy 162.002978 -387.818884)
			(xy 161.993973 -387.810853) (xy 161.971044 -387.803454) (xy 161.959036 -387.80466) (xy 161.865818 -387.819392)
			(xy 161.84626 -387.833362) (xy 161.840672 -387.844284) (xy 161.830039 -387.864299) (xy 161.804116 -387.901474)
			(xy 161.773357 -387.93476) (xy 161.75609 -387.94944) (xy 161.7472 -387.956552) (xy 161.737802 -387.97611)
			(xy 161.735008 -388.075424) (xy 161.743644 -388.09549) (xy 161.752026 -388.10311) (xy 161.770446 -388.120599)
			(xy 161.801786 -388.160567) (xy 161.82608 -388.20517) (xy 161.842661 -388.253178) (xy 161.85107 -388.303267)
			(xy 161.851594 -388.328662) (xy 161.851522 -388.33802) (xy 161.850376 -388.356702) (xy 161.849308 -388.366)
			(xy 161.848292 -388.37489) (xy 161.852102 -388.391654) (xy 161.896044 -388.461504) (xy 161.90976 -388.471918)
			(xy 161.918142 -388.474712) (xy 161.942235 -388.483198) (xy 161.987517 -388.506832) (xy 162.028404 -388.537448)
			(xy 162.06383 -388.574245) (xy 162.092871 -388.616264) (xy 162.11477 -388.662411) (xy 162.122358 -388.686802)
			(xy 162.123882 -388.692644) (xy 162.443668 -389.245602) (xy 162.447732 -389.24992) (xy 162.463947 -389.267619)
			(xy 162.491377 -389.307009) (xy 162.512522 -389.3501) (xy 162.526894 -389.395898) (xy 162.53416 -389.443344)
			(xy 162.5346 -389.467344) (xy 162.534135 -389.492147) (xy 162.526365 -389.541141) (xy 162.511024 -389.588315)
			(xy 162.48849 -389.632507) (xy 162.459317 -389.672629) (xy 162.424226 -389.70769) (xy 162.38408 -389.736829)
			(xy 162.339869 -389.759326) (xy 162.292682 -389.774627) (xy 162.243681 -389.782356) (xy 162.218878 -389.782812)
			(xy 162.193485 -389.782303) (xy 162.143355 -389.774169) (xy 162.095174 -389.758116) (xy 162.050183 -389.734557)
			(xy 162.009544 -389.7041) (xy 161.974305 -389.667529) (xy 161.945375 -389.62579) (xy 161.923499 -389.579957)
			(xy 161.915856 -389.555736) (xy 161.914332 -389.549894) (xy 161.593784 -388.995412) (xy 161.58972 -388.991094)
			(xy 161.573616 -388.973425) (xy 161.546378 -388.934139) (xy 161.525369 -388.891199) (xy 161.511068 -388.845583)
			(xy 161.503802 -388.798334) (xy 161.50336 -388.774432) (xy 161.503518 -388.76238) (xy 161.505427 -388.738352)
			(xy 161.50717 -388.726426) (xy 161.50844 -388.717536) (xy 161.505392 -388.700518) (xy 161.463228 -388.629652)
			(xy 161.45002 -388.618476) (xy 161.441638 -388.615428) (xy 161.4199 -388.60702) (xy 161.37906 -388.584564)
			(xy 161.342108 -388.556163) (xy 161.3099 -388.522476) (xy 161.283185 -388.484286) (xy 161.262584 -388.44248)
			(xy 161.248575 -388.398029) (xy 161.241483 -388.351965) (xy 161.240978 -388.328662) (xy 161.241477 -388.303264)
			(xy 161.249877 -388.253167) (xy 161.266453 -388.205151) (xy 161.29075 -388.160543) (xy 161.322097 -388.120572)
			(xy 161.340546 -388.10311) (xy 161.348928 -388.09549) (xy 161.357564 -388.075424) (xy 161.35477 -387.97611)
			(xy 161.345372 -387.956552) (xy 161.336482 -387.94944) (xy 161.317922 -387.933637) (xy 161.285197 -387.89751)
			(xy 161.258125 -387.856973) (xy 161.237294 -387.812903) (xy 161.223152 -387.766254) (xy 161.216007 -387.718035)
			(xy 161.215578 -387.693662) (xy 161.216017 -387.669546) (xy 161.223022 -387.621825) (xy 161.236879 -387.575627)
			(xy 161.257293 -387.531928) (xy 161.270188 -387.511544) (xy 161.27603 -387.502654) (xy 161.279586 -387.482588)
			(xy 161.258504 -387.390386) (xy 161.246312 -387.373622) (xy 161.237422 -387.368288) (xy 161.216622 -387.355431)
			(xy 161.178708 -387.324551) (xy 161.14576 -387.28842) (xy 161.118499 -387.247826) (xy 161.097519 -387.203657)
			(xy 161.08328 -387.156878) (xy 161.076092 -387.108511) (xy 161.075624 -387.084062) (xy 161.076392 -387.052132)
			(xy 161.088669 -386.989461) (xy 161.100008 -386.959602) (xy 161.105596 -386.945378) (xy 161.099754 -386.91566)
			(xy 161.063686 -386.879592) (xy 161.056286 -386.872748) (xy 161.037689 -386.86502) (xy 161.027618 -386.864606)
			(xy 159.553148 -386.864606) (xy 159.541727 -386.86506) (xy 159.521091 -386.874837) (xy 159.513524 -386.883402)
			(xy 159.456628 -386.954014) (xy 159.451294 -386.976366) (xy 159.453834 -386.987542) (xy 159.458631 -387.011382)
			(xy 159.463718 -387.059746) (xy 159.463994 -387.084062) (xy 159.46339 -387.117382) (xy 159.453721 -387.183317)
			(xy 159.434596 -387.247154) (xy 159.421068 -387.27761) (xy 159.416806 -387.288079) (xy 159.41688 -387.310653)
			(xy 159.426636 -387.331011) (xy 159.435038 -387.33857) (xy 159.457285 -387.357244) (xy 159.497348 -387.3993)
			(xy 159.531769 -387.446087) (xy 159.559996 -387.496851) (xy 159.581573 -387.550779) (xy 159.596155 -387.607003)
			(xy 159.603508 -387.66462) (xy 159.603948 -387.693662) (xy 159.603497 -387.722666) (xy 159.596167 -387.78021)
			(xy 159.581632 -387.836368) (xy 159.560123 -387.890242) (xy 159.531986 -387.94097) (xy 159.497671 -387.987741)
			(xy 159.457726 -388.029805) (xy 159.435546 -388.0485) (xy 159.428434 -388.054088) (xy 159.41929 -388.069328)
			(xy 159.40405 -388.152132) (xy 159.406844 -388.169404) (xy 159.411416 -388.177532) (xy 159.424009 -388.200711)
			(xy 159.441895 -388.250331) (xy 159.450976 -388.302289) (xy 159.451548 -388.328662) (xy 160.040828 -388.328662)
			(xy 160.04135 -388.303407) (xy 160.049663 -388.253585) (xy 160.066064 -388.205811) (xy 160.090105 -388.161388)
			(xy 160.121129 -388.121528) (xy 160.158291 -388.087318) (xy 160.200577 -388.059692) (xy 160.246833 -388.039402)
			(xy 160.295798 -388.027002) (xy 160.346136 -388.022831) (xy 160.396474 -388.027002) (xy 160.445439 -388.039402)
			(xy 160.491695 -388.059692) (xy 160.533981 -388.087318) (xy 160.571143 -388.121528) (xy 160.602167 -388.161388)
			(xy 160.626208 -388.205811) (xy 160.642609 -388.253585) (xy 160.650922 -388.303407) (xy 160.651444 -388.328662)
			(xy 160.651375 -388.338021) (xy 160.650232 -388.356703) (xy 160.649158 -388.366) (xy 160.648142 -388.37489)
			(xy 160.651952 -388.391654) (xy 160.695894 -388.461504) (xy 160.70961 -388.471918) (xy 160.717992 -388.474712)
			(xy 160.742011 -388.483205) (xy 160.787184 -388.506752) (xy 160.827991 -388.537245) (xy 160.863372 -388.573896)
			(xy 160.89241 -388.615751) (xy 160.91435 -388.661726) (xy 160.921954 -388.68604) (xy 160.923478 -388.691882)
			(xy 161.243772 -389.245602) (xy 161.247836 -389.24992) (xy 161.264034 -389.267633) (xy 161.291458 -389.307023)
			(xy 161.312601 -389.350112) (xy 161.326976 -389.395904) (xy 161.334252 -389.443346) (xy 161.334704 -389.467344)
			(xy 161.334247 -389.492148) (xy 161.326477 -389.541143) (xy 161.311136 -389.588319) (xy 161.288601 -389.632512)
			(xy 161.259428 -389.672635) (xy 161.224335 -389.707698) (xy 161.184188 -389.736838) (xy 161.139976 -389.759336)
			(xy 161.092788 -389.774638) (xy 161.043786 -389.782367) (xy 161.018982 -389.782812) (xy 160.993587 -389.782327)
			(xy 160.943453 -389.774194) (xy 160.895267 -389.75814) (xy 160.850272 -389.734579) (xy 160.80963 -389.70412)
			(xy 160.774387 -389.667547) (xy 160.745454 -389.625804) (xy 160.723576 -389.579967) (xy 160.71596 -389.555736)
			(xy 160.714436 -389.549894) (xy 160.394142 -388.996174) (xy 160.390078 -388.991856) (xy 160.373923 -388.974118)
			(xy 160.346553 -388.934718) (xy 160.325461 -388.891629) (xy 160.311133 -388.845845) (xy 160.303898 -388.798419)
			(xy 160.303464 -388.774432) (xy 160.303544 -388.762384) (xy 160.305327 -388.738355) (xy 160.30702 -388.726426)
			(xy 160.30829 -388.717536) (xy 160.305242 -388.700518) (xy 160.263078 -388.629652) (xy 160.24987 -388.618476)
			(xy 160.241488 -388.615428) (xy 160.219744 -388.607023) (xy 160.178885 -388.584584) (xy 160.141914 -388.556193)
			(xy 160.10969 -388.522509) (xy 160.082964 -388.484316) (xy 160.062358 -388.442504) (xy 160.04835 -388.398043)
			(xy 160.041266 -388.35197) (xy 160.040828 -388.328662) (xy 159.451548 -388.328662) (xy 159.451476 -388.33802)
			(xy 159.45033 -388.356702) (xy 159.449262 -388.366) (xy 159.448246 -388.37489) (xy 159.452056 -388.391654)
			(xy 159.495998 -388.461504) (xy 159.509714 -388.471918) (xy 159.518096 -388.474712) (xy 159.542132 -388.483165)
			(xy 159.587316 -388.506709) (xy 159.62813 -388.537205) (xy 159.663516 -388.573862) (xy 159.692555 -388.615726)
			(xy 159.714491 -388.661711) (xy 159.722058 -388.68604) (xy 159.723582 -388.691882) (xy 160.043876 -389.245602)
			(xy 160.04794 -389.24992) (xy 160.064155 -389.267619) (xy 160.091584 -389.307009) (xy 160.112729 -389.3501)
			(xy 160.1271 -389.395898) (xy 160.134366 -389.443344) (xy 160.134808 -389.467344) (xy 160.134343 -389.492147)
			(xy 160.126573 -389.541141) (xy 160.111232 -389.588316) (xy 160.088698 -389.632509) (xy 160.059526 -389.672631)
			(xy 160.024434 -389.707694) (xy 159.984289 -389.736833) (xy 159.940077 -389.759331) (xy 159.89289 -389.774633)
			(xy 159.84389 -389.782363) (xy 159.819086 -389.782812) (xy 159.793693 -389.782303) (xy 159.743562 -389.774171)
			(xy 159.695379 -389.758118) (xy 159.650388 -389.73456) (xy 159.609748 -389.704103) (xy 159.574508 -389.667533)
			(xy 159.545576 -389.625793) (xy 159.5237 -389.57996) (xy 159.516064 -389.555736) (xy 159.51454 -389.549894)
			(xy 159.194246 -388.996174) (xy 159.190182 -388.991856) (xy 159.173994 -388.974146) (xy 159.14662 -388.934743)
			(xy 159.125532 -388.891648) (xy 159.111216 -388.845855) (xy 159.104003 -388.798422) (xy 159.103568 -388.774432)
			(xy 159.103654 -388.762384) (xy 159.105437 -388.738355) (xy 159.107124 -388.726426) (xy 159.108394 -388.717536)
			(xy 159.105346 -388.700518) (xy 159.063182 -388.629652) (xy 159.049974 -388.618476) (xy 159.041592 -388.615428)
			(xy 159.01868 -388.606545) (xy 158.975814 -388.582526) (xy 158.937349 -388.55195) (xy 158.90428 -388.515606)
			(xy 158.890462 -388.495286) (xy 158.884112 -388.485634) (xy 158.864554 -388.473696) (xy 158.774638 -388.464298)
			(xy 158.763291 -388.46378) (xy 158.741936 -388.471434) (xy 158.73349 -388.47903) (xy 158.662624 -388.549896)
			(xy 158.655221 -388.556731) (xy 158.636623 -388.564438) (xy 158.626556 -388.564882) (xy 158.549086 -388.564882)
			(xy 158.539079 -388.565372) (xy 158.520589 -388.573033) (xy 158.506436 -388.587185) (xy 158.498773 -388.605675)
			(xy 158.498286 -388.615682) (xy 158.498286 -388.627366) (xy 158.503366 -388.63778) (xy 158.508857 -388.649499)
			(xy 158.518139 -388.673659) (xy 158.521908 -388.68604) (xy 158.523432 -388.691882) (xy 158.843726 -389.245602)
			(xy 158.84779 -389.24992) (xy 158.863981 -389.267628) (xy 158.89136 -389.30703) (xy 158.912453 -389.350125)
			(xy 158.926774 -389.395919) (xy 158.933991 -389.443353) (xy 158.934404 -389.467344) (xy 158.933915 -389.492132)
			(xy 158.926154 -389.541098) (xy 158.910829 -389.588247) (xy 158.888319 -389.632419) (xy 158.859177 -389.672526)
			(xy 158.82412 -389.707582) (xy 158.784012 -389.736723) (xy 158.73984 -389.759232) (xy 158.69269 -389.774556)
			(xy 158.643724 -389.782315) (xy 158.618936 -389.782812) (xy 158.593541 -389.782307) (xy 158.543404 -389.774181)
			(xy 158.495215 -389.758134) (xy 158.450217 -389.734578) (xy 158.40957 -389.704122) (xy 158.374324 -389.667552)
			(xy 158.345387 -389.625811) (xy 158.323506 -389.579975) (xy 158.315914 -389.555736) (xy 158.31439 -389.549894)
			(xy 157.994096 -388.996174) (xy 157.990032 -388.991856) (xy 157.973815 -388.974158) (xy 157.946383 -388.934769)
			(xy 157.925237 -388.891678) (xy 157.910865 -388.84588) (xy 157.903601 -388.798432) (xy 157.903164 -388.774432)
			(xy 157.903322 -388.76238) (xy 157.905231 -388.738352) (xy 157.906974 -388.726426) (xy 157.908244 -388.717536)
			(xy 157.905196 -388.700518) (xy 157.863032 -388.629652) (xy 157.849824 -388.618476) (xy 157.841442 -388.615428)
			(xy 157.821265 -388.607665) (xy 157.783149 -388.587267) (xy 157.765496 -388.574788) (xy 157.7588 -388.570198)
			(xy 157.743384 -388.565141) (xy 157.73527 -388.564882) (xy 157.34919 -388.564882) (xy 157.339182 -388.565371)
			(xy 157.320691 -388.573032) (xy 157.306537 -388.587184) (xy 157.298873 -388.605674) (xy 157.29839 -388.615682)
			(xy 157.29839 -388.627366) (xy 157.30347 -388.63778) (xy 157.308961 -388.649499) (xy 157.318243 -388.673659)
			(xy 157.322012 -388.68604) (xy 157.323536 -388.691882) (xy 157.64383 -389.245602) (xy 157.647894 -389.24992)
			(xy 157.664085 -389.267628) (xy 157.691463 -389.307031) (xy 157.712556 -389.350126) (xy 157.726877 -389.395919)
			(xy 157.734094 -389.443353) (xy 157.734508 -389.467344) (xy 157.734019 -389.492132) (xy 157.726258 -389.541098)
			(xy 157.710933 -389.588248) (xy 157.688423 -389.63242) (xy 157.659281 -389.672528) (xy 157.624225 -389.707584)
			(xy 157.584117 -389.736725) (xy 157.539944 -389.759235) (xy 157.492794 -389.774559) (xy 157.443829 -389.782319)
			(xy 157.41904 -389.782812) (xy 157.393644 -389.782307) (xy 157.343507 -389.774182) (xy 157.295318 -389.758135)
			(xy 157.250319 -389.73458) (xy 157.209672 -389.704124) (xy 157.174425 -389.667554) (xy 157.145488 -389.625812)
			(xy 157.123606 -389.579976) (xy 157.116018 -389.555736) (xy 157.114494 -389.549894) (xy 156.7942 -388.996174)
			(xy 156.790136 -388.991856) (xy 156.773919 -388.974158) (xy 156.746486 -388.934769) (xy 156.72534 -388.891678)
			(xy 156.710968 -388.84588) (xy 156.703704 -388.798432) (xy 156.703268 -388.774432) (xy 156.703426 -388.76238)
			(xy 156.705335 -388.738352) (xy 156.707078 -388.726426) (xy 156.708348 -388.717536) (xy 156.7053 -388.700518)
			(xy 156.663136 -388.629652) (xy 156.649928 -388.618476) (xy 156.641546 -388.615428) (xy 156.621369 -388.607665)
			(xy 156.583253 -388.587268) (xy 156.5656 -388.574788) (xy 156.558904 -388.570198) (xy 156.543488 -388.565139)
			(xy 156.535374 -388.564882) (xy 156.149294 -388.564882) (xy 156.139286 -388.565371) (xy 156.120793 -388.573031)
			(xy 156.106637 -388.587183) (xy 156.098973 -388.605674) (xy 156.098494 -388.615682) (xy 156.098494 -388.627366)
			(xy 156.103574 -388.63778) (xy 156.109167 -388.649674) (xy 156.11858 -388.674217) (xy 156.12237 -388.686802)
			(xy 156.123894 -388.692644) (xy 156.44368 -389.245602) (xy 156.447744 -389.24992) (xy 156.463963 -389.267617)
			(xy 156.491401 -389.307004) (xy 156.512552 -389.350095) (xy 156.526928 -389.395894) (xy 156.534196 -389.443343)
			(xy 156.534612 -389.467344) (xy 156.534147 -389.492147) (xy 156.526377 -389.541142) (xy 156.511036 -389.588317)
			(xy 156.488502 -389.63251) (xy 156.45933 -389.672632) (xy 156.424239 -389.707695) (xy 156.384093 -389.736835)
			(xy 156.339882 -389.759334) (xy 156.292694 -389.774636) (xy 156.243694 -389.782367) (xy 156.21889 -389.782812)
			(xy 156.193497 -389.782303) (xy 156.143365 -389.774172) (xy 156.095182 -389.75812) (xy 156.05019 -389.734561)
			(xy 156.00955 -389.704104) (xy 155.974309 -389.667534) (xy 155.945377 -389.625794) (xy 155.9235 -389.579961)
			(xy 155.915868 -389.555736) (xy 155.914344 -389.549894) (xy 155.593796 -388.995412) (xy 155.589732 -388.991094)
			(xy 155.573628 -388.973425) (xy 155.546389 -388.93414) (xy 155.525379 -388.891199) (xy 155.511077 -388.845584)
			(xy 155.503811 -388.798334) (xy 155.503372 -388.774432) (xy 155.50353 -388.76238) (xy 155.505439 -388.738352)
			(xy 155.507182 -388.726426) (xy 155.508452 -388.717536) (xy 155.505404 -388.700518) (xy 155.46324 -388.629652)
			(xy 155.450032 -388.618476) (xy 155.44165 -388.615428) (xy 155.421473 -388.607665) (xy 155.383356 -388.587269)
			(xy 155.365704 -388.574788) (xy 155.359008 -388.570197) (xy 155.343592 -388.565138) (xy 155.335478 -388.564882)
			(xy 154.949144 -388.564882) (xy 154.939116 -388.565294) (xy 154.920581 -388.572955) (xy 154.90639 -388.587128)
			(xy 154.898706 -388.605654) (xy 154.898344 -388.615682) (xy 154.898344 -388.627366) (xy 154.903424 -388.63778)
			(xy 154.908915 -388.649499) (xy 154.918199 -388.673659) (xy 154.921966 -388.68604) (xy 154.92349 -388.691882)
			(xy 155.243784 -389.245602) (xy 155.247848 -389.24992) (xy 155.264067 -389.267617) (xy 155.291504 -389.307005)
			(xy 155.312655 -389.350096) (xy 155.327031 -389.395894) (xy 155.334299 -389.443343) (xy 155.334716 -389.467344)
			(xy 155.334251 -389.492147) (xy 155.326481 -389.541142) (xy 155.31114 -389.588317) (xy 155.288606 -389.632511)
			(xy 155.259434 -389.672633) (xy 155.224343 -389.707697) (xy 155.184197 -389.736837) (xy 155.139986 -389.759336)
			(xy 155.092799 -389.77464) (xy 155.043798 -389.78237) (xy 155.018994 -389.782812) (xy 154.993601 -389.782304)
			(xy 154.943469 -389.774173) (xy 154.895285 -389.758121) (xy 154.850292 -389.734563) (xy 154.809651 -389.704106)
			(xy 154.77441 -389.667536) (xy 154.745478 -389.625796) (xy 154.723601 -389.579962) (xy 154.715972 -389.555736)
			(xy 154.714448 -389.549894) (xy 154.394154 -388.996174) (xy 154.39009 -388.991856) (xy 154.373901 -388.974147)
			(xy 154.346527 -388.934744) (xy 154.325439 -388.891648) (xy 154.311122 -388.845855) (xy 154.303909 -388.798422)
			(xy 154.303476 -388.774432) (xy 154.303562 -388.762384) (xy 154.305345 -388.738355) (xy 154.307032 -388.726426)
			(xy 154.308302 -388.717536) (xy 154.305254 -388.700518) (xy 154.26309 -388.629652) (xy 154.249882 -388.618476)
			(xy 154.2415 -388.615428) (xy 154.221322 -388.607668) (xy 154.183201 -388.587276) (xy 154.165554 -388.574788)
			(xy 154.158856 -388.570204) (xy 154.14344 -388.56516) (xy 154.135328 -388.564882) (xy 153.749248 -388.564882)
			(xy 153.739219 -388.565293) (xy 153.720683 -388.572954) (xy 153.706491 -388.587127) (xy 153.698806 -388.605654)
			(xy 153.698448 -388.615682) (xy 153.698448 -388.627366) (xy 153.703528 -388.63778) (xy 153.709019 -388.649499)
			(xy 153.718303 -388.673659) (xy 153.72207 -388.68604) (xy 153.723594 -388.691882) (xy 154.043888 -389.245602)
			(xy 154.047952 -389.24992) (xy 154.064171 -389.267617) (xy 154.091608 -389.307005) (xy 154.112758 -389.350096)
			(xy 154.127134 -389.395895) (xy 154.134402 -389.443343) (xy 154.13482 -389.467344) (xy 154.134355 -389.492145)
			(xy 154.126584 -389.541134) (xy 154.111242 -389.588303) (xy 154.088707 -389.632489) (xy 154.059533 -389.672604)
			(xy 154.02444 -389.707658) (xy 153.984294 -389.736788) (xy 153.940083 -389.759275) (xy 153.892897 -389.774565)
			(xy 153.843899 -389.782282) (xy 153.819098 -389.782812) (xy 153.793704 -389.782304) (xy 153.743572 -389.774173)
			(xy 153.695388 -389.758122) (xy 153.650395 -389.734564) (xy 153.609753 -389.704107) (xy 153.574512 -389.667537)
			(xy 153.545579 -389.625797) (xy 153.523701 -389.579963) (xy 153.516076 -389.555736) (xy 153.514552 -389.549894)
			(xy 153.194258 -388.996174) (xy 153.190194 -388.991856) (xy 153.174005 -388.974147) (xy 153.146631 -388.934744)
			(xy 153.125542 -388.891648) (xy 153.111225 -388.845855) (xy 153.104012 -388.798422) (xy 153.10358 -388.774432)
			(xy 153.103666 -388.762384) (xy 153.105449 -388.738355) (xy 153.107136 -388.726426) (xy 153.108406 -388.717536)
			(xy 153.105358 -388.700518) (xy 153.063194 -388.629652) (xy 153.049986 -388.618476) (xy 153.041604 -388.615428)
			(xy 153.019862 -388.607024) (xy 152.979015 -388.584573) (xy 152.942055 -388.556174) (xy 152.90984 -388.522488)
			(xy 152.883118 -388.484298) (xy 152.862512 -388.442489) (xy 152.8485 -388.398035) (xy 152.841406 -388.351967)
			(xy 152.840944 -388.328662) (xy 152.841447 -388.303654) (xy 152.849599 -388.254305) (xy 152.86568 -388.206944)
			(xy 152.877012 -388.184644) (xy 152.884886 -388.169658) (xy 152.88006 -388.136638) (xy 152.756616 -388.013194)
			(xy 152.749769 -388.005796) (xy 152.742034 -387.987198) (xy 152.74163 -387.977126) (xy 152.74163 -387.91388)
			(xy 152.73909 -387.902704) (xy 152.736296 -387.89737) (xy 152.721226 -387.86555) (xy 152.699944 -387.79844)
			(xy 152.689171 -387.728864) (xy 152.688544 -387.693662) (xy 152.689166 -387.658458) (xy 152.699912 -387.588876)
			(xy 152.721207 -387.521766) (xy 152.736296 -387.489954) (xy 152.738757 -387.484628) (xy 152.741449 -387.473212)
			(xy 152.74163 -387.467348) (xy 152.74163 -387.457442) (xy 152.716476 -387.438965) (xy 152.670931 -387.39629)
			(xy 152.631606 -387.347825) (xy 152.599228 -387.294466) (xy 152.574399 -387.237204) (xy 152.557579 -387.1771)
			(xy 152.549078 -387.115268) (xy 152.54859 -387.084062) (xy 152.549051 -387.054581) (xy 152.556627 -386.996108)
			(xy 152.57165 -386.939092) (xy 152.59387 -386.884477) (xy 152.622919 -386.833167) (xy 152.658317 -386.786013)
			(xy 152.699477 -386.743795) (xy 152.722326 -386.72516) (xy 152.731724 -386.717794) (xy 152.74163 -386.69722)
			(xy 152.74163 -386.655818) (xy 152.737312 -386.64134) (xy 152.73274 -386.63499) (xy 152.719248 -386.614307)
			(xy 152.697887 -386.569786) (xy 152.683379 -386.522585) (xy 152.676047 -386.473752) (xy 152.67559 -386.449062)
			(xy 152.675844 -386.43687) (xy 152.676098 -386.427218) (xy 152.670002 -386.409184) (xy 152.611328 -386.341874)
			(xy 152.594564 -386.333238) (xy 152.584658 -386.332222) (xy 152.557745 -386.328871) (xy 152.505445 -386.314526)
			(xy 152.456188 -386.291837) (xy 152.411295 -386.261414) (xy 152.371968 -386.224072) (xy 152.339264 -386.180812)
			(xy 152.314058 -386.132794) (xy 152.297027 -386.081306) (xy 152.292304 -386.0546) (xy 152.29078 -386.045202)
			(xy 152.017984 -385.57327) (xy 152.010618 -385.567428) (xy 151.99184 -385.551624) (xy 151.958709 -385.515417)
			(xy 151.93129 -385.474712) (xy 151.910187 -385.430402) (xy 151.895861 -385.383462) (xy 151.888628 -385.334919)
			(xy 151.88819 -385.31038) (xy 151.888701 -385.284394) (xy 151.896834 -385.233062) (xy 151.912897 -385.183634)
			(xy 151.936494 -385.137327) (xy 151.967044 -385.095281) (xy 152.003795 -385.058532) (xy 152.045842 -385.027984)
			(xy 152.09215 -385.00439) (xy 152.141579 -384.98833) (xy 152.192912 -384.9802) (xy 152.218898 -384.979672)
			(xy 152.244909 -384.980157) (xy 152.296289 -384.988303) (xy 152.345759 -385.004395) (xy 152.392099 -385.028036)
			(xy 152.434165 -385.058642) (xy 152.470919 -385.095457) (xy 152.501454 -385.137575) (xy 152.525017 -385.183954)
			(xy 152.541026 -385.233451) (xy 152.545542 -385.259072) (xy 152.547066 -385.26847) (xy 152.646888 -385.44119)
			(xy 152.652947 -385.450558) (xy 152.6712 -385.463344) (xy 152.693146 -385.467215) (xy 152.704038 -385.464812)
			(xy 152.720802 -385.46024) (xy 152.74163 -385.433062) (xy 152.74163 -384.286252) (xy 152.741199 -384.276185)
			(xy 152.733476 -384.25759) (xy 152.726644 -384.250184) (xy 151.452326 -382.975866) (xy 151.444927 -382.969024)
			(xy 151.426328 -382.961306) (xy 151.416258 -382.96088) (xy 151.375872 -382.96088) (xy 151.351234 -382.976882)
			(xy 151.344884 -382.990598) (xy 151.333973 -383.013299) (xy 151.306309 -383.055387) (xy 151.272583 -383.092793)
			(xy 151.233576 -383.124654) (xy 151.190189 -383.150233) (xy 151.143426 -383.168938) (xy 151.094368 -383.180337)
			(xy 151.044148 -383.184166) (xy 150.993928 -383.180337) (xy 150.94487 -383.168938) (xy 150.898107 -383.150233)
			(xy 150.85472 -383.124654) (xy 150.815713 -383.092793) (xy 150.781987 -383.055387) (xy 150.754323 -383.013299)
			(xy 150.743412 -382.990598) (xy 150.737062 -382.976882) (xy 150.712424 -382.96088) (xy 150.175976 -382.96088)
			(xy 150.151338 -382.976882) (xy 150.144988 -382.990598) (xy 150.134077 -383.013299) (xy 150.106413 -383.055387)
			(xy 150.072687 -383.092793) (xy 150.03368 -383.124654) (xy 149.990293 -383.150233) (xy 149.94353 -383.168938)
			(xy 149.894472 -383.180337) (xy 149.844252 -383.184166) (xy 149.794032 -383.180337) (xy 149.744974 -383.168938)
			(xy 149.698211 -383.150233) (xy 149.654824 -383.124654) (xy 149.615817 -383.092793) (xy 149.582091 -383.055387)
			(xy 149.554427 -383.013299) (xy 149.543516 -382.990598) (xy 149.537166 -382.976882) (xy 149.512528 -382.96088)
			(xy 148.97608 -382.96088) (xy 148.951442 -382.976882) (xy 148.945092 -382.990598) (xy 148.934181 -383.013299)
			(xy 148.906517 -383.055387) (xy 148.872791 -383.092793) (xy 148.833784 -383.124654) (xy 148.790397 -383.150233)
			(xy 148.743634 -383.168938) (xy 148.694576 -383.180337) (xy 148.644356 -383.184166) (xy 148.594136 -383.180337)
			(xy 148.545078 -383.168938) (xy 148.498315 -383.150233) (xy 148.454928 -383.124654) (xy 148.415921 -383.092793)
			(xy 148.382195 -383.055387) (xy 148.354531 -383.013299) (xy 148.34362 -382.990598) (xy 148.33727 -382.976882)
			(xy 148.312632 -382.96088) (xy 147.77593 -382.96088) (xy 147.751292 -382.976882) (xy 147.744942 -382.990598)
			(xy 147.734031 -383.013299) (xy 147.706367 -383.055387) (xy 147.672641 -383.092793) (xy 147.633634 -383.124654)
			(xy 147.590247 -383.150233) (xy 147.543484 -383.168938) (xy 147.494426 -383.180337) (xy 147.444206 -383.184166)
			(xy 147.393986 -383.180337) (xy 147.344928 -383.168938) (xy 147.298165 -383.150233) (xy 147.254778 -383.124654)
			(xy 147.215771 -383.092793) (xy 147.182045 -383.055387) (xy 147.154381 -383.013299) (xy 147.14347 -382.990598)
			(xy 147.13712 -382.976882) (xy 147.112482 -382.96088) (xy 146.446494 -382.96088) (xy 146.419316 -382.981454)
			(xy 146.414744 -382.997964) (xy 146.40697 -383.023646) (xy 146.384283 -383.072269) (xy 146.354051 -383.116596)
			(xy 146.317066 -383.155468) (xy 146.274297 -383.187867) (xy 146.226863 -383.212944) (xy 146.176005 -383.230043)
			(xy 146.123055 -383.238716) (xy 146.096228 -383.239264) (xy 146.071393 -383.238813) (xy 146.022284 -383.231373)
			(xy 145.97484 -383.216671) (xy 145.930128 -383.195039) (xy 145.889155 -383.166963) (xy 145.870676 -383.150364)
			(xy 145.863625 -383.144297) (xy 145.846429 -383.137249) (xy 145.837148 -383.136648) (xy 145.805906 -383.135886)
			(xy 145.796656 -383.136064) (xy 145.779216 -383.142198) (xy 145.77187 -383.147824) (xy 145.749326 -383.166018)
			(xy 145.699192 -383.195039) (xy 145.644772 -383.214891) (xy 145.587728 -383.224967) (xy 145.558764 -383.225548)
			(xy 145.535564 -383.225162) (xy 145.489618 -383.218687) (xy 145.445028 -383.205857) (xy 145.402667 -383.186923)
			(xy 145.363368 -383.162255) (xy 145.345404 -383.14757) (xy 145.338292 -383.141474) (xy 145.320766 -383.135378)
			(xy 145.235168 -383.137156) (xy 145.217896 -383.144268) (xy 145.211038 -383.150618) (xy 145.19261 -383.166953)
			(xy 145.151827 -383.194551) (xy 145.107407 -383.215804) (xy 145.060329 -383.230245) (xy 145.011631 -383.237554)
			(xy 144.98701 -383.237994) (xy 144.960257 -383.237471) (xy 144.90745 -383.228842) (xy 144.856722 -383.211824)
			(xy 144.809395 -383.186861) (xy 144.766705 -383.154605) (xy 144.729765 -383.115896) (xy 144.699538 -383.071744)
			(xy 144.676815 -383.023302) (xy 144.669002 -382.99771) (xy 144.664176 -382.981454) (xy 144.636998 -382.96088)
			(xy 141.819122 -382.96088) (xy 141.809058 -382.961317) (xy 141.790472 -382.969049) (xy 141.783054 -382.975866)
			(xy 141.01572 -383.7432) (xy 143.311624 -383.7432) (xy 143.315695 -383.687578) (xy 143.327821 -383.633141)
			(xy 143.347744 -383.58105) (xy 143.37504 -383.532415) (xy 143.409126 -383.488272) (xy 143.449275 -383.449563)
			(xy 143.494633 -383.417112) (xy 143.544233 -383.391611) (xy 143.597017 -383.373604) (xy 143.65186 -383.363474)
			(xy 143.707594 -383.361437) (xy 143.763031 -383.367537) (xy 143.816988 -383.381643) (xy 143.868317 -383.403455)
			(xy 143.915923 -383.432509) (xy 143.958791 -383.468184) (xy 143.996008 -383.509721) (xy 144.026781 -383.556234)
			(xy 144.050453 -383.606731) (xy 144.066521 -383.660138) (xy 144.074641 -383.715314) (xy 144.07515 -383.7432)
			(xy 144.074641 -383.771086) (xy 144.066521 -383.826262) (xy 144.050453 -383.879669) (xy 144.026781 -383.930166)
			(xy 143.996008 -383.976679) (xy 143.958791 -384.018216) (xy 143.915923 -384.053891) (xy 143.868317 -384.082945)
			(xy 143.816988 -384.104757) (xy 143.763031 -384.118863) (xy 143.707594 -384.124963) (xy 143.65186 -384.122926)
			(xy 143.597017 -384.112796) (xy 143.544233 -384.094789) (xy 143.494633 -384.069288) (xy 143.449275 -384.036837)
			(xy 143.409126 -383.998128) (xy 143.37504 -383.953985) (xy 143.347744 -383.90535) (xy 143.327821 -383.853259)
			(xy 143.315695 -383.798822) (xy 143.311624 -383.7432) (xy 141.01572 -383.7432) (xy 140.335762 -384.423158)
			(xy 140.328142 -384.441446) (xy 140.328142 -384.451606) (xy 140.32762 -384.482097) (xy 140.320182 -384.542625)
			(xy 140.305556 -384.601829) (xy 140.283954 -384.658859) (xy 140.281955 -384.66268) (xy 143.311624 -384.66268)
			(xy 143.315695 -384.607058) (xy 143.327821 -384.552621) (xy 143.347744 -384.50053) (xy 143.37504 -384.451895)
			(xy 143.409126 -384.407752) (xy 143.449275 -384.369043) (xy 143.494633 -384.336592) (xy 143.544233 -384.311091)
			(xy 143.597017 -384.293084) (xy 143.65186 -384.282954) (xy 143.707594 -384.280917) (xy 143.763031 -384.287017)
			(xy 143.816988 -384.301123) (xy 143.868317 -384.322935) (xy 143.915923 -384.351989) (xy 143.953618 -384.383359)
			(xy 144.698722 -384.383359) (xy 144.698722 -384.331385) (xy 144.706852 -384.28005) (xy 144.722913 -384.23062)
			(xy 144.746509 -384.18431) (xy 144.777059 -384.142262) (xy 144.81381 -384.105511) (xy 144.855858 -384.074961)
			(xy 144.902168 -384.051365) (xy 144.951598 -384.035304) (xy 145.002933 -384.027174) (xy 145.054907 -384.027174)
			(xy 145.106242 -384.035304) (xy 145.155672 -384.051365) (xy 145.201982 -384.074961) (xy 145.24403 -384.105511)
			(xy 145.280781 -384.142262) (xy 145.311331 -384.18431) (xy 145.334927 -384.23062) (xy 145.350988 -384.28005)
			(xy 145.359118 -384.331385) (xy 145.359628 -384.357372) (xy 145.359118 -384.383359) (xy 145.350988 -384.434694)
			(xy 145.334927 -384.484124) (xy 145.311331 -384.530434) (xy 145.280781 -384.572482) (xy 145.24403 -384.609233)
			(xy 145.201982 -384.639783) (xy 145.194277 -384.643709) (xy 146.759932 -384.643709) (xy 146.759932 -384.591735)
			(xy 146.768062 -384.5404) (xy 146.784123 -384.49097) (xy 146.807719 -384.44466) (xy 146.838269 -384.402612)
			(xy 146.87502 -384.365861) (xy 146.917068 -384.335311) (xy 146.963378 -384.311715) (xy 147.012808 -384.295654)
			(xy 147.064143 -384.287524) (xy 147.116117 -384.287524) (xy 147.167452 -384.295654) (xy 147.216882 -384.311715)
			(xy 147.263192 -384.335311) (xy 147.30524 -384.365861) (xy 147.341991 -384.402612) (xy 147.372541 -384.44466)
			(xy 147.396137 -384.49097) (xy 147.412198 -384.5404) (xy 147.420328 -384.591735) (xy 147.420838 -384.617722)
			(xy 147.420328 -384.643709) (xy 147.959828 -384.643709) (xy 147.959828 -384.591735) (xy 147.967958 -384.5404)
			(xy 147.984019 -384.49097) (xy 148.007615 -384.44466) (xy 148.038165 -384.402612) (xy 148.074916 -384.365861)
			(xy 148.116964 -384.335311) (xy 148.163274 -384.311715) (xy 148.212704 -384.295654) (xy 148.264039 -384.287524)
			(xy 148.316013 -384.287524) (xy 148.367348 -384.295654) (xy 148.416778 -384.311715) (xy 148.463088 -384.335311)
			(xy 148.505136 -384.365861) (xy 148.541887 -384.402612) (xy 148.572437 -384.44466) (xy 148.596033 -384.49097)
			(xy 148.612094 -384.5404) (xy 148.620224 -384.591735) (xy 148.620734 -384.617722) (xy 148.620224 -384.643709)
			(xy 149.159978 -384.643709) (xy 149.159978 -384.591735) (xy 149.168108 -384.5404) (xy 149.184169 -384.49097)
			(xy 149.207765 -384.44466) (xy 149.238315 -384.402612) (xy 149.275066 -384.365861) (xy 149.317114 -384.335311)
			(xy 149.363424 -384.311715) (xy 149.412854 -384.295654) (xy 149.464189 -384.287524) (xy 149.516163 -384.287524)
			(xy 149.567498 -384.295654) (xy 149.616928 -384.311715) (xy 149.663238 -384.335311) (xy 149.705286 -384.365861)
			(xy 149.742037 -384.402612) (xy 149.772587 -384.44466) (xy 149.796183 -384.49097) (xy 149.812244 -384.5404)
			(xy 149.820374 -384.591735) (xy 149.820884 -384.617722) (xy 149.820374 -384.643709) (xy 150.359874 -384.643709)
			(xy 150.359874 -384.591735) (xy 150.368004 -384.5404) (xy 150.384065 -384.49097) (xy 150.407661 -384.44466)
			(xy 150.438211 -384.402612) (xy 150.474962 -384.365861) (xy 150.51701 -384.335311) (xy 150.56332 -384.311715)
			(xy 150.61275 -384.295654) (xy 150.664085 -384.287524) (xy 150.716059 -384.287524) (xy 150.767394 -384.295654)
			(xy 150.816824 -384.311715) (xy 150.863134 -384.335311) (xy 150.905182 -384.365861) (xy 150.941933 -384.402612)
			(xy 150.972483 -384.44466) (xy 150.996079 -384.49097) (xy 151.01214 -384.5404) (xy 151.02027 -384.591735)
			(xy 151.02078 -384.617722) (xy 151.02027 -384.643709) (xy 151.560024 -384.643709) (xy 151.560024 -384.591735)
			(xy 151.568154 -384.5404) (xy 151.584215 -384.49097) (xy 151.607811 -384.44466) (xy 151.638361 -384.402612)
			(xy 151.675112 -384.365861) (xy 151.71716 -384.335311) (xy 151.76347 -384.311715) (xy 151.8129 -384.295654)
			(xy 151.864235 -384.287524) (xy 151.916209 -384.287524) (xy 151.967544 -384.295654) (xy 152.016974 -384.311715)
			(xy 152.063284 -384.335311) (xy 152.105332 -384.365861) (xy 152.142083 -384.402612) (xy 152.172633 -384.44466)
			(xy 152.196229 -384.49097) (xy 152.21229 -384.5404) (xy 152.22042 -384.591735) (xy 152.22093 -384.617722)
			(xy 152.22042 -384.643709) (xy 152.21229 -384.695044) (xy 152.196229 -384.744474) (xy 152.172633 -384.790784)
			(xy 152.142083 -384.832832) (xy 152.105332 -384.869583) (xy 152.063284 -384.900133) (xy 152.016974 -384.923729)
			(xy 151.967544 -384.93979) (xy 151.916209 -384.94792) (xy 151.864235 -384.94792) (xy 151.8129 -384.93979)
			(xy 151.76347 -384.923729) (xy 151.71716 -384.900133) (xy 151.675112 -384.869583) (xy 151.638361 -384.832832)
			(xy 151.607811 -384.790784) (xy 151.584215 -384.744474) (xy 151.568154 -384.695044) (xy 151.560024 -384.643709)
			(xy 151.02027 -384.643709) (xy 151.01214 -384.695044) (xy 150.996079 -384.744474) (xy 150.972483 -384.790784)
			(xy 150.941933 -384.832832) (xy 150.905182 -384.869583) (xy 150.863134 -384.900133) (xy 150.816824 -384.923729)
			(xy 150.767394 -384.93979) (xy 150.716059 -384.94792) (xy 150.664085 -384.94792) (xy 150.61275 -384.93979)
			(xy 150.56332 -384.923729) (xy 150.51701 -384.900133) (xy 150.474962 -384.869583) (xy 150.438211 -384.832832)
			(xy 150.407661 -384.790784) (xy 150.384065 -384.744474) (xy 150.368004 -384.695044) (xy 150.359874 -384.643709)
			(xy 149.820374 -384.643709) (xy 149.812244 -384.695044) (xy 149.796183 -384.744474) (xy 149.772587 -384.790784)
			(xy 149.742037 -384.832832) (xy 149.705286 -384.869583) (xy 149.663238 -384.900133) (xy 149.616928 -384.923729)
			(xy 149.567498 -384.93979) (xy 149.516163 -384.94792) (xy 149.464189 -384.94792) (xy 149.412854 -384.93979)
			(xy 149.363424 -384.923729) (xy 149.317114 -384.900133) (xy 149.275066 -384.869583) (xy 149.238315 -384.832832)
			(xy 149.207765 -384.790784) (xy 149.184169 -384.744474) (xy 149.168108 -384.695044) (xy 149.159978 -384.643709)
			(xy 148.620224 -384.643709) (xy 148.612094 -384.695044) (xy 148.596033 -384.744474) (xy 148.572437 -384.790784)
			(xy 148.541887 -384.832832) (xy 148.505136 -384.869583) (xy 148.463088 -384.900133) (xy 148.416778 -384.923729)
			(xy 148.367348 -384.93979) (xy 148.316013 -384.94792) (xy 148.264039 -384.94792) (xy 148.212704 -384.93979)
			(xy 148.163274 -384.923729) (xy 148.116964 -384.900133) (xy 148.074916 -384.869583) (xy 148.038165 -384.832832)
			(xy 148.007615 -384.790784) (xy 147.984019 -384.744474) (xy 147.967958 -384.695044) (xy 147.959828 -384.643709)
			(xy 147.420328 -384.643709) (xy 147.412198 -384.695044) (xy 147.396137 -384.744474) (xy 147.372541 -384.790784)
			(xy 147.341991 -384.832832) (xy 147.30524 -384.869583) (xy 147.263192 -384.900133) (xy 147.216882 -384.923729)
			(xy 147.167452 -384.93979) (xy 147.116117 -384.94792) (xy 147.064143 -384.94792) (xy 147.012808 -384.93979)
			(xy 146.963378 -384.923729) (xy 146.917068 -384.900133) (xy 146.87502 -384.869583) (xy 146.838269 -384.832832)
			(xy 146.807719 -384.790784) (xy 146.784123 -384.744474) (xy 146.768062 -384.695044) (xy 146.759932 -384.643709)
			(xy 145.194277 -384.643709) (xy 145.155672 -384.663379) (xy 145.106242 -384.67944) (xy 145.054907 -384.68757)
			(xy 145.002933 -384.68757) (xy 144.951598 -384.67944) (xy 144.902168 -384.663379) (xy 144.855858 -384.639783)
			(xy 144.81381 -384.609233) (xy 144.777059 -384.572482) (xy 144.746509 -384.530434) (xy 144.722913 -384.484124)
			(xy 144.706852 -384.434694) (xy 144.698722 -384.383359) (xy 143.953618 -384.383359) (xy 143.958791 -384.387664)
			(xy 143.996008 -384.429201) (xy 144.026781 -384.475714) (xy 144.050453 -384.526211) (xy 144.066521 -384.579618)
			(xy 144.074641 -384.634794) (xy 144.07515 -384.66268) (xy 144.074641 -384.690566) (xy 144.066521 -384.745742)
			(xy 144.050453 -384.799149) (xy 144.026781 -384.849646) (xy 143.996008 -384.896159) (xy 143.958791 -384.937696)
			(xy 143.915923 -384.973371) (xy 143.868317 -385.002425) (xy 143.816988 -385.024237) (xy 143.763031 -385.038343)
			(xy 143.707594 -385.044443) (xy 143.65186 -385.042406) (xy 143.597017 -385.032276) (xy 143.544233 -385.014269)
			(xy 143.494633 -384.988768) (xy 143.449275 -384.956317) (xy 143.409126 -384.917608) (xy 143.37504 -384.873465)
			(xy 143.347744 -384.82483) (xy 143.327821 -384.772739) (xy 143.315695 -384.718302) (xy 143.311624 -384.66268)
			(xy 140.281955 -384.66268) (xy 140.255686 -384.712895) (xy 140.221157 -384.763162) (xy 140.180862 -384.808937)
			(xy 140.135382 -384.849564) (xy 140.085369 -384.884459) (xy 140.058648 -384.899154) (xy 140.050701 -384.903818)
			(xy 140.038556 -384.917655) (xy 140.032121 -384.934904) (xy 140.031724 -384.944112) (xy 140.031724 -385.58216)
			(xy 143.311624 -385.58216) (xy 143.315695 -385.526538) (xy 143.327821 -385.472101) (xy 143.347744 -385.42001)
			(xy 143.37504 -385.371375) (xy 143.409126 -385.327232) (xy 143.449275 -385.288523) (xy 143.494633 -385.256072)
			(xy 143.544233 -385.230571) (xy 143.597017 -385.212564) (xy 143.65186 -385.202434) (xy 143.707594 -385.200397)
			(xy 143.763031 -385.206497) (xy 143.816988 -385.220603) (xy 143.868317 -385.242415) (xy 143.915923 -385.271469)
			(xy 143.958791 -385.307144) (xy 143.996008 -385.348681) (xy 144.026781 -385.395194) (xy 144.050453 -385.445691)
			(xy 144.066521 -385.499098) (xy 144.074641 -385.554274) (xy 144.07515 -385.58216) (xy 144.074641 -385.610046)
			(xy 144.071893 -385.628721) (xy 144.277336 -385.628721) (xy 144.277336 -385.576747) (xy 144.285466 -385.525412)
			(xy 144.301527 -385.475982) (xy 144.325123 -385.429672) (xy 144.355673 -385.387624) (xy 144.392424 -385.350873)
			(xy 144.434472 -385.320323) (xy 144.480782 -385.296727) (xy 144.530212 -385.280666) (xy 144.581547 -385.272536)
			(xy 144.633521 -385.272536) (xy 144.684856 -385.280666) (xy 144.734286 -385.296727) (xy 144.761082 -385.31038)
			(xy 147.088352 -385.31038) (xy 147.088883 -385.284394) (xy 147.097015 -385.233063) (xy 147.113077 -385.183636)
			(xy 147.136671 -385.137329) (xy 147.167219 -385.095282) (xy 147.203967 -385.058532) (xy 147.246012 -385.027982)
			(xy 147.292317 -385.004384) (xy 147.341743 -384.98832) (xy 147.393074 -384.980185) (xy 147.41906 -384.979672)
			(xy 147.445072 -384.980087) (xy 147.496451 -384.988255) (xy 147.545918 -385.004364) (xy 147.592254 -385.028017)
			(xy 147.634317 -385.058632) (xy 147.671069 -385.095453) (xy 147.701605 -385.137573) (xy 147.725172 -385.183953)
			(xy 147.741189 -385.23345) (xy 147.745704 -385.259072) (xy 147.747228 -385.26847) (xy 147.771454 -385.31038)
			(xy 148.288248 -385.31038) (xy 148.288783 -385.284394) (xy 148.296915 -385.233064) (xy 148.312976 -385.183636)
			(xy 148.336571 -385.13733) (xy 148.367118 -385.095284) (xy 148.403866 -385.058533) (xy 148.445909 -385.027983)
			(xy 148.492214 -385.004385) (xy 148.54164 -384.988321) (xy 148.592971 -384.980185) (xy 148.618956 -384.979672)
			(xy 148.644968 -384.980091) (xy 148.696347 -384.988258) (xy 148.745814 -385.004366) (xy 148.79215 -385.028019)
			(xy 148.834213 -385.058633) (xy 148.870965 -385.095454) (xy 148.901501 -385.137573) (xy 148.925068 -385.183953)
			(xy 148.941085 -385.23345) (xy 148.9456 -385.259072) (xy 148.947124 -385.26847) (xy 148.97135 -385.31038)
			(xy 149.488398 -385.31038) (xy 149.488883 -385.284392) (xy 149.497017 -385.233056) (xy 149.513081 -385.183625)
			(xy 149.53668 -385.137315) (xy 149.567232 -385.095267) (xy 149.603987 -385.058516) (xy 149.646037 -385.027966)
			(xy 149.692349 -385.004371) (xy 149.741782 -384.988311) (xy 149.793118 -384.980181) (xy 149.819106 -384.979672)
			(xy 149.84515 -384.980128) (xy 149.896591 -384.988316) (xy 149.946115 -385.004459) (xy 149.9925 -385.028158)
			(xy 150.034602 -385.058828) (xy 150.071382 -385.095712) (xy 150.101933 -385.137901) (xy 150.1255 -385.184353)
			(xy 150.141503 -385.233923) (xy 150.146004 -385.25958) (xy 150.147274 -385.268978) (xy 150.17121 -385.31038)
			(xy 150.688294 -385.31038) (xy 150.688783 -385.284392) (xy 150.696917 -385.233057) (xy 150.712981 -385.183626)
			(xy 150.736579 -385.137316) (xy 150.767131 -385.095268) (xy 150.803885 -385.058517) (xy 150.845935 -385.027968)
			(xy 150.892246 -385.004372) (xy 150.941678 -384.988312) (xy 150.993014 -384.980181) (xy 151.019002 -384.979672)
			(xy 151.045012 -384.98014) (xy 151.096389 -384.988299) (xy 151.145855 -385.0044) (xy 151.192191 -385.028046)
			(xy 151.234254 -385.058654) (xy 151.271008 -385.095469) (xy 151.301545 -385.137583) (xy 151.325113 -385.183959)
			(xy 151.341131 -385.233452) (xy 151.345646 -385.259072) (xy 151.34717 -385.26847) (xy 151.619966 -385.740402)
			(xy 151.627332 -385.746244) (xy 151.64612 -385.762034) (xy 151.679236 -385.798254) (xy 151.706643 -385.838965)
			(xy 151.727742 -385.883275) (xy 151.742071 -385.930214) (xy 151.749315 -385.978753) (xy 151.74976 -386.003292)
			(xy 151.749506 -386.015484) (xy 151.749252 -386.025136) (xy 151.755348 -386.04317) (xy 151.814022 -386.11048)
			(xy 151.830786 -386.119116) (xy 151.840438 -386.120132) (xy 151.867204 -386.12346) (xy 151.919228 -386.137689)
			(xy 151.968253 -386.160169) (xy 152.012982 -386.190305) (xy 152.052229 -386.227299) (xy 152.084954 -386.270171)
			(xy 152.110289 -386.317784) (xy 152.127564 -386.368877) (xy 152.136321 -386.422095) (xy 152.136856 -386.449062)
			(xy 152.136346 -386.475049) (xy 152.128216 -386.526384) (xy 152.112155 -386.575814) (xy 152.088559 -386.622124)
			(xy 152.058009 -386.664172) (xy 152.021258 -386.700923) (xy 151.97921 -386.731473) (xy 151.9329 -386.755069)
			(xy 151.88347 -386.77113) (xy 151.832135 -386.77926) (xy 151.780161 -386.77926) (xy 151.728826 -386.77113)
			(xy 151.679396 -386.755069) (xy 151.633086 -386.731473) (xy 151.591038 -386.700923) (xy 151.554287 -386.664172)
			(xy 151.523737 -386.622124) (xy 151.500141 -386.575814) (xy 151.48408 -386.526384) (xy 151.47595 -386.475049)
			(xy 151.47544 -386.449062) (xy 151.475694 -386.43687) (xy 151.475948 -386.427218) (xy 151.469852 -386.409184)
			(xy 151.411178 -386.341874) (xy 151.394414 -386.333238) (xy 151.384762 -386.332222) (xy 151.357855 -386.328849)
			(xy 151.30557 -386.314485) (xy 151.256326 -386.291787) (xy 151.211444 -386.261362) (xy 151.172124 -386.224025)
			(xy 151.139419 -386.180775) (xy 151.114205 -386.132771) (xy 151.097158 -386.081298) (xy 151.092408 -386.0546)
			(xy 151.090884 -386.045202) (xy 150.818088 -385.57327) (xy 150.810722 -385.567428) (xy 150.79198 -385.551586)
			(xy 150.758859 -385.515378) (xy 150.731444 -385.474678) (xy 150.710337 -385.430378) (xy 150.695999 -385.383448)
			(xy 150.688745 -385.334916) (xy 150.688294 -385.31038) (xy 150.17121 -385.31038) (xy 150.419816 -385.740402)
			(xy 150.427182 -385.746244) (xy 150.44596 -385.762046) (xy 150.479078 -385.798262) (xy 150.506488 -385.83897)
			(xy 150.527589 -385.883278) (xy 150.541919 -385.930216) (xy 150.549164 -385.978754) (xy 150.54961 -386.003292)
			(xy 150.549356 -386.015484) (xy 150.549102 -386.025136) (xy 150.555198 -386.04317) (xy 150.613872 -386.11048)
			(xy 150.630636 -386.119116) (xy 150.640542 -386.120132) (xy 150.667309 -386.123457) (xy 150.719332 -386.137686)
			(xy 150.768358 -386.160167) (xy 150.813087 -386.190304) (xy 150.852333 -386.227298) (xy 150.885058 -386.27017)
			(xy 150.910393 -386.317783) (xy 150.927668 -386.368876) (xy 150.936425 -386.422095) (xy 150.93696 -386.449062)
			(xy 150.93641 -386.476346) (xy 150.927457 -386.530175) (xy 150.909787 -386.581804) (xy 150.883881 -386.629831)
			(xy 150.850441 -386.672952) (xy 150.830788 -386.691886) (xy 150.823389 -386.699409) (xy 150.814863 -386.718688)
			(xy 150.814278 -386.729224) (xy 150.814278 -386.8039) (xy 150.8148 -386.81445) (xy 150.823341 -386.833745)
			(xy 150.830788 -386.841238) (xy 150.850438 -386.860174) (xy 150.883868 -386.9033) (xy 150.90977 -386.951327)
			(xy 150.927439 -387.002953) (xy 150.936399 -387.056779) (xy 150.93696 -387.084062) (xy 150.936508 -387.108178)
			(xy 150.929512 -387.1559) (xy 150.915663 -387.202101) (xy 150.895254 -387.245802) (xy 150.88235 -387.26618)
			(xy 150.876508 -387.27507) (xy 150.872952 -387.295136) (xy 150.894034 -387.387338) (xy 150.906226 -387.404102)
			(xy 150.915116 -387.409436) (xy 150.935913 -387.422298) (xy 150.973819 -387.453185) (xy 151.006763 -387.489319)
			(xy 151.034025 -387.529911) (xy 151.055011 -387.574076) (xy 151.069263 -387.62085) (xy 151.076471 -387.669213)
			(xy 151.076914 -387.693662) (xy 151.076488 -387.718035) (xy 151.069342 -387.766254) (xy 151.055201 -387.812903)
			(xy 151.034368 -387.856973) (xy 151.007296 -387.89751) (xy 150.974571 -387.933637) (xy 150.95601 -387.94944)
			(xy 150.94712 -387.956552) (xy 150.937722 -387.97611) (xy 150.934928 -388.075424) (xy 150.943564 -388.09549)
			(xy 150.951946 -388.10311) (xy 150.970393 -388.120574) (xy 151.001741 -388.160544) (xy 151.026038 -388.205152)
			(xy 151.042615 -388.253167) (xy 151.051015 -388.303264) (xy 151.051514 -388.328662) (xy 151.640794 -388.328662)
			(xy 151.641316 -388.303407) (xy 151.649629 -388.253585) (xy 151.66603 -388.205811) (xy 151.690071 -388.161388)
			(xy 151.721095 -388.121528) (xy 151.758257 -388.087318) (xy 151.800543 -388.059692) (xy 151.846799 -388.039402)
			(xy 151.895764 -388.027002) (xy 151.946102 -388.022831) (xy 151.99644 -388.027002) (xy 152.045405 -388.039402)
			(xy 152.091661 -388.059692) (xy 152.133947 -388.087318) (xy 152.171109 -388.121528) (xy 152.202133 -388.161388)
			(xy 152.226174 -388.205811) (xy 152.242575 -388.253585) (xy 152.250888 -388.303407) (xy 152.25141 -388.328662)
			(xy 152.251341 -388.338021) (xy 152.250198 -388.356703) (xy 152.249124 -388.366) (xy 152.248108 -388.37489)
			(xy 152.251918 -388.391654) (xy 152.29586 -388.461504) (xy 152.309576 -388.471918) (xy 152.317958 -388.474712)
			(xy 152.34199 -388.48317) (xy 152.387162 -388.506725) (xy 152.427966 -388.537227) (xy 152.463345 -388.573884)
			(xy 152.492379 -388.615745) (xy 152.514317 -388.661724) (xy 152.52192 -388.68604) (xy 152.523444 -388.691882)
			(xy 152.843738 -389.245602) (xy 152.847802 -389.24992) (xy 152.86399 -389.267629) (xy 152.891356 -389.307037)
			(xy 152.912442 -389.350133) (xy 152.926762 -389.395924) (xy 152.933987 -389.443355) (xy 152.934416 -389.467344)
			(xy 152.933923 -389.492132) (xy 152.926162 -389.541098) (xy 152.910838 -389.588247) (xy 152.888328 -389.63242)
			(xy 152.859187 -389.672528) (xy 152.824131 -389.707584) (xy 152.784023 -389.736726) (xy 152.739851 -389.759236)
			(xy 152.692702 -389.774561) (xy 152.643736 -389.782322) (xy 152.618948 -389.782812) (xy 152.593555 -389.782269)
			(xy 152.543423 -389.774146) (xy 152.495239 -389.758102) (xy 152.450245 -389.73455) (xy 152.409601 -389.704098)
			(xy 152.374358 -389.667532) (xy 152.345423 -389.625796) (xy 152.323543 -389.579965) (xy 152.315926 -389.555736)
			(xy 152.314402 -389.549894) (xy 151.994108 -388.996174) (xy 151.990044 -388.991856) (xy 151.973831 -388.974156)
			(xy 151.946411 -388.934762) (xy 151.92527 -388.89167) (xy 151.910899 -388.845875) (xy 151.903626 -388.798431)
			(xy 151.903176 -388.774432) (xy 151.903318 -388.76238) (xy 151.905224 -388.73835) (xy 151.906986 -388.726426)
			(xy 151.908256 -388.717536) (xy 151.905208 -388.700518) (xy 151.863044 -388.629652) (xy 151.849836 -388.618476)
			(xy 151.841454 -388.615428) (xy 151.819703 -388.607042) (xy 151.778845 -388.584599) (xy 151.741875 -388.556203)
			(xy 151.709653 -388.522517) (xy 151.682928 -388.484322) (xy 151.662322 -388.442507) (xy 151.648315 -388.398045)
			(xy 151.641232 -388.35197) (xy 151.640794 -388.328662) (xy 151.051514 -388.328662) (xy 151.051445 -388.338021)
			(xy 151.050302 -388.356703) (xy 151.049228 -388.366) (xy 151.048212 -388.37489) (xy 151.052022 -388.391654)
			(xy 151.095964 -388.461504) (xy 151.10968 -388.471918) (xy 151.118062 -388.474712) (xy 151.142095 -388.483168)
			(xy 151.187266 -388.506724) (xy 151.228071 -388.537226) (xy 151.263449 -388.573883) (xy 151.292484 -388.615744)
			(xy 151.314421 -388.661724) (xy 151.322024 -388.68604) (xy 151.323548 -388.691882) (xy 151.643842 -389.245602)
			(xy 151.647906 -389.24992) (xy 151.664095 -389.267628) (xy 151.69146 -389.307037) (xy 151.712546 -389.350133)
			(xy 151.726867 -389.395924) (xy 151.734091 -389.443355) (xy 151.73452 -389.467344) (xy 151.734147 -389.492139)
			(xy 151.726383 -389.541118) (xy 151.711052 -389.588279) (xy 151.688532 -389.632461) (xy 151.659377 -389.672577)
			(xy 151.624307 -389.707637) (xy 151.584183 -389.73678) (xy 151.539994 -389.759287) (xy 151.492828 -389.774604)
			(xy 151.443847 -389.782355) (xy 151.419052 -389.782812) (xy 151.393656 -389.782354) (xy 151.343521 -389.774216)
			(xy 151.295334 -389.758157) (xy 151.25034 -389.734593) (xy 151.209697 -389.704129) (xy 151.174456 -389.667553)
			(xy 151.145523 -389.625807) (xy 151.123646 -389.579968) (xy 151.11603 -389.555736) (xy 151.114506 -389.549894)
			(xy 150.794212 -388.996174) (xy 150.790148 -388.991856) (xy 150.773936 -388.974155) (xy 150.746515 -388.934761)
			(xy 150.725375 -388.89167) (xy 150.711003 -388.845874) (xy 150.70373 -388.798431) (xy 150.70328 -388.774432)
			(xy 150.703422 -388.76238) (xy 150.705328 -388.73835) (xy 150.70709 -388.726426) (xy 150.70836 -388.717536)
			(xy 150.705312 -388.700518) (xy 150.663148 -388.629652) (xy 150.64994 -388.618476) (xy 150.641558 -388.615428)
			(xy 150.619808 -388.607039) (xy 150.578949 -388.584597) (xy 150.541979 -388.556202) (xy 150.509757 -388.522516)
			(xy 150.483032 -388.484321) (xy 150.462427 -388.442507) (xy 150.448419 -388.398045) (xy 150.441336 -388.35197)
			(xy 150.440898 -388.328662) (xy 150.441424 -388.303267) (xy 150.449834 -388.253178) (xy 150.466414 -388.205171)
			(xy 150.490708 -388.160568) (xy 150.522046 -388.120599) (xy 150.540466 -388.10311) (xy 150.548848 -388.09549)
			(xy 150.557484 -388.075424) (xy 150.55469 -387.97611) (xy 150.545292 -387.956552) (xy 150.536402 -387.94944)
			(xy 150.517875 -387.933601) (xy 150.485151 -387.897479) (xy 150.458078 -387.856948) (xy 150.437242 -387.812886)
			(xy 150.423092 -387.766244) (xy 150.415936 -387.718032) (xy 150.415498 -387.693662) (xy 150.415904 -387.669544)
			(xy 150.422912 -387.62182) (xy 150.436774 -387.575619) (xy 150.457197 -387.53192) (xy 150.470108 -387.511544)
			(xy 150.47595 -387.502654) (xy 150.479506 -387.482588) (xy 150.458424 -387.390386) (xy 150.446232 -387.373622)
			(xy 150.437342 -387.368288) (xy 150.416546 -387.355425) (xy 150.378642 -387.324536) (xy 150.3457 -387.288401)
			(xy 150.318439 -387.247809) (xy 150.297452 -387.203645) (xy 150.283199 -387.156872) (xy 150.275989 -387.10851)
			(xy 150.275544 -387.084062) (xy 150.276109 -387.056778) (xy 150.285058 -387.00295) (xy 150.302724 -386.951322)
			(xy 150.328627 -386.903294) (xy 150.362064 -386.860172) (xy 150.381716 -386.841238) (xy 150.389105 -386.833706)
			(xy 150.397636 -386.814434) (xy 150.398226 -386.8039) (xy 150.398226 -386.729224) (xy 150.39769 -386.718675)
			(xy 150.389159 -386.69938) (xy 150.381716 -386.691886) (xy 150.362079 -386.672938) (xy 150.328646 -386.629815)
			(xy 150.302743 -386.581791) (xy 150.28507 -386.530168) (xy 150.276107 -386.476344) (xy 150.275544 -386.449062)
			(xy 150.275798 -386.43687) (xy 150.276052 -386.427218) (xy 150.269956 -386.409184) (xy 150.211282 -386.341874)
			(xy 150.194518 -386.333238) (xy 150.184612 -386.332222) (xy 150.157711 -386.328809) (xy 150.105426 -386.314453)
			(xy 150.056182 -386.291762) (xy 150.011299 -386.261343) (xy 149.971978 -386.224012) (xy 149.939272 -386.180766)
			(xy 149.914057 -386.132766) (xy 149.897008 -386.081296) (xy 149.892258 -386.0546) (xy 149.890734 -386.045202)
			(xy 149.617684 -385.572762) (xy 149.610572 -385.56692) (xy 149.591835 -385.551146) (xy 149.558782 -385.515002)
			(xy 149.531426 -385.474375) (xy 149.510368 -385.430155) (xy 149.496069 -385.383311) (xy 149.488841 -385.334869)
			(xy 149.488398 -385.31038) (xy 148.97135 -385.31038) (xy 149.21992 -385.740402) (xy 149.227286 -385.746244)
			(xy 149.246064 -385.762045) (xy 149.279183 -385.798262) (xy 149.306592 -385.83897) (xy 149.327693 -385.883278)
			(xy 149.342023 -385.930216) (xy 149.349268 -385.978754) (xy 149.349714 -386.003292) (xy 149.34946 -386.015484)
			(xy 149.349206 -386.025136) (xy 149.355302 -386.04317) (xy 149.413976 -386.11048) (xy 149.43074 -386.119116)
			(xy 149.440646 -386.120132) (xy 149.467413 -386.123454) (xy 149.519437 -386.137683) (xy 149.568462 -386.160165)
			(xy 149.613191 -386.190302) (xy 149.652438 -386.227297) (xy 149.685162 -386.270169) (xy 149.710497 -386.317783)
			(xy 149.727772 -386.368876) (xy 149.736529 -386.422095) (xy 149.737064 -386.449062) (xy 149.736513 -386.476346)
			(xy 149.72756 -386.530175) (xy 149.70989 -386.581803) (xy 149.683985 -386.62983) (xy 149.650545 -386.672952)
			(xy 149.630892 -386.691886) (xy 149.623494 -386.69941) (xy 149.614968 -386.718688) (xy 149.614382 -386.729224)
			(xy 149.614382 -386.8039) (xy 149.614903 -386.814451) (xy 149.623444 -386.833745) (xy 149.630892 -386.841238)
			(xy 149.650542 -386.860173) (xy 149.683973 -386.9033) (xy 149.709874 -386.951327) (xy 149.727544 -387.002953)
			(xy 149.736503 -387.056779) (xy 149.737064 -387.084062) (xy 149.736612 -387.108178) (xy 149.729616 -387.1559)
			(xy 149.715767 -387.202101) (xy 149.695358 -387.245802) (xy 149.682454 -387.26618) (xy 149.676612 -387.27507)
			(xy 149.673056 -387.295136) (xy 149.694138 -387.387338) (xy 149.70633 -387.404102) (xy 149.71522 -387.409436)
			(xy 149.736018 -387.422296) (xy 149.773924 -387.453184) (xy 149.806867 -387.489319) (xy 149.834129 -387.529911)
			(xy 149.855115 -387.574076) (xy 149.869367 -387.62085) (xy 149.876575 -387.669213) (xy 149.877018 -387.693662)
			(xy 149.87659 -387.718035) (xy 149.869445 -387.766254) (xy 149.855303 -387.812903) (xy 149.834471 -387.856973)
			(xy 149.8074 -387.89751) (xy 149.774674 -387.933637) (xy 149.756114 -387.94944) (xy 149.747224 -387.956552)
			(xy 149.737826 -387.97611) (xy 149.735032 -388.075424) (xy 149.743668 -388.09549) (xy 149.75205 -388.10311)
			(xy 149.770498 -388.120573) (xy 149.801845 -388.160543) (xy 149.826142 -388.205152) (xy 149.842719 -388.253167)
			(xy 149.851119 -388.303264) (xy 149.851618 -388.328662) (xy 149.851549 -388.338021) (xy 149.850406 -388.356703)
			(xy 149.849332 -388.366) (xy 149.848316 -388.37489) (xy 149.852126 -388.391654) (xy 149.896068 -388.461504)
			(xy 149.909784 -388.471918) (xy 149.918166 -388.474712) (xy 149.942257 -388.48321) (xy 149.987549 -388.506831)
			(xy 150.028445 -388.537438) (xy 150.063878 -388.574232) (xy 150.092922 -388.616252) (xy 150.114819 -388.662402)
			(xy 150.122382 -388.686802) (xy 150.123906 -388.692644) (xy 150.443692 -389.245602) (xy 150.447756 -389.24992)
			(xy 150.463957 -389.26763) (xy 150.49138 -389.307021) (xy 150.512522 -389.350111) (xy 150.526897 -389.395904)
			(xy 150.534172 -389.443346) (xy 150.534624 -389.467344) (xy 150.534246 -389.492152) (xy 150.526474 -389.541155)
			(xy 150.511128 -389.588337) (xy 150.488586 -389.632536) (xy 150.459404 -389.672662) (xy 150.424302 -389.707727)
			(xy 150.384144 -389.736865) (xy 150.339921 -389.759359) (xy 150.292721 -389.774654) (xy 150.24371 -389.782373)
			(xy 150.218902 -389.782812) (xy 150.193508 -389.78231) (xy 150.143374 -389.774179) (xy 150.095189 -389.758128)
			(xy 150.050194 -389.73457) (xy 150.009551 -389.704113) (xy 149.974309 -389.667542) (xy 149.945375 -389.625801)
			(xy 149.923497 -389.579966) (xy 149.91588 -389.555736) (xy 149.914356 -389.549894) (xy 149.593808 -388.995412)
			(xy 149.589744 -388.991094) (xy 149.573639 -388.973426) (xy 149.546391 -388.934146) (xy 149.525381 -388.891206)
			(xy 149.511089 -388.845587) (xy 149.503842 -388.798334) (xy 149.503384 -388.774432) (xy 149.503526 -388.76238)
			(xy 149.505432 -388.73835) (xy 149.507194 -388.726426) (xy 149.508464 -388.717536) (xy 149.505416 -388.700518)
			(xy 149.463252 -388.629652) (xy 149.450044 -388.618476) (xy 149.441662 -388.615428) (xy 149.419913 -388.607037)
			(xy 149.379054 -388.584595) (xy 149.342084 -388.556201) (xy 149.309862 -388.522515) (xy 149.283137 -388.48432)
			(xy 149.262531 -388.442506) (xy 149.248523 -388.398045) (xy 149.24144 -388.35197) (xy 149.241002 -388.328662)
			(xy 149.241527 -388.303267) (xy 149.249936 -388.253178) (xy 149.266517 -388.20517) (xy 149.290811 -388.160568)
			(xy 149.32215 -388.120599) (xy 149.34057 -388.10311) (xy 149.348952 -388.09549) (xy 149.357588 -388.075424)
			(xy 149.354794 -387.97611) (xy 149.345396 -387.956552) (xy 149.336506 -387.94944) (xy 149.317959 -387.933623)
			(xy 149.285241 -387.897494) (xy 149.258173 -387.856958) (xy 149.237341 -387.812892) (xy 149.223195 -387.766247)
			(xy 149.216039 -387.718033) (xy 149.215602 -387.693662) (xy 149.216007 -387.669544) (xy 149.223016 -387.62182)
			(xy 149.236878 -387.575619) (xy 149.257301 -387.53192) (xy 149.270212 -387.511544) (xy 149.276054 -387.502654)
			(xy 149.27961 -387.482588) (xy 149.258528 -387.390386) (xy 149.246336 -387.373622) (xy 149.237446 -387.368288)
			(xy 149.216651 -387.355424) (xy 149.178747 -387.324535) (xy 149.145805 -387.288401) (xy 149.118543 -387.247809)
			(xy 149.097557 -387.203645) (xy 149.083303 -387.156872) (xy 149.076093 -387.10851) (xy 149.075648 -387.084062)
			(xy 149.076211 -387.056778) (xy 149.085161 -387.00295) (xy 149.102827 -386.951321) (xy 149.12873 -386.903294)
			(xy 149.162168 -386.860172) (xy 149.18182 -386.841238) (xy 149.18921 -386.833707) (xy 149.19774 -386.814434)
			(xy 149.19833 -386.8039) (xy 149.19833 -386.729224) (xy 149.197793 -386.718675) (xy 149.189262 -386.699381)
			(xy 149.18182 -386.691886) (xy 149.162183 -386.672937) (xy 149.128751 -386.629815) (xy 149.102847 -386.581791)
			(xy 149.085174 -386.530168) (xy 149.076211 -386.476344) (xy 149.075648 -386.449062) (xy 149.075902 -386.43687)
			(xy 149.076156 -386.427218) (xy 149.07006 -386.409184) (xy 149.011386 -386.341874) (xy 148.994622 -386.333238)
			(xy 148.984716 -386.332222) (xy 148.957815 -386.328806) (xy 148.90553 -386.314451) (xy 148.856287 -386.29176)
			(xy 148.811403 -386.261342) (xy 148.772082 -386.22401) (xy 148.739376 -386.180766) (xy 148.714161 -386.132766)
			(xy 148.697112 -386.081296) (xy 148.692362 -386.0546) (xy 148.690838 -386.045202) (xy 148.418042 -385.57327)
			(xy 148.410676 -385.567428) (xy 148.391924 -385.551597) (xy 148.358806 -385.515386) (xy 148.331394 -385.474683)
			(xy 148.310288 -385.430381) (xy 148.295952 -385.38345) (xy 148.288698 -385.334916) (xy 148.288248 -385.31038)
			(xy 147.771454 -385.31038) (xy 148.020024 -385.740402) (xy 148.02739 -385.746244) (xy 148.046169 -385.762044)
			(xy 148.079287 -385.798261) (xy 148.106697 -385.83897) (xy 148.127798 -385.883278) (xy 148.142127 -385.930215)
			(xy 148.149372 -385.978754) (xy 148.149818 -386.003292) (xy 148.149564 -386.015484) (xy 148.14931 -386.025136)
			(xy 148.155406 -386.04317) (xy 148.21408 -386.11048) (xy 148.230844 -386.119116) (xy 148.240496 -386.120132)
			(xy 148.267257 -386.123495) (xy 148.31928 -386.137717) (xy 148.368306 -386.160191) (xy 148.413036 -386.190322)
			(xy 148.452283 -386.227312) (xy 148.485009 -386.27018) (xy 148.510346 -386.31779) (xy 148.527621 -386.36888)
			(xy 148.536378 -386.422096) (xy 148.536914 -386.449062) (xy 148.536378 -386.476347) (xy 148.527424 -386.530177)
			(xy 148.509752 -386.581807) (xy 148.483842 -386.629833) (xy 148.450398 -386.672954) (xy 148.430742 -386.691886)
			(xy 148.423351 -386.699417) (xy 148.414819 -386.71869) (xy 148.414232 -386.729224) (xy 148.414232 -386.8039)
			(xy 148.414738 -386.814453) (xy 148.423288 -386.833748) (xy 148.430742 -386.841238) (xy 148.450383 -386.860182)
			(xy 148.483817 -386.903305) (xy 148.509721 -386.95133) (xy 148.527392 -387.002955) (xy 148.536353 -387.056779)
			(xy 148.536914 -387.084062) (xy 148.53647 -387.108178) (xy 148.529473 -387.155901) (xy 148.515622 -387.202102)
			(xy 148.49521 -387.245803) (xy 148.482304 -387.26618) (xy 148.476462 -387.27507) (xy 148.472906 -387.295136)
			(xy 148.493988 -387.387338) (xy 148.50618 -387.404102) (xy 148.51507 -387.409436) (xy 148.535879 -387.422278)
			(xy 148.573783 -387.453171) (xy 148.606724 -387.489309) (xy 148.633983 -387.529905) (xy 148.654967 -387.574072)
			(xy 148.669218 -387.620848) (xy 148.676425 -387.669213) (xy 148.676868 -387.693662) (xy 148.676459 -387.718036)
			(xy 148.669312 -387.766256) (xy 148.655168 -387.812907) (xy 148.634333 -387.856977) (xy 148.607257 -387.897513)
			(xy 148.574527 -387.933639) (xy 148.555964 -387.94944) (xy 148.547074 -387.956552) (xy 148.537676 -387.97611)
			(xy 148.534882 -388.075424) (xy 148.543518 -388.09549) (xy 148.5519 -388.10311) (xy 148.570339 -388.120583)
			(xy 148.601689 -388.160549) (xy 148.625989 -388.205155) (xy 148.642568 -388.253168) (xy 148.650968 -388.303264)
			(xy 148.651468 -388.328662) (xy 148.651399 -388.338021) (xy 148.650256 -388.356703) (xy 148.649182 -388.366)
			(xy 148.648166 -388.37489) (xy 148.651976 -388.391654) (xy 148.695918 -388.461504) (xy 148.709634 -388.471918)
			(xy 148.718016 -388.474712) (xy 148.74204 -388.483193) (xy 148.787212 -388.506742) (xy 148.828018 -388.537239)
			(xy 148.863398 -388.573891) (xy 148.892435 -388.615749) (xy 148.914374 -388.661725) (xy 148.921978 -388.68604)
			(xy 148.923502 -388.691882) (xy 149.243796 -389.245602) (xy 149.24786 -389.24992) (xy 149.264062 -389.26763)
			(xy 149.291484 -389.307021) (xy 149.312626 -389.35011) (xy 149.327001 -389.395904) (xy 149.334276 -389.443346)
			(xy 149.334728 -389.467344) (xy 149.334346 -389.492151) (xy 149.326574 -389.541154) (xy 149.311228 -389.588336)
			(xy 149.288687 -389.632535) (xy 149.259506 -389.672661) (xy 149.224404 -389.707725) (xy 149.184246 -389.736864)
			(xy 149.140023 -389.759358) (xy 149.092825 -389.774653) (xy 149.043814 -389.782373) (xy 149.019006 -389.782812)
			(xy 148.993612 -389.782306) (xy 148.943478 -389.774177) (xy 148.895293 -389.758126) (xy 148.850299 -389.734568)
			(xy 148.809656 -389.704112) (xy 148.774413 -389.667541) (xy 148.745479 -389.625801) (xy 148.723601 -389.579966)
			(xy 148.715984 -389.555736) (xy 148.71446 -389.549894) (xy 148.394166 -388.996174) (xy 148.390102 -388.991856)
			(xy 148.373951 -388.974115) (xy 148.34658 -388.934716) (xy 148.325487 -388.891628) (xy 148.311157 -388.845844)
			(xy 148.303922 -388.798419) (xy 148.303488 -388.774432) (xy 148.303569 -388.762384) (xy 148.305352 -388.738355)
			(xy 148.307044 -388.726426) (xy 148.308314 -388.717536) (xy 148.305266 -388.700518) (xy 148.263102 -388.629652)
			(xy 148.249894 -388.618476) (xy 148.241512 -388.615428) (xy 148.219773 -388.60701) (xy 148.178914 -388.584574)
			(xy 148.141941 -388.556185) (xy 148.109717 -388.522504) (xy 148.08299 -388.484313) (xy 148.062383 -388.442501)
			(xy 148.048374 -388.398042) (xy 148.04129 -388.351969) (xy 148.040852 -388.328662) (xy 148.041361 -388.303266)
			(xy 148.049772 -388.253176) (xy 148.066355 -388.205167) (xy 148.090653 -388.160564) (xy 148.121997 -388.120597)
			(xy 148.14042 -388.10311) (xy 148.148802 -388.09549) (xy 148.157438 -388.075424) (xy 148.154644 -387.97611)
			(xy 148.145246 -387.956552) (xy 148.136356 -387.94944) (xy 148.11782 -387.933611) (xy 148.085098 -387.897486)
			(xy 148.058028 -387.856953) (xy 148.037194 -387.812889) (xy 148.023046 -387.766246) (xy 148.01589 -387.718033)
			(xy 148.015452 -387.693662) (xy 148.015865 -387.669544) (xy 148.022873 -387.621821) (xy 148.036733 -387.57562)
			(xy 148.057153 -387.53192) (xy 148.070062 -387.511544) (xy 148.075904 -387.502654) (xy 148.07946 -387.482588)
			(xy 148.058378 -387.390386) (xy 148.046186 -387.373622) (xy 148.037296 -387.368288) (xy 148.016513 -387.355406)
			(xy 147.978606 -387.324522) (xy 147.945661 -387.288391) (xy 147.918397 -387.247803) (xy 147.897409 -387.203641)
			(xy 147.883154 -387.15687) (xy 147.875943 -387.10851) (xy 147.875498 -387.084062) (xy 147.876045 -387.056777)
			(xy 147.884996 -387.002947) (xy 147.902665 -386.951318) (xy 147.928573 -386.903291) (xy 147.962015 -386.860171)
			(xy 147.98167 -386.841238) (xy 147.989053 -386.8337) (xy 147.997589 -386.814433) (xy 147.99818 -386.8039)
			(xy 147.99818 -386.729224) (xy 147.997657 -386.718673) (xy 147.989118 -386.699378) (xy 147.98167 -386.691886)
			(xy 147.962043 -386.672928) (xy 147.928607 -386.629809) (xy 147.9027 -386.581788) (xy 147.885025 -386.530166)
			(xy 147.876061 -386.476344) (xy 147.875498 -386.449062) (xy 147.875752 -386.43687) (xy 147.876006 -386.427218)
			(xy 147.86991 -386.409184) (xy 147.811236 -386.341874) (xy 147.794472 -386.333238) (xy 147.78482 -386.332222)
			(xy 147.757909 -386.328882) (xy 147.705622 -386.314512) (xy 147.656379 -386.291808) (xy 147.611497 -386.261378)
			(xy 147.572178 -386.224036) (xy 147.539474 -386.180783) (xy 147.514262 -386.132775) (xy 147.497215 -386.081299)
			(xy 147.492466 -386.0546) (xy 147.490942 -386.045202) (xy 147.218146 -385.57327) (xy 147.21078 -385.567428)
			(xy 147.192029 -385.551596) (xy 147.15891 -385.515385) (xy 147.131498 -385.474683) (xy 147.110393 -385.430381)
			(xy 147.096056 -385.383449) (xy 147.088802 -385.334916) (xy 147.088352 -385.31038) (xy 144.761082 -385.31038)
			(xy 144.780596 -385.320323) (xy 144.822644 -385.350873) (xy 144.859395 -385.387624) (xy 144.889945 -385.429672)
			(xy 144.913541 -385.475982) (xy 144.929602 -385.525412) (xy 144.937732 -385.576747) (xy 144.938242 -385.602734)
			(xy 144.937732 -385.628721) (xy 144.929602 -385.680056) (xy 144.913541 -385.729486) (xy 144.889945 -385.775796)
			(xy 144.859395 -385.817844) (xy 144.822644 -385.854595) (xy 144.79383 -385.87553) (xy 146.461734 -385.87553)
			(xy 146.462244 -385.849543) (xy 146.470374 -385.798208) (xy 146.486435 -385.748778) (xy 146.510031 -385.702468)
			(xy 146.540581 -385.66042) (xy 146.577332 -385.623669) (xy 146.61938 -385.593119) (xy 146.66569 -385.569523)
			(xy 146.71512 -385.553462) (xy 146.766455 -385.545332) (xy 146.818429 -385.545332) (xy 146.869764 -385.553462)
			(xy 146.919194 -385.569523) (xy 146.965504 -385.593119) (xy 147.007552 -385.623669) (xy 147.044303 -385.66042)
			(xy 147.074853 -385.702468) (xy 147.098449 -385.748778) (xy 147.11451 -385.798208) (xy 147.12264 -385.849543)
			(xy 147.12315 -385.87553) (xy 147.122767 -385.899206) (xy 147.116034 -385.946077) (xy 147.102668 -385.991504)
			(xy 147.093178 -386.013198) (xy 147.08886 -386.022596) (xy 147.088098 -386.042662) (xy 147.120356 -386.129022)
			(xy 147.134072 -386.143754) (xy 147.14347 -386.148072) (xy 147.167843 -386.159753) (xy 147.212712 -386.189883)
			(xy 147.252089 -386.226903) (xy 147.284927 -386.269829) (xy 147.310352 -386.317522) (xy 147.32769 -386.368712)
			(xy 147.336479 -386.422039) (xy 147.337018 -386.449062) (xy 147.336481 -386.476347) (xy 147.327527 -386.530177)
			(xy 147.309855 -386.581806) (xy 147.283946 -386.629833) (xy 147.250502 -386.672954) (xy 147.230846 -386.691886)
			(xy 147.223455 -386.699417) (xy 147.214923 -386.71869) (xy 147.214336 -386.729224) (xy 147.214336 -386.8039)
			(xy 147.214841 -386.814453) (xy 147.223392 -386.833749) (xy 147.230846 -386.841238) (xy 147.250488 -386.860182)
			(xy 147.283921 -386.903305) (xy 147.309825 -386.95133) (xy 147.327496 -387.002955) (xy 147.336457 -387.056779)
			(xy 147.337018 -387.084062) (xy 147.336573 -387.108178) (xy 147.329576 -387.155901) (xy 147.315725 -387.202102)
			(xy 147.295314 -387.245803) (xy 147.282408 -387.26618) (xy 147.276566 -387.27507) (xy 147.27301 -387.295136)
			(xy 147.294092 -387.387338) (xy 147.306284 -387.404102) (xy 147.315174 -387.409436) (xy 147.335984 -387.422277)
			(xy 147.373888 -387.45317) (xy 147.406828 -387.489309) (xy 147.434088 -387.529904) (xy 147.455071 -387.574072)
			(xy 147.469322 -387.620848) (xy 147.476529 -387.669213) (xy 147.476972 -387.693662) (xy 147.476561 -387.718036)
			(xy 147.469415 -387.766256) (xy 147.455271 -387.812906) (xy 147.434436 -387.856977) (xy 147.40736 -387.897513)
			(xy 147.374631 -387.933639) (xy 147.356068 -387.94944) (xy 147.347178 -387.956552) (xy 147.33778 -387.97611)
			(xy 147.334986 -388.075424) (xy 147.343622 -388.09549) (xy 147.352004 -388.10311) (xy 147.370443 -388.120582)
			(xy 147.401793 -388.160549) (xy 147.426093 -388.205155) (xy 147.442672 -388.253168) (xy 147.451072 -388.303264)
			(xy 147.451572 -388.328662) (xy 147.451503 -388.338021) (xy 147.45036 -388.356703) (xy 147.449286 -388.366)
			(xy 147.44827 -388.37489) (xy 147.45208 -388.391654) (xy 147.496022 -388.461504) (xy 147.509738 -388.471918)
			(xy 147.51812 -388.474712) (xy 147.542144 -388.48319) (xy 147.587317 -388.506741) (xy 147.628123 -388.537238)
			(xy 147.663503 -388.573891) (xy 147.692539 -388.615748) (xy 147.714479 -388.661725) (xy 147.722082 -388.68604)
			(xy 147.723606 -388.691882) (xy 148.0439 -389.245602) (xy 148.047964 -389.24992) (xy 148.064166 -389.267629)
			(xy 148.091588 -389.307021) (xy 148.11273 -389.35011) (xy 148.127105 -389.395904) (xy 148.13438 -389.443346)
			(xy 148.134832 -389.467344) (xy 148.134447 -389.492151) (xy 148.126674 -389.541153) (xy 148.111329 -389.588335)
			(xy 148.088788 -389.632534) (xy 148.059607 -389.67266) (xy 148.024505 -389.707724) (xy 147.984349 -389.736862)
			(xy 147.940126 -389.759357) (xy 147.892928 -389.774652) (xy 147.843918 -389.782373) (xy 147.81911 -389.782812)
			(xy 147.793716 -389.782303) (xy 147.743583 -389.774174) (xy 147.695397 -389.758124) (xy 147.650403 -389.734567)
			(xy 147.60976 -389.70411) (xy 147.574517 -389.66754) (xy 147.545583 -389.6258) (xy 147.523705 -389.579966)
			(xy 147.516088 -389.555736) (xy 147.514564 -389.549894) (xy 147.19427 -388.996174) (xy 147.190206 -388.991856)
			(xy 147.174039 -388.974129) (xy 147.146673 -388.934724) (xy 147.125585 -388.891633) (xy 147.111259 -388.845846)
			(xy 147.104026 -388.79842) (xy 147.103592 -388.774432) (xy 147.103673 -388.762384) (xy 147.105456 -388.738355)
			(xy 147.107148 -388.726426) (xy 147.108418 -388.717536) (xy 147.10537 -388.700518) (xy 147.063206 -388.629652)
			(xy 147.049998 -388.618476) (xy 147.041616 -388.615428) (xy 147.019878 -388.607008) (xy 146.979018 -388.584573)
			(xy 146.942046 -388.556184) (xy 146.909821 -388.522503) (xy 146.883094 -388.484312) (xy 146.862487 -388.442501)
			(xy 146.848478 -388.398042) (xy 146.841394 -388.351969) (xy 146.840956 -388.328662) (xy 146.841464 -388.303266)
			(xy 146.849875 -388.253175) (xy 146.866458 -388.205167) (xy 146.890757 -388.160564) (xy 146.922101 -388.120597)
			(xy 146.940524 -388.10311) (xy 146.948906 -388.09549) (xy 146.957542 -388.075424) (xy 146.954748 -387.97611)
			(xy 146.94535 -387.956552) (xy 146.93646 -387.94944) (xy 146.917924 -387.93361) (xy 146.885203 -387.897485)
			(xy 146.858132 -387.856952) (xy 146.837298 -387.812888) (xy 146.82315 -387.766246) (xy 146.815994 -387.718033)
			(xy 146.815556 -387.693662) (xy 146.815969 -387.669544) (xy 146.822976 -387.621821) (xy 146.836836 -387.57562)
			(xy 146.857257 -387.53192) (xy 146.870166 -387.511544) (xy 146.876008 -387.502654) (xy 146.879564 -387.482588)
			(xy 146.858482 -387.390386) (xy 146.84629 -387.373622) (xy 146.8374 -387.368288) (xy 146.816618 -387.355404)
			(xy 146.77871 -387.324521) (xy 146.745765 -387.288391) (xy 146.718501 -387.247802) (xy 146.697513 -387.203641)
			(xy 146.683258 -387.15687) (xy 146.676047 -387.10851) (xy 146.675602 -387.084062) (xy 146.676148 -387.056777)
			(xy 146.685099 -387.002947) (xy 146.702768 -386.951318) (xy 146.728676 -386.903291) (xy 146.762119 -386.86017)
			(xy 146.781774 -386.841238) (xy 146.789157 -386.833701) (xy 146.797693 -386.814433) (xy 146.798284 -386.8039)
			(xy 146.798284 -386.729224) (xy 146.79776 -386.718674) (xy 146.789222 -386.699378) (xy 146.781774 -386.691886)
			(xy 146.762147 -386.672927) (xy 146.728711 -386.629808) (xy 146.702804 -386.581787) (xy 146.685129 -386.530166)
			(xy 146.676165 -386.476344) (xy 146.675602 -386.449062) (xy 146.675987 -386.425386) (xy 146.68272 -386.378515)
			(xy 146.696084 -386.333089) (xy 146.705574 -386.311394) (xy 146.709892 -386.301996) (xy 146.710654 -386.28193)
			(xy 146.678396 -386.19557) (xy 146.66468 -386.180838) (xy 146.655282 -386.17652) (xy 146.630917 -386.164821)
			(xy 146.586046 -386.134697) (xy 146.546666 -386.097681) (xy 146.513827 -386.054758) (xy 146.4884 -386.007067)
			(xy 146.471061 -385.955879) (xy 146.462273 -385.902553) (xy 146.461734 -385.87553) (xy 144.79383 -385.87553)
			(xy 144.780596 -385.885145) (xy 144.734286 -385.908741) (xy 144.684856 -385.924802) (xy 144.633521 -385.932932)
			(xy 144.581547 -385.932932) (xy 144.530212 -385.924802) (xy 144.480782 -385.908741) (xy 144.434472 -385.885145)
			(xy 144.392424 -385.854595) (xy 144.355673 -385.817844) (xy 144.325123 -385.775796) (xy 144.301527 -385.729486)
			(xy 144.285466 -385.680056) (xy 144.277336 -385.628721) (xy 144.071893 -385.628721) (xy 144.066521 -385.665222)
			(xy 144.050453 -385.718629) (xy 144.026781 -385.769126) (xy 143.996008 -385.815639) (xy 143.958791 -385.857176)
			(xy 143.915923 -385.892851) (xy 143.868317 -385.921905) (xy 143.816988 -385.943717) (xy 143.763031 -385.957823)
			(xy 143.707594 -385.963923) (xy 143.65186 -385.961886) (xy 143.597017 -385.951756) (xy 143.544233 -385.933749)
			(xy 143.494633 -385.908248) (xy 143.449275 -385.875797) (xy 143.409126 -385.837088) (xy 143.37504 -385.792945)
			(xy 143.347744 -385.74431) (xy 143.327821 -385.692219) (xy 143.315695 -385.637782) (xy 143.311624 -385.58216)
			(xy 140.031724 -385.58216) (xy 140.031724 -387.479286) (xy 140.032307 -387.491617) (xy 140.04375 -387.513461)
			(xy 140.053568 -387.520942) (xy 140.076669 -387.537487) (xy 140.118166 -387.576301) (xy 140.153446 -387.62084)
			(xy 140.181729 -387.67012) (xy 140.20239 -387.723051) (xy 140.214971 -387.77846) (xy 140.219193 -387.835123)
			(xy 140.214964 -387.891785) (xy 140.202377 -387.947193) (xy 140.18171 -388.000121) (xy 140.153421 -388.049397)
			(xy 140.118135 -388.093933) (xy 140.076634 -388.132741) (xy 140.053568 -388.149338) (xy 140.043905 -388.156955)
			(xy 140.032504 -388.178714) (xy 140.031724 -388.190994) (xy 140.031724 -388.402068) (xy 140.032084 -388.410765)
			(xy 140.037911 -388.427155) (xy 140.048874 -388.44066) (xy 140.056108 -388.445502) (xy 140.079633 -388.460469)
			(xy 140.122475 -388.49615) (xy 140.159668 -388.537687) (xy 140.190419 -388.584195) (xy 140.214073 -388.634683)
			(xy 140.230128 -388.688077) (xy 140.238241 -388.743238) (xy 140.238238 -388.798993) (xy 140.230121 -388.854154)
			(xy 140.214062 -388.907546) (xy 140.190403 -388.958033) (xy 140.169229 -388.990051) (xy 140.51651 -388.990051)
			(xy 140.524268 -388.936092) (xy 140.539625 -388.883787) (xy 140.562271 -388.834199) (xy 140.591743 -388.788339)
			(xy 140.627442 -388.74714) (xy 140.668641 -388.711442) (xy 140.714501 -388.68197) (xy 140.764088 -388.659325)
			(xy 140.816394 -388.643967) (xy 140.870353 -388.63621) (xy 140.89761 -388.635748) (xy 140.9065 -388.635748)
			(xy 140.91793 -388.636002) (xy 140.93825 -388.627366) (xy 141.004798 -388.552182) (xy 141.011148 -388.530846)
			(xy 141.009624 -388.51967) (xy 141.007741 -388.506032) (xy 141.005711 -388.478573) (xy 141.00556 -388.464806)
			(xy 141.005993 -388.438666) (xy 141.013122 -388.386874) (xy 141.027262 -388.336542) (xy 141.03731 -388.312406)
			(xy 141.042644 -388.29996) (xy 141.040104 -388.273544) (xy 140.974572 -388.180834) (xy 140.950442 -388.169404)
			(xy 140.937234 -388.17042) (xy 140.910564 -388.171436) (xy 140.8833 -388.170978) (xy 140.829328 -388.16321)
			(xy 140.777011 -388.147838) (xy 140.727416 -388.125175) (xy 140.681552 -388.095682) (xy 140.640354 -388.059961)
			(xy 140.604661 -388.018738) (xy 140.575199 -387.972854) (xy 140.55257 -387.923243) (xy 140.537234 -387.870916)
			(xy 140.529503 -387.816938) (xy 140.529056 -387.789674) (xy 140.529056 -386.926074) (xy 140.529499 -386.898815)
			(xy 140.537259 -386.844851) (xy 140.552615 -386.79254) (xy 140.575257 -386.742945) (xy 140.604724 -386.697076)
			(xy 140.640416 -386.655865) (xy 140.681608 -386.62015) (xy 140.727461 -386.590658) (xy 140.777043 -386.567989)
			(xy 140.829346 -386.552603) (xy 140.883305 -386.544814) (xy 140.910564 -386.544312) (xy 140.925679 -386.54447)
			(xy 140.955814 -386.546889) (xy 140.970762 -386.549138) (xy 140.98143 -386.550916) (xy 141.002258 -386.545328)
			(xy 141.07795 -386.484622) (xy 141.087602 -386.465572) (xy 141.08811 -386.45465) (xy 141.090323 -386.425843)
			(xy 141.102314 -386.369327) (xy 141.122685 -386.315263) (xy 141.150971 -386.264887) (xy 141.186526 -386.219349)
			(xy 141.228537 -386.179689) (xy 141.276045 -386.146813) (xy 141.327965 -386.121472) (xy 141.383111 -386.104244)
			(xy 141.440223 -386.095524) (xy 141.46911 -386.094986) (xy 141.49636 -386.095484) (xy 141.550306 -386.103242)
			(xy 141.602599 -386.118598) (xy 141.652174 -386.141239) (xy 141.698023 -386.170705) (xy 141.739211 -386.206396)
			(xy 141.774901 -386.247586) (xy 141.804366 -386.293435) (xy 141.827006 -386.34301) (xy 141.84236 -386.395304)
			(xy 141.850116 -386.44925) (xy 141.850116 -386.489448) (xy 144.37868 -386.489448) (xy 144.37919 -386.463461)
			(xy 144.38732 -386.412126) (xy 144.403381 -386.362696) (xy 144.426977 -386.316386) (xy 144.457527 -386.274338)
			(xy 144.494278 -386.237587) (xy 144.536326 -386.207037) (xy 144.582636 -386.183441) (xy 144.632066 -386.16738)
			(xy 144.683401 -386.15925) (xy 144.735375 -386.15925) (xy 144.78671 -386.16738) (xy 144.83614 -386.183441)
			(xy 144.88245 -386.207037) (xy 144.924498 -386.237587) (xy 144.961249 -386.274338) (xy 144.991799 -386.316386)
			(xy 145.015395 -386.362696) (xy 145.031456 -386.412126) (xy 145.039586 -386.463461) (xy 145.040096 -386.489448)
			(xy 145.039559 -386.516777) (xy 145.030564 -386.570691) (xy 145.012827 -386.622392) (xy 144.98683 -386.670473)
			(xy 144.9705 -386.692394) (xy 144.964912 -386.69976) (xy 144.959324 -386.716524) (xy 144.96288 -386.800598)
			(xy 144.969738 -386.816854) (xy 144.975834 -386.823712) (xy 144.992219 -386.84211) (xy 145.019869 -386.882883)
			(xy 145.04117 -386.927305) (xy 145.055651 -386.974393) (xy 145.062992 -387.023108) (xy 145.063464 -387.04774)
			(xy 145.062954 -387.073727) (xy 145.054824 -387.125062) (xy 145.038763 -387.174492) (xy 145.015167 -387.220802)
			(xy 144.984617 -387.26285) (xy 144.947866 -387.299601) (xy 144.905818 -387.330151) (xy 144.859508 -387.353747)
			(xy 144.810078 -387.369808) (xy 144.758743 -387.377938) (xy 144.706769 -387.377938) (xy 144.655434 -387.369808)
			(xy 144.606004 -387.353747) (xy 144.559694 -387.330151) (xy 144.517646 -387.299601) (xy 144.480895 -387.26285)
			(xy 144.450345 -387.220802) (xy 144.426749 -387.174492) (xy 144.410688 -387.125062) (xy 144.402558 -387.073727)
			(xy 144.402048 -387.04774) (xy 144.402643 -387.020413) (xy 144.411622 -386.966503) (xy 144.429343 -386.914802)
			(xy 144.455322 -386.866718) (xy 144.471644 -386.844794) (xy 144.477232 -386.837428) (xy 144.48282 -386.820664)
			(xy 144.479264 -386.73659) (xy 144.472406 -386.720334) (xy 144.46631 -386.713476) (xy 144.449974 -386.695037)
			(xy 144.422315 -386.654275) (xy 144.401004 -386.609864) (xy 144.386512 -386.562785) (xy 144.379158 -386.514077)
			(xy 144.37868 -386.489448) (xy 141.850116 -386.489448) (xy 141.850116 -386.50375) (xy 141.84236 -386.557696)
			(xy 141.827006 -386.60999) (xy 141.804366 -386.659565) (xy 141.774901 -386.705414) (xy 141.739211 -386.746604)
			(xy 141.698023 -386.782295) (xy 141.652174 -386.811761) (xy 141.602599 -386.834402) (xy 141.550306 -386.849758)
			(xy 141.49636 -386.857516) (xy 141.46911 -386.858002) (xy 141.446604 -386.857651) (xy 141.401909 -386.852304)
			(xy 141.379956 -386.847334) (xy 141.368471 -386.84518) (xy 141.345706 -386.850349) (xy 141.336268 -386.85724)
			(xy 141.311122 -386.87756) (xy 141.302325 -386.885294) (xy 141.292409 -386.90649) (xy 141.292072 -386.9182)
			(xy 141.292072 -386.926074) (xy 141.292072 -387.789674) (xy 141.291662 -387.815857) (xy 141.28454 -387.867736)
			(xy 141.270385 -387.918152) (xy 141.260322 -387.942328) (xy 141.254988 -387.95452) (xy 141.257782 -387.980936)
			(xy 141.323314 -388.073646) (xy 141.34719 -388.085076) (xy 141.360652 -388.084314) (xy 141.387068 -388.083298)
			(xy 141.414839 -388.083787) (xy 141.469792 -388.091857) (xy 141.522997 -388.107801) (xy 141.573331 -388.131284)
			(xy 141.619732 -388.16181) (xy 141.661223 -388.198735) (xy 141.696927 -388.241281) (xy 141.711934 -388.264654)
			(xy 141.71676 -388.272528) (xy 141.730984 -388.283704) (xy 141.812264 -388.309358) (xy 141.830298 -388.308342)
			(xy 141.83868 -388.304786) (xy 141.870686 -388.29156) (xy 141.937379 -388.272911) (xy 142.005985 -388.263479)
			(xy 142.04061 -388.262876) (xy 142.07257 -388.26341) (xy 142.135985 -388.271423) (xy 142.197896 -388.28732)
			(xy 142.224046 -388.297674) (xy 143.436592 -388.297674) (xy 143.440663 -388.242052) (xy 143.452789 -388.187615)
			(xy 143.472712 -388.135524) (xy 143.500008 -388.086889) (xy 143.534094 -388.042746) (xy 143.574243 -388.004037)
			(xy 143.619601 -387.971586) (xy 143.669201 -387.946085) (xy 143.721985 -387.928078) (xy 143.776828 -387.917948)
			(xy 143.832562 -387.915911) (xy 143.887999 -387.922011) (xy 143.941956 -387.936117) (xy 143.993285 -387.957929)
			(xy 144.040891 -387.986983) (xy 144.083759 -388.022658) (xy 144.120976 -388.064195) (xy 144.151749 -388.110708)
			(xy 144.175421 -388.161205) (xy 144.191489 -388.214612) (xy 144.199609 -388.269788) (xy 144.200118 -388.297674)
			(xy 144.199671 -388.322137) (xy 144.402558 -388.322137) (xy 144.402558 -388.270163) (xy 144.410688 -388.218828)
			(xy 144.426749 -388.169398) (xy 144.450345 -388.123088) (xy 144.480895 -388.08104) (xy 144.517646 -388.044289)
			(xy 144.559694 -388.013739) (xy 144.606004 -387.990143) (xy 144.655434 -387.974082) (xy 144.706769 -387.965952)
			(xy 144.758743 -387.965952) (xy 144.810078 -387.974082) (xy 144.859508 -387.990143) (xy 144.905818 -388.013739)
			(xy 144.947866 -388.044289) (xy 144.984617 -388.08104) (xy 145.015167 -388.123088) (xy 145.038763 -388.169398)
			(xy 145.054824 -388.218828) (xy 145.062954 -388.270163) (xy 145.063464 -388.29615) (xy 145.062954 -388.322137)
			(xy 145.054824 -388.373472) (xy 145.038763 -388.422902) (xy 145.015167 -388.469212) (xy 144.984617 -388.51126)
			(xy 144.947866 -388.548011) (xy 144.905818 -388.578561) (xy 144.859508 -388.602157) (xy 144.810078 -388.618218)
			(xy 144.758743 -388.626348) (xy 144.706769 -388.626348) (xy 144.655434 -388.618218) (xy 144.606004 -388.602157)
			(xy 144.559694 -388.578561) (xy 144.517646 -388.548011) (xy 144.480895 -388.51126) (xy 144.450345 -388.469212)
			(xy 144.426749 -388.422902) (xy 144.410688 -388.373472) (xy 144.402558 -388.322137) (xy 144.199671 -388.322137)
			(xy 144.199609 -388.32556) (xy 144.191489 -388.380736) (xy 144.175421 -388.434143) (xy 144.151749 -388.48464)
			(xy 144.120976 -388.531153) (xy 144.083759 -388.57269) (xy 144.040891 -388.608365) (xy 143.993285 -388.637419)
			(xy 143.941956 -388.659231) (xy 143.887999 -388.673337) (xy 143.832562 -388.679437) (xy 143.776828 -388.6774)
			(xy 143.721985 -388.66727) (xy 143.669201 -388.649263) (xy 143.619601 -388.623762) (xy 143.574243 -388.591311)
			(xy 143.534094 -388.552602) (xy 143.500008 -388.508459) (xy 143.472712 -388.459824) (xy 143.452789 -388.407733)
			(xy 143.440663 -388.353296) (xy 143.436592 -388.297674) (xy 142.224046 -388.297674) (xy 142.257326 -388.310851)
			(xy 142.313338 -388.341645) (xy 142.36505 -388.379217) (xy 142.411644 -388.422973) (xy 142.452388 -388.472224)
			(xy 142.486637 -388.526193) (xy 142.513852 -388.584029) (xy 142.533604 -388.64482) (xy 142.545581 -388.707607)
			(xy 142.549595 -388.7714) (xy 142.545581 -388.835193) (xy 142.533604 -388.89798) (xy 142.513852 -388.958771)
			(xy 142.486637 -389.016607) (xy 142.452388 -389.070576) (xy 142.411644 -389.119827) (xy 142.36505 -389.163583)
			(xy 142.313338 -389.201155) (xy 142.257326 -389.231949) (xy 142.197896 -389.25548) (xy 142.135985 -389.271377)
			(xy 142.07257 -389.27939) (xy 142.04061 -389.279892) (xy 142.007911 -389.279356) (xy 141.943055 -389.270962)
			(xy 141.87981 -389.254322) (xy 141.81922 -389.229713) (xy 141.762284 -389.19754) (xy 141.709942 -389.158334)
			(xy 141.663058 -389.112742) (xy 141.622404 -389.061515) (xy 141.588653 -389.005501) (xy 141.562361 -388.945622)
			(xy 141.552676 -388.914386) (xy 141.550136 -388.905496) (xy 141.539214 -388.891018) (xy 141.467586 -388.845044)
			(xy 141.45006 -388.841234) (xy 141.440916 -388.842504) (xy 141.427525 -388.844286) (xy 141.400576 -388.846193)
			(xy 141.387068 -388.846314) (xy 141.378178 -388.846314) (xy 141.366748 -388.84606) (xy 141.346428 -388.854696)
			(xy 141.27988 -388.92988) (xy 141.27353 -388.951216) (xy 141.275054 -388.962392) (xy 141.276933 -388.976031)
			(xy 141.278966 -389.003489) (xy 141.279118 -389.017256) (xy 141.278692 -389.044513) (xy 141.27094 -389.098473)
			(xy 141.255587 -389.15078) (xy 141.232947 -389.200369) (xy 141.203479 -389.246232) (xy 141.167784 -389.287434)
			(xy 141.126588 -389.323137) (xy 141.080731 -389.352613) (xy 141.031145 -389.375263) (xy 140.978841 -389.390625)
			(xy 140.924883 -389.398387) (xy 140.870369 -389.398391) (xy 140.81641 -389.390636) (xy 140.764103 -389.375281)
			(xy 140.714515 -389.352638) (xy 140.668653 -389.323168) (xy 140.627453 -389.287471) (xy 140.591752 -389.246274)
			(xy 140.562278 -389.200415) (xy 140.539631 -389.150829) (xy 140.524271 -389.098523) (xy 140.516512 -389.044565)
			(xy 140.51651 -388.990051) (xy 140.169229 -388.990051) (xy 140.159648 -389.004538) (xy 140.122452 -389.046072)
			(xy 140.079607 -389.08175) (xy 140.056108 -389.096758) (xy 140.048851 -389.101577) (xy 140.037863 -389.115079)
			(xy 140.032047 -389.131487) (xy 140.031724 -389.140192) (xy 140.031724 -389.591042) (xy 140.031294 -389.601109)
			(xy 140.023571 -389.619705) (xy 140.016738 -389.62711) (xy 140.002514 -389.641334) (xy 139.996331 -389.647984)
			(xy 139.98873 -389.664459) (xy 139.987391 -389.682554) (xy 139.98956 -389.691372) (xy 140.018008 -389.790178)
			(xy 140.038074 -389.809228) (xy 140.051536 -389.812276) (xy 140.081788 -389.819657) (xy 140.140356 -389.840812)
			(xy 140.195902 -389.868961) (xy 140.247594 -389.903684) (xy 140.294659 -389.944459) (xy 140.336391 -389.990678)
			(xy 140.372167 -390.041647) (xy 140.40145 -390.096604) (xy 140.423802 -390.154725) (xy 140.438888 -390.215142)
			(xy 140.446483 -390.276948) (xy 140.447014 -390.308084) (xy 140.44652 -390.340247) (xy 140.438405 -390.40406)
			(xy 140.422302 -390.466339) (xy 140.398468 -390.526088) (xy 140.367285 -390.582351) (xy 140.329252 -390.63423)
			(xy 140.284976 -390.680894) (xy 140.235165 -390.721599) (xy 140.180616 -390.755692) (xy 140.151612 -390.769602)
			(xy 140.142249 -390.774603) (xy 140.128322 -390.79059) (xy 140.121992 -390.810825) (xy 140.122656 -390.821418)
			(xy 140.124112 -390.835533) (xy 140.125639 -390.86387) (xy 140.125704 -390.87806) (xy 140.125161 -390.911867)
			(xy 140.116235 -390.97889) (xy 140.107924 -391.011664) (xy 140.105384 -391.021062) (xy 140.107416 -391.040112)
			(xy 140.149326 -391.118852) (xy 140.164058 -391.131298) (xy 140.173202 -391.134346) (xy 140.202983 -391.144991)
			(xy 140.259867 -391.172634) (xy 140.312887 -391.207113) (xy 140.361226 -391.247897) (xy 140.404139 -391.294356)
			(xy 140.440964 -391.345774) (xy 140.471133 -391.40136) (xy 140.494183 -391.460255) (xy 140.509756 -391.521553)
			(xy 140.517614 -391.584308) (xy 140.518134 -391.61593) (xy 140.517653 -391.646624) (xy 140.510229 -391.707563)
			(xy 140.495528 -391.767167) (xy 140.473764 -391.824569) (xy 140.445253 -391.878936) (xy 140.428218 -391.904474)
			(xy 140.42275 -391.913225) (xy 140.418631 -391.933425) (xy 140.42277 -391.953621) (xy 140.428218 -391.962386)
			(xy 140.445272 -391.987913) (xy 140.4738 -392.042276) (xy 140.495571 -392.09968) (xy 140.510266 -392.159288)
			(xy 140.517671 -392.220233) (xy 140.518134 -392.25093) (xy 140.517668 -392.28166) (xy 140.510257 -392.342673)
			(xy 140.495546 -392.402347) (xy 140.47375 -392.459813) (xy 140.445186 -392.514233) (xy 140.410271 -392.564814)
			(xy 140.369515 -392.610818) (xy 140.323511 -392.651574) (xy 140.27293 -392.686488) (xy 140.218509 -392.715051)
			(xy 140.161043 -392.736847) (xy 140.101369 -392.751558) (xy 140.040356 -392.758968) (xy 140.009626 -392.759438)
			(xy 139.988544 -392.75893) (xy 139.977622 -392.758422) (xy 139.958064 -392.766042) (xy 139.889738 -392.834368)
			(xy 139.882118 -392.853926) (xy 139.882626 -392.864848) (xy 139.883134 -392.88593) (xy 139.882653 -392.916624)
			(xy 139.875229 -392.977563) (xy 139.860528 -393.037167) (xy 139.838764 -393.094569) (xy 139.810253 -393.148936)
			(xy 139.793218 -393.174474) (xy 139.78775 -393.183225) (xy 139.783631 -393.203425) (xy 139.78777 -393.223621)
			(xy 139.793218 -393.232386) (xy 139.810272 -393.257913) (xy 139.8388 -393.312276) (xy 139.860571 -393.36968)
			(xy 139.875266 -393.429288) (xy 139.882671 -393.490233) (xy 139.883134 -393.52093) (xy 139.882668 -393.55166)
			(xy 139.875257 -393.612673) (xy 139.860546 -393.672347) (xy 139.83875 -393.729813) (xy 139.810186 -393.784233)
			(xy 139.775271 -393.834814) (xy 139.734515 -393.880818) (xy 139.688511 -393.921574) (xy 139.63793 -393.956488)
			(xy 139.583509 -393.985051) (xy 139.526043 -394.006847) (xy 139.466369 -394.021558) (xy 139.405356 -394.028968)
			(xy 139.374626 -394.029438) (xy 139.337041 -394.028745) (xy 139.262692 -394.017657) (xy 139.226544 -394.00734)
			(xy 139.215114 -394.003784) (xy 139.191238 -394.008102) (xy 139.116054 -394.063728) (xy 139.106823 -394.071337)
			(xy 139.096074 -394.092675) (xy 139.09548 -394.104622) (xy 139.09548 -394.703046) (xy 139.095911 -394.713113)
			(xy 139.103635 -394.731707) (xy 139.110466 -394.739114)
		)
		(stroke
			(width 0)
			(type solid)
		)
		(fill yes)
		(layer "In15.Cu")
		(net "P0V9_CPU1_RT2_2A_2D")
	)
	(gr_poly
		(pts
			(xy 385.536186 -406.654) (xy 385.540799 -406.653902) (xy 385.549874 -406.652246) (xy 385.55422 -406.650698)
			(xy 385.624347 -406.624275) (xy 385.764937 -406.572331) (xy 385.835398 -406.546812) (xy 390.228074 -404.958042)
			(xy 390.23325 -404.955992) (xy 390.242608 -404.949967) (xy 390.246616 -404.946104) (xy 391.233914 -403.958806)
			(xy 391.240771 -403.951412) (xy 391.248521 -403.932813) (xy 391.2489 -403.922738) (xy 391.2489 -401.655788)
			(xy 391.248273 -401.643654) (xy 391.237259 -401.622036) (xy 391.227818 -401.614386) (xy 391.150856 -401.559268)
			(xy 391.126726 -401.555458) (xy 391.115042 -401.559522) (xy 391.085488 -401.568809) (xy 391.024349 -401.578769)
			(xy 390.993376 -401.579334) (xy 390.966124 -401.578847) (xy 390.912175 -401.571087) (xy 390.85988 -401.555728)
			(xy 390.810302 -401.533084) (xy 390.764452 -401.503615) (xy 390.723262 -401.467921) (xy 390.68757 -401.426729)
			(xy 390.658104 -401.380877) (xy 390.635463 -401.331298) (xy 390.620108 -401.279001) (xy 390.612352 -401.225052)
			(xy 390.612352 -401.170548) (xy 390.620108 -401.116599) (xy 390.635463 -401.064302) (xy 390.658104 -401.014723)
			(xy 390.68757 -400.968871) (xy 390.723262 -400.927679) (xy 390.764452 -400.891985) (xy 390.810302 -400.862516)
			(xy 390.85988 -400.839872) (xy 390.912175 -400.824513) (xy 390.966124 -400.816753) (xy 390.993376 -400.816318)
			(xy 391.024348 -400.816899) (xy 391.085487 -400.826851) (xy 391.115042 -400.83613) (xy 391.126726 -400.840194)
			(xy 391.150856 -400.836384) (xy 391.227818 -400.781266) (xy 391.237235 -400.773601) (xy 391.248224 -400.751989)
			(xy 391.2489 -400.739864) (xy 391.2489 -399.010378) (xy 391.248466 -399.000668) (xy 391.241238 -398.982642)
			(xy 391.227828 -398.968595) (xy 391.219182 -398.96415) (xy 391.19302 -398.952212) (xy 391.184758 -398.948751)
			(xy 391.166917 -398.947271) (xy 391.14967 -398.952065) (xy 391.14222 -398.957038) (xy 391.127742 -398.966944)
			(xy 391.120179 -398.972205) (xy 391.109122 -398.986924) (xy 391.106152 -398.995646) (xy 391.097516 -399.025618)
			(xy 391.095322 -399.034568) (xy 391.096766 -399.052924) (xy 391.10031 -399.061432) (xy 391.110086 -399.083411)
			(xy 391.123889 -399.129489) (xy 391.13087 -399.177081) (xy 391.131298 -399.201132) (xy 391.130788 -399.227119)
			(xy 391.122658 -399.278454) (xy 391.106597 -399.327884) (xy 391.083001 -399.374194) (xy 391.052451 -399.416242)
			(xy 391.0157 -399.452993) (xy 390.973652 -399.483543) (xy 390.927342 -399.507139) (xy 390.877912 -399.5232)
			(xy 390.826577 -399.53133) (xy 390.774603 -399.53133) (xy 390.723268 -399.5232) (xy 390.673838 -399.507139)
			(xy 390.627528 -399.483543) (xy 390.58548 -399.452993) (xy 390.548729 -399.416242) (xy 390.518179 -399.374194)
			(xy 390.494583 -399.327884) (xy 390.478522 -399.278454) (xy 390.470392 -399.227119) (xy 390.469882 -399.201132)
			(xy 390.47044 -399.173543) (xy 390.479606 -399.119132) (xy 390.497672 -399.066996) (xy 390.524138 -399.01858)
			(xy 390.55827 -398.975226) (xy 390.599122 -398.938136) (xy 390.622028 -398.922748) (xy 390.629594 -398.917489)
			(xy 390.640655 -398.902771) (xy 390.643618 -398.894046) (xy 390.652254 -398.864074) (xy 390.654448 -398.855124)
			(xy 390.653 -398.836769) (xy 390.64946 -398.82826) (xy 390.639683 -398.806282) (xy 390.625878 -398.760203)
			(xy 390.618897 -398.712611) (xy 390.618472 -398.68856) (xy 390.618887 -398.664787) (xy 390.625701 -398.617731)
			(xy 390.639184 -398.572137) (xy 390.659056 -398.528942) (xy 390.68491 -398.489039) (xy 390.70026 -398.470882)
			(xy 390.705937 -398.463759) (xy 390.712313 -398.446709) (xy 390.712706 -398.437608) (xy 390.712706 -398.406112)
			(xy 390.712328 -398.397009) (xy 390.705943 -398.37996) (xy 390.70026 -398.372838) (xy 390.68491 -398.354679)
			(xy 390.659042 -398.314784) (xy 390.639163 -398.271591) (xy 390.625684 -398.225993) (xy 390.618884 -398.178934)
			(xy 390.618472 -398.15516) (xy 390.618905 -398.130749) (xy 390.626078 -398.082458) (xy 390.640276 -398.035747)
			(xy 390.661191 -397.991633) (xy 390.688368 -397.951075) (xy 390.721215 -397.914956) (xy 390.759017 -397.884061)
			(xy 390.779762 -397.871188) (xy 390.791192 -397.86433) (xy 390.8044 -397.841216) (xy 390.8044 -397.726916)
			(xy 390.791446 -397.703802) (xy 390.779762 -397.69669) (xy 390.759054 -397.683814) (xy 390.721319 -397.652929)
			(xy 390.688533 -397.616834) (xy 390.661407 -397.576312) (xy 390.640531 -397.532244) (xy 390.626358 -397.485587)
			(xy 390.619196 -397.437353) (xy 390.618726 -397.412972) (xy 390.619283 -397.385352) (xy 390.628462 -397.330879)
			(xy 390.646559 -397.278687) (xy 390.673073 -397.230226) (xy 390.707267 -397.18684) (xy 390.748191 -397.149736)
			(xy 390.771126 -397.134334) (xy 390.782556 -397.127222) (xy 390.795002 -397.1036) (xy 390.791446 -396.9893)
			(xy 390.77773 -396.966694) (xy 390.765792 -396.96009) (xy 390.745469 -396.948291) (xy 390.708081 -396.919824)
			(xy 390.675112 -396.886338) (xy 390.64723 -396.848512) (xy 390.635744 -396.82801) (xy 390.628886 -396.815564)
			(xy 390.60501 -396.80134) (xy 389.222488 -396.80134) (xy 389.21306 -396.80172) (xy 389.195481 -396.808543)
			(xy 389.181559 -396.82126) (xy 389.177022 -396.829534) (xy 389.130286 -396.924276) (xy 389.13308 -396.953232)
			(xy 389.14197 -396.964662) (xy 389.159151 -396.988223) (xy 389.185486 -397.040242) (xy 389.194294 -397.06804)
			(xy 389.195818 -397.073882) (xy 389.516112 -397.627602) (xy 389.520176 -397.63192) (xy 389.536394 -397.649618)
			(xy 389.563829 -397.689006) (xy 389.584978 -397.732097) (xy 389.599352 -397.777896) (xy 389.60662 -397.825343)
			(xy 389.607044 -397.849344) (xy 389.606579 -397.874145) (xy 389.598809 -397.923136) (xy 389.583467 -397.970306)
			(xy 389.560932 -398.014495) (xy 389.531758 -398.054611) (xy 389.496666 -398.089668) (xy 389.45652 -398.1188)
			(xy 389.412308 -398.14129) (xy 389.365122 -398.156584) (xy 389.316124 -398.164304) (xy 389.291322 -398.164812)
			(xy 389.265927 -398.164306) (xy 389.215792 -398.156178) (xy 389.167605 -398.140129) (xy 389.122609 -398.116573)
			(xy 389.081964 -398.086117) (xy 389.046719 -398.049547) (xy 389.017784 -398.007806) (xy 388.995904 -397.961971)
			(xy 388.9883 -397.937736) (xy 388.986776 -397.931894) (xy 388.666482 -397.378174) (xy 388.662418 -397.373856)
			(xy 388.646228 -397.356147) (xy 388.618852 -397.316745) (xy 388.597761 -397.27365) (xy 388.583443 -397.227856)
			(xy 388.576229 -397.180422) (xy 388.575804 -397.156432) (xy 388.57589 -397.144384) (xy 388.577672 -397.120355)
			(xy 388.57936 -397.108426) (xy 388.58063 -397.099536) (xy 388.577582 -397.082518) (xy 388.535418 -397.011652)
			(xy 388.52221 -397.000476) (xy 388.513828 -396.997428) (xy 388.490696 -396.988466) (xy 388.447462 -396.964148)
			(xy 388.408721 -396.933168) (xy 388.375491 -396.896339) (xy 388.348643 -396.854628) (xy 388.338314 -396.832074)
			(xy 388.332218 -396.81785) (xy 388.307072 -396.80134) (xy 388.022592 -396.80134) (xy 388.013163 -396.801719)
			(xy 387.995584 -396.808541) (xy 387.98166 -396.821258) (xy 387.977126 -396.829534) (xy 387.93039 -396.924276)
			(xy 387.933184 -396.953232) (xy 387.942074 -396.964662) (xy 387.959396 -396.988373) (xy 387.985863 -397.040784)
			(xy 387.994652 -397.068802) (xy 387.996176 -397.074644) (xy 388.315962 -397.627602) (xy 388.320026 -397.63192)
			(xy 388.336215 -397.649629) (xy 388.363591 -397.689032) (xy 388.384682 -397.732127) (xy 388.399001 -397.77792)
			(xy 388.406217 -397.825354) (xy 388.40664 -397.849344) (xy 388.40615 -397.874131) (xy 388.398389 -397.923092)
			(xy 388.383064 -397.970237) (xy 388.360552 -398.014404) (xy 388.331409 -398.054507) (xy 388.296352 -398.089556)
			(xy 388.256243 -398.11869) (xy 388.212071 -398.141191) (xy 388.164922 -398.156506) (xy 388.115959 -398.164256)
			(xy 388.091172 -398.164812) (xy 388.06578 -398.164302) (xy 388.01565 -398.156168) (xy 387.967469 -398.140114)
			(xy 387.92248 -398.116555) (xy 387.881842 -398.086097) (xy 387.846603 -398.049527) (xy 387.817673 -398.007788)
			(xy 387.795798 -397.961955) (xy 387.78815 -397.937736) (xy 387.786626 -397.931894) (xy 387.466078 -397.377412)
			(xy 387.462014 -397.373094) (xy 387.445937 -397.355415) (xy 387.418754 -397.316116) (xy 387.397799 -397.273171)
			(xy 387.383551 -397.22756) (xy 387.376335 -397.180324) (xy 387.375908 -397.156432) (xy 387.375994 -397.144384)
			(xy 387.377777 -397.120355) (xy 387.379464 -397.108426) (xy 387.380734 -397.099536) (xy 387.377686 -397.082518)
			(xy 387.335522 -397.011652) (xy 387.322314 -397.000476) (xy 387.313932 -396.997428) (xy 387.2908 -396.988466)
			(xy 387.247565 -396.964149) (xy 387.208824 -396.933169) (xy 387.175593 -396.89634) (xy 387.148745 -396.854629)
			(xy 387.138418 -396.832074) (xy 387.132322 -396.81785) (xy 387.107176 -396.80134) (xy 386.822442 -396.80134)
			(xy 386.813009 -396.801711) (xy 386.795415 -396.808522) (xy 386.781476 -396.821237) (xy 386.776976 -396.829534)
			(xy 386.73024 -396.924276) (xy 386.733034 -396.953232) (xy 386.741924 -396.964662) (xy 386.759103 -396.988224)
			(xy 386.785433 -397.040245) (xy 386.794248 -397.06804) (xy 386.795772 -397.073882) (xy 387.116066 -397.627602)
			(xy 387.12013 -397.63192) (xy 387.136319 -397.649629) (xy 387.163695 -397.689032) (xy 387.184785 -397.732128)
			(xy 387.199104 -397.77792) (xy 387.20632 -397.825354) (xy 387.206744 -397.849344) (xy 387.206254 -397.874131)
			(xy 387.198493 -397.923093) (xy 387.183168 -397.970238) (xy 387.160657 -398.014405) (xy 387.131513 -398.054508)
			(xy 387.096456 -398.089558) (xy 387.056347 -398.118692) (xy 387.012175 -398.141194) (xy 386.965026 -398.156509)
			(xy 386.916063 -398.16426) (xy 386.891276 -398.164812) (xy 386.865883 -398.164302) (xy 386.815754 -398.156169)
			(xy 386.767572 -398.140115) (xy 386.722582 -398.116556) (xy 386.681943 -398.086099) (xy 386.646705 -398.049529)
			(xy 386.617774 -398.007789) (xy 386.595899 -397.961957) (xy 386.588254 -397.937736) (xy 386.58673 -397.931894)
			(xy 386.266436 -397.378174) (xy 386.262372 -397.373856) (xy 386.246158 -397.356157) (xy 386.21873 -397.316766)
			(xy 386.197588 -397.273675) (xy 386.18322 -397.227877) (xy 386.175957 -397.180431) (xy 386.175504 -397.156432)
			(xy 386.175662 -397.14438) (xy 386.177571 -397.120352) (xy 386.179314 -397.108426) (xy 386.180584 -397.099536)
			(xy 386.177536 -397.082518) (xy 386.135372 -397.011652) (xy 386.122164 -397.000476) (xy 386.113782 -396.997428)
			(xy 386.092042 -396.989023) (xy 386.051197 -396.96657) (xy 386.014239 -396.93817) (xy 385.982026 -396.904484)
			(xy 385.955307 -396.866294) (xy 385.934703 -396.824486) (xy 385.920691 -396.780033) (xy 385.913599 -396.733966)
			(xy 385.913122 -396.710662) (xy 385.913215 -396.700406) (xy 385.914616 -396.679942) (xy 385.915916 -396.669768)
			(xy 385.91744 -396.658084) (xy 385.90982 -396.635478) (xy 385.475226 -396.200884) (xy 385.466224 -396.192844)
			(xy 385.443291 -396.185423) (xy 385.431284 -396.18666) (xy 385.338066 -396.201392) (xy 385.318508 -396.215362)
			(xy 385.31292 -396.226284) (xy 385.302285 -396.246297) (xy 385.276359 -396.28347) (xy 385.245598 -396.316752)
			(xy 385.228338 -396.33144) (xy 385.219448 -396.338552) (xy 385.21005 -396.35811) (xy 385.207256 -396.457424)
			(xy 385.215892 -396.47749) (xy 385.224274 -396.48511) (xy 385.242697 -396.502597) (xy 385.274042 -396.542564)
			(xy 385.298341 -396.587167) (xy 385.314924 -396.635175) (xy 385.323335 -396.685266) (xy 385.323842 -396.710662)
			(xy 385.32377 -396.72002) (xy 385.322624 -396.738702) (xy 385.321556 -396.748) (xy 385.32054 -396.75689)
			(xy 385.32435 -396.773654) (xy 385.368292 -396.843504) (xy 385.382008 -396.853918) (xy 385.39039 -396.856712)
			(xy 385.414486 -396.865195) (xy 385.459774 -396.888825) (xy 385.500667 -396.919437) (xy 385.536099 -396.956233)
			(xy 385.565145 -396.998252) (xy 385.587049 -397.0444) (xy 385.594606 -397.068802) (xy 385.59613 -397.074644)
			(xy 385.915916 -397.627602) (xy 385.91998 -397.63192) (xy 385.936198 -397.649618) (xy 385.963632 -397.689006)
			(xy 385.984781 -397.732097) (xy 385.999155 -397.777896) (xy 386.006422 -397.825343) (xy 386.006848 -397.849344)
			(xy 386.006383 -397.874145) (xy 385.998613 -397.923136) (xy 385.983271 -397.970307) (xy 385.960736 -398.014495)
			(xy 385.931563 -398.054613) (xy 385.89647 -398.089669) (xy 385.856324 -398.118802) (xy 385.812113 -398.141293)
			(xy 385.764926 -398.156587) (xy 385.715928 -398.164308) (xy 385.691126 -398.164812) (xy 385.665731 -398.164306)
			(xy 385.615596 -398.156179) (xy 385.567408 -398.140131) (xy 385.522411 -398.116575) (xy 385.481766 -398.086118)
			(xy 385.446521 -398.049548) (xy 385.417585 -398.007807) (xy 385.395704 -397.961972) (xy 385.388104 -397.937736)
			(xy 385.38658 -397.931894) (xy 385.066032 -397.377412) (xy 385.061968 -397.373094) (xy 385.045862 -397.355426)
			(xy 385.01862 -397.316142) (xy 384.997608 -397.273201) (xy 384.983305 -397.227585) (xy 384.976037 -397.180334)
			(xy 384.975608 -397.156432) (xy 384.975766 -397.14438) (xy 384.977675 -397.120352) (xy 384.979418 -397.108426)
			(xy 384.980688 -397.099536) (xy 384.97764 -397.082518) (xy 384.935476 -397.011652) (xy 384.922268 -397.000476)
			(xy 384.913886 -396.997428) (xy 384.892145 -396.989023) (xy 384.8513 -396.96657) (xy 384.814342 -396.938171)
			(xy 384.782129 -396.904485) (xy 384.755409 -396.866294) (xy 384.734805 -396.824487) (xy 384.720793 -396.780033)
			(xy 384.7137 -396.733967) (xy 384.713226 -396.710662) (xy 384.713726 -396.685264) (xy 384.722126 -396.635168)
			(xy 384.738705 -396.587155) (xy 384.763005 -396.542549) (xy 384.794354 -396.502582) (xy 384.812794 -396.48511)
			(xy 384.821176 -396.47749) (xy 384.829812 -396.457424) (xy 384.827018 -396.35811) (xy 384.81762 -396.338552)
			(xy 384.80873 -396.33144) (xy 384.790167 -396.315638) (xy 384.757438 -396.279513) (xy 384.730363 -396.238976)
			(xy 384.709528 -396.194906) (xy 384.695384 -396.148256) (xy 384.688238 -396.100036) (xy 384.687826 -396.075662)
			(xy 384.688265 -396.051546) (xy 384.695271 -396.003826) (xy 384.709129 -395.957628) (xy 384.729546 -395.913931)
			(xy 384.742436 -395.893544) (xy 384.748278 -395.884654) (xy 384.751834 -395.864588) (xy 384.730752 -395.772386)
			(xy 384.71856 -395.755622) (xy 384.70967 -395.750288) (xy 384.688867 -395.737433) (xy 384.650948 -395.706556)
			(xy 384.617996 -395.670426) (xy 384.59073 -395.629832) (xy 384.569747 -395.585662) (xy 384.555505 -395.538882)
			(xy 384.548316 -395.490512) (xy 384.547872 -395.466062) (xy 384.54864 -395.434132) (xy 384.560919 -395.371462)
			(xy 384.572256 -395.341602) (xy 384.577844 -395.327378) (xy 384.572002 -395.29766) (xy 384.535934 -395.261592)
			(xy 384.528532 -395.254757) (xy 384.509933 -395.247048) (xy 384.499866 -395.246606) (xy 383.025396 -395.246606)
			(xy 383.01398 -395.24707) (xy 382.993361 -395.25686) (xy 382.985772 -395.265402) (xy 382.928876 -395.336014)
			(xy 382.923542 -395.358366) (xy 382.926082 -395.369542) (xy 382.93088 -395.393382) (xy 382.935967 -395.441746)
			(xy 382.936242 -395.466062) (xy 382.935638 -395.499382) (xy 382.925968 -395.565316) (xy 382.906841 -395.629152)
			(xy 382.893316 -395.65961) (xy 382.889057 -395.67008) (xy 382.889132 -395.692655) (xy 382.898879 -395.713016)
			(xy 382.907286 -395.72057) (xy 382.929535 -395.739243) (xy 382.969603 -395.781297) (xy 383.004028 -395.828082)
			(xy 383.032257 -395.878847) (xy 383.053837 -395.932775) (xy 383.068421 -395.989001) (xy 383.075775 -396.046619)
			(xy 383.076196 -396.075662) (xy 383.075745 -396.104666) (xy 383.068414 -396.162209) (xy 383.053878 -396.218366)
			(xy 383.032368 -396.272238) (xy 383.004229 -396.322964) (xy 382.969911 -396.369731) (xy 382.929963 -396.411792)
			(xy 382.907794 -396.4305) (xy 382.900682 -396.436088) (xy 382.891538 -396.451328) (xy 382.876298 -396.534132)
			(xy 382.879092 -396.551404) (xy 382.883664 -396.559532) (xy 382.896259 -396.58271) (xy 382.914148 -396.63233)
			(xy 382.923231 -396.684289) (xy 382.923796 -396.710662) (xy 383.513076 -396.710662) (xy 383.513598 -396.685407)
			(xy 383.521911 -396.635585) (xy 383.538312 -396.587811) (xy 383.562353 -396.543388) (xy 383.593377 -396.503528)
			(xy 383.630539 -396.469318) (xy 383.672825 -396.441692) (xy 383.719081 -396.421402) (xy 383.768046 -396.409002)
			(xy 383.818384 -396.404831) (xy 383.868722 -396.409002) (xy 383.917687 -396.421402) (xy 383.963943 -396.441692)
			(xy 384.006229 -396.469318) (xy 384.043391 -396.503528) (xy 384.074415 -396.543388) (xy 384.098456 -396.587811)
			(xy 384.114857 -396.635585) (xy 384.12317 -396.685407) (xy 384.123692 -396.710662) (xy 384.123624 -396.720021)
			(xy 384.12248 -396.738703) (xy 384.121406 -396.748) (xy 384.12039 -396.75689) (xy 384.1242 -396.773654)
			(xy 384.168142 -396.843504) (xy 384.181858 -396.853918) (xy 384.19024 -396.856712) (xy 384.214268 -396.86518)
			(xy 384.259441 -396.888733) (xy 384.300246 -396.919232) (xy 384.335625 -396.955887) (xy 384.36466 -396.997746)
			(xy 384.386599 -397.043724) (xy 384.394202 -397.06804) (xy 384.395726 -397.073882) (xy 384.71602 -397.627602)
			(xy 384.720084 -397.63192) (xy 384.736273 -397.649641) (xy 384.7637 -397.689028) (xy 384.784846 -397.732114)
			(xy 384.799223 -397.777906) (xy 384.8065 -397.825346) (xy 384.806952 -397.849344) (xy 384.806547 -397.87415)
			(xy 384.798775 -397.92315) (xy 384.783431 -397.970331) (xy 384.760891 -398.014528) (xy 384.731713 -398.054653)
			(xy 384.696614 -398.089717) (xy 384.65646 -398.118856) (xy 384.61224 -398.141351) (xy 384.565045 -398.156648)
			(xy 384.516037 -398.164371) (xy 384.49123 -398.164812) (xy 384.465837 -398.164285) (xy 384.415704 -398.156159)
			(xy 384.367519 -398.140112) (xy 384.322525 -398.116558) (xy 384.281882 -398.086104) (xy 384.246638 -398.049536)
			(xy 384.217704 -398.007798) (xy 384.195825 -397.961965) (xy 384.188208 -397.937736) (xy 384.186684 -397.931894)
			(xy 383.86639 -397.378174) (xy 383.862326 -397.373856) (xy 383.846162 -397.356126) (xy 383.818796 -397.316723)
			(xy 383.797706 -397.273632) (xy 383.78338 -397.227846) (xy 383.776146 -397.18042) (xy 383.775712 -397.156432)
			(xy 383.775793 -397.144384) (xy 383.777576 -397.120355) (xy 383.779268 -397.108426) (xy 383.780538 -397.099536)
			(xy 383.77749 -397.082518) (xy 383.735326 -397.011652) (xy 383.722118 -397.000476) (xy 383.713736 -396.997428)
			(xy 383.691981 -396.989051) (xy 383.651123 -396.966606) (xy 383.614154 -396.938209) (xy 383.581933 -396.904521)
			(xy 383.555209 -396.866324) (xy 383.534604 -396.824509) (xy 383.520597 -396.780046) (xy 383.513514 -396.73397)
			(xy 383.513076 -396.710662) (xy 382.923796 -396.710662) (xy 382.923724 -396.72002) (xy 382.922578 -396.738702)
			(xy 382.92151 -396.748) (xy 382.920494 -396.75689) (xy 382.924304 -396.773654) (xy 382.968246 -396.843504)
			(xy 382.981962 -396.853918) (xy 382.990344 -396.856712) (xy 383.014378 -396.865168) (xy 383.059555 -396.888716)
			(xy 383.100364 -396.919215) (xy 383.135745 -396.955873) (xy 383.164778 -396.997737) (xy 383.186711 -397.04372)
			(xy 383.194306 -397.06804) (xy 383.19583 -397.073882) (xy 383.516124 -397.627602) (xy 383.520188 -397.63192)
			(xy 383.536405 -397.649618) (xy 383.563839 -397.689007) (xy 383.584987 -397.732098) (xy 383.599361 -397.777896)
			(xy 383.606628 -397.825344) (xy 383.607056 -397.849344) (xy 383.606591 -397.874146) (xy 383.598821 -397.923137)
			(xy 383.583479 -397.970308) (xy 383.560944 -398.014497) (xy 383.531771 -398.054615) (xy 383.496679 -398.089673)
			(xy 383.456533 -398.118806) (xy 383.412321 -398.141298) (xy 383.365135 -398.156593) (xy 383.316136 -398.164315)
			(xy 383.291334 -398.164812) (xy 383.265939 -398.164307) (xy 383.215802 -398.156181) (xy 383.167614 -398.140133)
			(xy 383.122616 -398.116577) (xy 383.081969 -398.086122) (xy 383.046723 -398.049551) (xy 383.017786 -398.00781)
			(xy 382.995905 -397.961974) (xy 382.988312 -397.937736) (xy 382.986788 -397.931894) (xy 382.666494 -397.378174)
			(xy 382.66243 -397.373856) (xy 382.64624 -397.356148) (xy 382.618862 -397.316746) (xy 382.597771 -397.27365)
			(xy 382.583452 -397.227857) (xy 382.576238 -397.180422) (xy 382.575816 -397.156432) (xy 382.575902 -397.144384)
			(xy 382.577685 -397.120355) (xy 382.579372 -397.108426) (xy 382.580642 -397.099536) (xy 382.577594 -397.082518)
			(xy 382.53543 -397.011652) (xy 382.522222 -397.000476) (xy 382.51384 -396.997428) (xy 382.490931 -396.988542)
			(xy 382.44807 -396.964518) (xy 382.409611 -396.933938) (xy 382.376547 -396.897592) (xy 382.36271 -396.877286)
			(xy 382.35636 -396.867634) (xy 382.336802 -396.855696) (xy 382.246886 -396.846298) (xy 382.235535 -396.84577)
			(xy 382.214166 -396.85341) (xy 382.205738 -396.86103) (xy 382.134872 -396.931896) (xy 382.127472 -396.938738)
			(xy 382.108874 -396.946463) (xy 382.098804 -396.946882) (xy 382.021334 -396.946882) (xy 382.011307 -396.947296)
			(xy 381.992775 -396.954959) (xy 381.978588 -396.969132) (xy 381.970906 -396.987655) (xy 381.970534 -396.997682)
			(xy 381.970534 -397.009366) (xy 381.975614 -397.01978) (xy 381.981104 -397.031499) (xy 381.990385 -397.05566)
			(xy 381.994156 -397.06804) (xy 381.99568 -397.073882) (xy 382.315974 -397.627602) (xy 382.320038 -397.63192)
			(xy 382.336227 -397.64963) (xy 382.363602 -397.689033) (xy 382.384692 -397.732128) (xy 382.39901 -397.777921)
			(xy 382.406226 -397.825354) (xy 382.406652 -397.849344) (xy 382.406162 -397.874131) (xy 382.398401 -397.923093)
			(xy 382.383076 -397.970239) (xy 382.360565 -398.014407) (xy 382.331422 -398.05451) (xy 382.296365 -398.089561)
			(xy 382.256256 -398.118696) (xy 382.212084 -398.141199) (xy 382.164935 -398.156515) (xy 382.115971 -398.164267)
			(xy 382.091184 -398.164812) (xy 382.065791 -398.164303) (xy 382.01566 -398.156171) (xy 381.967478 -398.140118)
			(xy 381.922487 -398.116559) (xy 381.881847 -398.086102) (xy 381.846607 -398.049532) (xy 381.817676 -398.007792)
			(xy 381.7958 -397.961959) (xy 381.788162 -397.937736) (xy 381.786638 -397.931894) (xy 381.466344 -397.378174)
			(xy 381.46228 -397.373856) (xy 381.446065 -397.356157) (xy 381.418637 -397.316767) (xy 381.397495 -397.273675)
			(xy 381.383126 -397.227878) (xy 381.375863 -397.180431) (xy 381.375412 -397.156432) (xy 381.37557 -397.14438)
			(xy 381.377479 -397.120352) (xy 381.379222 -397.108426) (xy 381.380492 -397.099536) (xy 381.377444 -397.082518)
			(xy 381.33528 -397.011652) (xy 381.322072 -397.000476) (xy 381.31369 -396.997428) (xy 381.293512 -396.989667)
			(xy 381.255392 -396.969275) (xy 381.237744 -396.956788) (xy 381.231046 -396.952206) (xy 381.21563 -396.947165)
			(xy 381.207518 -396.946882) (xy 380.821438 -396.946882) (xy 380.81141 -396.947295) (xy 380.792877 -396.954957)
			(xy 380.778689 -396.96913) (xy 380.771006 -396.987655) (xy 380.770638 -396.997682) (xy 380.770638 -397.009366)
			(xy 380.775718 -397.01978) (xy 380.781208 -397.031499) (xy 380.790489 -397.05566) (xy 380.79426 -397.06804)
			(xy 380.795784 -397.073882) (xy 381.116078 -397.627602) (xy 381.120142 -397.63192) (xy 381.13633 -397.64963)
			(xy 381.163705 -397.689033) (xy 381.184795 -397.732128) (xy 381.199113 -397.777921) (xy 381.206329 -397.825354)
			(xy 381.206756 -397.849344) (xy 381.206266 -397.874131) (xy 381.198505 -397.923094) (xy 381.18318 -397.97024)
			(xy 381.160669 -398.014408) (xy 381.131526 -398.054511) (xy 381.096469 -398.089562) (xy 381.05636 -398.118698)
			(xy 381.012188 -398.141201) (xy 380.965039 -398.156518) (xy 380.916075 -398.164271) (xy 380.891288 -398.164812)
			(xy 380.865895 -398.164303) (xy 380.815764 -398.156171) (xy 380.767581 -398.140119) (xy 380.722589 -398.116561)
			(xy 380.681949 -398.086103) (xy 380.646708 -398.049533) (xy 380.617777 -398.007793) (xy 380.5959 -397.96196)
			(xy 380.588266 -397.937736) (xy 380.586742 -397.931894) (xy 380.266448 -397.378174) (xy 380.262384 -397.373856)
			(xy 380.246169 -397.356157) (xy 380.218741 -397.316767) (xy 380.197598 -397.273675) (xy 380.183229 -397.227878)
			(xy 380.175966 -397.180432) (xy 380.175516 -397.156432) (xy 380.175674 -397.14438) (xy 380.177583 -397.120352)
			(xy 380.179326 -397.108426) (xy 380.180596 -397.099536) (xy 380.177548 -397.082518) (xy 380.135384 -397.011652)
			(xy 380.122176 -397.000476) (xy 380.113794 -396.997428) (xy 380.093616 -396.989668) (xy 380.055496 -396.969276)
			(xy 380.037848 -396.956788) (xy 380.03115 -396.952205) (xy 380.015734 -396.947163) (xy 380.007622 -396.946882)
			(xy 379.621542 -396.946882) (xy 379.611514 -396.947294) (xy 379.592979 -396.954956) (xy 379.57879 -396.969129)
			(xy 379.571106 -396.987654) (xy 379.570742 -396.997682) (xy 379.570742 -397.009366) (xy 379.575822 -397.01978)
			(xy 379.581414 -397.031675) (xy 379.590826 -397.056217) (xy 379.594618 -397.068802) (xy 379.596142 -397.074644)
			(xy 379.915928 -397.627602) (xy 379.919992 -397.63192) (xy 379.936209 -397.649618) (xy 379.963643 -397.689007)
			(xy 379.98479 -397.732098) (xy 379.999164 -397.777896) (xy 380.006431 -397.825344) (xy 380.00686 -397.849344)
			(xy 380.006395 -397.874146) (xy 379.998625 -397.923137) (xy 379.983283 -397.970309) (xy 379.960748 -398.014498)
			(xy 379.931575 -398.054616) (xy 379.896483 -398.089674) (xy 379.856337 -398.118808) (xy 379.812126 -398.1413)
			(xy 379.764939 -398.156596) (xy 379.71594 -398.164319) (xy 379.691138 -398.164812) (xy 379.665742 -398.164307)
			(xy 379.615606 -398.156182) (xy 379.567416 -398.140134) (xy 379.522418 -398.116579) (xy 379.481771 -398.086123)
			(xy 379.446524 -398.049553) (xy 379.417587 -398.007811) (xy 379.395706 -397.961975) (xy 379.388116 -397.937736)
			(xy 379.386592 -397.931894) (xy 379.066044 -397.377412) (xy 379.06198 -397.373094) (xy 379.045874 -397.355427)
			(xy 379.018631 -397.316142) (xy 378.997617 -397.273202) (xy 378.983314 -397.227585) (xy 378.976046 -397.180335)
			(xy 378.97562 -397.156432) (xy 378.975778 -397.14438) (xy 378.977687 -397.120352) (xy 378.97943 -397.108426)
			(xy 378.9807 -397.099536) (xy 378.977652 -397.082518) (xy 378.935488 -397.011652) (xy 378.92228 -397.000476)
			(xy 378.913898 -396.997428) (xy 378.89372 -396.989668) (xy 378.855599 -396.969276) (xy 378.837952 -396.956788)
			(xy 378.831254 -396.952204) (xy 378.815838 -396.947161) (xy 378.807726 -396.946882) (xy 378.421392 -396.946882)
			(xy 378.411384 -396.947371) (xy 378.392892 -396.955031) (xy 378.378737 -396.969183) (xy 378.371073 -396.987674)
			(xy 378.370592 -396.997682) (xy 378.370592 -397.009366) (xy 378.375672 -397.01978) (xy 378.381163 -397.031499)
			(xy 378.390445 -397.055659) (xy 378.394214 -397.06804) (xy 378.395738 -397.073882) (xy 378.716032 -397.627602)
			(xy 378.720096 -397.63192) (xy 378.736313 -397.649618) (xy 378.763746 -397.689007) (xy 378.784894 -397.732098)
			(xy 378.799267 -397.777896) (xy 378.806534 -397.825344) (xy 378.806964 -397.849344) (xy 378.806499 -397.874146)
			(xy 378.798729 -397.923137) (xy 378.783387 -397.970309) (xy 378.760852 -398.014499) (xy 378.73168 -398.054617)
			(xy 378.696587 -398.089676) (xy 378.656441 -398.11881) (xy 378.61223 -398.141303) (xy 378.565043 -398.156599)
			(xy 378.516044 -398.164322) (xy 378.491242 -398.164812) (xy 378.465846 -398.164307) (xy 378.415709 -398.156183)
			(xy 378.367519 -398.140136) (xy 378.32252 -398.11658) (xy 378.281873 -398.086125) (xy 378.246626 -398.049554)
			(xy 378.217688 -398.007813) (xy 378.195806 -397.961977) (xy 378.18822 -397.937736) (xy 378.186696 -397.931894)
			(xy 377.866402 -397.378174) (xy 377.862338 -397.373856) (xy 377.846147 -397.356148) (xy 377.818769 -397.316746)
			(xy 377.797677 -397.273651) (xy 377.783358 -397.227857) (xy 377.776144 -397.180422) (xy 377.775724 -397.156432)
			(xy 377.77581 -397.144384) (xy 377.777593 -397.120355) (xy 377.77928 -397.108426) (xy 377.78055 -397.099536)
			(xy 377.777502 -397.082518) (xy 377.735338 -397.011652) (xy 377.72213 -397.000476) (xy 377.713748 -396.997428)
			(xy 377.693571 -396.989665) (xy 377.655454 -396.969268) (xy 377.637802 -396.956788) (xy 377.631106 -396.952197)
			(xy 377.61569 -396.947139) (xy 377.607576 -396.946882) (xy 377.221496 -396.946882) (xy 377.211488 -396.94737)
			(xy 377.192994 -396.95503) (xy 377.178838 -396.969182) (xy 377.171173 -396.987674) (xy 377.170696 -396.997682)
			(xy 377.170696 -397.009366) (xy 377.175776 -397.01978) (xy 377.181266 -397.031499) (xy 377.190549 -397.055659)
			(xy 377.194318 -397.06804) (xy 377.195842 -397.073882) (xy 377.516136 -397.627602) (xy 377.5202 -397.63192)
			(xy 377.536417 -397.649618) (xy 377.56385 -397.689007) (xy 377.584997 -397.732098) (xy 377.59937 -397.777896)
			(xy 377.606637 -397.825344) (xy 377.607068 -397.849344) (xy 377.606603 -397.874146) (xy 377.598833 -397.923138)
			(xy 377.583491 -397.97031) (xy 377.560957 -398.0145) (xy 377.531784 -398.054619) (xy 377.496692 -398.089678)
			(xy 377.456545 -398.118813) (xy 377.412334 -398.141306) (xy 377.365148 -398.156602) (xy 377.316148 -398.164326)
			(xy 377.291346 -398.164812) (xy 377.26595 -398.164308) (xy 377.215812 -398.156183) (xy 377.167622 -398.140137)
			(xy 377.122623 -398.116582) (xy 377.081975 -398.086126) (xy 377.046727 -398.049556) (xy 377.017789 -398.007814)
			(xy 376.995907 -397.961978) (xy 376.988324 -397.937736) (xy 376.9868 -397.931894) (xy 376.666506 -397.378174)
			(xy 376.662442 -397.373856) (xy 376.646251 -397.356148) (xy 376.618872 -397.316746) (xy 376.59778 -397.273651)
			(xy 376.583461 -397.227857) (xy 376.576247 -397.180423) (xy 376.575828 -397.156432) (xy 376.575914 -397.144384)
			(xy 376.577697 -397.120355) (xy 376.579384 -397.108426) (xy 376.580654 -397.099536) (xy 376.577606 -397.082518)
			(xy 376.535442 -397.011652) (xy 376.522234 -397.000476) (xy 376.513852 -396.997428) (xy 376.492113 -396.989021)
			(xy 376.451272 -396.966566) (xy 376.414318 -396.938165) (xy 376.382108 -396.904478) (xy 376.355392 -396.866288)
			(xy 376.33479 -396.824482) (xy 376.32078 -396.78003) (xy 376.313688 -396.733966) (xy 376.313192 -396.710662)
			(xy 376.313695 -396.685653) (xy 376.321846 -396.636305) (xy 376.337924 -396.588942) (xy 376.34926 -396.566644)
			(xy 376.357134 -396.551658) (xy 376.352308 -396.518638) (xy 376.228864 -396.395194) (xy 376.222011 -396.387798)
			(xy 376.214269 -396.3692) (xy 376.213878 -396.359126) (xy 376.213878 -396.29588) (xy 376.211338 -396.284704)
			(xy 376.208544 -396.27937) (xy 376.193475 -396.24755) (xy 376.172196 -396.180439) (xy 376.161425 -396.110864)
			(xy 376.160792 -396.075662) (xy 376.161414 -396.040458) (xy 376.172159 -395.970875) (xy 376.193451 -395.903765)
			(xy 376.208544 -395.871954) (xy 376.211006 -395.866629) (xy 376.213701 -395.855212) (xy 376.213878 -395.849348)
			(xy 376.213878 -395.839442) (xy 376.188726 -395.820963) (xy 376.143187 -395.778286) (xy 376.103865 -395.72982)
			(xy 376.071492 -395.676461) (xy 376.046666 -395.6192) (xy 376.029847 -395.559097) (xy 376.021348 -395.497267)
			(xy 376.020838 -395.466062) (xy 376.021236 -395.438157) (xy 376.027981 -395.382755) (xy 376.0343 -395.355572)
			(xy 376.037602 -395.342364) (xy 376.03049 -395.31671) (xy 375.975372 -395.261592) (xy 375.967971 -395.254751)
			(xy 375.949374 -395.247028) (xy 375.939304 -395.246606) (xy 374.494298 -395.246606) (xy 374.482536 -395.247191)
			(xy 374.461462 -395.257638) (xy 374.453912 -395.266672) (xy 374.397778 -395.341094) (xy 374.39346 -395.364208)
			(xy 374.396762 -395.375892) (xy 374.402603 -395.397975) (xy 374.408851 -395.443223) (xy 374.409208 -395.466062)
			(xy 374.408775 -395.49018) (xy 374.401779 -395.537905) (xy 374.387931 -395.584109) (xy 374.367523 -395.627814)
			(xy 374.354598 -395.64818) (xy 374.348756 -395.65707) (xy 374.3452 -395.677136) (xy 374.366282 -395.769338)
			(xy 374.378474 -395.786102) (xy 374.387364 -395.791436) (xy 374.408164 -395.804293) (xy 374.446077 -395.835172)
			(xy 374.479024 -395.871304) (xy 374.506283 -395.911898) (xy 374.527261 -395.956067) (xy 374.541498 -396.002846)
			(xy 374.548682 -396.051213) (xy 374.549162 -396.075662) (xy 374.548724 -396.100033) (xy 374.541569 -396.148246)
			(xy 374.527421 -396.19489) (xy 374.506587 -396.238954) (xy 374.479518 -396.279488) (xy 374.446797 -396.315615)
			(xy 374.428258 -396.33144) (xy 374.419368 -396.338552) (xy 374.40997 -396.35811) (xy 374.407176 -396.457424)
			(xy 374.415812 -396.47749) (xy 374.424194 -396.48511) (xy 374.442616 -396.502598) (xy 374.473959 -396.542565)
			(xy 374.498256 -396.587168) (xy 374.514838 -396.635176) (xy 374.523248 -396.685266) (xy 374.523762 -396.710662)
			(xy 375.113042 -396.710662) (xy 375.113564 -396.685407) (xy 375.121877 -396.635585) (xy 375.138278 -396.587811)
			(xy 375.162319 -396.543388) (xy 375.193343 -396.503528) (xy 375.230505 -396.469318) (xy 375.272791 -396.441692)
			(xy 375.319047 -396.421402) (xy 375.368012 -396.409002) (xy 375.41835 -396.404831) (xy 375.468688 -396.409002)
			(xy 375.517653 -396.421402) (xy 375.563909 -396.441692) (xy 375.606195 -396.469318) (xy 375.643357 -396.503528)
			(xy 375.674381 -396.543388) (xy 375.698422 -396.587811) (xy 375.714823 -396.635585) (xy 375.723136 -396.685407)
			(xy 375.723658 -396.710662) (xy 375.723589 -396.720021) (xy 375.722446 -396.738703) (xy 375.721372 -396.748)
			(xy 375.720356 -396.75689) (xy 375.724166 -396.773654) (xy 375.768108 -396.843504) (xy 375.781824 -396.853918)
			(xy 375.790206 -396.856712) (xy 375.814228 -396.865198) (xy 375.859401 -396.888746) (xy 375.900207 -396.919242)
			(xy 375.935587 -396.955893) (xy 375.964624 -396.99775) (xy 375.986564 -397.043725) (xy 375.994168 -397.06804)
			(xy 375.995692 -397.073882) (xy 376.315986 -397.627602) (xy 376.32005 -397.63192) (xy 376.336246 -397.649622)
			(xy 376.363609 -397.689033) (xy 376.384693 -397.732131) (xy 376.399011 -397.777923) (xy 376.406236 -397.825354)
			(xy 376.406664 -397.849344) (xy 376.406223 -397.874135) (xy 376.39846 -397.923106) (xy 376.383133 -397.970259)
			(xy 376.360619 -398.014435) (xy 376.331471 -398.054545) (xy 376.296409 -398.089603) (xy 376.256294 -398.118744)
			(xy 376.212115 -398.141251) (xy 376.164959 -398.156571) (xy 376.115987 -398.164326) (xy 376.091196 -398.164812)
			(xy 376.065802 -398.164315) (xy 376.015668 -398.156184) (xy 375.967482 -398.140132) (xy 375.922488 -398.116573)
			(xy 375.881845 -398.086115) (xy 375.846602 -398.049543) (xy 375.817669 -398.007802) (xy 375.795791 -397.961967)
			(xy 375.788174 -397.937736) (xy 375.78665 -397.931894) (xy 375.466356 -397.378174) (xy 375.462292 -397.373856)
			(xy 375.446088 -397.356149) (xy 375.418664 -397.316757) (xy 375.397521 -397.273668) (xy 375.383148 -397.227873)
			(xy 375.375874 -397.180431) (xy 375.375424 -397.156432) (xy 375.375566 -397.14438) (xy 375.377472 -397.12035)
			(xy 375.379234 -397.108426) (xy 375.380504 -397.099536) (xy 375.377456 -397.082518) (xy 375.335292 -397.011652)
			(xy 375.322084 -397.000476) (xy 375.313702 -396.997428) (xy 375.291961 -396.989015) (xy 375.251102 -396.966578)
			(xy 375.21413 -396.938189) (xy 375.181906 -396.904506) (xy 375.155179 -396.866314) (xy 375.134572 -396.824502)
			(xy 375.120564 -396.780042) (xy 375.11348 -396.733969) (xy 375.113042 -396.710662) (xy 374.523762 -396.710662)
			(xy 374.52369 -396.72002) (xy 374.522544 -396.738702) (xy 374.521476 -396.748) (xy 374.52046 -396.75689)
			(xy 374.52427 -396.773654) (xy 374.568212 -396.843504) (xy 374.581928 -396.853918) (xy 374.59031 -396.856712)
			(xy 374.614346 -396.865166) (xy 374.659527 -396.888711) (xy 374.70034 -396.919208) (xy 374.735724 -396.955865)
			(xy 374.764761 -396.997729) (xy 374.786697 -397.043714) (xy 374.794272 -397.06804) (xy 374.795796 -397.073882)
			(xy 375.11609 -397.627602) (xy 375.120154 -397.63192) (xy 375.136347 -397.649628) (xy 375.163728 -397.689029)
			(xy 375.184824 -397.732124) (xy 375.199147 -397.777918) (xy 375.206365 -397.825353) (xy 375.206768 -397.849344)
			(xy 375.206278 -397.874131) (xy 375.198517 -397.923095) (xy 375.183192 -397.970241) (xy 375.160681 -398.014411)
			(xy 375.131539 -398.054515) (xy 375.096482 -398.089567) (xy 375.056373 -398.118704) (xy 375.012201 -398.141209)
			(xy 374.965052 -398.156527) (xy 374.916087 -398.164282) (xy 374.8913 -398.164812) (xy 374.865906 -398.164304)
			(xy 374.815774 -398.156174) (xy 374.767589 -398.140123) (xy 374.722596 -398.116565) (xy 374.681954 -398.086108)
			(xy 374.646712 -398.049538) (xy 374.617779 -398.007798) (xy 374.595901 -397.961964) (xy 374.588278 -397.937736)
			(xy 374.586754 -397.931894) (xy 374.26646 -397.378174) (xy 374.262396 -397.373856) (xy 374.246181 -397.356157)
			(xy 374.218751 -397.316767) (xy 374.197608 -397.273676) (xy 374.183238 -397.227878) (xy 374.175975 -397.180432)
			(xy 374.175528 -397.156432) (xy 374.175686 -397.14438) (xy 374.177595 -397.120352) (xy 374.179338 -397.108426)
			(xy 374.180608 -397.099536) (xy 374.17756 -397.082518) (xy 374.135396 -397.011652) (xy 374.122188 -397.000476)
			(xy 374.113806 -396.997428) (xy 374.092064 -396.989024) (xy 374.051217 -396.966573) (xy 374.014256 -396.938175)
			(xy 373.982041 -396.904489) (xy 373.955319 -396.866298) (xy 373.934713 -396.82449) (xy 373.9207 -396.780035)
			(xy 373.913607 -396.733967) (xy 373.913146 -396.710662) (xy 373.913645 -396.685263) (xy 373.922044 -396.635166)
			(xy 373.938619 -396.587149) (xy 373.962915 -396.542539) (xy 373.994259 -396.502566) (xy 374.012714 -396.48511)
			(xy 374.021096 -396.47749) (xy 374.029732 -396.457424) (xy 374.026938 -396.35811) (xy 374.01754 -396.338552)
			(xy 374.00865 -396.33144) (xy 373.990086 -396.315639) (xy 373.957355 -396.279514) (xy 373.930278 -396.238978)
			(xy 373.909442 -396.194908) (xy 373.895297 -396.148257) (xy 373.88815 -396.100036) (xy 373.887746 -396.075662)
			(xy 373.888185 -396.051546) (xy 373.895191 -396.003826) (xy 373.90905 -395.957629) (xy 373.929468 -395.913933)
			(xy 373.942356 -395.893544) (xy 373.948198 -395.884654) (xy 373.951754 -395.864588) (xy 373.930672 -395.772386)
			(xy 373.91848 -395.755622) (xy 373.90959 -395.750288) (xy 373.888786 -395.737434) (xy 373.850865 -395.706558)
			(xy 373.81791 -395.670428) (xy 373.790643 -395.629834) (xy 373.769659 -395.585664) (xy 373.755416 -395.538883)
			(xy 373.748226 -395.490513) (xy 373.747792 -395.466062) (xy 373.748163 -395.443224) (xy 373.754414 -395.397978)
			(xy 373.760238 -395.375892) (xy 373.76354 -395.364208) (xy 373.759222 -395.341094) (xy 373.703088 -395.266672)
			(xy 373.695497 -395.25768) (xy 373.674453 -395.247206) (xy 373.662702 -395.246606) (xy 373.294402 -395.246606)
			(xy 373.28264 -395.24719) (xy 373.261564 -395.257636) (xy 373.254016 -395.266672) (xy 373.197882 -395.341094)
			(xy 373.193564 -395.364208) (xy 373.196866 -395.375892) (xy 373.202707 -395.397975) (xy 373.208955 -395.443223)
			(xy 373.209312 -395.466062) (xy 373.208879 -395.49018) (xy 373.201883 -395.537905) (xy 373.188035 -395.584109)
			(xy 373.167628 -395.627815) (xy 373.154702 -395.64818) (xy 373.14886 -395.65707) (xy 373.145304 -395.677136)
			(xy 373.166386 -395.769338) (xy 373.178578 -395.786102) (xy 373.187468 -395.791436) (xy 373.208268 -395.804293)
			(xy 373.246181 -395.835173) (xy 373.279127 -395.871305) (xy 373.306386 -395.911899) (xy 373.327363 -395.956068)
			(xy 373.3416 -396.002847) (xy 373.348784 -396.051213) (xy 373.349266 -396.075662) (xy 373.348828 -396.100033)
			(xy 373.341673 -396.148246) (xy 373.327525 -396.19489) (xy 373.306692 -396.238955) (xy 373.279622 -396.279489)
			(xy 373.246902 -396.315616) (xy 373.228362 -396.33144) (xy 373.219472 -396.338552) (xy 373.210074 -396.35811)
			(xy 373.20728 -396.457424) (xy 373.215916 -396.47749) (xy 373.224298 -396.48511) (xy 373.24272 -396.502598)
			(xy 373.274062 -396.542566) (xy 373.298359 -396.587168) (xy 373.314941 -396.635176) (xy 373.323351 -396.685266)
			(xy 373.323866 -396.710662) (xy 373.323794 -396.72002) (xy 373.322648 -396.738702) (xy 373.32158 -396.748)
			(xy 373.320564 -396.75689) (xy 373.324374 -396.773654) (xy 373.368316 -396.843504) (xy 373.382032 -396.853918)
			(xy 373.390414 -396.856712) (xy 373.414509 -396.865196) (xy 373.459794 -396.888828) (xy 373.500684 -396.919442)
			(xy 373.536113 -396.956238) (xy 373.565157 -396.998258) (xy 373.587058 -397.044405) (xy 373.59463 -397.068802)
			(xy 373.596154 -397.074644) (xy 373.91594 -397.627602) (xy 373.920004 -397.63192) (xy 373.936221 -397.649618)
			(xy 373.963653 -397.689007) (xy 373.9848 -397.732099) (xy 373.999173 -397.777897) (xy 374.00644 -397.825344)
			(xy 374.006872 -397.849344) (xy 374.006407 -397.874146) (xy 373.998637 -397.923138) (xy 373.983295 -397.970311)
			(xy 373.960761 -398.014501) (xy 373.931588 -398.05462) (xy 373.896496 -398.089679) (xy 373.85635 -398.118815)
			(xy 373.812139 -398.141308) (xy 373.764952 -398.156605) (xy 373.715953 -398.16433) (xy 373.69115 -398.164812)
			(xy 373.665754 -398.164308) (xy 373.615616 -398.156184) (xy 373.567425 -398.140138) (xy 373.522425 -398.116583)
			(xy 373.481777 -398.086128) (xy 373.446528 -398.049558) (xy 373.41759 -398.007816) (xy 373.395707 -397.961979)
			(xy 373.388128 -397.937736) (xy 373.386604 -397.931894) (xy 373.066056 -397.377412) (xy 373.061992 -397.373094)
			(xy 373.04589 -397.355425) (xy 373.018654 -397.316138) (xy 372.997647 -397.273197) (xy 372.983347 -397.227582)
			(xy 372.976082 -397.180333) (xy 372.975632 -397.156432) (xy 372.97579 -397.14438) (xy 372.977699 -397.120352)
			(xy 372.979442 -397.108426) (xy 372.980712 -397.099536) (xy 372.977664 -397.082518) (xy 372.9355 -397.011652)
			(xy 372.922292 -397.000476) (xy 372.91391 -396.997428) (xy 372.892168 -396.989024) (xy 372.85132 -396.966573)
			(xy 372.814359 -396.938175) (xy 372.782143 -396.90449) (xy 372.755422 -396.866299) (xy 372.734815 -396.82449)
			(xy 372.720802 -396.780035) (xy 372.713708 -396.733967) (xy 372.71325 -396.710662) (xy 372.713749 -396.685263)
			(xy 372.722148 -396.635166) (xy 372.738724 -396.587149) (xy 372.763019 -396.542539) (xy 372.794364 -396.502567)
			(xy 372.812818 -396.48511) (xy 372.8212 -396.47749) (xy 372.829836 -396.457424) (xy 372.827042 -396.35811)
			(xy 372.817644 -396.338552) (xy 372.808754 -396.33144) (xy 372.79019 -396.315639) (xy 372.757458 -396.279515)
			(xy 372.730381 -396.238978) (xy 372.709545 -396.194908) (xy 372.6954 -396.148257) (xy 372.688253 -396.100036)
			(xy 372.68785 -396.075662) (xy 372.688289 -396.051546) (xy 372.695295 -396.003826) (xy 372.709155 -395.957629)
			(xy 372.729573 -395.913933) (xy 372.74246 -395.893544) (xy 372.748302 -395.884654) (xy 372.751858 -395.864588)
			(xy 372.730776 -395.772386) (xy 372.718584 -395.755622) (xy 372.709694 -395.750288) (xy 372.68889 -395.737434)
			(xy 372.650968 -395.706558) (xy 372.618013 -395.670429) (xy 372.590746 -395.629835) (xy 372.569761 -395.585665)
			(xy 372.555518 -395.538883) (xy 372.548328 -395.490513) (xy 372.547896 -395.466062) (xy 372.548267 -395.443224)
			(xy 372.554518 -395.397978) (xy 372.560342 -395.375892) (xy 372.563644 -395.364208) (xy 372.559326 -395.341094)
			(xy 372.503192 -395.266672) (xy 372.495595 -395.257696) (xy 372.47455 -395.247261) (xy 372.462806 -395.246606)
			(xy 372.094252 -395.246606) (xy 372.082495 -395.247201) (xy 372.061437 -395.257659) (xy 372.053866 -395.266672)
			(xy 371.997732 -395.341094) (xy 371.993414 -395.364208) (xy 371.996716 -395.375892) (xy 372.002558 -395.397975)
			(xy 372.008806 -395.443223) (xy 372.009162 -395.466062) (xy 372.008729 -395.490179) (xy 372.001732 -395.537904)
			(xy 371.987882 -395.584108) (xy 371.967472 -395.627811) (xy 371.954552 -395.64818) (xy 371.94871 -395.65707)
			(xy 371.945154 -395.677136) (xy 371.966236 -395.769338) (xy 371.978428 -395.786102) (xy 371.987318 -395.791436)
			(xy 372.008121 -395.804291) (xy 372.046038 -395.835168) (xy 372.078989 -395.871299) (xy 372.106253 -395.911892)
			(xy 372.127234 -395.956062) (xy 372.141473 -396.002843) (xy 372.148659 -396.051212) (xy 372.149116 -396.075662)
			(xy 372.148678 -396.100032) (xy 372.141522 -396.148245) (xy 372.127373 -396.194887) (xy 372.106537 -396.23895)
			(xy 372.079465 -396.279481) (xy 372.046742 -396.315604) (xy 372.028212 -396.33144) (xy 372.019322 -396.338552)
			(xy 372.009924 -396.35811) (xy 372.00713 -396.457424) (xy 372.015766 -396.47749) (xy 372.024148 -396.48511)
			(xy 372.042567 -396.502599) (xy 372.073904 -396.542569) (xy 372.098197 -396.587172) (xy 372.114776 -396.635179)
			(xy 372.123185 -396.685267) (xy 372.123716 -396.710662) (xy 372.123644 -396.72002) (xy 372.122498 -396.738702)
			(xy 372.12143 -396.748) (xy 372.120414 -396.75689) (xy 372.124224 -396.773654) (xy 372.168166 -396.843504)
			(xy 372.181882 -396.853918) (xy 372.190264 -396.856712) (xy 372.214297 -396.865169) (xy 372.259472 -396.888719)
			(xy 372.300278 -396.919219) (xy 372.335657 -396.955877) (xy 372.364688 -396.997741) (xy 372.386619 -397.043725)
			(xy 372.394226 -397.06804) (xy 372.39575 -397.073882) (xy 372.716044 -397.627602) (xy 372.720108 -397.63192)
			(xy 372.736325 -397.649618) (xy 372.763757 -397.689008) (xy 372.784903 -397.732099) (xy 372.799276 -397.777897)
			(xy 372.806543 -397.825344) (xy 372.806976 -397.849344) (xy 372.806511 -397.874146) (xy 372.798741 -397.923139)
			(xy 372.7834 -397.970311) (xy 372.760865 -398.014502) (xy 372.731692 -398.054621) (xy 372.6966 -398.089681)
			(xy 372.656454 -398.118817) (xy 372.612243 -398.141311) (xy 372.565056 -398.156609) (xy 372.516057 -398.164333)
			(xy 372.491254 -398.164812) (xy 372.465862 -398.164301) (xy 372.415735 -398.156164) (xy 372.367556 -398.140109)
			(xy 372.322569 -398.116548) (xy 372.281934 -398.08609) (xy 372.246697 -398.04952) (xy 372.21777 -398.007781)
			(xy 372.195896 -397.96195) (xy 372.188232 -397.937736) (xy 372.186708 -397.931894) (xy 371.866414 -397.378174)
			(xy 371.86235 -397.373856) (xy 371.846159 -397.356148) (xy 371.818779 -397.316746) (xy 371.797687 -397.273651)
			(xy 371.783367 -397.227857) (xy 371.776153 -397.180423) (xy 371.775736 -397.156432) (xy 371.775822 -397.144384)
			(xy 371.777605 -397.120355) (xy 371.779292 -397.108426) (xy 371.780562 -397.099536) (xy 371.777514 -397.082518)
			(xy 371.73535 -397.011652) (xy 371.722142 -397.000476) (xy 371.71376 -396.997428) (xy 371.692021 -396.989021)
			(xy 371.651179 -396.966567) (xy 371.614223 -396.938167) (xy 371.582013 -396.90448) (xy 371.555296 -396.86629)
			(xy 371.534693 -396.824483) (xy 371.520683 -396.780031) (xy 371.513591 -396.733966) (xy 371.5131 -396.710662)
			(xy 371.5136 -396.685264) (xy 371.522 -396.635167) (xy 371.538577 -396.587153) (xy 371.562875 -396.542546)
			(xy 371.594224 -396.502577) (xy 371.612668 -396.48511) (xy 371.62105 -396.47749) (xy 371.629686 -396.457424)
			(xy 371.626892 -396.35811) (xy 371.617494 -396.338552) (xy 371.608604 -396.33144) (xy 371.590043 -396.315638)
			(xy 371.557316 -396.279511) (xy 371.530242 -396.238974) (xy 371.509409 -396.194904) (xy 371.495267 -396.148255)
			(xy 371.488121 -396.100035) (xy 371.4877 -396.075662) (xy 371.488139 -396.051546) (xy 371.495144 -396.003826)
			(xy 371.509002 -395.957627) (xy 371.529417 -395.913929) (xy 371.54231 -395.893544) (xy 371.548152 -395.884654)
			(xy 371.551708 -395.864588) (xy 371.530626 -395.772386) (xy 371.518434 -395.755622) (xy 371.509544 -395.750288)
			(xy 371.488742 -395.737432) (xy 371.450826 -395.706553) (xy 371.417876 -395.670423) (xy 371.390613 -395.629829)
			(xy 371.369632 -395.58566) (xy 371.355391 -395.53888) (xy 371.348203 -395.490512) (xy 371.347746 -395.466062)
			(xy 371.348117 -395.443224) (xy 371.354369 -395.397978) (xy 371.360192 -395.375892) (xy 371.363494 -395.364208)
			(xy 371.359176 -395.341094) (xy 371.303042 -395.266672) (xy 371.295448 -395.257687) (xy 371.274403 -395.247232)
			(xy 371.262656 -395.246606) (xy 370.894356 -395.246606) (xy 370.882599 -395.2472) (xy 370.861539 -395.257657)
			(xy 370.85397 -395.266672) (xy 370.797836 -395.341094) (xy 370.793518 -395.364208) (xy 370.79682 -395.375892)
			(xy 370.802662 -395.397975) (xy 370.80891 -395.443223) (xy 370.809266 -395.466062) (xy 370.808833 -395.490179)
			(xy 370.801836 -395.537904) (xy 370.787987 -395.584108) (xy 370.767577 -395.627811) (xy 370.754656 -395.64818)
			(xy 370.748814 -395.65707) (xy 370.745258 -395.677136) (xy 370.76634 -395.769338) (xy 370.778532 -395.786102)
			(xy 370.787422 -395.791436) (xy 370.808224 -395.804291) (xy 370.846142 -395.835168) (xy 370.879092 -395.871299)
			(xy 370.906356 -395.911893) (xy 370.927336 -395.956063) (xy 370.941575 -396.002843) (xy 370.948761 -396.051212)
			(xy 370.94922 -396.075662) (xy 370.948782 -396.100032) (xy 370.941626 -396.148245) (xy 370.927477 -396.194887)
			(xy 370.906641 -396.23895) (xy 370.87957 -396.279481) (xy 370.846847 -396.315605) (xy 370.828316 -396.33144)
			(xy 370.819426 -396.338552) (xy 370.810028 -396.35811) (xy 370.807234 -396.457424) (xy 370.81587 -396.47749)
			(xy 370.824252 -396.48511) (xy 370.842671 -396.502599) (xy 370.874008 -396.542569) (xy 370.8983 -396.587172)
			(xy 370.914879 -396.635179) (xy 370.923288 -396.685267) (xy 370.92382 -396.710662) (xy 370.923748 -396.72002)
			(xy 370.922602 -396.738702) (xy 370.921534 -396.748) (xy 370.920518 -396.75689) (xy 370.924328 -396.773654)
			(xy 370.96827 -396.843504) (xy 370.981986 -396.853918) (xy 370.990368 -396.856712) (xy 371.014401 -396.865169)
			(xy 371.059575 -396.88872) (xy 371.100381 -396.91922) (xy 371.135759 -396.955878) (xy 371.16479 -396.997742)
			(xy 371.186721 -397.043725) (xy 371.19433 -397.06804) (xy 371.195854 -397.073882) (xy 371.516148 -397.627602)
			(xy 371.520212 -397.63192) (xy 371.536428 -397.649618) (xy 371.56386 -397.689008) (xy 371.585006 -397.732099)
			(xy 371.599379 -397.777897) (xy 371.606646 -397.825344) (xy 371.60708 -397.849344) (xy 371.606615 -397.874146)
			(xy 371.598845 -397.923139) (xy 371.583504 -397.970312) (xy 371.560969 -398.014503) (xy 371.531796 -398.054622)
			(xy 371.496705 -398.089682) (xy 371.456558 -398.118819) (xy 371.412347 -398.141313) (xy 371.36516 -398.156612)
			(xy 371.316161 -398.164337) (xy 371.291358 -398.164812) (xy 371.265966 -398.164301) (xy 371.215838 -398.156165)
			(xy 371.167659 -398.14011) (xy 371.122672 -398.11655) (xy 371.082035 -398.086092) (xy 371.046799 -398.049522)
			(xy 371.01787 -398.007783) (xy 370.995997 -397.961951) (xy 370.988336 -397.937736) (xy 370.986812 -397.931894)
			(xy 370.666518 -397.378174) (xy 370.662454 -397.373856) (xy 370.646263 -397.356148) (xy 370.618883 -397.316747)
			(xy 370.59779 -397.273651) (xy 370.583471 -397.227858) (xy 370.576256 -397.180423) (xy 370.57584 -397.156432)
			(xy 370.575926 -397.144384) (xy 370.577709 -397.120355) (xy 370.579396 -397.108426) (xy 370.580666 -397.099536)
			(xy 370.577618 -397.082518) (xy 370.535454 -397.011652) (xy 370.522246 -397.000476) (xy 370.513864 -396.997428)
			(xy 370.492125 -396.989022) (xy 370.451282 -396.966567) (xy 370.414326 -396.938167) (xy 370.382116 -396.904481)
			(xy 370.355398 -396.86629) (xy 370.334795 -396.824484) (xy 370.320785 -396.780031) (xy 370.313692 -396.733966)
			(xy 370.313204 -396.710662) (xy 370.313704 -396.685264) (xy 370.322104 -396.635168) (xy 370.338682 -396.587153)
			(xy 370.36298 -396.542546) (xy 370.394328 -396.502577) (xy 370.412772 -396.48511) (xy 370.421154 -396.47749)
			(xy 370.42979 -396.457424) (xy 370.426996 -396.35811) (xy 370.417598 -396.338552) (xy 370.408708 -396.33144)
			(xy 370.390146 -396.315638) (xy 370.357419 -396.279511) (xy 370.330346 -396.238975) (xy 370.309512 -396.194905)
			(xy 370.295369 -396.148255) (xy 370.288224 -396.100035) (xy 370.287804 -396.075662) (xy 370.288243 -396.051546)
			(xy 370.295248 -396.003826) (xy 370.309106 -395.957628) (xy 370.329522 -395.91393) (xy 370.342414 -395.893544)
			(xy 370.348256 -395.884654) (xy 370.351812 -395.864588) (xy 370.33073 -395.772386) (xy 370.318538 -395.755622)
			(xy 370.309648 -395.750288) (xy 370.288846 -395.737432) (xy 370.250929 -395.706554) (xy 370.217979 -395.670423)
			(xy 370.190716 -395.629829) (xy 370.169734 -395.58566) (xy 370.155494 -395.53888) (xy 370.148305 -395.490512)
			(xy 370.14785 -395.466062) (xy 370.148221 -395.443224) (xy 370.154473 -395.397978) (xy 370.160296 -395.375892)
			(xy 370.163598 -395.364208) (xy 370.15928 -395.341094) (xy 370.103146 -395.266672) (xy 370.095552 -395.257687)
			(xy 370.074508 -395.24723) (xy 370.06276 -395.246606) (xy 368.629438 -395.246606) (xy 368.618196 -395.247184)
			(xy 368.597878 -395.256805) (xy 368.590322 -395.265148) (xy 368.533172 -395.334236) (xy 368.527584 -395.35608)
			(xy 368.52987 -395.367256) (xy 368.532641 -395.382727) (xy 368.53557 -395.414023) (xy 368.535712 -395.42974)
			(xy 368.535202 -395.455727) (xy 368.527072 -395.507062) (xy 368.511011 -395.556492) (xy 368.487415 -395.602802)
			(xy 368.456865 -395.64485) (xy 368.420114 -395.681601) (xy 368.378066 -395.712151) (xy 368.331756 -395.735747)
			(xy 368.282326 -395.751808) (xy 368.230991 -395.759938) (xy 368.179017 -395.759938) (xy 368.127682 -395.751808)
			(xy 368.078252 -395.735747) (xy 368.031942 -395.712151) (xy 367.989894 -395.681601) (xy 367.953143 -395.64485)
			(xy 367.922593 -395.602802) (xy 367.898997 -395.556492) (xy 367.882936 -395.507062) (xy 367.874806 -395.455727)
			(xy 367.874296 -395.42974) (xy 367.874458 -395.414024) (xy 367.877382 -395.382729) (xy 367.880138 -395.367256)
			(xy 367.882424 -395.35608) (xy 367.876836 -395.334236) (xy 367.819686 -395.265148) (xy 367.812088 -395.256856)
			(xy 367.791798 -395.247216) (xy 367.78057 -395.246606) (xy 366.272318 -395.246606) (xy 366.262255 -395.247044)
			(xy 366.243672 -395.25478) (xy 366.23625 -395.261592) (xy 364.931706 -396.566136) (xy 364.928912 -396.603982)
			(xy 364.940596 -396.619222) (xy 364.958871 -396.644286) (xy 364.977617 -396.679674) (xy 366.90884 -396.679674)
			(xy 366.912911 -396.624052) (xy 366.925037 -396.569615) (xy 366.94496 -396.517524) (xy 366.972256 -396.468889)
			(xy 367.006342 -396.424746) (xy 367.046491 -396.386037) (xy 367.091849 -396.353586) (xy 367.141449 -396.328085)
			(xy 367.194233 -396.310078) (xy 367.249076 -396.299948) (xy 367.30481 -396.297911) (xy 367.360247 -396.304011)
			(xy 367.414204 -396.318117) (xy 367.465533 -396.339929) (xy 367.513139 -396.368983) (xy 367.556007 -396.404658)
			(xy 367.593224 -396.446195) (xy 367.623997 -396.492708) (xy 367.647669 -396.543205) (xy 367.663737 -396.596612)
			(xy 367.671857 -396.651788) (xy 367.672366 -396.679674) (xy 367.671919 -396.704137) (xy 367.874806 -396.704137)
			(xy 367.874806 -396.652163) (xy 367.882936 -396.600828) (xy 367.898997 -396.551398) (xy 367.922593 -396.505088)
			(xy 367.953143 -396.46304) (xy 367.989894 -396.426289) (xy 368.031942 -396.395739) (xy 368.078252 -396.372143)
			(xy 368.127682 -396.356082) (xy 368.179017 -396.347952) (xy 368.230991 -396.347952) (xy 368.282326 -396.356082)
			(xy 368.331756 -396.372143) (xy 368.378066 -396.395739) (xy 368.420114 -396.426289) (xy 368.456865 -396.46304)
			(xy 368.487415 -396.505088) (xy 368.511011 -396.551398) (xy 368.527072 -396.600828) (xy 368.535202 -396.652163)
			(xy 368.535712 -396.67815) (xy 368.535202 -396.704137) (xy 368.527072 -396.755472) (xy 368.511011 -396.804902)
			(xy 368.487415 -396.851212) (xy 368.456865 -396.89326) (xy 368.420114 -396.930011) (xy 368.378066 -396.960561)
			(xy 368.331756 -396.984157) (xy 368.282326 -397.000218) (xy 368.230991 -397.008348) (xy 368.179017 -397.008348)
			(xy 368.127682 -397.000218) (xy 368.078252 -396.984157) (xy 368.031942 -396.960561) (xy 367.989894 -396.930011)
			(xy 367.953143 -396.89326) (xy 367.922593 -396.851212) (xy 367.898997 -396.804902) (xy 367.882936 -396.755472)
			(xy 367.874806 -396.704137) (xy 367.671919 -396.704137) (xy 367.671857 -396.70756) (xy 367.663737 -396.762736)
			(xy 367.647669 -396.816143) (xy 367.623997 -396.86664) (xy 367.593224 -396.913153) (xy 367.556007 -396.95469)
			(xy 367.513139 -396.990365) (xy 367.465533 -397.019419) (xy 367.414204 -397.041231) (xy 367.360247 -397.055337)
			(xy 367.30481 -397.061437) (xy 367.249076 -397.0594) (xy 367.194233 -397.04927) (xy 367.141449 -397.031263)
			(xy 367.091849 -397.005762) (xy 367.046491 -396.973311) (xy 367.006342 -396.934602) (xy 366.972256 -396.890459)
			(xy 366.94496 -396.841824) (xy 366.925037 -396.789733) (xy 366.912911 -396.735296) (xy 366.90884 -396.679674)
			(xy 364.977617 -396.679674) (xy 364.987907 -396.699098) (xy 365.007698 -396.757883) (xy 365.017725 -396.819094)
			(xy 365.01832 -396.850108) (xy 365.017848 -396.877478) (xy 365.010024 -396.931656) (xy 364.994536 -396.98416)
			(xy 364.971704 -397.033911) (xy 364.941996 -397.079888) (xy 364.92434 -397.100806) (xy 364.918244 -397.107918)
			(xy 364.911894 -397.124936) (xy 364.911894 -397.21028) (xy 364.918244 -397.227298) (xy 364.92434 -397.23441)
			(xy 364.941984 -397.25534) (xy 364.971713 -397.301306) (xy 364.994559 -397.351052) (xy 365.01005 -397.403556)
			(xy 365.017869 -397.457737) (xy 365.01832 -397.485108) (xy 365.017834 -397.512359) (xy 365.010076 -397.566307)
			(xy 364.994721 -397.618601) (xy 364.972079 -397.668178) (xy 364.942613 -397.714028) (xy 364.906922 -397.755219)
			(xy 364.865732 -397.79091) (xy 364.819882 -397.820377) (xy 364.770305 -397.843019) (xy 364.718011 -397.858375)
			(xy 364.664063 -397.866133) (xy 364.636812 -397.866616) (xy 364.609652 -397.866138) (xy 364.555882 -397.858435)
			(xy 364.503747 -397.843183) (xy 364.454303 -397.820691) (xy 364.408549 -397.791414) (xy 364.36741 -397.755943)
			(xy 364.331718 -397.714995) (xy 364.302195 -397.669399) (xy 364.279438 -397.620077) (xy 364.263906 -397.568025)
			(xy 364.255914 -397.514297) (xy 364.255304 -397.48714) (xy 364.255304 -397.471646) (xy 364.238286 -397.4465)
			(xy 364.137194 -397.404844) (xy 364.127745 -397.401497) (xy 364.107721 -397.401563) (xy 364.089245 -397.409282)
			(xy 364.081822 -397.41602) (xy 363.248702 -398.24914) (xy 363.241822 -398.256579) (xy 363.234085 -398.275289)
			(xy 363.234211 -398.295536) (xy 363.23778 -398.30502) (xy 363.280452 -398.406112) (xy 363.30636 -398.422876)
			(xy 363.321854 -398.422622) (xy 363.329474 -398.422622) (xy 363.360206 -398.423066) (xy 363.421224 -398.430472)
			(xy 363.480903 -398.44518) (xy 363.538374 -398.466974) (xy 363.592799 -398.495537) (xy 363.643384 -398.530453)
			(xy 363.689391 -398.571212) (xy 363.73015 -398.617219) (xy 363.765065 -398.667804) (xy 363.793628 -398.72223)
			(xy 363.815421 -398.779701) (xy 363.830128 -398.83938) (xy 363.837534 -398.900398) (xy 363.837982 -398.93113)
			(xy 363.837427 -398.965315) (xy 363.82827 -399.033069) (xy 363.810126 -399.098988) (xy 363.78332 -399.161885)
			(xy 363.748336 -399.220627) (xy 363.705803 -399.274156) (xy 363.656487 -399.321511) (xy 363.629194 -399.342102)
			(xy 363.61751 -399.350484) (xy 363.606842 -399.376138) (xy 363.623352 -399.493232) (xy 363.641132 -399.514822)
			(xy 363.654594 -399.519648) (xy 363.683721 -399.530666) (xy 363.739272 -399.558811) (xy 363.79097 -399.59353)
			(xy 363.838042 -399.634303) (xy 363.879781 -399.680519) (xy 363.915563 -399.731487) (xy 363.944853 -399.786444)
			(xy 363.967213 -399.844566) (xy 363.982306 -399.904984) (xy 363.989908 -399.966793) (xy 363.990382 -399.99793)
			(xy 363.989902 -400.028625) (xy 363.982478 -400.089564) (xy 363.967778 -400.149168) (xy 363.946015 -400.206571)
			(xy 363.917506 -400.260939) (xy 363.900466 -400.286474) (xy 363.895003 -400.295226) (xy 363.890888 -400.315425)
			(xy 363.895022 -400.33562) (xy 363.900466 -400.344386) (xy 363.917522 -400.369913) (xy 363.946053 -400.424275)
			(xy 363.967825 -400.481678) (xy 363.982522 -400.541287) (xy 363.989928 -400.602233) (xy 363.990382 -400.63293)
			(xy 363.989916 -400.663659) (xy 363.982505 -400.724669) (xy 363.967793 -400.784341) (xy 363.945996 -400.841805)
			(xy 363.917432 -400.896222) (xy 363.882517 -400.946799) (xy 363.84176 -400.992799) (xy 363.795755 -401.033551)
			(xy 363.745174 -401.068461) (xy 363.690753 -401.097019) (xy 363.633288 -401.11881) (xy 363.573614 -401.133515)
			(xy 363.512603 -401.14092) (xy 363.481874 -401.141438) (xy 363.460792 -401.14093) (xy 363.44987 -401.140422)
			(xy 363.430312 -401.148042) (xy 363.361986 -401.216368) (xy 363.354366 -401.235926) (xy 363.354874 -401.246848)
			(xy 363.355382 -401.26793) (xy 363.354902 -401.298625) (xy 363.347478 -401.359564) (xy 363.332778 -401.419168)
			(xy 363.311015 -401.476571) (xy 363.282506 -401.530939) (xy 363.265466 -401.556474) (xy 363.260003 -401.565226)
			(xy 363.255888 -401.585425) (xy 363.260022 -401.60562) (xy 363.265466 -401.614386) (xy 363.282522 -401.639913)
			(xy 363.311053 -401.694275) (xy 363.332825 -401.751678) (xy 363.347522 -401.811287) (xy 363.354928 -401.872233)
			(xy 363.355382 -401.90293) (xy 364.210346 -401.90293) (xy 364.210818 -401.87556) (xy 364.218633 -401.821381)
			(xy 364.23412 -401.768877) (xy 364.256961 -401.71913) (xy 364.286685 -401.673163) (xy 364.304326 -401.652232)
			(xy 364.310422 -401.64512) (xy 364.316772 -401.628102) (xy 364.316772 -401.542758) (xy 364.310422 -401.52574)
			(xy 364.304326 -401.518628) (xy 364.286715 -401.497671) (xy 364.256989 -401.451708) (xy 364.234142 -401.401965)
			(xy 364.218643 -401.349467) (xy 364.210812 -401.295292) (xy 364.210809 -401.240553) (xy 364.218634 -401.186377)
			(xy 364.234126 -401.133877) (xy 364.256967 -401.084132) (xy 364.286687 -401.038165) (xy 364.304326 -401.017232)
			(xy 364.310422 -401.01012) (xy 364.316772 -400.993102) (xy 364.316772 -400.907758) (xy 364.310422 -400.89074)
			(xy 364.304326 -400.883628) (xy 364.286715 -400.862671) (xy 364.256989 -400.816708) (xy 364.234142 -400.766965)
			(xy 364.218643 -400.714467) (xy 364.210812 -400.660292) (xy 364.210809 -400.605553) (xy 364.218634 -400.551377)
			(xy 364.234126 -400.498877) (xy 364.256967 -400.449132) (xy 364.286687 -400.403165) (xy 364.304326 -400.382232)
			(xy 364.310422 -400.37512) (xy 364.316772 -400.358102) (xy 364.316772 -400.272758) (xy 364.310422 -400.25574)
			(xy 364.304326 -400.248628) (xy 364.286691 -400.227693) (xy 364.256977 -400.181721) (xy 364.23414 -400.131975)
			(xy 364.218648 -400.079474) (xy 364.21082 -400.025299) (xy 364.210346 -399.99793) (xy 364.210834 -399.97046)
			(xy 364.218718 -399.916089) (xy 364.234312 -399.863409) (xy 364.257296 -399.813508) (xy 364.287193 -399.767415)
			(xy 364.323388 -399.726084) (xy 364.34395 -399.707862) (xy 364.35157 -399.701258) (xy 364.360714 -399.683478)
			(xy 364.367826 -399.591276) (xy 364.361476 -399.571972) (xy 364.354618 -399.564352) (xy 364.337232 -399.54344)
			(xy 364.307922 -399.497634) (xy 364.2854 -399.448135) (xy 364.270122 -399.395944) (xy 364.262396 -399.342115)
			(xy 364.261908 -399.314924) (xy 364.262386 -399.287554) (xy 364.270201 -399.233376) (xy 364.285687 -399.180872)
			(xy 364.308526 -399.131125) (xy 364.338248 -399.085158) (xy 364.355888 -399.064226) (xy 364.361984 -399.057114)
			(xy 364.368334 -399.040096) (xy 364.368334 -398.954752) (xy 364.361984 -398.937734) (xy 364.355888 -398.930622)
			(xy 364.338244 -398.909694) (xy 364.308533 -398.86372) (xy 364.285698 -398.813971) (xy 364.270209 -398.76147)
			(xy 364.262381 -398.707293) (xy 364.261908 -398.679924) (xy 364.262394 -398.652673) (xy 364.27015 -398.598725)
			(xy 364.285505 -398.54643) (xy 364.308147 -398.496853) (xy 364.337613 -398.451003) (xy 364.373304 -398.409812)
			(xy 364.414495 -398.374121) (xy 364.460345 -398.344655) (xy 364.509922 -398.322013) (xy 364.562217 -398.306658)
			(xy 364.616165 -398.298902) (xy 364.670667 -398.298902) (xy 364.724615 -398.306658) (xy 364.77691 -398.322013)
			(xy 364.826487 -398.344655) (xy 364.872337 -398.374121) (xy 364.913528 -398.409812) (xy 364.949219 -398.451003)
			(xy 364.978685 -398.496853) (xy 365.001327 -398.54643) (xy 365.016682 -398.598725) (xy 365.024438 -398.652673)
			(xy 365.024924 -398.679924) (xy 365.024491 -398.707296) (xy 365.016668 -398.761477) (xy 365.001172 -398.813981)
			(xy 364.978323 -398.863727) (xy 364.94859 -398.909692) (xy 364.930944 -398.930622) (xy 364.924848 -398.937734)
			(xy 364.918498 -398.954752) (xy 364.918498 -399.008092) (xy 367.862612 -399.008092) (xy 367.86302 -398.984859)
			(xy 367.869514 -398.938848) (xy 367.882388 -398.8942) (xy 367.901388 -398.851795) (xy 367.926138 -398.812469)
			(xy 367.940844 -398.794478) (xy 367.94694 -398.787366) (xy 367.953036 -398.770856) (xy 367.953036 -398.686528)
			(xy 367.94694 -398.670018) (xy 367.940844 -398.662906) (xy 367.926131 -398.644921) (xy 367.901384 -398.605591)
			(xy 367.882384 -398.563184) (xy 367.869507 -398.518537) (xy 367.863005 -398.472526) (xy 367.862612 -398.449292)
			(xy 367.863122 -398.423305) (xy 367.871252 -398.37197) (xy 367.887313 -398.32254) (xy 367.910909 -398.27623)
			(xy 367.941459 -398.234182) (xy 367.97821 -398.197431) (xy 368.020258 -398.166881) (xy 368.066568 -398.143285)
			(xy 368.115998 -398.127224) (xy 368.167333 -398.119094) (xy 368.219307 -398.119094) (xy 368.270642 -398.127224)
			(xy 368.320072 -398.143285) (xy 368.366382 -398.166881) (xy 368.40843 -398.197431) (xy 368.445181 -398.234182)
			(xy 368.475731 -398.27623) (xy 368.499327 -398.32254) (xy 368.515388 -398.37197) (xy 368.523518 -398.423305)
			(xy 368.524028 -398.449292) (xy 368.52366 -398.472527) (xy 368.517154 -398.518539) (xy 368.510384 -398.542002)
			(xy 370.1852 -398.542002) (xy 370.18916 -398.492948) (xy 370.200937 -398.445164) (xy 370.220228 -398.399888)
			(xy 370.246531 -398.358292) (xy 370.279166 -398.321455) (xy 370.317287 -398.29033) (xy 370.359908 -398.265723)
			(xy 370.405924 -398.248271) (xy 370.454143 -398.238427) (xy 370.503318 -398.236446) (xy 370.552173 -398.242378)
			(xy 370.599444 -398.25607) (xy 370.643906 -398.277168) (xy 370.684409 -398.305124) (xy 370.719902 -398.339216)
			(xy 370.749467 -398.37856) (xy 370.772338 -398.422137) (xy 370.787922 -398.468818) (xy 370.795817 -398.517395)
			(xy 370.796312 -398.542002) (xy 371.38535 -398.542002) (xy 371.38931 -398.492948) (xy 371.401087 -398.445164)
			(xy 371.420378 -398.399888) (xy 371.446681 -398.358292) (xy 371.479316 -398.321455) (xy 371.517437 -398.29033)
			(xy 371.560058 -398.265723) (xy 371.606074 -398.248271) (xy 371.654293 -398.238427) (xy 371.703468 -398.236446)
			(xy 371.752323 -398.242378) (xy 371.799594 -398.25607) (xy 371.844056 -398.277168) (xy 371.884559 -398.305124)
			(xy 371.920052 -398.339216) (xy 371.949617 -398.37856) (xy 371.972488 -398.422137) (xy 371.988072 -398.468818)
			(xy 371.995967 -398.517395) (xy 371.996462 -398.542002) (xy 372.5855 -398.542002) (xy 372.58946 -398.492948)
			(xy 372.601237 -398.445164) (xy 372.620528 -398.399888) (xy 372.646831 -398.358292) (xy 372.679466 -398.321455)
			(xy 372.717587 -398.29033) (xy 372.760208 -398.265723) (xy 372.806224 -398.248271) (xy 372.854443 -398.238427)
			(xy 372.903618 -398.236446) (xy 372.952473 -398.242378) (xy 372.999744 -398.25607) (xy 373.044206 -398.277168)
			(xy 373.084709 -398.305124) (xy 373.120202 -398.339216) (xy 373.149767 -398.37856) (xy 373.172638 -398.422137)
			(xy 373.188222 -398.468818) (xy 373.196117 -398.517395) (xy 373.196612 -398.542002) (xy 373.785396 -398.542002)
			(xy 373.789356 -398.492948) (xy 373.801133 -398.445164) (xy 373.820424 -398.399888) (xy 373.846727 -398.358292)
			(xy 373.879362 -398.321455) (xy 373.917483 -398.29033) (xy 373.960104 -398.265723) (xy 374.00612 -398.248271)
			(xy 374.054339 -398.238427) (xy 374.103514 -398.236446) (xy 374.152369 -398.242378) (xy 374.19964 -398.25607)
			(xy 374.244102 -398.277168) (xy 374.284605 -398.305124) (xy 374.320098 -398.339216) (xy 374.349663 -398.37856)
			(xy 374.372534 -398.422137) (xy 374.388118 -398.468818) (xy 374.396013 -398.517395) (xy 374.396508 -398.542002)
			(xy 374.985546 -398.542002) (xy 374.989506 -398.492948) (xy 375.001283 -398.445164) (xy 375.020574 -398.399888)
			(xy 375.046877 -398.358292) (xy 375.079512 -398.321455) (xy 375.117633 -398.29033) (xy 375.160254 -398.265723)
			(xy 375.20627 -398.248271) (xy 375.254489 -398.238427) (xy 375.303664 -398.236446) (xy 375.352519 -398.242378)
			(xy 375.39979 -398.25607) (xy 375.444252 -398.277168) (xy 375.484755 -398.305124) (xy 375.520248 -398.339216)
			(xy 375.549813 -398.37856) (xy 375.572684 -398.422137) (xy 375.588268 -398.468818) (xy 375.596163 -398.517395)
			(xy 375.596658 -398.542002) (xy 376.185442 -398.542002) (xy 376.189402 -398.492948) (xy 376.201179 -398.445164)
			(xy 376.22047 -398.399888) (xy 376.246773 -398.358292) (xy 376.279408 -398.321455) (xy 376.317529 -398.29033)
			(xy 376.36015 -398.265723) (xy 376.406166 -398.248271) (xy 376.454385 -398.238427) (xy 376.50356 -398.236446)
			(xy 376.552415 -398.242378) (xy 376.599686 -398.25607) (xy 376.644148 -398.277168) (xy 376.684651 -398.305124)
			(xy 376.720144 -398.339216) (xy 376.749709 -398.37856) (xy 376.77258 -398.422137) (xy 376.788164 -398.468818)
			(xy 376.796059 -398.517395) (xy 376.796554 -398.542002) (xy 377.385338 -398.542002) (xy 377.389298 -398.492948)
			(xy 377.401075 -398.445164) (xy 377.420366 -398.399888) (xy 377.446669 -398.358292) (xy 377.479304 -398.321455)
			(xy 377.517425 -398.29033) (xy 377.560046 -398.265723) (xy 377.606062 -398.248271) (xy 377.654281 -398.238427)
			(xy 377.703456 -398.236446) (xy 377.752311 -398.242378) (xy 377.799582 -398.25607) (xy 377.844044 -398.277168)
			(xy 377.884547 -398.305124) (xy 377.92004 -398.339216) (xy 377.949605 -398.37856) (xy 377.972476 -398.422137)
			(xy 377.98806 -398.468818) (xy 377.995955 -398.517395) (xy 377.99645 -398.542002) (xy 378.585488 -398.542002)
			(xy 378.589448 -398.492948) (xy 378.601225 -398.445164) (xy 378.620516 -398.399888) (xy 378.646819 -398.358292)
			(xy 378.679454 -398.321455) (xy 378.717575 -398.29033) (xy 378.760196 -398.265723) (xy 378.806212 -398.248271)
			(xy 378.854431 -398.238427) (xy 378.903606 -398.236446) (xy 378.952461 -398.242378) (xy 378.999732 -398.25607)
			(xy 379.044194 -398.277168) (xy 379.084697 -398.305124) (xy 379.12019 -398.339216) (xy 379.149755 -398.37856)
			(xy 379.172626 -398.422137) (xy 379.18821 -398.468818) (xy 379.196105 -398.517395) (xy 379.1966 -398.542002)
			(xy 379.785384 -398.542002) (xy 379.789344 -398.492948) (xy 379.801121 -398.445164) (xy 379.820412 -398.399888)
			(xy 379.846715 -398.358292) (xy 379.87935 -398.321455) (xy 379.917471 -398.29033) (xy 379.960092 -398.265723)
			(xy 380.006108 -398.248271) (xy 380.054327 -398.238427) (xy 380.103502 -398.236446) (xy 380.152357 -398.242378)
			(xy 380.199628 -398.25607) (xy 380.24409 -398.277168) (xy 380.284593 -398.305124) (xy 380.320086 -398.339216)
			(xy 380.349651 -398.37856) (xy 380.372522 -398.422137) (xy 380.388106 -398.468818) (xy 380.396001 -398.517395)
			(xy 380.396496 -398.542002) (xy 380.985534 -398.542002) (xy 380.989494 -398.492948) (xy 381.001271 -398.445164)
			(xy 381.020562 -398.399888) (xy 381.046865 -398.358292) (xy 381.0795 -398.321455) (xy 381.117621 -398.29033)
			(xy 381.160242 -398.265723) (xy 381.206258 -398.248271) (xy 381.254477 -398.238427) (xy 381.303652 -398.236446)
			(xy 381.352507 -398.242378) (xy 381.399778 -398.25607) (xy 381.44424 -398.277168) (xy 381.484743 -398.305124)
			(xy 381.520236 -398.339216) (xy 381.549801 -398.37856) (xy 381.572672 -398.422137) (xy 381.588256 -398.468818)
			(xy 381.596151 -398.517395) (xy 381.596646 -398.542002) (xy 382.18543 -398.542002) (xy 382.18939 -398.492948)
			(xy 382.201167 -398.445164) (xy 382.220458 -398.399888) (xy 382.246761 -398.358292) (xy 382.279396 -398.321455)
			(xy 382.317517 -398.29033) (xy 382.360138 -398.265723) (xy 382.406154 -398.248271) (xy 382.454373 -398.238427)
			(xy 382.503548 -398.236446) (xy 382.552403 -398.242378) (xy 382.599674 -398.25607) (xy 382.644136 -398.277168)
			(xy 382.684639 -398.305124) (xy 382.720132 -398.339216) (xy 382.749697 -398.37856) (xy 382.772568 -398.422137)
			(xy 382.788152 -398.468818) (xy 382.796047 -398.517395) (xy 382.796542 -398.542002) (xy 383.385326 -398.542002)
			(xy 383.389286 -398.492948) (xy 383.401063 -398.445164) (xy 383.420354 -398.399888) (xy 383.446657 -398.358292)
			(xy 383.479292 -398.321455) (xy 383.517413 -398.29033) (xy 383.560034 -398.265723) (xy 383.60605 -398.248271)
			(xy 383.654269 -398.238427) (xy 383.703444 -398.236446) (xy 383.752299 -398.242378) (xy 383.79957 -398.25607)
			(xy 383.844032 -398.277168) (xy 383.884535 -398.305124) (xy 383.920028 -398.339216) (xy 383.949593 -398.37856)
			(xy 383.972464 -398.422137) (xy 383.988048 -398.468818) (xy 383.995943 -398.517395) (xy 383.996438 -398.542002)
			(xy 384.585476 -398.542002) (xy 384.589436 -398.492948) (xy 384.601213 -398.445164) (xy 384.620504 -398.399888)
			(xy 384.646807 -398.358292) (xy 384.679442 -398.321455) (xy 384.717563 -398.29033) (xy 384.760184 -398.265723)
			(xy 384.8062 -398.248271) (xy 384.854419 -398.238427) (xy 384.903594 -398.236446) (xy 384.952449 -398.242378)
			(xy 384.99972 -398.25607) (xy 385.044182 -398.277168) (xy 385.084685 -398.305124) (xy 385.120178 -398.339216)
			(xy 385.149743 -398.37856) (xy 385.172614 -398.422137) (xy 385.188198 -398.468818) (xy 385.196093 -398.517395)
			(xy 385.196588 -398.542002) (xy 385.785372 -398.542002) (xy 385.789332 -398.492948) (xy 385.801109 -398.445164)
			(xy 385.8204 -398.399888) (xy 385.846703 -398.358292) (xy 385.879338 -398.321455) (xy 385.917459 -398.29033)
			(xy 385.96008 -398.265723) (xy 386.006096 -398.248271) (xy 386.054315 -398.238427) (xy 386.10349 -398.236446)
			(xy 386.152345 -398.242378) (xy 386.199616 -398.25607) (xy 386.244078 -398.277168) (xy 386.284581 -398.305124)
			(xy 386.320074 -398.339216) (xy 386.349639 -398.37856) (xy 386.37251 -398.422137) (xy 386.388094 -398.468818)
			(xy 386.395989 -398.517395) (xy 386.396484 -398.542002) (xy 386.985522 -398.542002) (xy 386.989482 -398.492948)
			(xy 387.001259 -398.445164) (xy 387.02055 -398.399888) (xy 387.046853 -398.358292) (xy 387.079488 -398.321455)
			(xy 387.117609 -398.29033) (xy 387.16023 -398.265723) (xy 387.206246 -398.248271) (xy 387.254465 -398.238427)
			(xy 387.30364 -398.236446) (xy 387.352495 -398.242378) (xy 387.399766 -398.25607) (xy 387.444228 -398.277168)
			(xy 387.484731 -398.305124) (xy 387.520224 -398.339216) (xy 387.549789 -398.37856) (xy 387.57266 -398.422137)
			(xy 387.588244 -398.468818) (xy 387.596139 -398.517395) (xy 387.596634 -398.542002) (xy 388.185418 -398.542002)
			(xy 388.189378 -398.492948) (xy 388.201155 -398.445164) (xy 388.220446 -398.399888) (xy 388.246749 -398.358292)
			(xy 388.279384 -398.321455) (xy 388.317505 -398.29033) (xy 388.360126 -398.265723) (xy 388.406142 -398.248271)
			(xy 388.454361 -398.238427) (xy 388.503536 -398.236446) (xy 388.552391 -398.242378) (xy 388.599662 -398.25607)
			(xy 388.644124 -398.277168) (xy 388.684627 -398.305124) (xy 388.72012 -398.339216) (xy 388.749685 -398.37856)
			(xy 388.772556 -398.422137) (xy 388.78814 -398.468818) (xy 388.796035 -398.517395) (xy 388.79653 -398.542002)
			(xy 388.796035 -398.566609) (xy 388.795811 -398.567989) (xy 389.515098 -398.567989) (xy 389.515098 -398.516015)
			(xy 389.523228 -398.46468) (xy 389.539289 -398.41525) (xy 389.562885 -398.36894) (xy 389.593435 -398.326892)
			(xy 389.630186 -398.290141) (xy 389.672234 -398.259591) (xy 389.718544 -398.235995) (xy 389.767974 -398.219934)
			(xy 389.819309 -398.211804) (xy 389.871283 -398.211804) (xy 389.922618 -398.219934) (xy 389.972048 -398.235995)
			(xy 390.018358 -398.259591) (xy 390.060406 -398.290141) (xy 390.097157 -398.326892) (xy 390.127707 -398.36894)
			(xy 390.151303 -398.41525) (xy 390.167364 -398.46468) (xy 390.175494 -398.516015) (xy 390.176004 -398.542002)
			(xy 390.175494 -398.567989) (xy 390.167364 -398.619324) (xy 390.151303 -398.668754) (xy 390.127707 -398.715064)
			(xy 390.097157 -398.757112) (xy 390.060406 -398.793863) (xy 390.018358 -398.824413) (xy 389.972048 -398.848009)
			(xy 389.922618 -398.86407) (xy 389.871283 -398.8722) (xy 389.819309 -398.8722) (xy 389.767974 -398.86407)
			(xy 389.718544 -398.848009) (xy 389.672234 -398.824413) (xy 389.630186 -398.793863) (xy 389.593435 -398.757112)
			(xy 389.562885 -398.715064) (xy 389.539289 -398.668754) (xy 389.523228 -398.619324) (xy 389.515098 -398.567989)
			(xy 388.795811 -398.567989) (xy 388.78814 -398.615186) (xy 388.772556 -398.661867) (xy 388.749685 -398.705444)
			(xy 388.72012 -398.744788) (xy 388.684627 -398.77888) (xy 388.644124 -398.806836) (xy 388.599662 -398.827934)
			(xy 388.552391 -398.841626) (xy 388.503536 -398.847558) (xy 388.454361 -398.845577) (xy 388.406142 -398.835733)
			(xy 388.360126 -398.818281) (xy 388.317505 -398.793674) (xy 388.279384 -398.762549) (xy 388.246749 -398.725712)
			(xy 388.220446 -398.684116) (xy 388.201155 -398.63884) (xy 388.189378 -398.591056) (xy 388.185418 -398.542002)
			(xy 387.596634 -398.542002) (xy 387.596139 -398.566609) (xy 387.588244 -398.615186) (xy 387.57266 -398.661867)
			(xy 387.549789 -398.705444) (xy 387.520224 -398.744788) (xy 387.484731 -398.77888) (xy 387.444228 -398.806836)
			(xy 387.399766 -398.827934) (xy 387.352495 -398.841626) (xy 387.30364 -398.847558) (xy 387.254465 -398.845577)
			(xy 387.206246 -398.835733) (xy 387.16023 -398.818281) (xy 387.117609 -398.793674) (xy 387.079488 -398.762549)
			(xy 387.046853 -398.725712) (xy 387.02055 -398.684116) (xy 387.001259 -398.63884) (xy 386.989482 -398.591056)
			(xy 386.985522 -398.542002) (xy 386.396484 -398.542002) (xy 386.395989 -398.566609) (xy 386.388094 -398.615186)
			(xy 386.37251 -398.661867) (xy 386.349639 -398.705444) (xy 386.320074 -398.744788) (xy 386.284581 -398.77888)
			(xy 386.244078 -398.806836) (xy 386.199616 -398.827934) (xy 386.152345 -398.841626) (xy 386.10349 -398.847558)
			(xy 386.054315 -398.845577) (xy 386.006096 -398.835733) (xy 385.96008 -398.818281) (xy 385.917459 -398.793674)
			(xy 385.879338 -398.762549) (xy 385.846703 -398.725712) (xy 385.8204 -398.684116) (xy 385.801109 -398.63884)
			(xy 385.789332 -398.591056) (xy 385.785372 -398.542002) (xy 385.196588 -398.542002) (xy 385.196093 -398.566609)
			(xy 385.188198 -398.615186) (xy 385.172614 -398.661867) (xy 385.149743 -398.705444) (xy 385.120178 -398.744788)
			(xy 385.084685 -398.77888) (xy 385.044182 -398.806836) (xy 384.99972 -398.827934) (xy 384.952449 -398.841626)
			(xy 384.903594 -398.847558) (xy 384.854419 -398.845577) (xy 384.8062 -398.835733) (xy 384.760184 -398.818281)
			(xy 384.717563 -398.793674) (xy 384.679442 -398.762549) (xy 384.646807 -398.725712) (xy 384.620504 -398.684116)
			(xy 384.601213 -398.63884) (xy 384.589436 -398.591056) (xy 384.585476 -398.542002) (xy 383.996438 -398.542002)
			(xy 383.995943 -398.566609) (xy 383.988048 -398.615186) (xy 383.972464 -398.661867) (xy 383.949593 -398.705444)
			(xy 383.920028 -398.744788) (xy 383.884535 -398.77888) (xy 383.844032 -398.806836) (xy 383.79957 -398.827934)
			(xy 383.752299 -398.841626) (xy 383.703444 -398.847558) (xy 383.654269 -398.845577) (xy 383.60605 -398.835733)
			(xy 383.560034 -398.818281) (xy 383.517413 -398.793674) (xy 383.479292 -398.762549) (xy 383.446657 -398.725712)
			(xy 383.420354 -398.684116) (xy 383.401063 -398.63884) (xy 383.389286 -398.591056) (xy 383.385326 -398.542002)
			(xy 382.796542 -398.542002) (xy 382.796047 -398.566609) (xy 382.788152 -398.615186) (xy 382.772568 -398.661867)
			(xy 382.749697 -398.705444) (xy 382.720132 -398.744788) (xy 382.684639 -398.77888) (xy 382.644136 -398.806836)
			(xy 382.599674 -398.827934) (xy 382.552403 -398.841626) (xy 382.503548 -398.847558) (xy 382.454373 -398.845577)
			(xy 382.406154 -398.835733) (xy 382.360138 -398.818281) (xy 382.317517 -398.793674) (xy 382.279396 -398.762549)
			(xy 382.246761 -398.725712) (xy 382.220458 -398.684116) (xy 382.201167 -398.63884) (xy 382.18939 -398.591056)
			(xy 382.18543 -398.542002) (xy 381.596646 -398.542002) (xy 381.596151 -398.566609) (xy 381.588256 -398.615186)
			(xy 381.572672 -398.661867) (xy 381.549801 -398.705444) (xy 381.520236 -398.744788) (xy 381.484743 -398.77888)
			(xy 381.44424 -398.806836) (xy 381.399778 -398.827934) (xy 381.352507 -398.841626) (xy 381.303652 -398.847558)
			(xy 381.254477 -398.845577) (xy 381.206258 -398.835733) (xy 381.160242 -398.818281) (xy 381.117621 -398.793674)
			(xy 381.0795 -398.762549) (xy 381.046865 -398.725712) (xy 381.020562 -398.684116) (xy 381.001271 -398.63884)
			(xy 380.989494 -398.591056) (xy 380.985534 -398.542002) (xy 380.396496 -398.542002) (xy 380.396001 -398.566609)
			(xy 380.388106 -398.615186) (xy 380.372522 -398.661867) (xy 380.349651 -398.705444) (xy 380.320086 -398.744788)
			(xy 380.284593 -398.77888) (xy 380.24409 -398.806836) (xy 380.199628 -398.827934) (xy 380.152357 -398.841626)
			(xy 380.103502 -398.847558) (xy 380.054327 -398.845577) (xy 380.006108 -398.835733) (xy 379.960092 -398.818281)
			(xy 379.917471 -398.793674) (xy 379.87935 -398.762549) (xy 379.846715 -398.725712) (xy 379.820412 -398.684116)
			(xy 379.801121 -398.63884) (xy 379.789344 -398.591056) (xy 379.785384 -398.542002) (xy 379.1966 -398.542002)
			(xy 379.196105 -398.566609) (xy 379.18821 -398.615186) (xy 379.172626 -398.661867) (xy 379.149755 -398.705444)
			(xy 379.12019 -398.744788) (xy 379.084697 -398.77888) (xy 379.044194 -398.806836) (xy 378.999732 -398.827934)
			(xy 378.952461 -398.841626) (xy 378.903606 -398.847558) (xy 378.854431 -398.845577) (xy 378.806212 -398.835733)
			(xy 378.760196 -398.818281) (xy 378.717575 -398.793674) (xy 378.679454 -398.762549) (xy 378.646819 -398.725712)
			(xy 378.620516 -398.684116) (xy 378.601225 -398.63884) (xy 378.589448 -398.591056) (xy 378.585488 -398.542002)
			(xy 377.99645 -398.542002) (xy 377.995955 -398.566609) (xy 377.98806 -398.615186) (xy 377.972476 -398.661867)
			(xy 377.949605 -398.705444) (xy 377.92004 -398.744788) (xy 377.884547 -398.77888) (xy 377.844044 -398.806836)
			(xy 377.799582 -398.827934) (xy 377.752311 -398.841626) (xy 377.703456 -398.847558) (xy 377.654281 -398.845577)
			(xy 377.606062 -398.835733) (xy 377.560046 -398.818281) (xy 377.517425 -398.793674) (xy 377.479304 -398.762549)
			(xy 377.446669 -398.725712) (xy 377.420366 -398.684116) (xy 377.401075 -398.63884) (xy 377.389298 -398.591056)
			(xy 377.385338 -398.542002) (xy 376.796554 -398.542002) (xy 376.796059 -398.566609) (xy 376.788164 -398.615186)
			(xy 376.77258 -398.661867) (xy 376.749709 -398.705444) (xy 376.720144 -398.744788) (xy 376.684651 -398.77888)
			(xy 376.644148 -398.806836) (xy 376.599686 -398.827934) (xy 376.552415 -398.841626) (xy 376.50356 -398.847558)
			(xy 376.454385 -398.845577) (xy 376.406166 -398.835733) (xy 376.36015 -398.818281) (xy 376.317529 -398.793674)
			(xy 376.279408 -398.762549) (xy 376.246773 -398.725712) (xy 376.22047 -398.684116) (xy 376.201179 -398.63884)
			(xy 376.189402 -398.591056) (xy 376.185442 -398.542002) (xy 375.596658 -398.542002) (xy 375.596163 -398.566609)
			(xy 375.588268 -398.615186) (xy 375.572684 -398.661867) (xy 375.549813 -398.705444) (xy 375.520248 -398.744788)
			(xy 375.484755 -398.77888) (xy 375.444252 -398.806836) (xy 375.39979 -398.827934) (xy 375.352519 -398.841626)
			(xy 375.303664 -398.847558) (xy 375.254489 -398.845577) (xy 375.20627 -398.835733) (xy 375.160254 -398.818281)
			(xy 375.117633 -398.793674) (xy 375.079512 -398.762549) (xy 375.046877 -398.725712) (xy 375.020574 -398.684116)
			(xy 375.001283 -398.63884) (xy 374.989506 -398.591056) (xy 374.985546 -398.542002) (xy 374.396508 -398.542002)
			(xy 374.396013 -398.566609) (xy 374.388118 -398.615186) (xy 374.372534 -398.661867) (xy 374.349663 -398.705444)
			(xy 374.320098 -398.744788) (xy 374.284605 -398.77888) (xy 374.244102 -398.806836) (xy 374.19964 -398.827934)
			(xy 374.152369 -398.841626) (xy 374.103514 -398.847558) (xy 374.054339 -398.845577) (xy 374.00612 -398.835733)
			(xy 373.960104 -398.818281) (xy 373.917483 -398.793674) (xy 373.879362 -398.762549) (xy 373.846727 -398.725712)
			(xy 373.820424 -398.684116) (xy 373.801133 -398.63884) (xy 373.789356 -398.591056) (xy 373.785396 -398.542002)
			(xy 373.196612 -398.542002) (xy 373.196117 -398.566609) (xy 373.188222 -398.615186) (xy 373.172638 -398.661867)
			(xy 373.149767 -398.705444) (xy 373.120202 -398.744788) (xy 373.084709 -398.77888) (xy 373.044206 -398.806836)
			(xy 372.999744 -398.827934) (xy 372.952473 -398.841626) (xy 372.903618 -398.847558) (xy 372.854443 -398.845577)
			(xy 372.806224 -398.835733) (xy 372.760208 -398.818281) (xy 372.717587 -398.793674) (xy 372.679466 -398.762549)
			(xy 372.646831 -398.725712) (xy 372.620528 -398.684116) (xy 372.601237 -398.63884) (xy 372.58946 -398.591056)
			(xy 372.5855 -398.542002) (xy 371.996462 -398.542002) (xy 371.995967 -398.566609) (xy 371.988072 -398.615186)
			(xy 371.972488 -398.661867) (xy 371.949617 -398.705444) (xy 371.920052 -398.744788) (xy 371.884559 -398.77888)
			(xy 371.844056 -398.806836) (xy 371.799594 -398.827934) (xy 371.752323 -398.841626) (xy 371.703468 -398.847558)
			(xy 371.654293 -398.845577) (xy 371.606074 -398.835733) (xy 371.560058 -398.818281) (xy 371.517437 -398.793674)
			(xy 371.479316 -398.762549) (xy 371.446681 -398.725712) (xy 371.420378 -398.684116) (xy 371.401087 -398.63884)
			(xy 371.38931 -398.591056) (xy 371.38535 -398.542002) (xy 370.796312 -398.542002) (xy 370.795817 -398.566609)
			(xy 370.787922 -398.615186) (xy 370.772338 -398.661867) (xy 370.749467 -398.705444) (xy 370.719902 -398.744788)
			(xy 370.684409 -398.77888) (xy 370.643906 -398.806836) (xy 370.599444 -398.827934) (xy 370.552173 -398.841626)
			(xy 370.503318 -398.847558) (xy 370.454143 -398.845577) (xy 370.405924 -398.835733) (xy 370.359908 -398.818281)
			(xy 370.317287 -398.793674) (xy 370.279166 -398.762549) (xy 370.246531 -398.725712) (xy 370.220228 -398.684116)
			(xy 370.200937 -398.63884) (xy 370.18916 -398.591056) (xy 370.1852 -398.542002) (xy 368.510384 -398.542002)
			(xy 368.504271 -398.563187) (xy 368.485263 -398.605591) (xy 368.460505 -398.644916) (xy 368.445796 -398.662906)
			(xy 368.4397 -398.670018) (xy 368.433604 -398.686528) (xy 368.433604 -398.770856) (xy 368.4397 -398.787366)
			(xy 368.445796 -398.794478) (xy 368.460508 -398.812464) (xy 368.485254 -398.851795) (xy 368.504253 -398.894201)
			(xy 368.517131 -398.938848) (xy 368.523634 -398.984858) (xy 368.524028 -399.008092) (xy 368.523612 -399.032185)
			(xy 368.516634 -399.079862) (xy 368.502823 -399.126025) (xy 368.49304 -399.148046) (xy 368.487706 -399.159476)
			(xy 368.488976 -399.184622) (xy 368.54511 -399.278602) (xy 368.5667 -399.291556) (xy 368.5794 -399.292318)
			(xy 368.604399 -399.294129) (xy 368.653444 -399.304467) (xy 368.700368 -399.322086) (xy 368.744097 -399.346583)
			(xy 368.783629 -399.377397) (xy 368.818059 -399.413823) (xy 368.846599 -399.455027) (xy 368.868595 -399.500066)
			(xy 368.883545 -399.547907) (xy 368.891104 -399.597457) (xy 368.891566 -399.622518) (xy 368.891056 -399.648505)
			(xy 368.882926 -399.69984) (xy 368.866865 -399.74927) (xy 368.843269 -399.79558) (xy 368.812719 -399.837628)
			(xy 368.775968 -399.874379) (xy 368.73392 -399.904929) (xy 368.68761 -399.928525) (xy 368.63818 -399.944586)
			(xy 368.586845 -399.952716) (xy 368.534871 -399.952716) (xy 368.483536 -399.944586) (xy 368.434106 -399.928525)
			(xy 368.387796 -399.904929) (xy 368.345748 -399.874379) (xy 368.308997 -399.837628) (xy 368.278447 -399.79558)
			(xy 368.254851 -399.74927) (xy 368.23879 -399.69984) (xy 368.23066 -399.648505) (xy 368.23015 -399.622518)
			(xy 368.230572 -399.598426) (xy 368.237548 -399.550749) (xy 368.251356 -399.504585) (xy 368.261138 -399.482564)
			(xy 368.266472 -399.471134) (xy 368.265202 -399.445988) (xy 368.209068 -399.352008) (xy 368.187478 -399.339054)
			(xy 368.174778 -399.338292) (xy 368.149786 -399.336403) (xy 368.100743 -399.326078) (xy 368.05382 -399.30847)
			(xy 368.010092 -399.283983) (xy 367.970559 -399.253177) (xy 367.936127 -399.216759) (xy 367.907585 -399.175563)
			(xy 367.885587 -399.130531) (xy 367.870636 -399.082695) (xy 367.863074 -399.033151) (xy 367.862612 -399.008092)
			(xy 364.918498 -399.008092) (xy 364.918498 -399.040096) (xy 364.924848 -399.057114) (xy 364.930944 -399.064226)
			(xy 364.948569 -399.085169) (xy 364.978282 -399.13114) (xy 365.00112 -399.180884) (xy 365.016614 -399.233382)
			(xy 365.024447 -399.287556) (xy 365.024924 -399.314924) (xy 365.024342 -399.344534) (xy 365.015182 -399.403042)
			(xy 364.9971 -399.459435) (xy 364.97053 -399.512361) (xy 364.936108 -399.560551) (xy 364.894661 -399.60285)
			(xy 364.871254 -399.620994) (xy 364.862807 -399.627905) (xy 364.852273 -399.646993) (xy 364.850934 -399.657824)
			(xy 364.84687 -399.713958) (xy 364.858046 -399.724626) (xy 364.865368 -399.731177) (xy 364.883538 -399.738612)
			(xy 364.893352 -399.739104) (xy 364.925356 -399.739104) (xy 364.935172 -399.738636) (xy 364.953336 -399.731178)
			(xy 364.960662 -399.724626) (xy 364.982174 -399.704467) (xy 365.030231 -399.670321) (xy 365.082967 -399.643972)
			(xy 365.139128 -399.626048) (xy 365.197378 -399.616974) (xy 365.226854 -399.616422) (xy 365.254224 -399.61691)
			(xy 365.308402 -399.624721) (xy 365.360905 -399.640205) (xy 365.410652 -399.663042) (xy 365.45662 -399.692763)
			(xy 365.477552 -399.710402) (xy 365.484664 -399.716498) (xy 365.501682 -399.722848) (xy 365.587026 -399.722848)
			(xy 365.604044 -399.716498) (xy 365.611156 -399.710402) (xy 365.632089 -399.692761) (xy 365.678057 -399.663037)
			(xy 365.727803 -399.640191) (xy 365.780305 -399.624695) (xy 365.834483 -399.616866) (xy 365.889225 -399.616866)
			(xy 365.943403 -399.624695) (xy 365.995905 -399.640191) (xy 366.045651 -399.663037) (xy 366.091619 -399.692761)
			(xy 366.112552 -399.710402) (xy 366.119664 -399.716498) (xy 366.136682 -399.722848) (xy 366.222026 -399.722848)
			(xy 366.239044 -399.716498) (xy 366.246156 -399.710402) (xy 366.267094 -399.69277) (xy 366.313065 -399.663057)
			(xy 366.362811 -399.64022) (xy 366.415311 -399.624727) (xy 366.469485 -399.616897) (xy 366.496854 -399.616422)
			(xy 366.524107 -399.616898) (xy 366.578059 -399.62465) (xy 366.630359 -399.640001) (xy 366.679941 -399.662641)
			(xy 366.725795 -399.692107) (xy 366.766989 -399.727799) (xy 366.802684 -399.768992) (xy 366.832152 -399.814845)
			(xy 366.854793 -399.864426) (xy 366.870147 -399.916725) (xy 366.877901 -399.970677) (xy 366.878362 -399.99793)
			(xy 366.877923 -400.025301) (xy 366.8701 -400.079482) (xy 366.854605 -400.131986) (xy 366.831757 -400.181732)
			(xy 366.802026 -400.227697) (xy 366.784382 -400.248628) (xy 366.778286 -400.25574) (xy 366.771936 -400.272758)
			(xy 366.771936 -400.358102) (xy 366.778286 -400.37512) (xy 366.784382 -400.382232) (xy 366.802052 -400.403141)
			(xy 366.831775 -400.449113) (xy 366.854618 -400.498863) (xy 366.870111 -400.551369) (xy 366.877937 -400.605551)
			(xy 366.877935 -400.633946) (xy 367.163096 -400.633946) (xy 367.163582 -400.606695) (xy 367.171338 -400.552747)
			(xy 367.186693 -400.500452) (xy 367.209335 -400.450875) (xy 367.238801 -400.405025) (xy 367.274492 -400.363834)
			(xy 367.315683 -400.328143) (xy 367.361533 -400.298677) (xy 367.41111 -400.276035) (xy 367.463405 -400.26068)
			(xy 367.517353 -400.252924) (xy 367.571855 -400.252924) (xy 367.625803 -400.26068) (xy 367.678098 -400.276035)
			(xy 367.727675 -400.298677) (xy 367.773525 -400.328143) (xy 367.814716 -400.363834) (xy 367.850407 -400.405025)
			(xy 367.879873 -400.450875) (xy 367.902515 -400.500452) (xy 367.91787 -400.552747) (xy 367.925626 -400.606695)
			(xy 367.926112 -400.633946) (xy 367.925625 -400.662181) (xy 367.917522 -400.71675) (xy 369.264184 -400.71675)
			(xy 369.264574 -400.693516) (xy 369.271074 -400.647505) (xy 369.283952 -400.602857) (xy 369.302955 -400.560453)
			(xy 369.327709 -400.521127) (xy 369.342416 -400.503136) (xy 369.348512 -400.496024) (xy 369.354608 -400.479514)
			(xy 369.354608 -400.395186) (xy 369.348512 -400.378676) (xy 369.342416 -400.371564) (xy 369.327725 -400.353561)
			(xy 369.302976 -400.314235) (xy 369.283973 -400.271834) (xy 369.27109 -400.22719) (xy 369.264581 -400.181183)
			(xy 369.264184 -400.15795) (xy 369.264694 -400.131963) (xy 369.272824 -400.080628) (xy 369.288885 -400.031198)
			(xy 369.312481 -399.984888) (xy 369.343031 -399.94284) (xy 369.379782 -399.906089) (xy 369.42183 -399.875539)
			(xy 369.46814 -399.851943) (xy 369.51757 -399.835882) (xy 369.568905 -399.827752) (xy 369.620879 -399.827752)
			(xy 369.672214 -399.835882) (xy 369.721644 -399.851943) (xy 369.767954 -399.875539) (xy 369.810002 -399.906089)
			(xy 369.846753 -399.94284) (xy 369.877303 -399.984888) (xy 369.900899 -400.031198) (xy 369.91696 -400.080628)
			(xy 369.92509 -400.131963) (xy 369.9256 -400.15795) (xy 369.925213 -400.181184) (xy 369.918713 -400.227196)
			(xy 369.905835 -400.271843) (xy 369.88683 -400.314248) (xy 369.862076 -400.353573) (xy 369.847368 -400.371564)
			(xy 369.841272 -400.378676) (xy 369.835176 -400.395186) (xy 369.835176 -400.479514) (xy 369.841272 -400.496024)
			(xy 369.847368 -400.503136) (xy 369.862056 -400.521141) (xy 369.886807 -400.560466) (xy 369.905811 -400.602867)
			(xy 369.918694 -400.64751) (xy 369.925203 -400.693517) (xy 369.9256 -400.71675) (xy 369.92509 -400.742737)
			(xy 369.91696 -400.794072) (xy 369.900899 -400.843502) (xy 369.877303 -400.889812) (xy 369.846753 -400.93186)
			(xy 369.810002 -400.968611) (xy 369.767954 -400.999161) (xy 369.721644 -401.022757) (xy 369.672214 -401.038818)
			(xy 369.620879 -401.046948) (xy 369.568905 -401.046948) (xy 369.51757 -401.038818) (xy 369.46814 -401.022757)
			(xy 369.42183 -400.999161) (xy 369.379782 -400.968611) (xy 369.343031 -400.93186) (xy 369.312481 -400.889812)
			(xy 369.288885 -400.843502) (xy 369.272824 -400.794072) (xy 369.264694 -400.742737) (xy 369.264184 -400.71675)
			(xy 367.917522 -400.71675) (xy 367.917331 -400.718037) (xy 367.909602 -400.745198) (xy 367.9063 -400.755866)
			(xy 367.90884 -400.776948) (xy 367.960148 -400.860768) (xy 367.977674 -400.872706) (xy 367.988596 -400.874738)
			(xy 368.014628 -400.879932) (xy 368.065026 -400.896603) (xy 368.112627 -400.920098) (xy 368.156513 -400.949962)
			(xy 368.195838 -400.98562) (xy 368.229842 -401.026383) (xy 368.257869 -401.071464) (xy 368.279378 -401.119995)
			(xy 368.293955 -401.171038) (xy 368.301318 -401.223608) (xy 368.301778 -401.25015) (xy 368.301292 -401.277401)
			(xy 368.293536 -401.331349) (xy 368.278181 -401.383644) (xy 368.255539 -401.433221) (xy 368.226073 -401.479071)
			(xy 368.190382 -401.520262) (xy 368.149191 -401.555953) (xy 368.103341 -401.585419) (xy 368.053764 -401.608061)
			(xy 368.001469 -401.623416) (xy 367.947521 -401.631172) (xy 367.893019 -401.631172) (xy 367.839071 -401.623416)
			(xy 367.786776 -401.608061) (xy 367.737199 -401.585419) (xy 367.691349 -401.555953) (xy 367.650158 -401.520262)
			(xy 367.614467 -401.479071) (xy 367.585001 -401.433221) (xy 367.562359 -401.383644) (xy 367.547004 -401.331349)
			(xy 367.539248 -401.277401) (xy 367.538762 -401.25015) (xy 367.539249 -401.221915) (xy 367.547543 -401.166059)
			(xy 367.555272 -401.138898) (xy 367.558574 -401.12823) (xy 367.556034 -401.107148) (xy 367.504726 -401.023328)
			(xy 367.4872 -401.01139) (xy 367.476278 -401.009358) (xy 367.450241 -401.004187) (xy 367.399843 -400.987512)
			(xy 367.352242 -400.964014) (xy 367.308356 -400.934147) (xy 367.269032 -400.898487) (xy 367.235029 -400.857721)
			(xy 367.207003 -400.812637) (xy 367.185494 -400.764105) (xy 367.170918 -400.71306) (xy 367.163556 -400.660488)
			(xy 367.163096 -400.633946) (xy 366.877935 -400.633946) (xy 366.877934 -400.660294) (xy 366.870102 -400.714475)
			(xy 366.854602 -400.766979) (xy 366.831753 -400.816726) (xy 366.802024 -400.862695) (xy 366.784382 -400.883628)
			(xy 366.778286 -400.89074) (xy 366.771936 -400.907758) (xy 366.771936 -400.993102) (xy 366.778286 -401.01012)
			(xy 366.784382 -401.017232) (xy 366.802052 -401.038141) (xy 366.831775 -401.084113) (xy 366.854618 -401.133863)
			(xy 366.870111 -401.186369) (xy 366.877937 -401.240551) (xy 366.877934 -401.295294) (xy 366.870102 -401.349475)
			(xy 366.854602 -401.401979) (xy 366.831753 -401.451726) (xy 366.802024 -401.497695) (xy 366.784382 -401.518628)
			(xy 366.778286 -401.52574) (xy 366.771936 -401.542758) (xy 366.771936 -401.628102) (xy 366.778286 -401.64512)
			(xy 366.784382 -401.652232) (xy 366.802 -401.673181) (xy 366.831716 -401.719149) (xy 366.854556 -401.768892)
			(xy 366.870052 -401.821389) (xy 366.877885 -401.875562) (xy 366.878362 -401.90293) (xy 366.877973 -401.930186)
			(xy 366.870211 -401.984142) (xy 366.854848 -402.036444) (xy 366.832199 -402.086027) (xy 366.802724 -402.131882)
			(xy 366.767022 -402.173076) (xy 366.725822 -402.208769) (xy 366.67996 -402.238236) (xy 366.630373 -402.260875)
			(xy 366.578067 -402.276227) (xy 366.52411 -402.283978) (xy 366.496854 -402.284438) (xy 370.530628 -402.284438)
			(xy 370.531099 -402.256162) (xy 370.539385 -402.20022) (xy 370.555785 -402.146098) (xy 370.579943 -402.094965)
			(xy 370.611338 -402.047928) (xy 370.629942 -402.026628) (xy 370.635868 -402.019454) (xy 370.642639 -402.002137)
			(xy 370.64315 -401.992846) (xy 370.643404 -401.961604) (xy 370.642968 -401.95227) (xy 370.636342 -401.934818)
			(xy 370.63045 -401.927568) (xy 370.612487 -401.906554) (xy 370.582206 -401.860304) (xy 370.558927 -401.810163)
			(xy 370.543139 -401.757184) (xy 370.535173 -401.702479) (xy 370.534692 -401.674838) (xy 370.534692 -400.811238)
			(xy 370.535155 -400.784882) (xy 370.542419 -400.732672) (xy 370.5568 -400.681958) (xy 370.578025 -400.633707)
			(xy 370.605689 -400.588837) (xy 370.639265 -400.548201) (xy 370.65839 -400.53006) (xy 370.665502 -400.52371)
			(xy 370.67363 -400.506946) (xy 370.682012 -400.420332) (xy 370.676932 -400.402552) (xy 370.671344 -400.394678)
			(xy 370.657193 -400.374832) (xy 370.634736 -400.331573) (xy 370.619424 -400.2853) (xy 370.611644 -400.237184)
			(xy 370.611146 -400.212814) (xy 370.611668 -400.187559) (xy 370.619981 -400.137737) (xy 370.636382 -400.089963)
			(xy 370.660423 -400.04554) (xy 370.691447 -400.00568) (xy 370.728609 -399.97147) (xy 370.770895 -399.943844)
			(xy 370.817151 -399.923554) (xy 370.866116 -399.911154) (xy 370.916454 -399.906983) (xy 370.966792 -399.911154)
			(xy 371.015757 -399.923554) (xy 371.062013 -399.943844) (xy 371.104299 -399.97147) (xy 371.141461 -400.00568)
			(xy 371.172485 -400.04554) (xy 371.196526 -400.089963) (xy 371.212927 -400.137737) (xy 371.22124 -400.187559)
			(xy 371.221762 -400.212814) (xy 371.221281 -400.237186) (xy 371.213523 -400.285309) (xy 371.198206 -400.331585)
			(xy 371.175721 -400.374833) (xy 371.161564 -400.394678) (xy 371.155976 -400.402552) (xy 371.150896 -400.420332)
			(xy 371.159278 -400.506946) (xy 371.167406 -400.52371) (xy 371.174518 -400.53006) (xy 371.193646 -400.5482)
			(xy 371.227236 -400.588829) (xy 371.254909 -400.633697) (xy 371.276137 -400.681949) (xy 371.290517 -400.732666)
			(xy 371.297773 -400.78488) (xy 371.298216 -400.811238) (xy 371.298216 -401.674838) (xy 371.297745 -401.70275)
			(xy 371.289605 -401.757976) (xy 371.273504 -401.811427) (xy 371.249787 -401.861962) (xy 371.218959 -401.908501)
			(xy 371.20068 -401.9296) (xy 371.194781 -401.936776) (xy 371.188132 -401.954102) (xy 371.187726 -401.963382)
			(xy 371.187726 -401.994624) (xy 371.188154 -402.003897) (xy 371.194807 -402.021215) (xy 371.20068 -402.028406)
			(xy 371.218966 -402.049652) (xy 371.249812 -402.096457) (xy 371.273529 -402.147247) (xy 371.289614 -402.200945)
			(xy 371.297725 -402.25641) (xy 371.298216 -402.284438) (xy 371.730524 -402.284438) (xy 371.730996 -402.256162)
			(xy 371.739282 -402.20022) (xy 371.755682 -402.146098) (xy 371.77984 -402.094966) (xy 371.811234 -402.047928)
			(xy 371.829838 -402.026628) (xy 371.835763 -402.019453) (xy 371.842535 -402.002137) (xy 371.843046 -401.992846)
			(xy 371.8433 -401.961604) (xy 371.842865 -401.95227) (xy 371.836239 -401.934818) (xy 371.830346 -401.927568)
			(xy 371.812382 -401.906555) (xy 371.782102 -401.860304) (xy 371.758823 -401.810163) (xy 371.743035 -401.757184)
			(xy 371.735069 -401.702479) (xy 371.734588 -401.674838) (xy 371.734588 -400.811238) (xy 371.735052 -400.784882)
			(xy 371.742316 -400.732672) (xy 371.756697 -400.681959) (xy 371.777921 -400.633708) (xy 371.805585 -400.588837)
			(xy 371.839161 -400.548201) (xy 371.858286 -400.53006) (xy 371.865398 -400.523456) (xy 371.87378 -400.506946)
			(xy 371.881908 -400.420078) (xy 371.877082 -400.402298) (xy 371.87124 -400.394678) (xy 371.857129 -400.374814)
			(xy 371.834709 -400.331557) (xy 371.819453 -400.285285) (xy 371.81175 -400.237175) (xy 371.811296 -400.212814)
			(xy 371.811818 -400.187559) (xy 371.820131 -400.137737) (xy 371.836532 -400.089963) (xy 371.860573 -400.04554)
			(xy 371.891597 -400.00568) (xy 371.928759 -399.97147) (xy 371.971045 -399.943844) (xy 372.017301 -399.923554)
			(xy 372.066266 -399.911154) (xy 372.116604 -399.906983) (xy 372.166942 -399.911154) (xy 372.215907 -399.923554)
			(xy 372.262163 -399.943844) (xy 372.304449 -399.97147) (xy 372.341611 -400.00568) (xy 372.372635 -400.04554)
			(xy 372.396676 -400.089963) (xy 372.413077 -400.137737) (xy 372.42139 -400.187559) (xy 372.421912 -400.212814)
			(xy 372.421455 -400.237217) (xy 372.413694 -400.285402) (xy 372.398372 -400.331741) (xy 372.375878 -400.375054)
			(xy 372.361714 -400.394932) (xy 372.356126 -400.402552) (xy 372.351046 -400.420332) (xy 372.359174 -400.5072)
			(xy 372.367556 -400.52371) (xy 372.374668 -400.530314) (xy 372.393727 -400.548477) (xy 372.42722 -400.589096)
			(xy 372.45482 -400.633928) (xy 372.476004 -400.682125) (xy 372.49037 -400.732774) (xy 372.497647 -400.784915)
			(xy 372.498112 -400.811238) (xy 372.498112 -401.674838) (xy 372.497642 -401.70275) (xy 372.489502 -401.757976)
			(xy 372.473401 -401.811427) (xy 372.449683 -401.861962) (xy 372.418855 -401.908501) (xy 372.400576 -401.9296)
			(xy 372.394676 -401.936775) (xy 372.388028 -401.954102) (xy 372.387622 -401.963382) (xy 372.387622 -401.994624)
			(xy 372.388051 -402.003897) (xy 372.394703 -402.021215) (xy 372.400576 -402.028406) (xy 372.418862 -402.049653)
			(xy 372.449708 -402.096457) (xy 372.473425 -402.147248) (xy 372.48951 -402.200945) (xy 372.497621 -402.25641)
			(xy 372.498112 -402.284438) (xy 372.497659 -402.309838) (xy 372.93042 -402.309838) (xy 372.930915 -402.282141)
			(xy 372.938858 -402.227319) (xy 372.954598 -402.174209) (xy 372.977809 -402.123912) (xy 373.008008 -402.077474)
			(xy 373.025924 -402.056346) (xy 373.032274 -402.049488) (xy 373.038624 -402.03247) (xy 373.039132 -401.94738)
			(xy 373.032782 -401.930362) (xy 373.026686 -401.92325) (xy 373.009472 -401.902375) (xy 372.980451 -401.856713)
			(xy 372.958167 -401.80741) (xy 372.943067 -401.755456) (xy 372.935451 -401.70189) (xy 372.934992 -401.674838)
			(xy 372.934992 -400.811238) (xy 372.935443 -400.784893) (xy 372.942691 -400.732703) (xy 372.957041 -400.682004)
			(xy 372.978222 -400.633757) (xy 373.005831 -400.588879) (xy 373.039344 -400.54822) (xy 373.058436 -400.53006)
			(xy 373.065548 -400.52371) (xy 373.073676 -400.506946) (xy 373.082058 -400.420332) (xy 373.076978 -400.402552)
			(xy 373.07139 -400.394678) (xy 373.057245 -400.374828) (xy 373.034785 -400.331571) (xy 373.019471 -400.285299)
			(xy 373.011691 -400.237184) (xy 373.011192 -400.212814) (xy 373.011714 -400.187559) (xy 373.020027 -400.137737)
			(xy 373.036428 -400.089963) (xy 373.060469 -400.04554) (xy 373.091493 -400.00568) (xy 373.128655 -399.97147)
			(xy 373.170941 -399.943844) (xy 373.217197 -399.923554) (xy 373.266162 -399.911154) (xy 373.3165 -399.906983)
			(xy 373.366838 -399.911154) (xy 373.415803 -399.923554) (xy 373.462059 -399.943844) (xy 373.504345 -399.97147)
			(xy 373.541507 -400.00568) (xy 373.572531 -400.04554) (xy 373.596572 -400.089963) (xy 373.612973 -400.137737)
			(xy 373.621286 -400.187559) (xy 373.621808 -400.212814) (xy 373.621338 -400.237187) (xy 373.613578 -400.285311)
			(xy 373.598258 -400.331586) (xy 373.575769 -400.374834) (xy 373.56161 -400.394678) (xy 373.556022 -400.402552)
			(xy 373.550942 -400.420332) (xy 373.559324 -400.506946) (xy 373.567452 -400.52371) (xy 373.574564 -400.53006)
			(xy 373.59367 -400.548207) (xy 373.62719 -400.588864) (xy 373.654803 -400.633744) (xy 373.675983 -400.681994)
			(xy 373.690329 -400.732697) (xy 373.697568 -400.784891) (xy 373.698008 -400.811238) (xy 373.698008 -401.674838)
			(xy 373.697544 -401.702137) (xy 373.689768 -401.75618) (xy 373.674364 -401.808561) (xy 373.651649 -401.85821)
			(xy 373.622087 -401.904113) (xy 373.604536 -401.925028) (xy 373.59844 -401.93214) (xy 373.59209 -401.949158)
			(xy 373.59209 -402.034248) (xy 373.59844 -402.051266) (xy 373.604536 -402.058378) (xy 373.622148 -402.07942)
			(xy 373.651843 -402.125561) (xy 373.674669 -402.175458) (xy 373.690163 -402.228096) (xy 373.694633 -402.259038)
			(xy 374.130316 -402.259038) (xy 374.130733 -402.232172) (xy 374.138235 -402.178967) (xy 374.153085 -402.127329)
			(xy 374.174992 -402.078266) (xy 374.203527 -402.032738) (xy 374.220486 -402.011896) (xy 374.225864 -402.004927)
			(xy 374.231967 -401.988429) (xy 374.232424 -401.979638) (xy 374.232678 -401.949158) (xy 374.2324 -401.940307)
			(xy 374.226406 -401.923655) (xy 374.220994 -401.916646) (xy 374.204755 -401.896096) (xy 374.17749 -401.851374)
			(xy 374.156587 -401.803348) (xy 374.142438 -401.752917) (xy 374.135308 -401.701027) (xy 374.134888 -401.674838)
			(xy 374.134888 -400.811238) (xy 374.13534 -400.784893) (xy 374.142588 -400.732703) (xy 374.156938 -400.682004)
			(xy 374.178119 -400.633758) (xy 374.205727 -400.588879) (xy 374.23924 -400.54822) (xy 374.258332 -400.53006)
			(xy 374.265444 -400.52371) (xy 374.273572 -400.506946) (xy 374.281954 -400.420332) (xy 374.276874 -400.402552)
			(xy 374.271286 -400.394678) (xy 374.25714 -400.374828) (xy 374.234681 -400.331571) (xy 374.219367 -400.285299)
			(xy 374.211587 -400.237184) (xy 374.211088 -400.212814) (xy 374.21161 -400.187559) (xy 374.219923 -400.137737)
			(xy 374.236324 -400.089963) (xy 374.260365 -400.04554) (xy 374.291389 -400.00568) (xy 374.328551 -399.97147)
			(xy 374.370837 -399.943844) (xy 374.417093 -399.923554) (xy 374.466058 -399.911154) (xy 374.516396 -399.906983)
			(xy 374.566734 -399.911154) (xy 374.615699 -399.923554) (xy 374.661955 -399.943844) (xy 374.704241 -399.97147)
			(xy 374.741403 -400.00568) (xy 374.772427 -400.04554) (xy 374.796468 -400.089963) (xy 374.812869 -400.137737)
			(xy 374.821182 -400.187559) (xy 374.821704 -400.212814) (xy 374.821235 -400.237187) (xy 374.813475 -400.285311)
			(xy 374.798155 -400.331586) (xy 374.775665 -400.374834) (xy 374.761506 -400.394678) (xy 374.755918 -400.402552)
			(xy 374.750838 -400.420332) (xy 374.75922 -400.506946) (xy 374.767348 -400.52371) (xy 374.77446 -400.53006)
			(xy 374.793565 -400.548208) (xy 374.827086 -400.588865) (xy 374.854698 -400.633744) (xy 374.875879 -400.681994)
			(xy 374.890225 -400.732697) (xy 374.897464 -400.784891) (xy 374.897904 -400.811238) (xy 374.897904 -401.674838)
			(xy 374.897468 -401.701295) (xy 374.890191 -401.753706) (xy 374.875742 -401.804608) (xy 374.854396 -401.853025)
			(xy 374.826565 -401.898028) (xy 374.81002 -401.918678) (xy 374.804694 -401.925734) (xy 374.798718 -401.942358)
			(xy 374.798336 -401.95119) (xy 374.798336 -401.98167) (xy 374.798724 -401.990444) (xy 374.804692 -402.006946)
			(xy 374.81002 -402.013928) (xy 374.82666 -402.03468) (xy 374.854631 -402.079923) (xy 374.87609 -402.128593)
			(xy 374.890627 -402.179759) (xy 374.897963 -402.232442) (xy 374.898412 -402.259038) (xy 374.897923 -402.286471)
			(xy 374.894563 -402.309838) (xy 375.33072 -402.309838) (xy 375.331151 -402.282148) (xy 375.33905 -402.227335)
			(xy 375.354747 -402.174227) (xy 375.377915 -402.123927) (xy 375.408074 -402.077481) (xy 375.42597 -402.056346)
			(xy 375.43232 -402.049488) (xy 375.43867 -402.03247) (xy 375.439178 -401.94738) (xy 375.432828 -401.930362)
			(xy 375.426732 -401.92325) (xy 375.409491 -401.902385) (xy 375.380406 -401.856739) (xy 375.358064 -401.807441)
			(xy 375.342914 -401.755481) (xy 375.335259 -401.7019) (xy 375.334784 -401.674838) (xy 375.334784 -400.811238)
			(xy 375.33525 -400.784882) (xy 375.342513 -400.732672) (xy 375.356894 -400.681959) (xy 375.378118 -400.633708)
			(xy 375.405782 -400.588837) (xy 375.439357 -400.548201) (xy 375.458482 -400.53006) (xy 375.465594 -400.52371)
			(xy 375.473722 -400.506946) (xy 375.482104 -400.420332) (xy 375.477024 -400.402552) (xy 375.471436 -400.394678)
			(xy 375.457284 -400.374833) (xy 375.434827 -400.331573) (xy 375.419516 -400.2853) (xy 375.411736 -400.237184)
			(xy 375.411238 -400.212814) (xy 375.41176 -400.187559) (xy 375.420073 -400.137737) (xy 375.436474 -400.089963)
			(xy 375.460515 -400.04554) (xy 375.491539 -400.00568) (xy 375.528701 -399.97147) (xy 375.570987 -399.943844)
			(xy 375.617243 -399.923554) (xy 375.666208 -399.911154) (xy 375.716546 -399.906983) (xy 375.766884 -399.911154)
			(xy 375.815849 -399.923554) (xy 375.862105 -399.943844) (xy 375.904391 -399.97147) (xy 375.941553 -400.00568)
			(xy 375.972577 -400.04554) (xy 375.996618 -400.089963) (xy 376.013019 -400.137737) (xy 376.021332 -400.187559)
			(xy 376.021854 -400.212814) (xy 376.021375 -400.237186) (xy 376.013616 -400.285309) (xy 375.998299 -400.331585)
			(xy 375.975813 -400.374833) (xy 375.961656 -400.394678) (xy 375.956068 -400.402552) (xy 375.950988 -400.420332)
			(xy 375.95937 -400.506946) (xy 375.967498 -400.52371) (xy 375.97461 -400.53006) (xy 375.993736 -400.548202)
			(xy 376.027326 -400.58883) (xy 376.055 -400.633698) (xy 376.076229 -400.68195) (xy 376.090609 -400.732666)
			(xy 376.097865 -400.78488) (xy 376.098308 -400.811238) (xy 376.098308 -401.674838) (xy 376.097763 -401.702141)
			(xy 376.089916 -401.756182) (xy 376.074459 -401.808557) (xy 376.051707 -401.858199) (xy 376.022122 -401.904098)
			(xy 376.004582 -401.925028) (xy 375.998486 -401.93214) (xy 375.992136 -401.949158) (xy 375.992136 -402.034248)
			(xy 375.998486 -402.051266) (xy 376.004582 -402.058378) (xy 376.022188 -402.079417) (xy 376.05186 -402.125559)
			(xy 376.074648 -402.175461) (xy 376.090088 -402.228103) (xy 376.097863 -402.282408) (xy 376.098308 -402.309838)
			(xy 376.530616 -402.309838) (xy 376.531048 -402.282148) (xy 376.538947 -402.227335) (xy 376.554644 -402.174227)
			(xy 376.577812 -402.123928) (xy 376.60797 -402.077481) (xy 376.625866 -402.056346) (xy 376.632216 -402.049488)
			(xy 376.638566 -402.03247) (xy 376.639074 -401.94738) (xy 376.632724 -401.930362) (xy 376.626628 -401.92325)
			(xy 376.609386 -401.902385) (xy 376.580302 -401.856739) (xy 376.55796 -401.807441) (xy 376.54281 -401.755481)
			(xy 376.535155 -401.7019) (xy 376.53468 -401.674838) (xy 376.53468 -400.811238) (xy 376.535147 -400.784882)
			(xy 376.542411 -400.732672) (xy 376.556791 -400.681959) (xy 376.578015 -400.633708) (xy 376.605678 -400.588837)
			(xy 376.639254 -400.548201) (xy 376.658378 -400.53006) (xy 376.66549 -400.52371) (xy 376.673618 -400.506946)
			(xy 376.682 -400.420332) (xy 376.67692 -400.402552) (xy 376.671332 -400.394678) (xy 376.657179 -400.374833)
			(xy 376.634723 -400.331573) (xy 376.619412 -400.2853) (xy 376.611632 -400.237184) (xy 376.611134 -400.212814)
			(xy 376.611656 -400.187559) (xy 376.619969 -400.137737) (xy 376.63637 -400.089963) (xy 376.660411 -400.04554)
			(xy 376.691435 -400.00568) (xy 376.728597 -399.97147) (xy 376.770883 -399.943844) (xy 376.817139 -399.923554)
			(xy 376.866104 -399.911154) (xy 376.916442 -399.906983) (xy 376.96678 -399.911154) (xy 377.015745 -399.923554)
			(xy 377.062001 -399.943844) (xy 377.104287 -399.97147) (xy 377.141449 -400.00568) (xy 377.172473 -400.04554)
			(xy 377.196514 -400.089963) (xy 377.212915 -400.137737) (xy 377.221228 -400.187559) (xy 377.22175 -400.212814)
			(xy 377.221272 -400.237186) (xy 377.213513 -400.28531) (xy 377.198195 -400.331585) (xy 377.175709 -400.374833)
			(xy 377.161552 -400.394678) (xy 377.155964 -400.402552) (xy 377.150884 -400.420332) (xy 377.159266 -400.506946)
			(xy 377.167394 -400.52371) (xy 377.174506 -400.53006) (xy 377.193632 -400.548203) (xy 377.227222 -400.58883)
			(xy 377.254896 -400.633698) (xy 377.276125 -400.68195) (xy 377.290505 -400.732666) (xy 377.297761 -400.78488)
			(xy 377.298204 -400.811238) (xy 377.298204 -401.674838) (xy 377.29766 -401.702141) (xy 377.289813 -401.756182)
			(xy 377.274356 -401.808557) (xy 377.251603 -401.858199) (xy 377.222018 -401.904098) (xy 377.204478 -401.925028)
			(xy 377.198382 -401.93214) (xy 377.192032 -401.949158) (xy 377.192032 -402.034248) (xy 377.198382 -402.051266)
			(xy 377.204478 -402.058378) (xy 377.222084 -402.079417) (xy 377.251756 -402.125559) (xy 377.274544 -402.175461)
			(xy 377.289984 -402.228103) (xy 377.294413 -402.259038) (xy 377.730512 -402.259038) (xy 377.73093 -402.232172)
			(xy 377.738432 -402.178967) (xy 377.753282 -402.127329) (xy 377.775188 -402.078266) (xy 377.803723 -402.032738)
			(xy 377.820682 -402.011896) (xy 377.826059 -402.004927) (xy 377.832163 -401.988429) (xy 377.83262 -401.979638)
			(xy 377.832874 -401.949158) (xy 377.832576 -401.94031) (xy 377.826594 -401.923659) (xy 377.82119 -401.916646)
			(xy 377.80495 -401.896096) (xy 377.777685 -401.851374) (xy 377.756783 -401.803348) (xy 377.742634 -401.752917)
			(xy 377.735504 -401.701027) (xy 377.735084 -401.674838) (xy 377.735084 -400.811238) (xy 377.735537 -400.784893)
			(xy 377.742785 -400.732703) (xy 377.757135 -400.682004) (xy 377.778316 -400.633758) (xy 377.805924 -400.588879)
			(xy 377.839436 -400.54822) (xy 377.858528 -400.53006) (xy 377.86564 -400.52371) (xy 377.873768 -400.506946)
			(xy 377.88215 -400.420332) (xy 377.87707 -400.402552) (xy 377.871482 -400.394678) (xy 377.857336 -400.374829)
			(xy 377.834876 -400.331571) (xy 377.819563 -400.285299) (xy 377.811782 -400.237184) (xy 377.811284 -400.212814)
			(xy 377.811806 -400.187559) (xy 377.820119 -400.137737) (xy 377.83652 -400.089963) (xy 377.860561 -400.04554)
			(xy 377.891585 -400.00568) (xy 377.928747 -399.97147) (xy 377.971033 -399.943844) (xy 378.017289 -399.923554)
			(xy 378.066254 -399.911154) (xy 378.116592 -399.906983) (xy 378.16693 -399.911154) (xy 378.215895 -399.923554)
			(xy 378.262151 -399.943844) (xy 378.304437 -399.97147) (xy 378.341599 -400.00568) (xy 378.372623 -400.04554)
			(xy 378.396664 -400.089963) (xy 378.413065 -400.137737) (xy 378.421378 -400.187559) (xy 378.4219 -400.212814)
			(xy 378.421431 -400.237187) (xy 378.413671 -400.285311) (xy 378.398351 -400.331586) (xy 378.375861 -400.374834)
			(xy 378.361702 -400.394678) (xy 378.356114 -400.402552) (xy 378.351034 -400.420332) (xy 378.359416 -400.506946)
			(xy 378.367544 -400.52371) (xy 378.374656 -400.53006) (xy 378.39376 -400.548209) (xy 378.427281 -400.588865)
			(xy 378.454894 -400.633745) (xy 378.476075 -400.681994) (xy 378.490421 -400.732697) (xy 378.49766 -400.784891)
			(xy 378.4981 -400.811238) (xy 378.4981 -401.674838) (xy 378.497665 -401.701295) (xy 378.490388 -401.753706)
			(xy 378.475938 -401.804608) (xy 378.454593 -401.853025) (xy 378.426761 -401.898028) (xy 378.410216 -401.918678)
			(xy 378.40489 -401.925734) (xy 378.398914 -401.942358) (xy 378.398532 -401.95119) (xy 378.398532 -401.98167)
			(xy 378.398921 -401.990444) (xy 378.404889 -402.006946) (xy 378.410216 -402.013928) (xy 378.426855 -402.03468)
			(xy 378.454826 -402.079923) (xy 378.476286 -402.128593) (xy 378.490823 -402.179759) (xy 378.498159 -402.232442)
			(xy 378.498608 -402.259038) (xy 378.498155 -402.284438) (xy 378.930408 -402.284438) (xy 378.930936 -402.256153)
			(xy 378.93925 -402.200197) (xy 378.955688 -402.146067) (xy 378.979894 -402.094938) (xy 379.011344 -402.047915)
			(xy 379.029976 -402.026628) (xy 379.035894 -402.019447) (xy 379.042672 -402.002136) (xy 379.043184 -401.992846)
			(xy 379.043438 -401.961604) (xy 379.043017 -401.952268) (xy 379.036382 -401.934816) (xy 379.030484 -401.927568)
			(xy 379.012571 -401.906527) (xy 378.982355 -401.860261) (xy 378.959132 -401.81012) (xy 378.943388 -401.757153)
			(xy 378.935452 -401.702467) (xy 378.93498 -401.674838) (xy 378.93498 -400.811238) (xy 378.935434 -400.784893)
			(xy 378.942682 -400.732703) (xy 378.957032 -400.682004) (xy 378.978212 -400.633758) (xy 379.00582 -400.58888)
			(xy 379.039332 -400.54822) (xy 379.058424 -400.53006) (xy 379.065536 -400.52371) (xy 379.073664 -400.506946)
			(xy 379.082046 -400.420332) (xy 379.076966 -400.402552) (xy 379.071378 -400.394678) (xy 379.057231 -400.374829)
			(xy 379.034772 -400.331571) (xy 379.019459 -400.285299) (xy 379.011678 -400.237184) (xy 379.01118 -400.212814)
			(xy 379.011702 -400.187559) (xy 379.020015 -400.137737) (xy 379.036416 -400.089963) (xy 379.060457 -400.04554)
			(xy 379.091481 -400.00568) (xy 379.128643 -399.97147) (xy 379.170929 -399.943844) (xy 379.217185 -399.923554)
			(xy 379.26615 -399.911154) (xy 379.316488 -399.906983) (xy 379.366826 -399.911154) (xy 379.415791 -399.923554)
			(xy 379.462047 -399.943844) (xy 379.504333 -399.97147) (xy 379.541495 -400.00568) (xy 379.572519 -400.04554)
			(xy 379.59656 -400.089963) (xy 379.612961 -400.137737) (xy 379.621274 -400.187559) (xy 379.621796 -400.212814)
			(xy 379.621328 -400.237187) (xy 379.613568 -400.285311) (xy 379.598247 -400.331587) (xy 379.575757 -400.374834)
			(xy 379.561598 -400.394678) (xy 379.55601 -400.402552) (xy 379.55093 -400.420332) (xy 379.559312 -400.506946)
			(xy 379.56744 -400.52371) (xy 379.574552 -400.53006) (xy 379.593655 -400.548209) (xy 379.627177 -400.588866)
			(xy 379.65479 -400.633745) (xy 379.675971 -400.681994) (xy 379.690317 -400.732697) (xy 379.697556 -400.784891)
			(xy 379.697996 -400.811238) (xy 379.697996 -401.674838) (xy 379.697566 -401.702741) (xy 379.689473 -401.757957)
			(xy 379.67342 -401.811405) (xy 379.649751 -401.861943) (xy 379.61897 -401.908492) (xy 379.600714 -401.9296)
			(xy 379.594819 -401.936779) (xy 379.588167 -401.954103) (xy 379.58776 -401.963382) (xy 379.58776 -401.994624)
			(xy 379.58818 -402.003898) (xy 379.594838 -402.021216) (xy 379.600714 -402.028406) (xy 379.619049 -402.049624)
			(xy 379.64995 -402.096419) (xy 379.673718 -402.14721) (xy 379.689848 -402.200917) (xy 379.697997 -402.256399)
			(xy 379.698504 -402.284438) (xy 379.698051 -402.309838) (xy 380.130812 -402.309838) (xy 380.131245 -402.282148)
			(xy 380.139144 -402.227335) (xy 380.15484 -402.174227) (xy 380.178008 -402.123928) (xy 380.208166 -402.077481)
			(xy 380.226062 -402.056346) (xy 380.232412 -402.049488) (xy 380.238762 -402.03247) (xy 380.23927 -401.94738)
			(xy 380.23292 -401.930362) (xy 380.226824 -401.92325) (xy 380.209582 -401.902386) (xy 380.180497 -401.85674)
			(xy 380.158156 -401.807442) (xy 380.143006 -401.755481) (xy 380.135351 -401.7019) (xy 380.134876 -401.674838)
			(xy 380.134876 -400.811238) (xy 380.135294 -400.78491) (xy 380.142545 -400.732755) (xy 380.156901 -400.682094)
			(xy 380.178088 -400.633888) (xy 380.205705 -400.589055) (xy 380.239226 -400.548446) (xy 380.25832 -400.530314)
			(xy 380.265432 -400.52371) (xy 380.273814 -400.5072) (xy 380.281942 -400.420332) (xy 380.276862 -400.402552)
			(xy 380.271274 -400.394932) (xy 380.257115 -400.375052) (xy 380.234629 -400.331737) (xy 380.219312 -400.285399)
			(xy 380.211554 -400.237216) (xy 380.211076 -400.212814) (xy 380.211598 -400.187559) (xy 380.219911 -400.137737)
			(xy 380.236312 -400.089963) (xy 380.260353 -400.04554) (xy 380.291377 -400.00568) (xy 380.328539 -399.97147)
			(xy 380.370825 -399.943844) (xy 380.417081 -399.923554) (xy 380.466046 -399.911154) (xy 380.516384 -399.906983)
			(xy 380.566722 -399.911154) (xy 380.615687 -399.923554) (xy 380.661943 -399.943844) (xy 380.704229 -399.97147)
			(xy 380.741391 -400.00568) (xy 380.772415 -400.04554) (xy 380.796456 -400.089963) (xy 380.812857 -400.137737)
			(xy 380.82117 -400.187559) (xy 380.821692 -400.212814) (xy 380.821205 -400.237173) (xy 380.813491 -400.285276)
			(xy 380.798245 -400.331546) (xy 380.775853 -400.374813) (xy 380.761748 -400.394678) (xy 380.755906 -400.402298)
			(xy 380.75108 -400.420078) (xy 380.759208 -400.506946) (xy 380.76759 -400.523456) (xy 380.774702 -400.53006)
			(xy 380.793827 -400.548203) (xy 380.827417 -400.588831) (xy 380.855091 -400.633698) (xy 380.876321 -400.68195)
			(xy 380.890701 -400.732667) (xy 380.897957 -400.78488) (xy 380.8984 -400.811238) (xy 380.8984 -401.674838)
			(xy 380.897856 -401.702141) (xy 380.890009 -401.756182) (xy 380.874552 -401.808557) (xy 380.851799 -401.858199)
			(xy 380.822214 -401.904098) (xy 380.804674 -401.925028) (xy 380.798578 -401.93214) (xy 380.792228 -401.949158)
			(xy 380.792228 -402.034248) (xy 380.798578 -402.051266) (xy 380.804674 -402.058378) (xy 380.822279 -402.079418)
			(xy 380.851951 -402.12556) (xy 380.87474 -402.175461) (xy 380.89018 -402.228103) (xy 380.897955 -402.282408)
			(xy 380.8984 -402.309838) (xy 381.330708 -402.309838) (xy 381.331142 -402.282148) (xy 381.339041 -402.227335)
			(xy 381.354737 -402.174228) (xy 381.377905 -402.123928) (xy 381.408063 -402.077481) (xy 381.425958 -402.056346)
			(xy 381.432308 -402.049488) (xy 381.438658 -402.03247) (xy 381.439166 -401.94738) (xy 381.432816 -401.930362)
			(xy 381.42672 -401.92325) (xy 381.409477 -401.902386) (xy 381.380393 -401.85674) (xy 381.358051 -401.807442)
			(xy 381.342901 -401.755481) (xy 381.335247 -401.7019) (xy 381.334772 -401.674838) (xy 381.334772 -400.811238)
			(xy 381.335242 -400.784882) (xy 381.342505 -400.732672) (xy 381.356885 -400.68196) (xy 381.378109 -400.633709)
			(xy 381.405771 -400.588838) (xy 381.439346 -400.548202) (xy 381.45847 -400.53006) (xy 381.465582 -400.52371)
			(xy 381.47371 -400.506946) (xy 381.482092 -400.420332) (xy 381.477012 -400.402552) (xy 381.471424 -400.394678)
			(xy 381.45727 -400.374834) (xy 381.434815 -400.331574) (xy 381.419503 -400.2853) (xy 381.411724 -400.237184)
			(xy 381.411226 -400.212814) (xy 381.411748 -400.187559) (xy 381.420061 -400.137737) (xy 381.436462 -400.089963)
			(xy 381.460503 -400.04554) (xy 381.491527 -400.00568) (xy 381.528689 -399.97147) (xy 381.570975 -399.943844)
			(xy 381.617231 -399.923554) (xy 381.666196 -399.911154) (xy 381.716534 -399.906983) (xy 381.766872 -399.911154)
			(xy 381.815837 -399.923554) (xy 381.862093 -399.943844) (xy 381.904379 -399.97147) (xy 381.941541 -400.00568)
			(xy 381.972565 -400.04554) (xy 381.996606 -400.089963) (xy 382.013007 -400.137737) (xy 382.02132 -400.187559)
			(xy 382.021842 -400.212814) (xy 382.021365 -400.237186) (xy 382.013606 -400.28531) (xy 381.998288 -400.331585)
			(xy 381.975801 -400.374833) (xy 381.961644 -400.394678) (xy 381.956056 -400.402552) (xy 381.950976 -400.420332)
			(xy 381.959358 -400.506946) (xy 381.967486 -400.52371) (xy 381.974598 -400.53006) (xy 381.993722 -400.548204)
			(xy 382.027313 -400.588831) (xy 382.054987 -400.633699) (xy 382.076216 -400.68195) (xy 382.090597 -400.732667)
			(xy 382.097853 -400.78488) (xy 382.098296 -400.811238) (xy 382.098296 -401.674838) (xy 382.097753 -401.702141)
			(xy 382.089906 -401.756182) (xy 382.074449 -401.808557) (xy 382.051696 -401.858199) (xy 382.02211 -401.904098)
			(xy 382.00457 -401.925028) (xy 381.998474 -401.93214) (xy 381.992124 -401.949158) (xy 381.992124 -402.034248)
			(xy 381.998474 -402.051266) (xy 382.00457 -402.058378) (xy 382.022175 -402.079418) (xy 382.051847 -402.12556)
			(xy 382.074636 -402.175462) (xy 382.090076 -402.228103) (xy 382.097851 -402.282408) (xy 382.098296 -402.309838)
			(xy 382.530604 -402.309838) (xy 382.531078 -402.28214) (xy 382.539023 -402.227316) (xy 382.554767 -402.174205)
			(xy 382.577983 -402.123908) (xy 382.608189 -402.077472) (xy 382.626108 -402.056346) (xy 382.632458 -402.049488)
			(xy 382.638808 -402.03247) (xy 382.639316 -401.94738) (xy 382.632966 -401.930362) (xy 382.62687 -401.92325)
			(xy 382.609654 -401.902377) (xy 382.580634 -401.856714) (xy 382.558351 -401.807411) (xy 382.54325 -401.755457)
			(xy 382.535635 -401.70189) (xy 382.535176 -401.674838) (xy 382.535176 -400.811238) (xy 382.535616 -400.784922)
			(xy 382.54284 -400.732787) (xy 382.557156 -400.682139) (xy 382.578293 -400.633937) (xy 382.60585 -400.589096)
			(xy 382.639305 -400.548464) (xy 382.658366 -400.530314) (xy 382.665478 -400.52371) (xy 382.67386 -400.5072)
			(xy 382.681988 -400.420332) (xy 382.676908 -400.402552) (xy 382.67132 -400.394932) (xy 382.657167 -400.375048)
			(xy 382.634678 -400.331735) (xy 382.619359 -400.285398) (xy 382.6116 -400.237216) (xy 382.611122 -400.212814)
			(xy 382.611644 -400.187559) (xy 382.619957 -400.137737) (xy 382.636358 -400.089963) (xy 382.660399 -400.04554)
			(xy 382.691423 -400.00568) (xy 382.728585 -399.97147) (xy 382.770871 -399.943844) (xy 382.817127 -399.923554)
			(xy 382.866092 -399.911154) (xy 382.91643 -399.906983) (xy 382.966768 -399.911154) (xy 383.015733 -399.923554)
			(xy 383.061989 -399.943844) (xy 383.104275 -399.97147) (xy 383.141437 -400.00568) (xy 383.172461 -400.04554)
			(xy 383.196502 -400.089963) (xy 383.212903 -400.137737) (xy 383.221216 -400.187559) (xy 383.221738 -400.212814)
			(xy 383.221243 -400.237172) (xy 383.21353 -400.285275) (xy 383.198287 -400.331545) (xy 383.175898 -400.374812)
			(xy 383.161794 -400.394678) (xy 383.155952 -400.402298) (xy 383.151126 -400.420078) (xy 383.159254 -400.506946)
			(xy 383.167636 -400.523456) (xy 383.174748 -400.53006) (xy 383.193851 -400.54821) (xy 383.227372 -400.588866)
			(xy 383.254985 -400.633745) (xy 383.276167 -400.681994) (xy 383.290513 -400.732697) (xy 383.297752 -400.784891)
			(xy 383.298192 -400.811238) (xy 383.298192 -401.674838) (xy 383.297732 -401.702138) (xy 383.289955 -401.75618)
			(xy 383.274551 -401.808561) (xy 383.251835 -401.85821) (xy 383.222271 -401.904113) (xy 383.20472 -401.925028)
			(xy 383.198624 -401.93214) (xy 383.192274 -401.949158) (xy 383.192274 -402.034248) (xy 383.198624 -402.051266)
			(xy 383.20472 -402.058378) (xy 383.22233 -402.079422) (xy 383.252025 -402.125562) (xy 383.274852 -402.175459)
			(xy 383.290346 -402.228096) (xy 383.298192 -402.282403) (xy 383.2987 -402.309838) (xy 383.7305 -402.309838)
			(xy 383.730975 -402.28214) (xy 383.73892 -402.227317) (xy 383.754664 -402.174205) (xy 383.777879 -402.123909)
			(xy 383.808085 -402.077472) (xy 383.826004 -402.056346) (xy 383.832354 -402.049488) (xy 383.838704 -402.03247)
			(xy 383.839212 -401.94738) (xy 383.832862 -401.930362) (xy 383.826766 -401.92325) (xy 383.809549 -401.902378)
			(xy 383.780529 -401.856714) (xy 383.758246 -401.807411) (xy 383.743146 -401.755457) (xy 383.735531 -401.701891)
			(xy 383.735072 -401.674838) (xy 383.735072 -400.811238) (xy 383.735529 -400.784893) (xy 383.742777 -400.732704)
			(xy 383.757127 -400.682005) (xy 383.778306 -400.633759) (xy 383.805913 -400.58888) (xy 383.839425 -400.54822)
			(xy 383.858516 -400.53006) (xy 383.865628 -400.52371) (xy 383.873756 -400.506946) (xy 383.882138 -400.420332)
			(xy 383.877058 -400.402552) (xy 383.87147 -400.394678) (xy 383.857322 -400.37483) (xy 383.834864 -400.331572)
			(xy 383.819551 -400.285299) (xy 383.81177 -400.237184) (xy 383.811272 -400.212814) (xy 383.811794 -400.187559)
			(xy 383.820107 -400.137737) (xy 383.836508 -400.089963) (xy 383.860549 -400.04554) (xy 383.891573 -400.00568)
			(xy 383.928735 -399.97147) (xy 383.971021 -399.943844) (xy 384.017277 -399.923554) (xy 384.066242 -399.911154)
			(xy 384.11658 -399.906983) (xy 384.166918 -399.911154) (xy 384.215883 -399.923554) (xy 384.262139 -399.943844)
			(xy 384.304425 -399.97147) (xy 384.341587 -400.00568) (xy 384.372611 -400.04554) (xy 384.396652 -400.089963)
			(xy 384.413053 -400.137737) (xy 384.421366 -400.187559) (xy 384.421888 -400.212814) (xy 384.421422 -400.237187)
			(xy 384.413661 -400.285311) (xy 384.39834 -400.331587) (xy 384.37585 -400.374834) (xy 384.36169 -400.394678)
			(xy 384.356102 -400.402552) (xy 384.351022 -400.420332) (xy 384.359404 -400.506946) (xy 384.367532 -400.52371)
			(xy 384.374644 -400.53006) (xy 384.393746 -400.548211) (xy 384.427267 -400.588867) (xy 384.454881 -400.633746)
			(xy 384.476062 -400.681995) (xy 384.490409 -400.732697) (xy 384.497648 -400.784891) (xy 384.498088 -400.811238)
			(xy 384.498088 -401.674838) (xy 384.497629 -401.702138) (xy 384.489852 -401.75618) (xy 384.474448 -401.808561)
			(xy 384.451732 -401.858211) (xy 384.422167 -401.904113) (xy 384.404616 -401.925028) (xy 384.39852 -401.93214)
			(xy 384.39217 -401.949158) (xy 384.39217 -402.034248) (xy 384.39852 -402.051266) (xy 384.404616 -402.058378)
			(xy 384.422225 -402.079422) (xy 384.451921 -402.125562) (xy 384.474748 -402.175459) (xy 384.490242 -402.228096)
			(xy 384.494712 -402.259038) (xy 384.930396 -402.259038) (xy 384.930818 -402.232173) (xy 384.93832 -402.178968)
			(xy 384.953169 -402.127329) (xy 384.975074 -402.078266) (xy 385.003608 -402.032738) (xy 385.020566 -402.011896)
			(xy 385.025953 -402.004934) (xy 385.032049 -401.98843) (xy 385.032504 -401.979638) (xy 385.032758 -401.949158)
			(xy 385.032463 -401.940309) (xy 385.026479 -401.923658) (xy 385.021074 -401.916646) (xy 385.004832 -401.896098)
			(xy 384.977568 -401.851375) (xy 384.956666 -401.803348) (xy 384.942517 -401.752918) (xy 384.935388 -401.701027)
			(xy 384.934968 -401.674838) (xy 384.934968 -400.811238) (xy 384.935426 -400.784893) (xy 384.942674 -400.732704)
			(xy 384.957024 -400.682005) (xy 384.978203 -400.633759) (xy 385.00581 -400.58888) (xy 385.039321 -400.54822)
			(xy 385.058412 -400.53006) (xy 385.065524 -400.52371) (xy 385.073652 -400.506946) (xy 385.082034 -400.420332)
			(xy 385.076954 -400.402552) (xy 385.071366 -400.394678) (xy 385.057218 -400.37483) (xy 385.034759 -400.331572)
			(xy 385.019446 -400.285299) (xy 385.011666 -400.237184) (xy 385.011168 -400.212814) (xy 385.01169 -400.187559)
			(xy 385.020003 -400.137737) (xy 385.036404 -400.089963) (xy 385.060445 -400.04554) (xy 385.091469 -400.00568)
			(xy 385.128631 -399.97147) (xy 385.170917 -399.943844) (xy 385.217173 -399.923554) (xy 385.266138 -399.911154)
			(xy 385.316476 -399.906983) (xy 385.366814 -399.911154) (xy 385.415779 -399.923554) (xy 385.462035 -399.943844)
			(xy 385.504321 -399.97147) (xy 385.541483 -400.00568) (xy 385.572507 -400.04554) (xy 385.596548 -400.089963)
			(xy 385.612949 -400.137737) (xy 385.621262 -400.187559) (xy 385.621784 -400.212814) (xy 385.621319 -400.237187)
			(xy 385.613558 -400.285311) (xy 385.598237 -400.331587) (xy 385.575746 -400.374834) (xy 385.561586 -400.394678)
			(xy 385.555998 -400.402552) (xy 385.550918 -400.420332) (xy 385.5593 -400.506946) (xy 385.567428 -400.52371)
			(xy 385.57454 -400.53006) (xy 385.593641 -400.548212) (xy 385.627163 -400.588867) (xy 385.654777 -400.633746)
			(xy 385.675958 -400.681995) (xy 385.690305 -400.732697) (xy 385.697544 -400.784891) (xy 385.697984 -400.811238)
			(xy 385.697984 -401.674838) (xy 385.697552 -401.701295) (xy 385.690275 -401.753706) (xy 385.675825 -401.804609)
			(xy 385.654478 -401.853026) (xy 385.626645 -401.898028) (xy 385.6101 -401.918678) (xy 385.604772 -401.925732)
			(xy 385.598797 -401.942358) (xy 385.598416 -401.95119) (xy 385.598416 -401.98167) (xy 385.598808 -401.990444)
			(xy 385.604774 -402.006946) (xy 385.6101 -402.013928) (xy 385.626737 -402.034682) (xy 385.654709 -402.079924)
			(xy 385.676169 -402.128594) (xy 385.690706 -402.17976) (xy 385.698043 -402.232442) (xy 385.698492 -402.259038)
			(xy 385.698003 -402.286471) (xy 385.694643 -402.309838) (xy 386.130292 -402.309838) (xy 386.130769 -402.28214)
			(xy 386.138714 -402.227317) (xy 386.154457 -402.174205) (xy 386.177672 -402.123909) (xy 386.207877 -402.077473)
			(xy 386.225796 -402.056346) (xy 386.232146 -402.049488) (xy 386.238496 -402.03247) (xy 386.239004 -401.94738)
			(xy 386.232654 -401.930362) (xy 386.226558 -401.92325) (xy 386.20934 -401.902379) (xy 386.180321 -401.856715)
			(xy 386.158038 -401.807412) (xy 386.142938 -401.755457) (xy 386.135323 -401.701891) (xy 386.134864 -401.674838)
			(xy 386.134864 -400.811238) (xy 386.135324 -400.784893) (xy 386.142571 -400.732704) (xy 386.156921 -400.682005)
			(xy 386.1781 -400.633759) (xy 386.205706 -400.588881) (xy 386.239217 -400.54822) (xy 386.258308 -400.53006)
			(xy 386.26542 -400.52371) (xy 386.273548 -400.506946) (xy 386.28193 -400.420332) (xy 386.27685 -400.402552)
			(xy 386.271262 -400.394678) (xy 386.257113 -400.37483) (xy 386.234655 -400.331572) (xy 386.219342 -400.285299)
			(xy 386.211562 -400.237184) (xy 386.211064 -400.212814) (xy 386.211586 -400.187559) (xy 386.219899 -400.137737)
			(xy 386.2363 -400.089963) (xy 386.260341 -400.04554) (xy 386.291365 -400.00568) (xy 386.328527 -399.97147)
			(xy 386.370813 -399.943844) (xy 386.417069 -399.923554) (xy 386.466034 -399.911154) (xy 386.516372 -399.906983)
			(xy 386.56671 -399.911154) (xy 386.615675 -399.923554) (xy 386.661931 -399.943844) (xy 386.704217 -399.97147)
			(xy 386.741379 -400.00568) (xy 386.772403 -400.04554) (xy 386.796444 -400.089963) (xy 386.812845 -400.137737)
			(xy 386.821158 -400.187559) (xy 386.82168 -400.212814) (xy 386.821215 -400.237187) (xy 386.813455 -400.285311)
			(xy 386.798133 -400.331587) (xy 386.775642 -400.374834) (xy 386.761482 -400.394678) (xy 386.755894 -400.402552)
			(xy 386.750814 -400.420332) (xy 386.759196 -400.506946) (xy 386.767324 -400.52371) (xy 386.774436 -400.53006)
			(xy 386.793536 -400.548213) (xy 386.827058 -400.588868) (xy 386.854672 -400.633746) (xy 386.875854 -400.681995)
			(xy 386.890201 -400.732698) (xy 386.89744 -400.784891) (xy 386.89788 -400.811238) (xy 386.89788 -401.674838)
			(xy 386.897423 -401.702138) (xy 386.889646 -401.75618) (xy 386.874241 -401.808562) (xy 386.851525 -401.858211)
			(xy 386.82196 -401.904113) (xy 386.804408 -401.925028) (xy 386.798312 -401.93214) (xy 386.791962 -401.949158)
			(xy 386.791962 -402.034248) (xy 386.798312 -402.051266) (xy 386.804408 -402.058378) (xy 386.822016 -402.079423)
			(xy 386.851712 -402.125563) (xy 386.87454 -402.175459) (xy 386.890034 -402.228097) (xy 386.89788 -402.282403)
			(xy 386.898388 -402.309838) (xy 387.330696 -402.309838) (xy 387.331133 -402.282148) (xy 387.339032 -402.227336)
			(xy 387.354727 -402.174228) (xy 387.377894 -402.123928) (xy 387.408051 -402.077481) (xy 387.425946 -402.056346)
			(xy 387.432296 -402.049488) (xy 387.438646 -402.03247) (xy 387.439154 -401.94738) (xy 387.432804 -401.930362)
			(xy 387.426708 -401.92325) (xy 387.409463 -401.902388) (xy 387.38038 -401.856741) (xy 387.358039 -401.807442)
			(xy 387.342889 -401.755481) (xy 387.335235 -401.7019) (xy 387.33476 -401.674838) (xy 387.33476 -400.811238)
			(xy 387.335233 -400.784882) (xy 387.342497 -400.732673) (xy 387.356877 -400.68196) (xy 387.378099 -400.633709)
			(xy 387.405761 -400.588839) (xy 387.439335 -400.548202) (xy 387.458458 -400.53006) (xy 387.46557 -400.52371)
			(xy 387.473698 -400.506946) (xy 387.48208 -400.420332) (xy 387.477 -400.402552) (xy 387.471412 -400.394678)
			(xy 387.457257 -400.374835) (xy 387.434802 -400.331574) (xy 387.419491 -400.2853) (xy 387.411712 -400.237184)
			(xy 387.411214 -400.212814) (xy 387.411736 -400.187559) (xy 387.420049 -400.137737) (xy 387.43645 -400.089963)
			(xy 387.460491 -400.04554) (xy 387.491515 -400.00568) (xy 387.528677 -399.97147) (xy 387.570963 -399.943844)
			(xy 387.617219 -399.923554) (xy 387.666184 -399.911154) (xy 387.716522 -399.906983) (xy 387.76686 -399.911154)
			(xy 387.815825 -399.923554) (xy 387.862081 -399.943844) (xy 387.904367 -399.97147) (xy 387.941529 -400.00568)
			(xy 387.972553 -400.04554) (xy 387.996594 -400.089963) (xy 388.012995 -400.137737) (xy 388.021308 -400.187559)
			(xy 388.02183 -400.212814) (xy 388.021356 -400.237187) (xy 388.013596 -400.28531) (xy 387.998278 -400.331586)
			(xy 387.97579 -400.374834) (xy 387.961632 -400.394678) (xy 387.956044 -400.402552) (xy 387.950964 -400.420332)
			(xy 387.959346 -400.506946) (xy 387.967474 -400.52371) (xy 387.974586 -400.53006) (xy 387.993727 -400.548187)
			(xy 388.027313 -400.58882) (xy 388.054982 -400.633691) (xy 388.076208 -400.681946) (xy 388.090586 -400.732664)
			(xy 388.097841 -400.78488) (xy 388.098284 -400.811238) (xy 388.098284 -401.674838) (xy 388.097744 -401.702141)
			(xy 388.089897 -401.756183) (xy 388.074439 -401.808557) (xy 388.051685 -401.858199) (xy 388.022099 -401.904098)
			(xy 388.004558 -401.925028) (xy 387.998462 -401.93214) (xy 387.992112 -401.949158) (xy 387.992112 -402.034248)
			(xy 387.998462 -402.051266) (xy 388.004558 -402.058378) (xy 388.022161 -402.07942) (xy 388.051834 -402.125561)
			(xy 388.074623 -402.175462) (xy 388.090064 -402.228103) (xy 388.097839 -402.282408) (xy 388.097872 -402.284438)
			(xy 388.530592 -402.284438) (xy 388.531072 -402.256162) (xy 388.539358 -402.200221) (xy 388.555756 -402.1461)
			(xy 388.579912 -402.094967) (xy 388.611304 -402.047929) (xy 388.629906 -402.026628) (xy 388.635828 -402.01945)
			(xy 388.642603 -402.002136) (xy 388.643114 -401.992846) (xy 388.643368 -401.961604) (xy 388.642941 -401.952269)
			(xy 388.63631 -401.934817) (xy 388.630414 -401.927568) (xy 388.612445 -401.906559) (xy 388.582167 -401.860307)
			(xy 388.558889 -401.810164) (xy 388.543103 -401.757184) (xy 388.535137 -401.702479) (xy 388.534656 -401.674838)
			(xy 388.534656 -400.811238) (xy 388.535131 -400.784882) (xy 388.542394 -400.732673) (xy 388.556774 -400.681961)
			(xy 388.577996 -400.63371) (xy 388.605657 -400.588839) (xy 388.639231 -400.548202) (xy 388.658354 -400.53006)
			(xy 388.665466 -400.52371) (xy 388.673594 -400.506946) (xy 388.681976 -400.420332) (xy 388.676896 -400.402552)
			(xy 388.671308 -400.394678) (xy 388.657165 -400.374826) (xy 388.634704 -400.33157) (xy 388.619389 -400.285298)
			(xy 388.611609 -400.237184) (xy 388.61111 -400.212814) (xy 388.611632 -400.187559) (xy 388.619945 -400.137737)
			(xy 388.636346 -400.089963) (xy 388.660387 -400.04554) (xy 388.691411 -400.00568) (xy 388.728573 -399.97147)
			(xy 388.770859 -399.943844) (xy 388.817115 -399.923554) (xy 388.86608 -399.911154) (xy 388.916418 -399.906983)
			(xy 388.966756 -399.911154) (xy 389.015721 -399.923554) (xy 389.061977 -399.943844) (xy 389.104263 -399.97147)
			(xy 389.141425 -400.00568) (xy 389.172449 -400.04554) (xy 389.19649 -400.089963) (xy 389.212891 -400.137737)
			(xy 389.221204 -400.187559) (xy 389.221726 -400.212814) (xy 389.221252 -400.237187) (xy 389.213493 -400.28531)
			(xy 389.198174 -400.331586) (xy 389.175686 -400.374834) (xy 389.161528 -400.394678) (xy 389.15594 -400.402552)
			(xy 389.15086 -400.420332) (xy 389.159242 -400.506946) (xy 389.16737 -400.52371) (xy 389.174482 -400.53006)
			(xy 389.193622 -400.548188) (xy 389.227208 -400.58882) (xy 389.254878 -400.633692) (xy 389.276104 -400.681946)
			(xy 389.290482 -400.732664) (xy 389.297737 -400.78488) (xy 389.29818 -400.811238) (xy 389.29818 -401.461986)
			(xy 389.298587 -401.470959) (xy 389.304815 -401.487792) (xy 389.316448 -401.50146) (xy 389.324088 -401.506182)
			(xy 389.413496 -401.55622) (xy 389.441182 -401.555712) (xy 389.452866 -401.548346) (xy 389.475529 -401.534906)
			(xy 389.523781 -401.513738) (xy 389.574482 -401.499396) (xy 389.626673 -401.49215) (xy 389.653018 -401.491704)
			(xy 389.680269 -401.492167) (xy 389.734217 -401.499926) (xy 389.786511 -401.515283) (xy 389.836087 -401.537926)
			(xy 389.881937 -401.567394) (xy 389.923126 -401.603086) (xy 389.958817 -401.644277) (xy 389.988283 -401.690128)
			(xy 390.010923 -401.739706) (xy 390.026278 -401.792001) (xy 390.034034 -401.845949) (xy 390.034034 -401.900451)
			(xy 390.026278 -401.954399) (xy 390.010923 -402.006694) (xy 389.988283 -402.056272) (xy 389.958817 -402.102123)
			(xy 389.923126 -402.143314) (xy 389.881937 -402.179006) (xy 389.836087 -402.208474) (xy 389.786511 -402.231117)
			(xy 389.734217 -402.246474) (xy 389.680269 -402.254233) (xy 389.653018 -402.25472) (xy 389.626705 -402.254268)
			(xy 389.574583 -402.246998) (xy 389.52395 -402.232647) (xy 389.475764 -402.211488) (xy 389.45312 -402.198078)
			(xy 389.441182 -402.190712) (xy 389.414004 -402.190204) (xy 389.31215 -402.2471) (xy 389.298434 -402.270722)
			(xy 389.29818 -402.284692) (xy 389.297723 -402.312096) (xy 389.289885 -402.366342) (xy 389.27441 -402.418921)
			(xy 389.251614 -402.468765) (xy 389.221959 -402.514858) (xy 389.186048 -402.556265) (xy 389.144613 -402.592142)
			(xy 389.098496 -402.621761) (xy 389.048634 -402.644517) (xy 388.996043 -402.65995) (xy 388.941791 -402.667745)
			(xy 388.914386 -402.668232) (xy 388.886973 -402.667718) (xy 388.832705 -402.659914) (xy 388.7801 -402.644467)
			(xy 388.730228 -402.621692) (xy 388.684105 -402.592051) (xy 388.642669 -402.556148) (xy 388.606764 -402.514715)
			(xy 388.57712 -402.468593) (xy 388.554341 -402.418723) (xy 388.538891 -402.366119) (xy 388.531084 -402.311851)
			(xy 388.530592 -402.284438) (xy 388.097872 -402.284438) (xy 388.098284 -402.309838) (xy 388.097795 -402.337253)
			(xy 388.089992 -402.391523) (xy 388.074545 -402.444131) (xy 388.051768 -402.494006) (xy 388.022125 -402.540131)
			(xy 387.98622 -402.581568) (xy 387.944783 -402.617473) (xy 387.898658 -402.647116) (xy 387.848783 -402.669893)
			(xy 387.796175 -402.68534) (xy 387.741905 -402.693143) (xy 387.687075 -402.693143) (xy 387.632805 -402.68534)
			(xy 387.580197 -402.669893) (xy 387.530322 -402.647116) (xy 387.484197 -402.617473) (xy 387.44276 -402.581568)
			(xy 387.406855 -402.540131) (xy 387.377212 -402.494006) (xy 387.354435 -402.444131) (xy 387.338988 -402.391523)
			(xy 387.331185 -402.337253) (xy 387.330696 -402.309838) (xy 386.898388 -402.309838) (xy 386.897899 -402.337271)
			(xy 386.890091 -402.391578) (xy 386.874633 -402.44422) (xy 386.851841 -402.494128) (xy 386.822179 -402.540283)
			(xy 386.78625 -402.581748) (xy 386.744785 -402.617677) (xy 386.69863 -402.647339) (xy 386.648722 -402.670131)
			(xy 386.59608 -402.685589) (xy 386.541773 -402.693397) (xy 386.486907 -402.693397) (xy 386.4326 -402.685589)
			(xy 386.379958 -402.670131) (xy 386.33005 -402.647339) (xy 386.283895 -402.617677) (xy 386.24243 -402.581748)
			(xy 386.206501 -402.540283) (xy 386.176839 -402.494128) (xy 386.154047 -402.44422) (xy 386.138589 -402.391578)
			(xy 386.130781 -402.337271) (xy 386.130292 -402.309838) (xy 385.694643 -402.309838) (xy 385.690195 -402.340778)
			(xy 385.674737 -402.39342) (xy 385.651945 -402.443328) (xy 385.622283 -402.489483) (xy 385.586354 -402.530948)
			(xy 385.544889 -402.566877) (xy 385.498734 -402.596539) (xy 385.448826 -402.619331) (xy 385.396184 -402.634789)
			(xy 385.341877 -402.642597) (xy 385.287011 -402.642597) (xy 385.232704 -402.634789) (xy 385.180062 -402.619331)
			(xy 385.130154 -402.596539) (xy 385.083999 -402.566877) (xy 385.042534 -402.530948) (xy 385.006605 -402.489483)
			(xy 384.976943 -402.443328) (xy 384.954151 -402.39342) (xy 384.938693 -402.340778) (xy 384.930885 -402.286471)
			(xy 384.930396 -402.259038) (xy 384.494712 -402.259038) (xy 384.498088 -402.282403) (xy 384.498596 -402.309838)
			(xy 384.498107 -402.337271) (xy 384.490299 -402.391578) (xy 384.474841 -402.44422) (xy 384.452049 -402.494128)
			(xy 384.422387 -402.540283) (xy 384.386458 -402.581748) (xy 384.344993 -402.617677) (xy 384.298838 -402.647339)
			(xy 384.24893 -402.670131) (xy 384.196288 -402.685589) (xy 384.141981 -402.693397) (xy 384.087115 -402.693397)
			(xy 384.032808 -402.685589) (xy 383.980166 -402.670131) (xy 383.930258 -402.647339) (xy 383.884103 -402.617677)
			(xy 383.842638 -402.581748) (xy 383.806709 -402.540283) (xy 383.777047 -402.494128) (xy 383.754255 -402.44422)
			(xy 383.738797 -402.391578) (xy 383.730989 -402.337271) (xy 383.7305 -402.309838) (xy 383.2987 -402.309838)
			(xy 383.298211 -402.337271) (xy 383.290403 -402.391578) (xy 383.274945 -402.44422) (xy 383.252153 -402.494128)
			(xy 383.222491 -402.540283) (xy 383.186562 -402.581748) (xy 383.145097 -402.617677) (xy 383.098942 -402.647339)
			(xy 383.049034 -402.670131) (xy 382.996392 -402.685589) (xy 382.942085 -402.693397) (xy 382.887219 -402.693397)
			(xy 382.832912 -402.685589) (xy 382.78027 -402.670131) (xy 382.730362 -402.647339) (xy 382.684207 -402.617677)
			(xy 382.642742 -402.581748) (xy 382.606813 -402.540283) (xy 382.577151 -402.494128) (xy 382.554359 -402.44422)
			(xy 382.538901 -402.391578) (xy 382.531093 -402.337271) (xy 382.530604 -402.309838) (xy 382.098296 -402.309838)
			(xy 382.097807 -402.337253) (xy 382.090004 -402.391523) (xy 382.074557 -402.444131) (xy 382.05178 -402.494006)
			(xy 382.022137 -402.540131) (xy 381.986232 -402.581568) (xy 381.944795 -402.617473) (xy 381.89867 -402.647116)
			(xy 381.848795 -402.669893) (xy 381.796187 -402.68534) (xy 381.741917 -402.693143) (xy 381.687087 -402.693143)
			(xy 381.632817 -402.68534) (xy 381.580209 -402.669893) (xy 381.530334 -402.647116) (xy 381.484209 -402.617473)
			(xy 381.442772 -402.581568) (xy 381.406867 -402.540131) (xy 381.377224 -402.494006) (xy 381.354447 -402.444131)
			(xy 381.339 -402.391523) (xy 381.331197 -402.337253) (xy 381.330708 -402.309838) (xy 380.8984 -402.309838)
			(xy 380.897911 -402.337253) (xy 380.890108 -402.391523) (xy 380.874661 -402.444131) (xy 380.851884 -402.494006)
			(xy 380.822241 -402.540131) (xy 380.786336 -402.581568) (xy 380.744899 -402.617473) (xy 380.698774 -402.647116)
			(xy 380.648899 -402.669893) (xy 380.596291 -402.68534) (xy 380.542021 -402.693143) (xy 380.487191 -402.693143)
			(xy 380.432921 -402.68534) (xy 380.380313 -402.669893) (xy 380.330438 -402.647116) (xy 380.284313 -402.617473)
			(xy 380.242876 -402.581568) (xy 380.206971 -402.540131) (xy 380.177328 -402.494006) (xy 380.154551 -402.444131)
			(xy 380.139104 -402.391523) (xy 380.131301 -402.337253) (xy 380.130812 -402.309838) (xy 379.698051 -402.309838)
			(xy 379.698015 -402.311871) (xy 379.690207 -402.366178) (xy 379.674749 -402.41882) (xy 379.651957 -402.468728)
			(xy 379.622295 -402.514883) (xy 379.586366 -402.556348) (xy 379.544901 -402.592277) (xy 379.498746 -402.621939)
			(xy 379.448838 -402.644731) (xy 379.396196 -402.660189) (xy 379.341889 -402.667997) (xy 379.287023 -402.667997)
			(xy 379.232716 -402.660189) (xy 379.180074 -402.644731) (xy 379.130166 -402.621939) (xy 379.084011 -402.592277)
			(xy 379.042546 -402.556348) (xy 379.006617 -402.514883) (xy 378.976955 -402.468728) (xy 378.954163 -402.41882)
			(xy 378.938705 -402.366178) (xy 378.930897 -402.311871) (xy 378.930408 -402.284438) (xy 378.498155 -402.284438)
			(xy 378.498119 -402.286471) (xy 378.490311 -402.340778) (xy 378.474853 -402.39342) (xy 378.452061 -402.443328)
			(xy 378.422399 -402.489483) (xy 378.38647 -402.530948) (xy 378.345005 -402.566877) (xy 378.29885 -402.596539)
			(xy 378.248942 -402.619331) (xy 378.1963 -402.634789) (xy 378.141993 -402.642597) (xy 378.087127 -402.642597)
			(xy 378.03282 -402.634789) (xy 377.980178 -402.619331) (xy 377.93027 -402.596539) (xy 377.884115 -402.566877)
			(xy 377.84265 -402.530948) (xy 377.806721 -402.489483) (xy 377.777059 -402.443328) (xy 377.754267 -402.39342)
			(xy 377.738809 -402.340778) (xy 377.731001 -402.286471) (xy 377.730512 -402.259038) (xy 377.294413 -402.259038)
			(xy 377.297759 -402.282408) (xy 377.298204 -402.309838) (xy 377.297715 -402.337253) (xy 377.289912 -402.391523)
			(xy 377.274465 -402.444131) (xy 377.251688 -402.494006) (xy 377.222045 -402.540131) (xy 377.18614 -402.581568)
			(xy 377.144703 -402.617473) (xy 377.098578 -402.647116) (xy 377.048703 -402.669893) (xy 376.996095 -402.68534)
			(xy 376.941825 -402.693143) (xy 376.886995 -402.693143) (xy 376.832725 -402.68534) (xy 376.780117 -402.669893)
			(xy 376.730242 -402.647116) (xy 376.684117 -402.617473) (xy 376.64268 -402.581568) (xy 376.606775 -402.540131)
			(xy 376.577132 -402.494006) (xy 376.554355 -402.444131) (xy 376.538908 -402.391523) (xy 376.531105 -402.337253)
			(xy 376.530616 -402.309838) (xy 376.098308 -402.309838) (xy 376.097819 -402.337253) (xy 376.090016 -402.391523)
			(xy 376.074569 -402.444131) (xy 376.051792 -402.494006) (xy 376.022149 -402.540131) (xy 375.986244 -402.581568)
			(xy 375.944807 -402.617473) (xy 375.898682 -402.647116) (xy 375.848807 -402.669893) (xy 375.796199 -402.68534)
			(xy 375.741929 -402.693143) (xy 375.687099 -402.693143) (xy 375.632829 -402.68534) (xy 375.580221 -402.669893)
			(xy 375.530346 -402.647116) (xy 375.484221 -402.617473) (xy 375.442784 -402.581568) (xy 375.406879 -402.540131)
			(xy 375.377236 -402.494006) (xy 375.354459 -402.444131) (xy 375.339012 -402.391523) (xy 375.331209 -402.337253)
			(xy 375.33072 -402.309838) (xy 374.894563 -402.309838) (xy 374.890115 -402.340778) (xy 374.874657 -402.39342)
			(xy 374.851865 -402.443328) (xy 374.822203 -402.489483) (xy 374.786274 -402.530948) (xy 374.744809 -402.566877)
			(xy 374.698654 -402.596539) (xy 374.648746 -402.619331) (xy 374.596104 -402.634789) (xy 374.541797 -402.642597)
			(xy 374.486931 -402.642597) (xy 374.432624 -402.634789) (xy 374.379982 -402.619331) (xy 374.330074 -402.596539)
			(xy 374.283919 -402.566877) (xy 374.242454 -402.530948) (xy 374.206525 -402.489483) (xy 374.176863 -402.443328)
			(xy 374.154071 -402.39342) (xy 374.138613 -402.340778) (xy 374.130805 -402.286471) (xy 374.130316 -402.259038)
			(xy 373.694633 -402.259038) (xy 373.698008 -402.282403) (xy 373.698516 -402.309838) (xy 373.698027 -402.337271)
			(xy 373.690219 -402.391578) (xy 373.674761 -402.44422) (xy 373.651969 -402.494128) (xy 373.622307 -402.540283)
			(xy 373.586378 -402.581748) (xy 373.544913 -402.617677) (xy 373.498758 -402.647339) (xy 373.44885 -402.670131)
			(xy 373.396208 -402.685589) (xy 373.341901 -402.693397) (xy 373.287035 -402.693397) (xy 373.232728 -402.685589)
			(xy 373.180086 -402.670131) (xy 373.130178 -402.647339) (xy 373.084023 -402.617677) (xy 373.042558 -402.581748)
			(xy 373.006629 -402.540283) (xy 372.976967 -402.494128) (xy 372.954175 -402.44422) (xy 372.938717 -402.391578)
			(xy 372.930909 -402.337271) (xy 372.93042 -402.309838) (xy 372.497659 -402.309838) (xy 372.497623 -402.311853)
			(xy 372.48982 -402.366123) (xy 372.474373 -402.418731) (xy 372.451596 -402.468606) (xy 372.421953 -402.514731)
			(xy 372.386048 -402.556168) (xy 372.344611 -402.592073) (xy 372.298486 -402.621716) (xy 372.248611 -402.644493)
			(xy 372.196003 -402.65994) (xy 372.141733 -402.667743) (xy 372.086903 -402.667743) (xy 372.032633 -402.65994)
			(xy 371.980025 -402.644493) (xy 371.93015 -402.621716) (xy 371.884025 -402.592073) (xy 371.842588 -402.556168)
			(xy 371.806683 -402.514731) (xy 371.77704 -402.468606) (xy 371.754263 -402.418731) (xy 371.738816 -402.366123)
			(xy 371.731013 -402.311853) (xy 371.730524 -402.284438) (xy 371.298216 -402.284438) (xy 371.297727 -402.311853)
			(xy 371.289924 -402.366123) (xy 371.274477 -402.418731) (xy 371.2517 -402.468606) (xy 371.222057 -402.514731)
			(xy 371.186152 -402.556168) (xy 371.144715 -402.592073) (xy 371.09859 -402.621716) (xy 371.048715 -402.644493)
			(xy 370.996107 -402.65994) (xy 370.941837 -402.667743) (xy 370.887007 -402.667743) (xy 370.832737 -402.65994)
			(xy 370.780129 -402.644493) (xy 370.730254 -402.621716) (xy 370.684129 -402.592073) (xy 370.642692 -402.556168)
			(xy 370.606787 -402.514731) (xy 370.577144 -402.468606) (xy 370.554367 -402.418731) (xy 370.53892 -402.366123)
			(xy 370.531117 -402.311853) (xy 370.530628 -402.284438) (xy 366.496854 -402.284438) (xy 366.469484 -402.283955)
			(xy 366.415305 -402.276144) (xy 366.362802 -402.26066) (xy 366.313054 -402.237821) (xy 366.267088 -402.208099)
			(xy 366.246156 -402.190458) (xy 366.239044 -402.184362) (xy 366.222026 -402.178012) (xy 366.136682 -402.178012)
			(xy 366.119664 -402.184362) (xy 366.112552 -402.190458) (xy 366.091619 -402.208099) (xy 366.045651 -402.237823)
			(xy 365.995905 -402.260669) (xy 365.943403 -402.276165) (xy 365.889225 -402.283994) (xy 365.834483 -402.283994)
			(xy 365.780305 -402.276165) (xy 365.727803 -402.260669) (xy 365.678057 -402.237823) (xy 365.632089 -402.208099)
			(xy 365.611156 -402.190458) (xy 365.604044 -402.184362) (xy 365.587026 -402.178012) (xy 365.501682 -402.178012)
			(xy 365.484664 -402.184362) (xy 365.477552 -402.190458) (xy 365.456619 -402.208099) (xy 365.410651 -402.237823)
			(xy 365.360905 -402.260669) (xy 365.308403 -402.276165) (xy 365.254225 -402.283994) (xy 365.199483 -402.283994)
			(xy 365.145305 -402.276165) (xy 365.092803 -402.260669) (xy 365.043057 -402.237823) (xy 364.997089 -402.208099)
			(xy 364.976156 -402.190458) (xy 364.969044 -402.184362) (xy 364.952026 -402.178012) (xy 364.866682 -402.178012)
			(xy 364.849664 -402.184362) (xy 364.842552 -402.190458) (xy 364.821606 -402.20808) (xy 364.775638 -402.237796)
			(xy 364.725894 -402.260636) (xy 364.673396 -402.276131) (xy 364.619222 -402.283962) (xy 364.591854 -402.284438)
			(xy 364.564603 -402.283965) (xy 364.510656 -402.276203) (xy 364.458363 -402.260844) (xy 364.408788 -402.238199)
			(xy 364.362939 -402.208731) (xy 364.32175 -402.173038) (xy 364.286059 -402.131848) (xy 364.256593 -402.085998)
			(xy 364.233951 -402.036422) (xy 364.218594 -401.984128) (xy 364.210834 -401.930181) (xy 364.210346 -401.90293)
			(xy 363.355382 -401.90293) (xy 363.354916 -401.933659) (xy 363.347505 -401.994669) (xy 363.332793 -402.054341)
			(xy 363.310996 -402.111805) (xy 363.282432 -402.166222) (xy 363.247517 -402.216799) (xy 363.20676 -402.262799)
			(xy 363.160755 -402.303551) (xy 363.110174 -402.338461) (xy 363.055753 -402.367019) (xy 362.998288 -402.38881)
			(xy 362.938614 -402.403515) (xy 362.877603 -402.41092) (xy 362.846874 -402.411438) (xy 362.809289 -402.410741)
			(xy 362.734943 -402.399645) (xy 362.698792 -402.38934) (xy 362.687362 -402.385784) (xy 362.663486 -402.390102)
			(xy 362.588302 -402.445728) (xy 362.579064 -402.453334) (xy 362.568304 -402.474672) (xy 362.567728 -402.486622)
			(xy 362.567728 -402.734018) (xy 369.305076 -402.734018) (xy 369.309147 -402.678396) (xy 369.321273 -402.623959)
			(xy 369.341196 -402.571868) (xy 369.368492 -402.523233) (xy 369.402578 -402.47909) (xy 369.442727 -402.440381)
			(xy 369.488085 -402.40793) (xy 369.537685 -402.382429) (xy 369.590469 -402.364422) (xy 369.645312 -402.354292)
			(xy 369.701046 -402.352255) (xy 369.756483 -402.358355) (xy 369.81044 -402.372461) (xy 369.861769 -402.394273)
			(xy 369.909375 -402.423327) (xy 369.952243 -402.459002) (xy 369.98946 -402.500539) (xy 370.020233 -402.547052)
			(xy 370.043905 -402.597549) (xy 370.059973 -402.650956) (xy 370.068093 -402.706132) (xy 370.068602 -402.734018)
			(xy 370.068093 -402.761904) (xy 370.059973 -402.81708) (xy 370.043905 -402.870487) (xy 370.020233 -402.920984)
			(xy 369.98946 -402.967497) (xy 369.952243 -403.009034) (xy 369.909375 -403.044709) (xy 369.861769 -403.073763)
			(xy 369.81044 -403.095575) (xy 369.756483 -403.109681) (xy 369.701046 -403.115781) (xy 369.645312 -403.113744)
			(xy 369.590469 -403.103614) (xy 369.537685 -403.085607) (xy 369.488085 -403.060106) (xy 369.442727 -403.027655)
			(xy 369.402578 -402.988946) (xy 369.368492 -402.944803) (xy 369.341196 -402.896168) (xy 369.321273 -402.844077)
			(xy 369.309147 -402.78964) (xy 369.305076 -402.734018) (xy 362.567728 -402.734018) (xy 362.567728 -404.639526)
			(xy 362.568156 -404.649594) (xy 362.575881 -404.668189) (xy 362.582714 -404.675594) (xy 362.844334 -404.937214)
			(xy 362.85173 -404.944065) (xy 362.870329 -404.9518) (xy 362.880402 -404.9522) (xy 367.236502 -404.9522)
			(xy 367.248832 -404.951614) (xy 367.270673 -404.940171) (xy 367.278158 -404.930356) (xy 367.333022 -404.851362)
			(xy 367.335816 -404.826724) (xy 367.331498 -404.814786) (xy 367.321207 -404.786109) (xy 367.306747 -404.726923)
			(xy 367.299449 -404.666434) (xy 367.298986 -404.63597) (xy 367.299488 -404.604009) (xy 367.307499 -404.540591)
			(xy 367.323396 -404.478677) (xy 367.346928 -404.419244) (xy 367.377722 -404.363229) (xy 367.415295 -404.311514)
			(xy 367.459052 -404.264917) (xy 367.508305 -404.224172) (xy 367.562276 -404.189921) (xy 367.620115 -404.162704)
			(xy 367.680908 -404.142951) (xy 367.743698 -404.130973) (xy 367.807494 -404.12696) (xy 367.87129 -404.130973)
			(xy 367.93408 -404.142951) (xy 367.994873 -404.162704) (xy 368.052712 -404.189921) (xy 368.106683 -404.224172)
			(xy 368.155936 -404.264917) (xy 368.199693 -404.311514) (xy 368.237266 -404.363229) (xy 368.26806 -404.419244)
			(xy 368.291592 -404.478677) (xy 368.307489 -404.540591) (xy 368.3155 -404.604009) (xy 368.316002 -404.63597)
			(xy 368.315606 -404.664057) (xy 368.30941 -404.719887) (xy 368.297111 -404.774697) (xy 368.278858 -404.827822)
			(xy 368.267234 -404.853394) (xy 368.262398 -404.86506) (xy 368.263584 -404.890255) (xy 368.26952 -404.9014)
			(xy 368.299746 -404.9522) (xy 368.30254 -404.9522) (xy 369.989354 -406.639014) (xy 369.996751 -406.645861)
			(xy 370.015351 -406.653589) (xy 370.025422 -406.654)
		)
		(stroke
			(width 0)
			(type solid)
		)
		(fill yes)
		(layer "In15.Cu")
		(net "P0V9_CPU0_RT3_2A_2D")
	)
	(gr_poly
		(pts
			(xy 121.823734 -440.719972) (xy 121.831899 -440.718666) (xy 121.846815 -440.711551) (xy 121.852944 -440.706002)
			(xy 123.053348 -439.505598) (xy 123.0602 -439.498202) (xy 123.067942 -439.479603) (xy 123.068334 -439.46953)
			(xy 123.068334 -422.8846) (xy 123.067909 -422.874531) (xy 123.060187 -422.855933) (xy 123.053348 -422.848532)
			(xy 117.606318 -417.401502) (xy 117.585998 -417.393882) (xy 117.574822 -417.394644) (xy 117.539262 -417.395914)
			(xy 117.508532 -417.395448) (xy 117.447522 -417.388035) (xy 117.387849 -417.373324) (xy 117.330385 -417.351527)
			(xy 117.275967 -417.322962) (xy 117.225388 -417.288048) (xy 117.179387 -417.247291) (xy 117.138633 -417.201287)
			(xy 117.103721 -417.150706) (xy 117.07516 -417.096286) (xy 117.053367 -417.03882) (xy 117.038659 -416.979147)
			(xy 117.03125 -416.918136) (xy 117.030754 -416.887406) (xy 117.032024 -416.851846) (xy 117.032786 -416.84067)
			(xy 117.025166 -416.82035) (xy 114.479578 -414.274762) (xy 114.472729 -414.267365) (xy 114.464996 -414.248766)
			(xy 114.464592 -414.238694) (xy 114.464592 -414.232598) (xy 114.444018 -414.217358) (xy 114.437922 -414.212024)
			(xy 113.592864 -413.366966) (xy 113.586219 -413.360855) (xy 113.569823 -413.353328) (xy 113.56086 -413.352234)
			(xy 113.547652 -413.351218) (xy 113.535968 -413.356298) (xy 113.503504 -413.369996) (xy 113.435745 -413.389318)
			(xy 113.365966 -413.399095) (xy 113.330736 -413.399732) (xy 113.330228 -413.399732) (xy 113.29948 -413.399288)
			(xy 113.238432 -413.391878) (xy 113.178723 -413.377164) (xy 113.121223 -413.355359) (xy 113.06677 -413.326781)
			(xy 113.01616 -413.291848) (xy 112.97013 -413.251069) (xy 112.929351 -413.205039) (xy 112.894418 -413.154428)
			(xy 112.865841 -413.099975) (xy 112.844036 -413.042475) (xy 112.829321 -412.982766) (xy 112.821912 -412.921718)
			(xy 112.821466 -412.89097) (xy 112.821948 -412.859248) (xy 112.82983 -412.796296) (xy 112.845479 -412.734812)
			(xy 112.868654 -412.675753) (xy 112.898994 -412.620034) (xy 112.936029 -412.568521) (xy 112.979182 -412.522014)
			(xy 113.027784 -412.481235) (xy 113.081081 -412.446817) (xy 113.138244 -412.419295) (xy 113.198386 -412.399095)
			(xy 113.22939 -412.392368) (xy 113.251234 -412.381954) (xy 113.251488 -412.381954) (xy 113.259878 -412.374334)
			(xy 113.269621 -412.3539) (xy 113.270284 -412.342584) (xy 113.270284 -407.789126) (xy 113.26985 -407.775493)
			(xy 113.262638 -407.749198) (xy 113.248722 -407.725752) (xy 113.229095 -407.706826) (xy 113.205157 -407.693772)
			(xy 113.178617 -407.687521) (xy 113.15137 -407.688521) (xy 113.125359 -407.696698) (xy 113.102442 -407.71147)
			(xy 113.092992 -407.721308) (xy 113.074821 -407.740966) (xy 113.033921 -407.775505) (xy 112.988593 -407.803984)
			(xy 112.939728 -407.825846) (xy 112.888286 -407.840659) (xy 112.835278 -407.848133) (xy 112.808512 -407.848562)
			(xy 112.78124 -407.848099) (xy 112.727252 -407.840339) (xy 112.674918 -407.824973) (xy 112.625303 -407.802316)
			(xy 112.579418 -407.772829) (xy 112.538197 -407.737112) (xy 112.502478 -407.695891) (xy 112.472989 -407.650007)
			(xy 112.450331 -407.600393) (xy 112.434964 -407.548059) (xy 112.427202 -407.494072) (xy 112.427202 -407.439528)
			(xy 112.434964 -407.385541) (xy 112.450331 -407.333207) (xy 112.472989 -407.283593) (xy 112.502478 -407.237709)
			(xy 112.538197 -407.196488) (xy 112.579418 -407.160771) (xy 112.625303 -407.131284) (xy 112.674918 -407.108627)
			(xy 112.727252 -407.093261) (xy 112.78124 -407.085501) (xy 112.808512 -407.085038) (xy 112.835277 -407.08549)
			(xy 112.888281 -407.092971) (xy 112.939719 -407.107785) (xy 112.988583 -407.129642) (xy 113.033914 -407.158111)
			(xy 113.074821 -407.192636) (xy 113.092992 -407.212292) (xy 113.102416 -407.22216) (xy 113.125342 -407.236938)
			(xy 113.151363 -407.245119) (xy 113.178621 -407.246118) (xy 113.205171 -407.239866) (xy 113.229118 -407.226807)
			(xy 113.248753 -407.207873) (xy 113.262675 -407.184417) (xy 113.26989 -407.158112) (xy 113.270284 -407.144474)
			(xy 113.270284 -406.773126) (xy 113.26985 -406.759493) (xy 113.262638 -406.733198) (xy 113.248722 -406.709752)
			(xy 113.229095 -406.690826) (xy 113.205157 -406.677772) (xy 113.178617 -406.671521) (xy 113.15137 -406.672521)
			(xy 113.125359 -406.680698) (xy 113.102442 -406.69547) (xy 113.092992 -406.705308) (xy 113.074821 -406.724966)
			(xy 113.033921 -406.759505) (xy 112.988593 -406.787984) (xy 112.939728 -406.809846) (xy 112.888286 -406.824659)
			(xy 112.835278 -406.832133) (xy 112.808512 -406.832562) (xy 112.78124 -406.832099) (xy 112.727252 -406.824339)
			(xy 112.674918 -406.808973) (xy 112.625303 -406.786316) (xy 112.579418 -406.756829) (xy 112.538197 -406.721112)
			(xy 112.502478 -406.679891) (xy 112.472989 -406.634007) (xy 112.450331 -406.584393) (xy 112.434964 -406.532059)
			(xy 112.427202 -406.478072) (xy 112.427202 -406.423528) (xy 112.434964 -406.369541) (xy 112.450331 -406.317207)
			(xy 112.472989 -406.267593) (xy 112.502478 -406.221709) (xy 112.538197 -406.180488) (xy 112.579418 -406.144771)
			(xy 112.625303 -406.115284) (xy 112.674918 -406.092627) (xy 112.727252 -406.077261) (xy 112.78124 -406.069501)
			(xy 112.808512 -406.069038) (xy 112.835277 -406.06949) (xy 112.888281 -406.076971) (xy 112.939719 -406.091785)
			(xy 112.988583 -406.113642) (xy 113.033914 -406.142111) (xy 113.074821 -406.176636) (xy 113.092992 -406.196292)
			(xy 113.102416 -406.20616) (xy 113.125342 -406.220938) (xy 113.151363 -406.229119) (xy 113.178621 -406.230118)
			(xy 113.205171 -406.223866) (xy 113.229118 -406.210807) (xy 113.248753 -406.191873) (xy 113.262675 -406.168417)
			(xy 113.26989 -406.142112) (xy 113.270284 -406.128474) (xy 113.270284 -405.199596) (xy 113.269817 -405.188874)
			(xy 113.261062 -405.169301) (xy 113.245052 -405.155037) (xy 113.234978 -405.151336) (xy 113.126774 -405.116538)
			(xy 113.095786 -405.126952) (xy 113.08588 -405.140668) (xy 113.066871 -405.16649) (xy 113.023376 -405.213604)
			(xy 112.974303 -405.254876) (xy 112.92043 -405.28965) (xy 112.862612 -405.317374) (xy 112.801767 -405.337608)
			(xy 112.738861 -405.350032) (xy 112.706912 -405.352758) (xy 112.697782 -405.353782) (xy 112.681116 -405.361475)
			(xy 112.6744 -405.367744) (xy 112.653064 -405.389334) (xy 112.638332 -405.421846) (xy 112.635777 -405.453676)
			(xy 112.623718 -405.516383) (xy 112.603903 -405.577087) (xy 112.576643 -405.634832) (xy 112.542367 -405.68871)
			(xy 112.501615 -405.737871) (xy 112.455028 -405.781544) (xy 112.403339 -405.819039) (xy 112.347362 -405.849768)
			(xy 112.287979 -405.873246) (xy 112.226123 -405.889103) (xy 112.162768 -405.897091) (xy 112.13084 -405.897588)
			(xy 112.100107 -405.897145) (xy 112.039088 -405.88974) (xy 111.979407 -405.875034) (xy 111.921934 -405.85324)
			(xy 111.867507 -405.824678) (xy 111.816919 -405.789763) (xy 111.77091 -405.749004) (xy 111.73015 -405.702996)
			(xy 111.695233 -405.652411) (xy 111.666668 -405.597985) (xy 111.644872 -405.540512) (xy 111.630164 -405.480832)
			(xy 111.622757 -405.419813) (xy 111.622332 -405.38908) (xy 111.622821 -405.357249) (xy 111.63076 -405.294085)
			(xy 111.646523 -405.232405) (xy 111.669864 -405.173177) (xy 111.700418 -405.117327) (xy 111.737706 -405.065728)
			(xy 111.781144 -405.019189) (xy 111.830054 -404.978438) (xy 111.883668 -404.944113) (xy 111.94115 -404.91675)
			(xy 112.001597 -404.896779) (xy 112.064066 -404.884511) (xy 112.095788 -404.881842) (xy 112.104918 -404.880818)
			(xy 112.121584 -404.873125) (xy 112.1283 -404.866856) (xy 112.149636 -404.845266) (xy 112.164368 -404.812754)
			(xy 112.166923 -404.780924) (xy 112.178982 -404.718217) (xy 112.198797 -404.657513) (xy 112.226057 -404.599768)
			(xy 112.260333 -404.54589) (xy 112.301085 -404.496729) (xy 112.347672 -404.453056) (xy 112.399361 -404.415561)
			(xy 112.455338 -404.384832) (xy 112.514721 -404.361354) (xy 112.576577 -404.345497) (xy 112.639932 -404.337509)
			(xy 112.67186 -404.337012) (xy 112.702108 -404.337451) (xy 112.762175 -404.344636) (xy 112.820965 -404.358897)
			(xy 112.877648 -404.380033) (xy 112.931422 -404.407745) (xy 112.981529 -404.441643) (xy 113.027259 -404.481245)
			(xy 113.067968 -404.525995) (xy 113.08588 -404.550372) (xy 113.095786 -404.564088) (xy 113.126774 -404.574502)
			(xy 113.234978 -404.539704) (xy 113.24498 -404.535892) (xy 113.260904 -404.521629) (xy 113.269672 -404.50213)
			(xy 113.270284 -404.491444) (xy 113.270284 -403.614128) (xy 113.27072 -403.604063) (xy 113.278451 -403.585476)
			(xy 113.28527 -403.57806) (xy 114.209068 -402.654262) (xy 114.215912 -402.646863) (xy 114.223638 -402.628265)
			(xy 114.224054 -402.618194) (xy 114.224054 -399.838164) (xy 114.223623 -399.828098) (xy 114.215894 -399.809507)
			(xy 114.209068 -399.802096) (xy 113.485168 -399.078196) (xy 113.477767 -399.071355) (xy 113.45917 -399.063633)
			(xy 113.4491 -399.06321) (xy 111.609886 -399.06321) (xy 111.599817 -399.063636) (xy 111.581217 -399.071355)
			(xy 111.573818 -399.078196) (xy 110.21441 -400.437604) (xy 111.592866 -400.437604) (xy 111.596937 -400.381982)
			(xy 111.609063 -400.327545) (xy 111.628986 -400.275454) (xy 111.656282 -400.226819) (xy 111.690368 -400.182676)
			(xy 111.730517 -400.143967) (xy 111.775875 -400.111516) (xy 111.825475 -400.086015) (xy 111.878259 -400.068008)
			(xy 111.933102 -400.057878) (xy 111.988836 -400.055841) (xy 112.044273 -400.061941) (xy 112.09823 -400.076047)
			(xy 112.149559 -400.097859) (xy 112.197165 -400.126913) (xy 112.240033 -400.162588) (xy 112.27725 -400.204125)
			(xy 112.308023 -400.250638) (xy 112.331695 -400.301135) (xy 112.347763 -400.354542) (xy 112.355883 -400.409718)
			(xy 112.356392 -400.437604) (xy 112.355883 -400.46549) (xy 112.347763 -400.520666) (xy 112.331695 -400.574073)
			(xy 112.308023 -400.62457) (xy 112.27725 -400.671083) (xy 112.240033 -400.71262) (xy 112.197165 -400.748295)
			(xy 112.149559 -400.777349) (xy 112.09823 -400.799161) (xy 112.044273 -400.813267) (xy 111.988836 -400.819367)
			(xy 111.933102 -400.81733) (xy 111.878259 -400.8072) (xy 111.825475 -400.789193) (xy 111.775875 -400.763692)
			(xy 111.730517 -400.731241) (xy 111.690368 -400.692532) (xy 111.656282 -400.648389) (xy 111.628986 -400.599754)
			(xy 111.609063 -400.547663) (xy 111.596937 -400.493226) (xy 111.592866 -400.437604) (xy 110.21441 -400.437604)
			(xy 109.406436 -401.245578) (xy 109.398067 -401.254769) (xy 109.39063 -401.278459) (xy 109.392212 -401.29079)
			(xy 109.409738 -401.385532) (xy 109.424978 -401.40509) (xy 109.436662 -401.41017) (xy 109.462369 -401.422307)
			(xy 109.510191 -401.453043) (xy 109.531912 -401.471384) (xy 109.54004 -401.478496) (xy 109.560614 -401.484846)
			(xy 109.656626 -401.473924) (xy 109.674914 -401.463002) (xy 109.681264 -401.454366) (xy 109.699215 -401.430229)
			(xy 109.739911 -401.38593) (xy 109.785551 -401.346744) (xy 109.835497 -401.313218) (xy 109.889051 -401.285822)
			(xy 109.945463 -401.264937) (xy 110.003946 -401.250855) (xy 110.063683 -401.243775) (xy 110.09376 -401.243292)
			(xy 110.125724 -401.243771) (xy 110.189148 -401.251778) (xy 110.251069 -401.267672) (xy 110.310509 -401.291202)
			(xy 110.366531 -401.321997) (xy 110.418252 -401.35957) (xy 110.464855 -401.40333) (xy 110.505606 -401.452586)
			(xy 110.539862 -401.506561) (xy 110.567082 -401.564404) (xy 110.586838 -401.625203) (xy 110.598817 -401.687998)
			(xy 110.602832 -401.7518) (xy 110.601428 -401.774109) (xy 111.742468 -401.774109) (xy 111.742468 -401.710187)
			(xy 111.750479 -401.646769) (xy 111.766376 -401.584855) (xy 111.789908 -401.525422) (xy 111.820702 -401.469407)
			(xy 111.858275 -401.417692) (xy 111.902032 -401.371095) (xy 111.951285 -401.33035) (xy 112.005256 -401.296099)
			(xy 112.063095 -401.268882) (xy 112.123888 -401.249129) (xy 112.186678 -401.237151) (xy 112.250474 -401.233138)
			(xy 112.31427 -401.237151) (xy 112.37706 -401.249129) (xy 112.437853 -401.268882) (xy 112.495692 -401.296099)
			(xy 112.549663 -401.33035) (xy 112.598916 -401.371095) (xy 112.642673 -401.417692) (xy 112.680246 -401.469407)
			(xy 112.71104 -401.525422) (xy 112.734572 -401.584855) (xy 112.750469 -401.646769) (xy 112.75848 -401.710187)
			(xy 112.758982 -401.742148) (xy 112.75848 -401.774109) (xy 112.750469 -401.837527) (xy 112.734572 -401.899441)
			(xy 112.71104 -401.958874) (xy 112.680246 -402.014889) (xy 112.642673 -402.066604) (xy 112.598916 -402.113201)
			(xy 112.549663 -402.153946) (xy 112.495692 -402.188197) (xy 112.437853 -402.215414) (xy 112.37706 -402.235167)
			(xy 112.31427 -402.247145) (xy 112.250474 -402.251159) (xy 112.186678 -402.247145) (xy 112.123888 -402.235167)
			(xy 112.063095 -402.215414) (xy 112.005256 -402.188197) (xy 111.951285 -402.153946) (xy 111.902032 -402.113201)
			(xy 111.858275 -402.066604) (xy 111.820702 -402.014889) (xy 111.789908 -401.958874) (xy 111.766376 -401.899441)
			(xy 111.750479 -401.837527) (xy 111.742468 -401.774109) (xy 110.601428 -401.774109) (xy 110.598817 -401.815602)
			(xy 110.586838 -401.878397) (xy 110.567082 -401.939196) (xy 110.539862 -401.997039) (xy 110.505606 -402.051014)
			(xy 110.464855 -402.10027) (xy 110.418252 -402.14403) (xy 110.366531 -402.181603) (xy 110.310509 -402.212398)
			(xy 110.251069 -402.235928) (xy 110.189148 -402.251822) (xy 110.125724 -402.259829) (xy 110.09376 -402.260308)
			(xy 110.059966 -402.259758) (xy 109.992973 -402.250813) (xy 109.927755 -402.233071) (xy 109.865463 -402.206846)
			(xy 109.807193 -402.172601) (xy 109.753974 -402.130938) (xy 109.706743 -402.082592) (xy 109.68609 -402.055838)
			(xy 109.67974 -402.047202) (xy 109.661198 -402.036788) (xy 109.564932 -402.02739) (xy 109.544612 -402.033994)
			(xy 109.536738 -402.04136) (xy 109.515578 -402.059821) (xy 109.468858 -402.090971) (xy 109.418077 -402.114938)
			(xy 109.364331 -402.131205) (xy 109.308783 -402.13942) (xy 109.280706 -402.139912) (xy 109.252346 -402.139393)
			(xy 109.196253 -402.130994) (xy 109.142021 -402.114381) (xy 109.090847 -402.08992) (xy 109.043861 -402.05815)
			(xy 109.022642 -402.039328) (xy 109.014768 -402.032216) (xy 108.994956 -402.025358) (xy 108.89996 -402.03247)
			(xy 108.881418 -402.042122) (xy 108.87456 -402.050504) (xy 108.853815 -402.07544) (xy 108.807026 -402.120366)
			(xy 108.754903 -402.158978) (xy 108.698293 -402.190646) (xy 108.638115 -402.214858) (xy 108.575347 -402.231221)
			(xy 108.511007 -402.239467) (xy 108.478574 -402.239988) (xy 108.438696 -402.238464) (xy 108.42752 -402.237448)
			(xy 108.406692 -402.245322) (xy 107.769406 -402.882608) (xy 107.762007 -402.889455) (xy 107.74341 -402.89719)
			(xy 107.733338 -402.897594) (xy 99.2505 -402.897594) (xy 99.222814 -402.919946) (xy 99.219004 -402.937726)
			(xy 99.211122 -402.971838) (xy 99.188057 -403.037943) (xy 99.157023 -403.100702) (xy 99.118494 -403.15916)
			(xy 99.073055 -403.212425) (xy 99.0214 -403.259686) (xy 98.964315 -403.300223) (xy 98.902671 -403.333418)
			(xy 98.837407 -403.358764) (xy 98.769518 -403.375877) (xy 98.700037 -403.384494) (xy 98.66503 -403.38502)
			(xy 98.633218 -403.384591) (xy 98.569994 -403.377466) (xy 98.507966 -403.363302) (xy 98.447915 -403.342278)
			(xy 98.390599 -403.314658) (xy 98.336737 -403.280791) (xy 98.28701 -403.241102) (xy 98.264218 -403.218904)
			(xy 97.957894 -402.91258) (xy 97.950499 -402.905726) (xy 97.9319 -402.897981) (xy 97.921826 -402.897594)
			(xy 97.128076 -402.897594) (xy 97.118008 -402.898021) (xy 97.099409 -402.905741) (xy 97.092008 -402.91258)
			(xy 96.55048 -403.454108) (xy 96.543626 -403.461503) (xy 96.535882 -403.480102) (xy 96.535494 -403.490176)
			(xy 96.535494 -404.31466) (xy 96.535906 -404.328133) (xy 96.542952 -404.35414) (xy 96.556564 -404.377395)
			(xy 96.575791 -404.396272) (xy 96.599291 -404.409455) (xy 96.625424 -404.416024) (xy 96.652364 -404.415519)
			(xy 96.678232 -404.407976) (xy 96.689926 -404.401274) (xy 96.719942 -404.383713) (xy 96.783722 -404.355999)
			(xy 96.85068 -404.337219) (xy 96.91957 -404.327724) (xy 96.95434 -404.327106) (xy 96.954594 -404.327106)
			(xy 96.986575 -404.327587) (xy 97.050031 -404.335602) (xy 97.111983 -404.351508) (xy 97.171453 -404.375053)
			(xy 97.227503 -404.405867) (xy 97.267183 -404.434696) (xy 99.314414 -404.434696) (xy 99.319621 -404.371832)
			(xy 99.332564 -404.310095) (xy 99.353043 -404.250433) (xy 99.380745 -404.193763) (xy 99.415244 -404.140954)
			(xy 99.45601 -404.092818) (xy 99.502417 -404.050093) (xy 99.553751 -404.013437) (xy 99.609226 -403.983412)
			(xy 99.667989 -403.96048) (xy 99.729137 -403.944991) (xy 99.791731 -403.937185) (xy 99.82327 -403.936708)
			(xy 99.82581 -403.936708) (xy 99.835462 -403.936708) (xy 99.853496 -403.929596) (xy 99.918774 -403.868636)
			(xy 99.926902 -403.85111) (xy 99.927664 -403.841204) (xy 99.929961 -403.812483) (xy 99.942089 -403.756158)
			(xy 99.96255 -403.702297) (xy 99.990879 -403.652127) (xy 100.026431 -403.606788) (xy 100.068397 -403.567312)
			(xy 100.115824 -403.534596) (xy 100.167631 -403.509385) (xy 100.222641 -403.492253) (xy 100.279602 -403.48359)
			(xy 100.30841 -403.483064) (xy 100.33566 -403.483568) (xy 100.389606 -403.491326) (xy 100.441899 -403.506681)
			(xy 100.491474 -403.529321) (xy 100.537323 -403.558786) (xy 100.578512 -403.594475) (xy 100.614204 -403.635663)
			(xy 100.643671 -403.68151) (xy 100.666313 -403.731085) (xy 100.681671 -403.783377) (xy 100.68943 -403.837322)
			(xy 100.689918 -403.864572) (xy 100.689387 -403.892792) (xy 100.681076 -403.948617) (xy 100.66463 -404.002608)
			(xy 100.640409 -404.053587) (xy 100.608942 -404.100441) (xy 100.570914 -404.142147) (xy 100.527157 -404.177795)
			(xy 100.478625 -404.206608) (xy 100.426378 -404.227955) (xy 100.399088 -404.235158) (xy 100.389436 -404.237444)
			(xy 100.373688 -404.24862) (xy 100.325174 -404.323804) (xy 100.321364 -404.342854) (xy 100.323142 -404.352506)
			(xy 100.327171 -404.375472) (xy 100.331494 -404.421901) (xy 100.331778 -404.445216) (xy 100.331315 -404.476755)
			(xy 100.323511 -404.53935) (xy 100.308025 -404.600498) (xy 100.285094 -404.659261) (xy 100.25507 -404.714737)
			(xy 100.218415 -404.766073) (xy 100.175692 -404.812481) (xy 100.127557 -404.853248) (xy 100.074749 -404.887748)
			(xy 100.01808 -404.915451) (xy 99.958418 -404.935933) (xy 99.896682 -404.948877) (xy 99.833818 -404.954086)
			(xy 99.770793 -404.951479) (xy 99.708575 -404.941097) (xy 99.648118 -404.923098) (xy 99.590352 -404.89776)
			(xy 99.536164 -404.865472) (xy 99.486385 -404.826728) (xy 99.441781 -404.782125) (xy 99.403036 -404.732348)
			(xy 99.370746 -404.67816) (xy 99.345407 -404.620395) (xy 99.327406 -404.559939) (xy 99.317022 -404.49772)
			(xy 99.314414 -404.434696) (xy 97.267183 -404.434696) (xy 97.279249 -404.443462) (xy 97.325875 -404.487246)
			(xy 97.366646 -404.536528) (xy 97.400918 -404.590532) (xy 97.428151 -404.648406) (xy 97.447917 -404.709237)
			(xy 97.459902 -404.772065) (xy 97.463918 -404.8359) (xy 97.459902 -404.899735) (xy 97.447917 -404.962563)
			(xy 97.439496 -404.988479) (xy 102.27792 -404.988479) (xy 102.27792 -404.924557) (xy 102.285931 -404.861139)
			(xy 102.301828 -404.799225) (xy 102.32536 -404.739792) (xy 102.356154 -404.683777) (xy 102.393727 -404.632062)
			(xy 102.437484 -404.585465) (xy 102.486737 -404.54472) (xy 102.540708 -404.510469) (xy 102.598547 -404.483252)
			(xy 102.65934 -404.463499) (xy 102.72213 -404.451521) (xy 102.785926 -404.447508) (xy 102.849722 -404.451521)
			(xy 102.912512 -404.463499) (xy 102.973305 -404.483252) (xy 103.031144 -404.510469) (xy 103.085115 -404.54472)
			(xy 103.134368 -404.585465) (xy 103.178125 -404.632062) (xy 103.215698 -404.683777) (xy 103.246492 -404.739792)
			(xy 103.270024 -404.799225) (xy 103.285921 -404.861139) (xy 103.293932 -404.924557) (xy 103.294434 -404.956518)
			(xy 103.293932 -404.988479) (xy 103.285921 -405.051897) (xy 103.270024 -405.113811) (xy 103.246492 -405.173244)
			(xy 103.215698 -405.229259) (xy 103.178125 -405.280974) (xy 103.134368 -405.327571) (xy 103.085115 -405.368316)
			(xy 103.031144 -405.402567) (xy 102.973305 -405.429784) (xy 102.912512 -405.449537) (xy 102.849722 -405.461515)
			(xy 102.785926 -405.465529) (xy 102.72213 -405.461515) (xy 102.65934 -405.449537) (xy 102.598547 -405.429784)
			(xy 102.540708 -405.402567) (xy 102.486737 -405.368316) (xy 102.437484 -405.327571) (xy 102.393727 -405.280974)
			(xy 102.356154 -405.229259) (xy 102.32536 -405.173244) (xy 102.301828 -405.113811) (xy 102.285931 -405.051897)
			(xy 102.27792 -404.988479) (xy 97.439496 -404.988479) (xy 97.428151 -405.023394) (xy 97.400918 -405.081268)
			(xy 97.366646 -405.135272) (xy 97.325875 -405.184554) (xy 97.279249 -405.228338) (xy 97.227503 -405.265933)
			(xy 97.171453 -405.296747) (xy 97.111983 -405.320292) (xy 97.050031 -405.336198) (xy 96.986575 -405.344213)
			(xy 96.954594 -405.34463) (xy 96.95434 -405.34463) (xy 96.919564 -405.34407) (xy 96.850661 -405.334601)
			(xy 96.783693 -405.315821) (xy 96.719913 -405.288081) (xy 96.689926 -405.270462) (xy 96.678216 -405.263815)
			(xy 96.652365 -405.256313) (xy 96.625452 -405.255831) (xy 96.599349 -405.262405) (xy 96.575874 -405.275575)
			(xy 96.556659 -405.294426) (xy 96.543043 -405.317646) (xy 96.535972 -405.343618) (xy 96.535494 -405.357076)
			(xy 96.535494 -405.407114) (xy 101.447852 -405.407114) (xy 101.451923 -405.351492) (xy 101.464049 -405.297055)
			(xy 101.483972 -405.244964) (xy 101.511268 -405.196329) (xy 101.545354 -405.152186) (xy 101.585503 -405.113477)
			(xy 101.630861 -405.081026) (xy 101.680461 -405.055525) (xy 101.733245 -405.037518) (xy 101.788088 -405.027388)
			(xy 101.843822 -405.025351) (xy 101.899259 -405.031451) (xy 101.953216 -405.045557) (xy 102.004545 -405.067369)
			(xy 102.052151 -405.096423) (xy 102.095019 -405.132098) (xy 102.132236 -405.173635) (xy 102.163009 -405.220148)
			(xy 102.186681 -405.270645) (xy 102.202749 -405.324052) (xy 102.210869 -405.379228) (xy 102.211378 -405.407114)
			(xy 102.210869 -405.435) (xy 102.202749 -405.490176) (xy 102.186681 -405.543583) (xy 102.163009 -405.59408)
			(xy 102.133615 -405.638508) (xy 103.883206 -405.638508) (xy 103.883743 -405.60731) (xy 103.891389 -405.545384)
			(xy 103.906553 -405.484859) (xy 103.929009 -405.426644) (xy 103.958419 -405.371614) (xy 103.994341 -405.320596)
			(xy 104.036235 -405.274356) (xy 104.083471 -405.233589) (xy 104.135341 -405.198908) (xy 104.191064 -405.170833)
			(xy 104.249804 -405.149788) (xy 104.310677 -405.136087) (xy 104.341676 -405.13254) (xy 104.35082 -405.131524)
			(xy 104.366314 -405.124158) (xy 104.488234 -405.002238) (xy 104.4956 -404.98649) (xy 104.496616 -404.9776)
			(xy 104.500121 -404.946591) (xy 104.513803 -404.885702) (xy 104.534836 -404.826946) (xy 104.562904 -404.771206)
			(xy 104.597583 -404.719322) (xy 104.638353 -404.672073) (xy 104.684601 -404.63017) (xy 104.735629 -404.594243)
			(xy 104.790672 -404.564833) (xy 104.848902 -404.542383) (xy 104.909441 -404.527229) (xy 104.97138 -404.519599)
			(xy 105.002584 -404.51913) (xy 105.032311 -404.519551) (xy 105.091358 -404.526497) (xy 105.149191 -404.540285)
			(xy 105.20502 -404.560726) (xy 105.258084 -404.587541) (xy 105.307657 -404.620364) (xy 105.353061 -404.658746)
			(xy 105.373678 -404.680166) (xy 105.380459 -404.68677) (xy 105.397546 -404.694873) (xy 105.406952 -404.695914)
			(xy 105.43794 -404.698454) (xy 105.447257 -404.69873) (xy 105.4651 -404.693384) (xy 105.472738 -404.68804)
			(xy 105.492815 -404.673078) (xy 105.536135 -404.647967) (xy 105.582371 -404.628746) (xy 105.630725 -404.615745)
			(xy 105.680366 -404.609188) (xy 105.705402 -404.608792) (xy 105.732653 -404.609278) (xy 105.786601 -404.617035)
			(xy 105.838895 -404.63239) (xy 105.888472 -404.655031) (xy 105.934322 -404.684498) (xy 105.975512 -404.720189)
			(xy 106.011204 -404.761379) (xy 106.04067 -404.80723) (xy 106.063311 -404.856807) (xy 106.078666 -404.909101)
			(xy 106.086422 -404.963049) (xy 106.086422 -405.017551) (xy 106.078666 -405.071499) (xy 106.063311 -405.123793)
			(xy 106.04067 -405.17337) (xy 106.011204 -405.219221) (xy 105.993214 -405.239982) (xy 106.697018 -405.239982)
			(xy 106.697527 -405.207585) (xy 106.705745 -405.143315) (xy 106.722058 -405.080608) (xy 106.746201 -405.020481)
			(xy 106.777785 -404.963906) (xy 106.816298 -404.9118) (xy 106.861115 -404.865007) (xy 106.885994 -404.84425)
			(xy 106.894122 -404.837646) (xy 106.903774 -404.82012) (xy 106.91241 -404.726648) (xy 106.906314 -404.707344)
			(xy 106.899456 -404.69947) (xy 106.882331 -404.678647) (xy 106.853497 -404.63309) (xy 106.831352 -404.583934)
			(xy 106.816334 -404.532154) (xy 106.808741 -404.478777) (xy 106.80827 -404.45182) (xy 106.808756 -404.424569)
			(xy 106.816512 -404.370621) (xy 106.831867 -404.318326) (xy 106.854509 -404.268749) (xy 106.883975 -404.222899)
			(xy 106.919666 -404.181708) (xy 106.960857 -404.146017) (xy 107.006707 -404.116551) (xy 107.056284 -404.093909)
			(xy 107.108579 -404.078554) (xy 107.162527 -404.070798) (xy 107.217029 -404.070798) (xy 107.270977 -404.078554)
			(xy 107.323272 -404.093909) (xy 107.372849 -404.116551) (xy 107.418699 -404.146017) (xy 107.45989 -404.181708)
			(xy 107.495581 -404.222899) (xy 107.525047 -404.268749) (xy 107.547689 -404.318326) (xy 107.563044 -404.370621)
			(xy 107.5708 -404.424569) (xy 107.571286 -404.45182) (xy 107.570856 -404.477238) (xy 107.564103 -404.527622)
			(xy 107.55072 -404.576665) (xy 107.530944 -404.623495) (xy 107.505125 -404.667286) (xy 107.489752 -404.687532)
			(xy 107.483148 -404.695914) (xy 107.477814 -404.715218) (xy 107.49026 -404.808182) (xy 107.50042 -404.825708)
			(xy 107.509056 -404.831804) (xy 107.528106 -404.84679) (xy 107.535104 -404.852062) (xy 107.551608 -404.857908)
			(xy 107.560364 -404.85822) (xy 107.714288 -404.85822) (xy 107.723034 -404.857846) (xy 107.739525 -404.852016)
			(xy 107.746546 -404.84679) (xy 107.773963 -404.825101) (xy 107.833584 -404.788599) (xy 107.89764 -404.760602)
			(xy 107.964925 -404.741636) (xy 108.034173 -404.732058) (xy 108.069126 -404.731474) (xy 108.099857 -404.731932)
			(xy 108.16087 -404.739343) (xy 108.220545 -404.754054) (xy 108.278012 -404.77585) (xy 108.332433 -404.804414)
			(xy 108.383015 -404.839329) (xy 108.429019 -404.880087) (xy 108.469776 -404.926092) (xy 108.50469 -404.976673)
			(xy 108.521684 -405.009053) (xy 108.698532 -405.009053) (xy 108.698532 -404.945131) (xy 108.706543 -404.881713)
			(xy 108.72244 -404.819799) (xy 108.745972 -404.760366) (xy 108.776766 -404.704351) (xy 108.814339 -404.652636)
			(xy 108.858096 -404.606039) (xy 108.907349 -404.565294) (xy 108.96132 -404.531043) (xy 109.019159 -404.503826)
			(xy 109.079952 -404.484073) (xy 109.142742 -404.472095) (xy 109.206538 -404.468082) (xy 109.270334 -404.472095)
			(xy 109.333124 -404.484073) (xy 109.393917 -404.503826) (xy 109.451756 -404.531043) (xy 109.505727 -404.565294)
			(xy 109.55498 -404.606039) (xy 109.598737 -404.652636) (xy 109.63631 -404.704351) (xy 109.667104 -404.760366)
			(xy 109.690636 -404.819799) (xy 109.706533 -404.881713) (xy 109.714544 -404.945131) (xy 109.715046 -404.977092)
			(xy 109.714544 -405.009053) (xy 109.706533 -405.072471) (xy 109.690636 -405.134385) (xy 109.667104 -405.193818)
			(xy 109.63631 -405.249833) (xy 109.598737 -405.301548) (xy 109.55498 -405.348145) (xy 109.505727 -405.38889)
			(xy 109.451756 -405.423141) (xy 109.393917 -405.450358) (xy 109.333124 -405.470111) (xy 109.270334 -405.482089)
			(xy 109.206538 -405.486103) (xy 109.142742 -405.482089) (xy 109.079952 -405.470111) (xy 109.019159 -405.450358)
			(xy 108.96132 -405.423141) (xy 108.907349 -405.38889) (xy 108.858096 -405.348145) (xy 108.814339 -405.301548)
			(xy 108.776766 -405.249833) (xy 108.745972 -405.193818) (xy 108.72244 -405.134385) (xy 108.706543 -405.072471)
			(xy 108.698532 -405.009053) (xy 108.521684 -405.009053) (xy 108.533253 -405.031095) (xy 108.555049 -405.088562)
			(xy 108.569759 -405.148238) (xy 108.577169 -405.209251) (xy 108.577634 -405.239982) (xy 108.577051 -405.274285)
			(xy 108.567799 -405.342266) (xy 108.549487 -405.408385) (xy 108.536486 -405.440134) (xy 108.53293 -405.44877)
			(xy 108.532168 -405.466804) (xy 108.558076 -405.54783) (xy 108.569252 -405.562054) (xy 108.577126 -405.56688)
			(xy 108.600713 -405.581823) (xy 108.643664 -405.617499) (xy 108.680957 -405.659054) (xy 108.711796 -405.7056)
			(xy 108.735522 -405.756144) (xy 108.751628 -405.809606) (xy 108.759771 -405.864844) (xy 108.76026 -405.892762)
			(xy 108.759774 -405.920013) (xy 108.752018 -405.973961) (xy 108.736663 -406.026256) (xy 108.714021 -406.075833)
			(xy 108.684555 -406.121683) (xy 108.648864 -406.162874) (xy 108.607673 -406.198565) (xy 108.561823 -406.228031)
			(xy 108.512246 -406.250673) (xy 108.459951 -406.266028) (xy 108.406003 -406.273784) (xy 108.351501 -406.273784)
			(xy 108.297553 -406.266028) (xy 108.245258 -406.250673) (xy 108.195681 -406.228031) (xy 108.149831 -406.198565)
			(xy 108.10864 -406.162874) (xy 108.072949 -406.121683) (xy 108.043483 -406.075833) (xy 108.020841 -406.026256)
			(xy 108.005486 -405.973961) (xy 107.99773 -405.920013) (xy 107.997244 -405.892762) (xy 107.997325 -405.879575)
			(xy 107.999108 -405.853262) (xy 108.0008 -405.840184) (xy 108.00207 -405.83104) (xy 107.99826 -405.81326)
			(xy 107.951778 -405.741886) (xy 107.9373 -405.731218) (xy 107.92841 -405.728678) (xy 107.895425 -405.718592)
			(xy 107.832324 -405.690741) (xy 107.773572 -405.654605) (xy 107.746546 -405.633174) (xy 107.739536 -405.62792)
			(xy 107.723042 -405.622064) (xy 107.714288 -405.621744) (xy 107.560364 -405.621744) (xy 107.551615 -405.622083)
			(xy 107.535123 -405.627936) (xy 107.528106 -405.633174) (xy 107.500702 -405.65488) (xy 107.441078 -405.69138)
			(xy 107.377019 -405.719374) (xy 107.309731 -405.738336) (xy 107.24048 -405.747909) (xy 107.205526 -405.74849)
			(xy 107.174794 -405.748038) (xy 107.113777 -405.740632) (xy 107.054098 -405.725925) (xy 106.996627 -405.704131)
			(xy 106.942202 -405.675568) (xy 106.891617 -405.640653) (xy 106.84561 -405.599895) (xy 106.804852 -405.553889)
			(xy 106.769936 -405.503304) (xy 106.741372 -405.44888) (xy 106.719578 -405.39141) (xy 106.70487 -405.331731)
			(xy 106.697463 -405.270714) (xy 106.697018 -405.239982) (xy 105.993214 -405.239982) (xy 105.975512 -405.260411)
			(xy 105.934322 -405.296102) (xy 105.888472 -405.325569) (xy 105.838895 -405.34821) (xy 105.786601 -405.363565)
			(xy 105.732653 -405.371322) (xy 105.705402 -405.371808) (xy 105.67917 -405.371368) (xy 105.627198 -405.364201)
			(xy 105.576696 -405.349986) (xy 105.528616 -405.328992) (xy 105.506012 -405.315674) (xy 105.497887 -405.311182)
			(xy 105.479649 -405.307798) (xy 105.470452 -405.30907) (xy 105.439972 -405.314658) (xy 105.430733 -405.316802)
			(xy 105.414573 -405.326698) (xy 105.408476 -405.333962) (xy 105.390022 -405.357615) (xy 105.348483 -405.4009)
			(xy 105.302142 -405.439001) (xy 105.251642 -405.471388) (xy 105.197685 -405.497613) (xy 105.141019 -405.517312)
			(xy 105.082429 -405.530211) (xy 105.052622 -405.533606) (xy 105.043732 -405.534622) (xy 105.027984 -405.541988)
			(xy 104.906064 -405.663908) (xy 104.898698 -405.679402) (xy 104.897682 -405.688546) (xy 104.893583 -405.723878)
			(xy 104.876802 -405.792999) (xy 104.850545 -405.859103) (xy 104.815326 -405.920899) (xy 104.79405 -405.949404)
			(xy 104.788804 -405.956874) (xy 104.783465 -405.974314) (xy 104.783636 -405.98344) (xy 104.785414 -406.01392)
			(xy 104.786338 -406.022908) (xy 104.793628 -406.03943) (xy 104.799638 -406.046178) (xy 104.819547 -406.067632)
			(xy 104.853225 -406.115497) (xy 104.879199 -406.167944) (xy 104.896858 -406.223742) (xy 104.905789 -406.281583)
			(xy 104.906318 -406.310846) (xy 104.905832 -406.338097) (xy 104.898076 -406.392045) (xy 104.882721 -406.44434)
			(xy 104.860079 -406.493917) (xy 104.830613 -406.539767) (xy 104.794922 -406.580958) (xy 104.754352 -406.616111)
			(xy 105.988352 -406.616111) (xy 105.988352 -406.552189) (xy 105.996363 -406.488771) (xy 106.01226 -406.426857)
			(xy 106.035792 -406.367424) (xy 106.066586 -406.311409) (xy 106.104159 -406.259694) (xy 106.147916 -406.213097)
			(xy 106.197169 -406.172352) (xy 106.25114 -406.138101) (xy 106.308979 -406.110884) (xy 106.369772 -406.091131)
			(xy 106.432562 -406.079153) (xy 106.496358 -406.07514) (xy 106.560154 -406.079153) (xy 106.622944 -406.091131)
			(xy 106.683737 -406.110884) (xy 106.741576 -406.138101) (xy 106.795547 -406.172352) (xy 106.8448 -406.213097)
			(xy 106.888557 -406.259694) (xy 106.92613 -406.311409) (xy 106.956924 -406.367424) (xy 106.980456 -406.426857)
			(xy 106.996353 -406.488771) (xy 107.004364 -406.552189) (xy 107.004866 -406.58415) (xy 107.004364 -406.616111)
			(xy 106.996353 -406.679529) (xy 106.980456 -406.741443) (xy 106.956924 -406.800876) (xy 106.92613 -406.856891)
			(xy 106.888557 -406.908606) (xy 106.8448 -406.955203) (xy 106.795547 -406.995948) (xy 106.741576 -407.030199)
			(xy 106.683737 -407.057416) (xy 106.622944 -407.077169) (xy 106.560154 -407.089147) (xy 106.496358 -407.093161)
			(xy 106.432562 -407.089147) (xy 106.369772 -407.077169) (xy 106.308979 -407.057416) (xy 106.25114 -407.030199)
			(xy 106.197169 -406.995948) (xy 106.147916 -406.955203) (xy 106.104159 -406.908606) (xy 106.066586 -406.856891)
			(xy 106.035792 -406.800876) (xy 106.01226 -406.741443) (xy 105.996363 -406.679529) (xy 105.988352 -406.616111)
			(xy 104.754352 -406.616111) (xy 104.753731 -406.616649) (xy 104.707881 -406.646115) (xy 104.658304 -406.668757)
			(xy 104.606009 -406.684112) (xy 104.552061 -406.691868) (xy 104.497559 -406.691868) (xy 104.443611 -406.684112)
			(xy 104.391316 -406.668757) (xy 104.341739 -406.646115) (xy 104.295889 -406.616649) (xy 104.254698 -406.580958)
			(xy 104.219007 -406.539767) (xy 104.189541 -406.493917) (xy 104.166899 -406.44434) (xy 104.151544 -406.392045)
			(xy 104.143788 -406.338097) (xy 104.143302 -406.310846) (xy 104.143676 -406.286952) (xy 104.149662 -406.23954)
			(xy 104.161534 -406.19325) (xy 104.169972 -406.170892) (xy 104.172937 -406.162341) (xy 104.173326 -406.144257)
			(xy 104.170734 -406.135586) (xy 104.160828 -406.106884) (xy 104.157492 -406.098294) (xy 104.145775 -406.084092)
			(xy 104.137968 -406.079198) (xy 104.109334 -406.062127) (xy 104.056407 -406.021591) (xy 104.009231 -405.974487)
			(xy 103.968612 -405.921624) (xy 103.935249 -405.863907) (xy 103.909713 -405.802326) (xy 103.892441 -405.737936)
			(xy 103.88373 -405.671841) (xy 103.883206 -405.638508) (xy 102.133615 -405.638508) (xy 102.132236 -405.640593)
			(xy 102.095019 -405.68213) (xy 102.052151 -405.717805) (xy 102.004545 -405.746859) (xy 101.953216 -405.768671)
			(xy 101.899259 -405.782777) (xy 101.843822 -405.788877) (xy 101.788088 -405.78684) (xy 101.733245 -405.77671)
			(xy 101.680461 -405.758703) (xy 101.630861 -405.733202) (xy 101.585503 -405.700751) (xy 101.545354 -405.662042)
			(xy 101.511268 -405.617899) (xy 101.483972 -405.569264) (xy 101.464049 -405.517173) (xy 101.451923 -405.462736)
			(xy 101.447852 -405.407114) (xy 96.535494 -405.407114) (xy 96.535494 -406.03805) (xy 96.535642 -406.043775)
			(xy 96.538206 -406.054934) (xy 96.540574 -406.060148) (xy 96.552258 -406.084278) (xy 96.558862 -406.09266)
			(xy 96.56318 -406.096216) (xy 96.582965 -406.113239) (xy 96.599109 -406.131225) (xy 98.382576 -406.131225)
			(xy 98.382576 -406.067303) (xy 98.390587 -406.003885) (xy 98.406484 -405.941971) (xy 98.430016 -405.882538)
			(xy 98.46081 -405.826523) (xy 98.498383 -405.774808) (xy 98.54214 -405.728211) (xy 98.591393 -405.687466)
			(xy 98.645364 -405.653215) (xy 98.703203 -405.625998) (xy 98.763996 -405.606245) (xy 98.826786 -405.594267)
			(xy 98.890582 -405.590254) (xy 98.954378 -405.594267) (xy 99.017168 -405.606245) (xy 99.077961 -405.625998)
			(xy 99.1358 -405.653215) (xy 99.189771 -405.687466) (xy 99.239024 -405.728211) (xy 99.282781 -405.774808)
			(xy 99.320354 -405.826523) (xy 99.351148 -405.882538) (xy 99.37468 -405.941971) (xy 99.390577 -406.003885)
			(xy 99.398588 -406.067303) (xy 99.39909 -406.099264) (xy 99.398588 -406.131225) (xy 99.390577 -406.194643)
			(xy 99.37468 -406.256557) (xy 99.351148 -406.31599) (xy 99.320354 -406.372005) (xy 99.282781 -406.42372)
			(xy 99.239024 -406.470317) (xy 99.189771 -406.511062) (xy 99.1358 -406.545313) (xy 99.077961 -406.57253)
			(xy 99.017168 -406.592283) (xy 98.954378 -406.604261) (xy 98.890582 -406.608275) (xy 98.826786 -406.604261)
			(xy 98.763996 -406.592283) (xy 98.703203 -406.57253) (xy 98.645364 -406.545313) (xy 98.591393 -406.511062)
			(xy 98.54214 -406.470317) (xy 98.498383 -406.42372) (xy 98.46081 -406.372005) (xy 98.430016 -406.31599)
			(xy 98.406484 -406.256557) (xy 98.390587 -406.194643) (xy 98.382576 -406.131225) (xy 96.599109 -406.131225)
			(xy 96.617828 -406.15208) (xy 96.646658 -406.195588) (xy 96.668839 -406.242833) (xy 96.683898 -406.292806)
			(xy 96.691514 -406.34444) (xy 96.691958 -406.370536) (xy 96.691958 -406.371044) (xy 96.691436 -406.39844)
			(xy 96.683002 -406.452579) (xy 96.666372 -406.504787) (xy 96.65462 -406.52954) (xy 96.64879 -406.542226)
			(xy 96.643582 -406.569645) (xy 96.645997 -406.597449) (xy 96.655854 -406.62356) (xy 96.672417 -406.646023)
			(xy 96.694446 -406.663159) (xy 96.720294 -406.673687) (xy 96.734122 -406.67559) (xy 96.75932 -406.678916)
			(xy 96.808352 -406.692298) (xy 96.854762 -406.713018) (xy 96.89746 -406.740588) (xy 96.935441 -406.77436)
			(xy 96.967815 -406.813542) (xy 96.993818 -406.857211) (xy 97.012842 -406.904342) (xy 97.024437 -406.953827)
			(xy 97.028333 -407.004502) (xy 97.024437 -407.055178) (xy 97.01284 -407.104662) (xy 96.993816 -407.151793)
			(xy 96.967812 -407.195462) (xy 96.935438 -407.234643) (xy 96.897456 -407.268415) (xy 96.854758 -407.295984)
			(xy 96.808348 -407.316704) (xy 96.759316 -407.330085) (xy 96.734122 -407.33345) (xy 96.720315 -407.335457)
			(xy 96.694488 -407.345988) (xy 96.672474 -407.363114) (xy 96.655914 -407.385558) (xy 96.646045 -407.411644)
			(xy 96.643601 -407.439428) (xy 96.648765 -407.466837) (xy 96.65462 -407.4795) (xy 96.666374 -407.504251)
			(xy 96.682991 -407.556463) (xy 96.691429 -407.610601) (xy 96.691958 -407.637996) (xy 96.691958 -407.638504)
			(xy 96.691503 -407.6646) (xy 96.683894 -407.716235) (xy 96.668838 -407.766208) (xy 96.646658 -407.813453)
			(xy 96.617828 -407.85696) (xy 96.582963 -407.895799) (xy 96.56318 -407.912824) (xy 96.558862 -407.91638)
			(xy 96.552258 -407.924762) (xy 96.540574 -407.948384) (xy 96.5382 -407.953663) (xy 96.53564 -407.964949)
			(xy 96.535494 -407.970736) (xy 96.535494 -408.381705) (xy 98.12048 -408.381705) (xy 98.124208 -408.328455)
			(xy 98.135323 -408.276245) (xy 98.153607 -408.226094) (xy 98.178703 -408.178981) (xy 98.210121 -408.135827)
			(xy 98.247247 -408.097472) (xy 98.268028 -408.080718) (xy 98.276782 -408.073149) (xy 98.286969 -408.052395)
			(xy 98.287586 -408.04084) (xy 98.287586 -407.960576) (xy 98.286977 -407.949013) (xy 98.27681 -407.928241)
			(xy 98.268028 -407.920698) (xy 98.245549 -407.902501) (xy 98.205813 -407.860483) (xy 98.172872 -407.81295)
			(xy 98.147483 -407.76099) (xy 98.130226 -407.705793) (xy 98.121497 -407.648624) (xy 98.120962 -407.619708)
			(xy 98.121448 -407.592457) (xy 98.129204 -407.538509) (xy 98.144559 -407.486214) (xy 98.167201 -407.436637)
			(xy 98.196667 -407.390787) (xy 98.232358 -407.349596) (xy 98.273549 -407.313905) (xy 98.319399 -407.284439)
			(xy 98.368976 -407.261797) (xy 98.421271 -407.246442) (xy 98.475219 -407.238686) (xy 98.529721 -407.238686)
			(xy 98.583669 -407.246442) (xy 98.635964 -407.261797) (xy 98.685541 -407.284439) (xy 98.731391 -407.313905)
			(xy 98.772582 -407.349596) (xy 98.808273 -407.390787) (xy 98.837739 -407.436637) (xy 98.860381 -407.486214)
			(xy 98.875736 -407.538509) (xy 98.883492 -407.592457) (xy 98.883978 -407.619708) (xy 98.883402 -407.648623)
			(xy 98.874686 -407.705792) (xy 98.85744 -407.76099) (xy 98.832059 -407.812952) (xy 98.799125 -407.860487)
			(xy 98.759393 -407.902506) (xy 98.736912 -407.920698) (xy 98.728157 -407.928267) (xy 98.717969 -407.94902)
			(xy 98.717354 -407.960576) (xy 98.717354 -408.04084) (xy 98.71794 -408.052406) (xy 98.728122 -408.073179)
			(xy 98.736912 -408.080718) (xy 98.757704 -408.097461) (xy 98.794837 -408.135814) (xy 98.826261 -408.17897)
			(xy 98.851362 -408.226084) (xy 98.869649 -408.276238) (xy 98.880767 -408.328451) (xy 98.884496 -408.381705)
			(xy 98.880765 -408.434958) (xy 98.869647 -408.487171) (xy 98.851358 -408.537325) (xy 98.826256 -408.584439)
			(xy 98.794831 -408.627593) (xy 98.757697 -408.665946) (xy 98.736912 -408.682698) (xy 98.728157 -408.690267)
			(xy 98.717969 -408.71102) (xy 98.717354 -408.722576) (xy 98.717354 -408.80284) (xy 98.71794 -408.814406)
			(xy 98.728122 -408.835179) (xy 98.736912 -408.842718) (xy 98.759407 -408.860896) (xy 98.799141 -408.902919)
			(xy 98.832078 -408.950456) (xy 98.857464 -409.00242) (xy 98.874718 -409.05762) (xy 98.883444 -409.114791)
			(xy 98.883978 -409.143708) (xy 98.883492 -409.170959) (xy 98.875736 -409.224907) (xy 98.860381 -409.277202)
			(xy 98.837739 -409.326779) (xy 98.808273 -409.372629) (xy 98.772582 -409.41382) (xy 98.731391 -409.449511)
			(xy 98.685541 -409.478977) (xy 98.635964 -409.501619) (xy 98.583669 -409.516974) (xy 98.529721 -409.52473)
			(xy 98.475219 -409.52473) (xy 98.421271 -409.516974) (xy 98.368976 -409.501619) (xy 98.319399 -409.478977)
			(xy 98.273549 -409.449511) (xy 98.232358 -409.41382) (xy 98.196667 -409.372629) (xy 98.167201 -409.326779)
			(xy 98.144559 -409.277202) (xy 98.129204 -409.224907) (xy 98.121448 -409.170959) (xy 98.120962 -409.143708)
			(xy 98.121463 -409.11479) (xy 98.130192 -409.057617) (xy 98.147452 -409.002417) (xy 98.172847 -408.950455)
			(xy 98.205795 -408.902921) (xy 98.24554 -408.860907) (xy 98.268028 -408.842718) (xy 98.276782 -408.835149)
			(xy 98.286969 -408.814395) (xy 98.287586 -408.80284) (xy 98.287586 -408.722576) (xy 98.286977 -408.711013)
			(xy 98.27681 -408.690241) (xy 98.268028 -408.682698) (xy 98.247254 -408.665934) (xy 98.210127 -408.627581)
			(xy 98.178708 -408.584427) (xy 98.153611 -408.537315) (xy 98.135326 -408.487164) (xy 98.12421 -408.434954)
			(xy 98.12048 -408.381705) (xy 96.535494 -408.381705) (xy 96.535494 -409.063698) (xy 96.535647 -409.069422)
			(xy 96.538221 -409.080576) (xy 96.540574 -409.085796) (xy 96.552258 -409.109926) (xy 96.558862 -409.118308)
			(xy 96.56318 -409.121864) (xy 96.582963 -409.138888) (xy 96.61782 -409.177731) (xy 96.646644 -409.221239)
			(xy 96.668819 -409.268484) (xy 96.683872 -409.318456) (xy 96.691481 -409.370089) (xy 96.691958 -409.396184)
			(xy 96.691958 -409.396692) (xy 96.691439 -409.424089) (xy 96.683013 -409.478231) (xy 96.66639 -409.530443)
			(xy 96.65462 -409.555188) (xy 96.648797 -409.567871) (xy 96.643601 -409.595281) (xy 96.644248 -409.6027)
			(xy 100.950454 -409.6027) (xy 100.954469 -409.538897) (xy 100.966449 -409.4761) (xy 100.986205 -409.415299)
			(xy 101.013426 -409.357455) (xy 101.047682 -409.303478) (xy 101.088434 -409.254221) (xy 101.135039 -409.21046)
			(xy 101.18676 -409.172886) (xy 101.242784 -409.14209) (xy 101.302225 -409.11856) (xy 101.364147 -409.102665)
			(xy 101.427573 -409.094657) (xy 101.459538 -409.094178) (xy 101.491157 -409.094724) (xy 101.553907 -409.102569)
			(xy 101.615199 -409.118134) (xy 101.67409 -409.141178) (xy 101.729668 -409.171346) (xy 101.781077 -409.208172)
			(xy 101.827524 -409.251087) (xy 101.868292 -409.299431) (xy 101.902751 -409.352456) (xy 101.916992 -409.38069)
			(xy 101.92385 -409.394406) (xy 101.94925 -409.4099) (xy 102.072694 -409.405582) (xy 102.097078 -409.388564)
			(xy 102.102666 -409.37434) (xy 102.117796 -409.33857) (xy 102.157342 -409.271729) (xy 102.181406 -409.241244)
			(xy 102.186659 -409.234233) (xy 102.192516 -409.21774) (xy 102.192836 -409.208986) (xy 102.192836 -409.055062)
			(xy 102.192482 -409.046314) (xy 102.186638 -409.029824) (xy 102.181406 -409.022804) (xy 102.159696 -408.995403)
			(xy 102.123197 -408.935778) (xy 102.095204 -408.871718) (xy 102.076243 -408.804429) (xy 102.066671 -408.735179)
			(xy 102.06609 -408.700224) (xy 102.06651 -408.67035) (xy 102.07352 -408.611013) (xy 102.087433 -408.552907)
			(xy 102.108058 -408.496831) (xy 102.135112 -408.443558) (xy 102.168221 -408.393822) (xy 102.187248 -408.370786)
			(xy 102.193344 -408.363674) (xy 102.19944 -408.346656) (xy 102.19817 -408.260804) (xy 102.191312 -408.24404)
			(xy 102.184962 -408.236928) (xy 102.174548 -408.224736) (xy 102.166166 -408.21483) (xy 102.142544 -408.205178)
			(xy 102.032054 -408.218386) (xy 102.011226 -408.233118) (xy 102.005384 -408.244802) (xy 101.991049 -408.272767)
			(xy 101.956465 -408.325238) (xy 101.91568 -408.37305) (xy 101.869317 -408.415473) (xy 101.818081 -408.451863)
			(xy 101.762753 -408.481664) (xy 101.704175 -408.504423) (xy 101.64324 -408.519794) (xy 101.580876 -408.527541)
			(xy 101.549454 -408.528012) (xy 101.517495 -408.527499) (xy 101.454082 -408.519483) (xy 101.392173 -408.503583)
			(xy 101.332746 -408.480049) (xy 101.276736 -408.449253) (xy 101.225027 -408.41168) (xy 101.178435 -408.367923)
			(xy 101.137694 -408.318672) (xy 101.103447 -408.264703) (xy 101.076234 -408.206868) (xy 101.056483 -408.146078)
			(xy 101.044507 -408.083292) (xy 101.040493 -408.0195) (xy 101.044507 -407.955708) (xy 101.056483 -407.892922)
			(xy 101.076234 -407.832132) (xy 101.103447 -407.774297) (xy 101.137694 -407.720328) (xy 101.178435 -407.671077)
			(xy 101.225027 -407.62732) (xy 101.276736 -407.589747) (xy 101.332746 -407.558951) (xy 101.392173 -407.535417)
			(xy 101.454082 -407.519517) (xy 101.517495 -407.511501) (xy 101.549454 -407.510996) (xy 101.582138 -407.511489)
			(xy 101.646968 -407.519854) (xy 101.71019 -407.536463) (xy 101.77076 -407.561044) (xy 101.827678 -407.593189)
			(xy 101.880003 -407.632368) (xy 101.926871 -407.677934) (xy 101.967509 -407.729135) (xy 101.98481 -407.756868)
			(xy 101.991668 -407.768044) (xy 102.013512 -407.780998) (xy 102.124764 -407.784554) (xy 102.147624 -407.773124)
			(xy 102.155244 -407.762456) (xy 102.170579 -407.741212) (xy 102.20617 -407.702759) (xy 102.246689 -407.669541)
			(xy 102.291375 -407.642184) (xy 102.339386 -407.621203) (xy 102.389818 -407.606993) (xy 102.44172 -407.599821)
			(xy 102.467918 -407.599388) (xy 102.499388 -407.60001) (xy 102.561472 -407.610345) (xy 102.621018 -407.630732)
			(xy 102.64902 -407.645108) (xy 102.66172 -407.651966) (xy 102.690168 -407.650442) (xy 102.788466 -407.581608)
			(xy 102.799896 -407.555446) (xy 102.797864 -407.541222) (xy 102.795386 -407.523163) (xy 102.792717 -407.486805)
			(xy 102.79253 -407.468578) (xy 102.792991 -407.437039) (xy 102.800796 -407.374446) (xy 102.816283 -407.313299)
			(xy 102.839214 -407.254537) (xy 102.869237 -407.199063) (xy 102.905892 -407.147728) (xy 102.948614 -407.101321)
			(xy 102.996749 -407.060555) (xy 103.049556 -407.026056) (xy 103.106225 -406.998353) (xy 103.165885 -406.977873)
			(xy 103.227621 -406.964929) (xy 103.290483 -406.95972) (xy 103.353507 -406.962327) (xy 103.415724 -406.972709)
			(xy 103.47618 -406.990707) (xy 103.533945 -407.016045) (xy 103.588133 -407.048333) (xy 103.63791 -407.087076)
			(xy 103.682514 -407.131678) (xy 103.721258 -407.181454) (xy 103.753548 -407.235641) (xy 103.778887 -407.293405)
			(xy 103.796887 -407.35386) (xy 103.807271 -407.416077) (xy 103.80988 -407.479101) (xy 103.804674 -407.541963)
			(xy 103.791732 -407.603699) (xy 103.771253 -407.66336) (xy 103.743552 -407.72003) (xy 103.709054 -407.772838)
			(xy 103.66829 -407.820974) (xy 103.621884 -407.863698) (xy 103.570551 -407.900354) (xy 103.545245 -407.914051)
			(xy 108.838994 -407.914051) (xy 108.838994 -407.850129) (xy 108.847005 -407.786711) (xy 108.862902 -407.724797)
			(xy 108.886434 -407.665364) (xy 108.917228 -407.609349) (xy 108.954801 -407.557634) (xy 108.998558 -407.511037)
			(xy 109.047811 -407.470292) (xy 109.101782 -407.436041) (xy 109.159621 -407.408824) (xy 109.220414 -407.389071)
			(xy 109.283204 -407.377093) (xy 109.347 -407.37308) (xy 109.410796 -407.377093) (xy 109.473586 -407.389071)
			(xy 109.534379 -407.408824) (xy 109.592218 -407.436041) (xy 109.646189 -407.470292) (xy 109.695442 -407.511037)
			(xy 109.739199 -407.557634) (xy 109.776772 -407.609349) (xy 109.807566 -407.665364) (xy 109.831098 -407.724797)
			(xy 109.846995 -407.786711) (xy 109.855006 -407.850129) (xy 109.855508 -407.88209) (xy 109.855006 -407.914051)
			(xy 109.846995 -407.977469) (xy 109.831098 -408.039383) (xy 109.807566 -408.098816) (xy 109.776772 -408.154831)
			(xy 109.739199 -408.206546) (xy 109.695442 -408.253143) (xy 109.646189 -408.293888) (xy 109.592218 -408.328139)
			(xy 109.534379 -408.355356) (xy 109.473586 -408.375109) (xy 109.410796 -408.387087) (xy 109.347 -408.391101)
			(xy 109.283204 -408.387087) (xy 109.220414 -408.375109) (xy 109.159621 -408.355356) (xy 109.101782 -408.328139)
			(xy 109.047811 -408.293888) (xy 108.998558 -408.253143) (xy 108.954801 -408.206546) (xy 108.917228 -408.154831)
			(xy 108.886434 -408.098816) (xy 108.862902 -408.039383) (xy 108.847005 -407.977469) (xy 108.838994 -407.914051)
			(xy 103.545245 -407.914051) (xy 103.515077 -407.930379) (xy 103.456316 -407.953312) (xy 103.39517 -407.968801)
			(xy 103.332577 -407.976608) (xy 103.301038 -407.977086) (xy 103.269939 -407.976598) (xy 103.208206 -407.969008)
			(xy 103.147862 -407.953938) (xy 103.089809 -407.931612) (xy 103.034917 -407.902365) (xy 103.009192 -407.884884)
			(xy 102.997254 -407.876756) (xy 102.968806 -407.874978) (xy 102.863142 -407.93162) (xy 102.848918 -407.956258)
			(xy 102.849172 -407.970736) (xy 102.849426 -407.980896) (xy 102.848926 -408.008949) (xy 102.840685 -408.064447)
			(xy 102.824393 -408.118137) (xy 102.81285 -408.14371) (xy 102.808786 -408.152346) (xy 102.807516 -408.17038)
			(xy 102.831138 -408.25293) (xy 102.841806 -408.267408) (xy 102.84968 -408.272488) (xy 102.876121 -408.290107)
			(xy 102.924288 -408.3304) (xy 104.545382 -408.3304) (xy 104.549453 -408.274778) (xy 104.561579 -408.220341)
			(xy 104.581502 -408.16825) (xy 104.608798 -408.119615) (xy 104.642884 -408.075472) (xy 104.683033 -408.036763)
			(xy 104.728391 -408.004312) (xy 104.777991 -407.978811) (xy 104.830775 -407.960804) (xy 104.885618 -407.950674)
			(xy 104.941352 -407.948637) (xy 104.996789 -407.954737) (xy 105.050746 -407.968843) (xy 105.102075 -407.990655)
			(xy 105.149681 -408.019709) (xy 105.192549 -408.055384) (xy 105.229766 -408.096921) (xy 105.260539 -408.143434)
			(xy 105.284211 -408.193931) (xy 105.300279 -408.247338) (xy 105.308399 -408.302514) (xy 105.308421 -408.30373)
			(xy 105.864404 -408.30373) (xy 105.868475 -408.248108) (xy 105.880601 -408.193671) (xy 105.900524 -408.14158)
			(xy 105.92782 -408.092945) (xy 105.961906 -408.048802) (xy 106.002055 -408.010093) (xy 106.047413 -407.977642)
			(xy 106.097013 -407.952141) (xy 106.149797 -407.934134) (xy 106.20464 -407.924004) (xy 106.260374 -407.921967)
			(xy 106.315811 -407.928067) (xy 106.369768 -407.942173) (xy 106.421097 -407.963985) (xy 106.468703 -407.993039)
			(xy 106.511571 -408.028714) (xy 106.548788 -408.070251) (xy 106.579561 -408.116764) (xy 106.603233 -408.167261)
			(xy 106.619301 -408.220668) (xy 106.627421 -408.275844) (xy 106.62793 -408.30373) (xy 106.627421 -408.331616)
			(xy 106.624796 -408.34945) (xy 107.156248 -408.34945) (xy 107.160319 -408.293828) (xy 107.172445 -408.239391)
			(xy 107.192368 -408.1873) (xy 107.219664 -408.138665) (xy 107.25375 -408.094522) (xy 107.293899 -408.055813)
			(xy 107.339257 -408.023362) (xy 107.388857 -407.997861) (xy 107.441641 -407.979854) (xy 107.496484 -407.969724)
			(xy 107.552218 -407.967687) (xy 107.607655 -407.973787) (xy 107.661612 -407.987893) (xy 107.712941 -408.009705)
			(xy 107.760547 -408.038759) (xy 107.803415 -408.074434) (xy 107.840632 -408.115971) (xy 107.871405 -408.162484)
			(xy 107.895077 -408.212981) (xy 107.911145 -408.266388) (xy 107.919265 -408.321564) (xy 107.919774 -408.34945)
			(xy 107.919265 -408.377336) (xy 107.911145 -408.432512) (xy 107.895077 -408.485919) (xy 107.871405 -408.536416)
			(xy 107.840632 -408.582929) (xy 107.803415 -408.624466) (xy 107.760547 -408.660141) (xy 107.712941 -408.689195)
			(xy 107.661612 -408.711007) (xy 107.607655 -408.725113) (xy 107.552218 -408.731213) (xy 107.496484 -408.729176)
			(xy 107.441641 -408.719046) (xy 107.388857 -408.701039) (xy 107.339257 -408.675538) (xy 107.293899 -408.643087)
			(xy 107.25375 -408.604378) (xy 107.219664 -408.560235) (xy 107.192368 -408.5116) (xy 107.172445 -408.459509)
			(xy 107.160319 -408.405072) (xy 107.156248 -408.34945) (xy 106.624796 -408.34945) (xy 106.619301 -408.386792)
			(xy 106.603233 -408.440199) (xy 106.579561 -408.490696) (xy 106.548788 -408.537209) (xy 106.511571 -408.578746)
			(xy 106.468703 -408.614421) (xy 106.421097 -408.643475) (xy 106.369768 -408.665287) (xy 106.315811 -408.679393)
			(xy 106.260374 -408.685493) (xy 106.20464 -408.683456) (xy 106.149797 -408.673326) (xy 106.097013 -408.655319)
			(xy 106.047413 -408.629818) (xy 106.002055 -408.597367) (xy 105.961906 -408.558658) (xy 105.92782 -408.514515)
			(xy 105.900524 -408.46588) (xy 105.880601 -408.413789) (xy 105.868475 -408.359352) (xy 105.864404 -408.30373)
			(xy 105.308421 -408.30373) (xy 105.308908 -408.3304) (xy 105.308399 -408.358286) (xy 105.300279 -408.413462)
			(xy 105.284211 -408.466869) (xy 105.260539 -408.517366) (xy 105.229766 -408.563879) (xy 105.192549 -408.605416)
			(xy 105.149681 -408.641091) (xy 105.102075 -408.670145) (xy 105.050746 -408.691957) (xy 104.996789 -408.706063)
			(xy 104.941352 -408.712163) (xy 104.885618 -408.710126) (xy 104.830775 -408.699996) (xy 104.777991 -408.681989)
			(xy 104.728391 -408.656488) (xy 104.683033 -408.624037) (xy 104.642884 -408.585328) (xy 104.608798 -408.541185)
			(xy 104.581502 -408.49255) (xy 104.561579 -408.440459) (xy 104.549453 -408.386022) (xy 104.545382 -408.3304)
			(xy 102.924288 -408.3304) (xy 102.924856 -408.330875) (xy 102.968134 -408.377396) (xy 103.005282 -408.428944)
			(xy 103.035722 -408.484717) (xy 103.058978 -408.543846) (xy 103.07469 -408.605412) (xy 103.082612 -408.668455)
			(xy 103.083106 -408.700224) (xy 103.082537 -408.73518) (xy 103.072972 -408.804433) (xy 103.054012 -408.871724)
			(xy 103.026014 -408.935785) (xy 102.989506 -408.995406) (xy 102.96779 -409.022804) (xy 102.962517 -409.029801)
			(xy 102.956672 -409.046305) (xy 102.95636 -409.055062) (xy 102.95636 -409.208986) (xy 102.956719 -409.217733)
			(xy 102.962558 -409.234225) (xy 102.96779 -409.241244) (xy 102.991231 -409.270911) (xy 103.029998 -409.335825)
			(xy 103.045006 -409.37053) (xy 103.048589 -409.378353) (xy 103.060003 -409.391212) (xy 103.067358 -409.395676)
			(xy 103.093266 -409.410154) (xy 103.100926 -409.413974) (xy 103.117795 -409.416826) (xy 103.126286 -409.415742)
			(xy 103.147337 -409.412413) (xy 103.189811 -409.408854) (xy 103.211122 -409.40863) (xy 103.243085 -409.409057)
			(xy 103.306505 -409.417072) (xy 103.368421 -409.432972) (xy 103.427857 -409.456506) (xy 103.483874 -409.487304)
			(xy 103.535589 -409.524879) (xy 103.582188 -409.56864) (xy 103.622934 -409.617896) (xy 103.62795 -409.6258)
			(xy 104.570782 -409.6258) (xy 104.574853 -409.570178) (xy 104.586979 -409.515741) (xy 104.606902 -409.46365)
			(xy 104.634198 -409.415015) (xy 104.668284 -409.370872) (xy 104.708433 -409.332163) (xy 104.753791 -409.299712)
			(xy 104.803391 -409.274211) (xy 104.856175 -409.256204) (xy 104.911018 -409.246074) (xy 104.966752 -409.244037)
			(xy 105.022189 -409.250137) (xy 105.076146 -409.264243) (xy 105.127475 -409.286055) (xy 105.175081 -409.315109)
			(xy 105.217949 -409.350784) (xy 105.255166 -409.392321) (xy 105.285939 -409.438834) (xy 105.309611 -409.489331)
			(xy 105.325679 -409.542738) (xy 105.326951 -409.551378) (xy 107.171488 -409.551378) (xy 107.175559 -409.495756)
			(xy 107.187685 -409.441319) (xy 107.207608 -409.389228) (xy 107.234904 -409.340593) (xy 107.26899 -409.29645)
			(xy 107.309139 -409.257741) (xy 107.354497 -409.22529) (xy 107.404097 -409.199789) (xy 107.456881 -409.181782)
			(xy 107.511724 -409.171652) (xy 107.567458 -409.169615) (xy 107.622895 -409.175715) (xy 107.676852 -409.189821)
			(xy 107.728181 -409.211633) (xy 107.775787 -409.240687) (xy 107.818655 -409.276362) (xy 107.855872 -409.317899)
			(xy 107.886645 -409.364412) (xy 107.910317 -409.414909) (xy 107.926385 -409.468316) (xy 107.934505 -409.523492)
			(xy 107.935014 -409.551378) (xy 107.934505 -409.579264) (xy 107.926385 -409.63444) (xy 107.910317 -409.687847)
			(xy 107.886645 -409.738344) (xy 107.855872 -409.784857) (xy 107.818655 -409.826394) (xy 107.775787 -409.862069)
			(xy 107.728181 -409.891123) (xy 107.676852 -409.912935) (xy 107.672598 -409.914047) (xy 108.838994 -409.914047)
			(xy 108.838994 -409.850125) (xy 108.847005 -409.786707) (xy 108.862902 -409.724793) (xy 108.886434 -409.66536)
			(xy 108.917228 -409.609345) (xy 108.954801 -409.55763) (xy 108.998558 -409.511033) (xy 109.047811 -409.470288)
			(xy 109.101782 -409.436037) (xy 109.159621 -409.40882) (xy 109.220414 -409.389067) (xy 109.283204 -409.377089)
			(xy 109.347 -409.373076) (xy 109.410796 -409.377089) (xy 109.473586 -409.389067) (xy 109.534379 -409.40882)
			(xy 109.592218 -409.436037) (xy 109.646189 -409.470288) (xy 109.695442 -409.511033) (xy 109.739199 -409.55763)
			(xy 109.776772 -409.609345) (xy 109.807566 -409.66536) (xy 109.831098 -409.724793) (xy 109.846995 -409.786707)
			(xy 109.855006 -409.850125) (xy 109.855508 -409.882086) (xy 109.855169 -409.903676) (xy 110.432596 -409.903676)
			(xy 110.433165 -409.86872) (xy 110.44273 -409.799467) (xy 110.46169 -409.732175) (xy 110.489688 -409.668115)
			(xy 110.526196 -409.608494) (xy 110.547912 -409.581096) (xy 110.55321 -409.574098) (xy 110.559184 -409.557606)
			(xy 110.559596 -409.548838) (xy 110.559596 -409.394914) (xy 110.55923 -409.386137) (xy 110.553248 -409.369635)
			(xy 110.547912 -409.362656) (xy 110.52618 -409.335271) (xy 110.489685 -409.275641) (xy 110.461696 -409.211577)
			(xy 110.44274 -409.144285) (xy 110.433173 -409.075032) (xy 110.432596 -409.040076) (xy 110.433034 -409.009344)
			(xy 110.440445 -408.948329) (xy 110.455156 -408.888653) (xy 110.476954 -408.831184) (xy 110.505519 -408.776762)
			(xy 110.540436 -408.72618) (xy 110.581195 -408.680175) (xy 110.627202 -408.639419) (xy 110.677786 -408.604505)
			(xy 110.73221 -408.575942) (xy 110.789679 -408.554148) (xy 110.849357 -408.53944) (xy 110.910372 -408.532032)
			(xy 110.941104 -408.531568) (xy 110.978952 -408.53227) (xy 111.053813 -408.54349) (xy 111.090202 -408.55392)
			(xy 111.099854 -408.556968) (xy 111.119412 -408.55519) (xy 111.200184 -408.513534) (xy 111.213138 -408.498548)
			(xy 111.216186 -408.48915) (xy 111.225015 -408.464234) (xy 111.248636 -408.416943) (xy 111.278559 -408.373365)
			(xy 111.31421 -408.334334) (xy 111.354907 -408.300598) (xy 111.399872 -408.272803) (xy 111.448242 -408.251479)
			(xy 111.499093 -408.237037) (xy 111.551451 -408.229752) (xy 111.577882 -408.229308) (xy 111.605137 -408.229738)
			(xy 111.659092 -408.237493) (xy 111.711394 -408.252848) (xy 111.760979 -408.27549) (xy 111.806836 -408.304959)
			(xy 111.848033 -408.340654) (xy 111.88373 -408.381849) (xy 111.913201 -408.427705) (xy 111.935846 -408.477289)
			(xy 111.951203 -408.52959) (xy 111.958961 -408.583545) (xy 111.958961 -408.638055) (xy 111.951203 -408.69201)
			(xy 111.935846 -408.744311) (xy 111.913201 -408.793895) (xy 111.88373 -408.839751) (xy 111.848033 -408.880946)
			(xy 111.806836 -408.916641) (xy 111.760979 -408.94611) (xy 111.711394 -408.968752) (xy 111.659092 -408.984107)
			(xy 111.605137 -408.991862) (xy 111.577882 -408.992324) (xy 111.555022 -408.991562) (xy 111.545116 -408.991054)
			(xy 111.52632 -408.997404) (xy 111.457486 -409.056586) (xy 111.448596 -409.074366) (xy 111.44758 -409.084272)
			(xy 111.44449 -409.11464) (xy 111.431991 -409.174388) (xy 111.412421 -409.232208) (xy 111.386063 -409.287265)
			(xy 111.353297 -409.338767) (xy 111.334296 -409.362656) (xy 111.329007 -409.36966) (xy 111.323029 -409.386148)
			(xy 111.322612 -409.394914) (xy 111.322612 -409.548838) (xy 111.323 -409.557613) (xy 111.328967 -409.574115)
			(xy 111.334296 -409.581096) (xy 111.352707 -409.604235) (xy 111.384646 -409.654003) (xy 111.410604 -409.707135)
			(xy 111.430232 -409.762916) (xy 111.437166 -409.791662) (xy 111.439198 -409.801314) (xy 111.449866 -409.817062)
			(xy 111.523272 -409.8671) (xy 111.541814 -409.871418) (xy 111.551466 -409.869894) (xy 111.565666 -409.867865)
			(xy 111.594272 -409.865707) (xy 111.608616 -409.865576) (xy 111.635865 -409.866095) (xy 111.689809 -409.873853)
			(xy 111.7421 -409.889209) (xy 111.791673 -409.91185) (xy 111.837519 -409.941316) (xy 111.878706 -409.977006)
			(xy 111.914394 -410.018194) (xy 111.943857 -410.064041) (xy 111.966496 -410.113615) (xy 111.98185 -410.165907)
			(xy 111.989606 -410.219851) (xy 111.989606 -410.274349) (xy 111.98185 -410.328293) (xy 111.966496 -410.380585)
			(xy 111.943857 -410.430159) (xy 111.914394 -410.476006) (xy 111.878706 -410.517194) (xy 111.837519 -410.552884)
			(xy 111.791673 -410.58235) (xy 111.7421 -410.604991) (xy 111.689809 -410.620347) (xy 111.635865 -410.628105)
			(xy 111.608616 -410.628592) (xy 111.582358 -410.628148) (xy 111.530342 -410.620923) (xy 111.479807 -410.606636)
			(xy 111.431708 -410.585555) (xy 111.386953 -410.55808) (xy 111.346387 -410.524729) (xy 111.310777 -410.486131)
			(xy 111.280794 -410.443015) (xy 111.26851 -410.419804) (xy 111.263938 -410.411168) (xy 111.249968 -410.398722)
			(xy 111.166402 -410.367988) (xy 111.147606 -410.368496) (xy 111.138462 -410.372306) (xy 111.107105 -410.384919)
			(xy 111.04189 -410.402673) (xy 110.974898 -410.41163) (xy 110.941104 -410.412184) (xy 110.910371 -410.411759)
			(xy 110.849353 -410.40435) (xy 110.789673 -410.38964) (xy 110.732202 -410.367844) (xy 110.677777 -410.339279)
			(xy 110.627192 -410.304361) (xy 110.581185 -410.263601) (xy 110.540426 -410.217592) (xy 110.505511 -410.167006)
			(xy 110.476948 -410.11258) (xy 110.455154 -410.055107) (xy 110.440447 -409.995427) (xy 110.43304 -409.934409)
			(xy 110.432596 -409.903676) (xy 109.855169 -409.903676) (xy 109.855006 -409.914047) (xy 109.846995 -409.977465)
			(xy 109.831098 -410.039379) (xy 109.807566 -410.098812) (xy 109.776772 -410.154827) (xy 109.739199 -410.206542)
			(xy 109.695442 -410.253139) (xy 109.646189 -410.293884) (xy 109.592218 -410.328135) (xy 109.534379 -410.355352)
			(xy 109.473586 -410.375105) (xy 109.410796 -410.387083) (xy 109.347 -410.391097) (xy 109.283204 -410.387083)
			(xy 109.220414 -410.375105) (xy 109.159621 -410.355352) (xy 109.101782 -410.328135) (xy 109.047811 -410.293884)
			(xy 108.998558 -410.253139) (xy 108.954801 -410.206542) (xy 108.917228 -410.154827) (xy 108.886434 -410.098812)
			(xy 108.862902 -410.039379) (xy 108.847005 -409.977465) (xy 108.838994 -409.914047) (xy 107.672598 -409.914047)
			(xy 107.622895 -409.927041) (xy 107.567458 -409.933141) (xy 107.511724 -409.931104) (xy 107.456881 -409.920974)
			(xy 107.404097 -409.902967) (xy 107.354497 -409.877466) (xy 107.309139 -409.845015) (xy 107.26899 -409.806306)
			(xy 107.234904 -409.762163) (xy 107.207608 -409.713528) (xy 107.187685 -409.661437) (xy 107.175559 -409.607)
			(xy 107.171488 -409.551378) (xy 105.326951 -409.551378) (xy 105.333799 -409.597914) (xy 105.334308 -409.6258)
			(xy 105.333799 -409.653686) (xy 105.325679 -409.708862) (xy 105.309611 -409.762269) (xy 105.285939 -409.812766)
			(xy 105.255166 -409.859279) (xy 105.217949 -409.900816) (xy 105.175081 -409.936491) (xy 105.127475 -409.965545)
			(xy 105.076146 -409.987357) (xy 105.022189 -410.001463) (xy 104.966752 -410.007563) (xy 104.911018 -410.005526)
			(xy 104.856175 -409.995396) (xy 104.803391 -409.977389) (xy 104.753791 -409.951888) (xy 104.708433 -409.919437)
			(xy 104.668284 -409.880728) (xy 104.634198 -409.836585) (xy 104.606902 -409.78795) (xy 104.586979 -409.735859)
			(xy 104.574853 -409.681422) (xy 104.570782 -409.6258) (xy 103.62795 -409.6258) (xy 103.657186 -409.67187)
			(xy 103.684403 -409.729712) (xy 103.704157 -409.790508) (xy 103.716135 -409.853301) (xy 103.720149 -409.9171)
			(xy 103.716135 -409.980899) (xy 103.704157 -410.043692) (xy 103.684403 -410.104488) (xy 103.657186 -410.16233)
			(xy 103.622934 -410.216304) (xy 103.582188 -410.26556) (xy 103.535589 -410.309321) (xy 103.483874 -410.346896)
			(xy 103.427857 -410.377694) (xy 103.368421 -410.401228) (xy 103.306505 -410.417128) (xy 103.243085 -410.425143)
			(xy 103.211122 -410.425646) (xy 103.18394 -410.42528) (xy 103.129886 -410.419487) (xy 103.076758 -410.407964)
			(xy 103.050848 -410.399738) (xy 103.041704 -410.39669) (xy 103.023162 -410.397452) (xy 102.943152 -410.433012)
			(xy 102.929944 -410.445966) (xy 102.926134 -410.454856) (xy 102.914497 -410.479778) (xy 102.885168 -410.526307)
			(xy 102.849464 -410.568143) (xy 102.808123 -410.604421) (xy 102.762003 -410.634387) (xy 102.712058 -410.657423)
			(xy 102.659324 -410.67305) (xy 102.604892 -410.680944) (xy 102.577392 -410.681424) (xy 102.550141 -410.68093)
			(xy 102.496195 -410.673173) (xy 102.443901 -410.657817) (xy 102.394325 -410.635176) (xy 102.348475 -410.605711)
			(xy 102.307286 -410.57002) (xy 102.271594 -410.528831) (xy 102.242128 -410.482982) (xy 102.219486 -410.433406)
			(xy 102.204129 -410.381113) (xy 102.196371 -410.327167) (xy 102.195884 -410.299916) (xy 102.196429 -410.27137)
			(xy 102.204945 -410.214916) (xy 102.221774 -410.160361) (xy 102.246542 -410.108921) (xy 102.262178 -410.085032)
			(xy 102.267512 -410.077158) (xy 102.27183 -410.059124) (xy 102.2604 -409.973018) (xy 102.25151 -409.956762)
			(xy 102.244398 -409.950412) (xy 102.218211 -409.92728) (xy 102.171784 -409.875064) (xy 102.132934 -409.816989)
			(xy 102.117144 -409.78582) (xy 102.110286 -409.772104) (xy 102.084886 -409.75661) (xy 101.961442 -409.760928)
			(xy 101.937058 -409.777946) (xy 101.93147 -409.79217) (xy 101.918421 -409.823141) (xy 101.885378 -409.881661)
			(xy 101.844914 -409.93532) (xy 101.797737 -409.983182) (xy 101.744666 -410.024414) (xy 101.686628 -410.058297)
			(xy 101.624632 -410.084241) (xy 101.55976 -410.101794) (xy 101.493141 -410.11065) (xy 101.459538 -410.111194)
			(xy 101.427573 -410.110743) (xy 101.364147 -410.102735) (xy 101.302225 -410.08684) (xy 101.242784 -410.06331)
			(xy 101.18676 -410.032514) (xy 101.135039 -409.99494) (xy 101.088434 -409.951179) (xy 101.047682 -409.901922)
			(xy 101.013426 -409.847945) (xy 100.986205 -409.790101) (xy 100.966449 -409.7293) (xy 100.954469 -409.666503)
			(xy 100.950454 -409.6027) (xy 96.644248 -409.6027) (xy 96.646024 -409.623074) (xy 96.655885 -409.649171)
			(xy 96.672445 -409.671622) (xy 96.694468 -409.688748) (xy 96.720307 -409.699268) (xy 96.734122 -409.701238)
			(xy 96.759324 -409.704564) (xy 96.808364 -409.717947) (xy 96.854782 -409.738669) (xy 96.897486 -409.766243)
			(xy 96.935475 -409.80002) (xy 96.967853 -409.839207) (xy 96.993862 -409.882883) (xy 97.012889 -409.930021)
			(xy 97.024487 -409.979513) (xy 97.028384 -410.030196) (xy 97.024488 -410.08088) (xy 97.012891 -410.130372)
			(xy 96.993865 -410.177511) (xy 96.967858 -410.221187) (xy 96.93548 -410.260374) (xy 96.897492 -410.294152)
			(xy 96.854788 -410.321727) (xy 96.808371 -410.34245) (xy 96.759331 -410.355835) (xy 96.734122 -410.359098)
			(xy 96.720319 -410.361106) (xy 96.6945 -410.371637) (xy 96.672495 -410.388761) (xy 96.655945 -410.411202)
			(xy 96.646085 -410.437284) (xy 96.643651 -410.465061) (xy 96.648824 -410.49246) (xy 96.65462 -410.505148)
			(xy 96.666371 -410.5299) (xy 96.68298 -410.582112) (xy 96.691412 -410.636249) (xy 96.691958 -410.663644)
			(xy 96.691958 -410.664152) (xy 96.691506 -410.69025) (xy 96.683904 -410.741888) (xy 96.668854 -410.791867)
			(xy 96.646678 -410.839117) (xy 96.617851 -410.88263) (xy 96.582988 -410.921475) (xy 96.56318 -410.938472)
			(xy 96.558862 -410.942028) (xy 96.55526 -410.9466) (xy 104.545382 -410.9466) (xy 104.549453 -410.890978)
			(xy 104.561579 -410.836541) (xy 104.581502 -410.78445) (xy 104.608798 -410.735815) (xy 104.642884 -410.691672)
			(xy 104.683033 -410.652963) (xy 104.728391 -410.620512) (xy 104.777991 -410.595011) (xy 104.830775 -410.577004)
			(xy 104.885618 -410.566874) (xy 104.941352 -410.564837) (xy 104.996789 -410.570937) (xy 105.050746 -410.585043)
			(xy 105.102075 -410.606855) (xy 105.149681 -410.635909) (xy 105.192549 -410.671584) (xy 105.229766 -410.713121)
			(xy 105.260539 -410.759634) (xy 105.284211 -410.810131) (xy 105.300279 -410.863538) (xy 105.308399 -410.918714)
			(xy 105.308908 -410.9466) (xy 105.308444 -410.972) (xy 105.916982 -410.972) (xy 105.921053 -410.916378)
			(xy 105.933179 -410.861941) (xy 105.953102 -410.80985) (xy 105.980398 -410.761215) (xy 106.014484 -410.717072)
			(xy 106.054633 -410.678363) (xy 106.099991 -410.645912) (xy 106.149591 -410.620411) (xy 106.202375 -410.602404)
			(xy 106.257218 -410.592274) (xy 106.312952 -410.590237) (xy 106.368389 -410.596337) (xy 106.422346 -410.610443)
			(xy 106.473675 -410.632255) (xy 106.521281 -410.661309) (xy 106.564149 -410.696984) (xy 106.601366 -410.738521)
			(xy 106.632139 -410.785034) (xy 106.655811 -410.835531) (xy 106.671879 -410.888938) (xy 106.678758 -410.935678)
			(xy 107.148628 -410.935678) (xy 107.152699 -410.880056) (xy 107.164825 -410.825619) (xy 107.184748 -410.773528)
			(xy 107.212044 -410.724893) (xy 107.24613 -410.68075) (xy 107.286279 -410.642041) (xy 107.331637 -410.60959)
			(xy 107.381237 -410.584089) (xy 107.434021 -410.566082) (xy 107.488864 -410.555952) (xy 107.544598 -410.553915)
			(xy 107.600035 -410.560015) (xy 107.653992 -410.574121) (xy 107.705321 -410.595933) (xy 107.752927 -410.624987)
			(xy 107.795795 -410.660662) (xy 107.833012 -410.702199) (xy 107.863785 -410.748712) (xy 107.887457 -410.799209)
			(xy 107.903525 -410.852616) (xy 107.911645 -410.907792) (xy 107.912154 -410.935678) (xy 107.911645 -410.963564)
			(xy 107.903525 -411.01874) (xy 107.887457 -411.072147) (xy 107.863785 -411.122644) (xy 107.833012 -411.169157)
			(xy 107.795795 -411.210694) (xy 107.752927 -411.246369) (xy 107.705321 -411.275423) (xy 107.653992 -411.297235)
			(xy 107.600035 -411.311341) (xy 107.544598 -411.317441) (xy 107.488864 -411.315404) (xy 107.434021 -411.305274)
			(xy 107.381237 -411.287267) (xy 107.331637 -411.261766) (xy 107.286279 -411.229315) (xy 107.24613 -411.190606)
			(xy 107.212044 -411.146463) (xy 107.184748 -411.097828) (xy 107.164825 -411.045737) (xy 107.152699 -410.9913)
			(xy 107.148628 -410.935678) (xy 106.678758 -410.935678) (xy 106.679999 -410.944114) (xy 106.680508 -410.972)
			(xy 106.679999 -410.999886) (xy 106.671879 -411.055062) (xy 106.655811 -411.108469) (xy 106.632139 -411.158966)
			(xy 106.601366 -411.205479) (xy 106.564149 -411.247016) (xy 106.521281 -411.282691) (xy 106.473675 -411.311745)
			(xy 106.422346 -411.333557) (xy 106.368389 -411.347663) (xy 106.312952 -411.353763) (xy 106.257218 -411.351726)
			(xy 106.202375 -411.341596) (xy 106.149591 -411.323589) (xy 106.099991 -411.298088) (xy 106.054633 -411.265637)
			(xy 106.014484 -411.226928) (xy 105.980398 -411.182785) (xy 105.953102 -411.13415) (xy 105.933179 -411.082059)
			(xy 105.921053 -411.027622) (xy 105.916982 -410.972) (xy 105.308444 -410.972) (xy 105.308399 -410.974486)
			(xy 105.300279 -411.029662) (xy 105.284211 -411.083069) (xy 105.260539 -411.133566) (xy 105.229766 -411.180079)
			(xy 105.192549 -411.221616) (xy 105.149681 -411.257291) (xy 105.102075 -411.286345) (xy 105.050746 -411.308157)
			(xy 104.996789 -411.322263) (xy 104.941352 -411.328363) (xy 104.885618 -411.326326) (xy 104.830775 -411.316196)
			(xy 104.777991 -411.298189) (xy 104.728391 -411.272688) (xy 104.683033 -411.240237) (xy 104.642884 -411.201528)
			(xy 104.608798 -411.157385) (xy 104.581502 -411.10875) (xy 104.561579 -411.056659) (xy 104.549453 -411.002222)
			(xy 104.545382 -410.9466) (xy 96.55526 -410.9466) (xy 96.552258 -410.95041) (xy 96.540574 -410.974032)
			(xy 96.538195 -410.97931) (xy 96.535623 -410.990596) (xy 96.535494 -410.996384) (xy 96.535494 -411.892961)
			(xy 98.297994 -411.892961) (xy 98.297994 -411.829039) (xy 98.306005 -411.765621) (xy 98.321902 -411.703707)
			(xy 98.345434 -411.644274) (xy 98.376228 -411.588259) (xy 98.413801 -411.536544) (xy 98.457558 -411.489947)
			(xy 98.506811 -411.449202) (xy 98.560782 -411.414951) (xy 98.618621 -411.387734) (xy 98.679414 -411.367981)
			(xy 98.742204 -411.356003) (xy 98.806 -411.35199) (xy 98.869796 -411.356003) (xy 98.932586 -411.367981)
			(xy 98.993379 -411.387734) (xy 99.051218 -411.414951) (xy 99.105189 -411.449202) (xy 99.154442 -411.489947)
			(xy 99.198199 -411.536544) (xy 99.235772 -411.588259) (xy 99.266566 -411.644274) (xy 99.290098 -411.703707)
			(xy 99.305995 -411.765621) (xy 99.314006 -411.829039) (xy 99.314508 -411.861) (xy 99.314006 -411.892961)
			(xy 99.567994 -411.892961) (xy 99.567994 -411.829039) (xy 99.576005 -411.765621) (xy 99.591902 -411.703707)
			(xy 99.615434 -411.644274) (xy 99.646228 -411.588259) (xy 99.683801 -411.536544) (xy 99.727558 -411.489947)
			(xy 99.776811 -411.449202) (xy 99.830782 -411.414951) (xy 99.888621 -411.387734) (xy 99.949414 -411.367981)
			(xy 100.012204 -411.356003) (xy 100.076 -411.35199) (xy 100.139796 -411.356003) (xy 100.202586 -411.367981)
			(xy 100.263379 -411.387734) (xy 100.321218 -411.414951) (xy 100.375189 -411.449202) (xy 100.424442 -411.489947)
			(xy 100.468199 -411.536544) (xy 100.505772 -411.588259) (xy 100.536566 -411.644274) (xy 100.560098 -411.703707)
			(xy 100.575995 -411.765621) (xy 100.584006 -411.829039) (xy 100.584508 -411.861) (xy 100.584006 -411.892961)
			(xy 101.188514 -411.892961) (xy 101.188514 -411.829039) (xy 101.196525 -411.765621) (xy 101.212422 -411.703707)
			(xy 101.235954 -411.644274) (xy 101.266748 -411.588259) (xy 101.304321 -411.536544) (xy 101.348078 -411.489947)
			(xy 101.397331 -411.449202) (xy 101.451302 -411.414951) (xy 101.509141 -411.387734) (xy 101.569934 -411.367981)
			(xy 101.632724 -411.356003) (xy 101.69652 -411.35199) (xy 101.760316 -411.356003) (xy 101.823106 -411.367981)
			(xy 101.883899 -411.387734) (xy 101.941738 -411.414951) (xy 101.995709 -411.449202) (xy 102.044962 -411.489947)
			(xy 102.088719 -411.536544) (xy 102.097095 -411.548072) (xy 102.472236 -411.548072) (xy 102.472738 -411.516111)
			(xy 102.480749 -411.452693) (xy 102.496646 -411.390779) (xy 102.520178 -411.331346) (xy 102.550972 -411.275331)
			(xy 102.588545 -411.223616) (xy 102.632302 -411.177019) (xy 102.681555 -411.136274) (xy 102.735526 -411.102023)
			(xy 102.793365 -411.074806) (xy 102.854158 -411.055053) (xy 102.916948 -411.043075) (xy 102.980744 -411.039062)
			(xy 103.04454 -411.043075) (xy 103.10733 -411.055053) (xy 103.168123 -411.074806) (xy 103.225962 -411.102023)
			(xy 103.279933 -411.136274) (xy 103.329186 -411.177019) (xy 103.372943 -411.223616) (xy 103.410516 -411.275331)
			(xy 103.44131 -411.331346) (xy 103.464842 -411.390779) (xy 103.480739 -411.452693) (xy 103.48875 -411.516111)
			(xy 103.489252 -411.548072) (xy 103.488728 -411.580705) (xy 103.480381 -411.645434) (xy 103.463822 -411.708564)
			(xy 103.439321 -411.769056) (xy 103.407283 -411.825917) (xy 103.38816 -411.852364) (xy 103.382759 -411.860169)
			(xy 103.377682 -411.878448) (xy 103.378254 -411.887924) (xy 103.381302 -411.918658) (xy 103.382598 -411.928036)
			(xy 103.39123 -411.944873) (xy 103.398066 -411.951424) (xy 103.420616 -411.972135) (xy 103.461115 -412.018056)
			(xy 103.495802 -412.06851) (xy 103.524175 -412.122768) (xy 103.545823 -412.180041) (xy 103.560431 -412.239501)
			(xy 103.567788 -412.300286) (xy 103.568246 -412.3309) (xy 103.567744 -412.362861) (xy 103.559733 -412.426279)
			(xy 103.543836 -412.488193) (xy 103.520304 -412.547626) (xy 103.50093 -412.582868) (xy 109.134148 -412.582868)
			(xy 109.134683 -412.549385) (xy 109.143485 -412.483) (xy 109.160917 -412.418343) (xy 109.186681 -412.356531)
			(xy 109.220329 -412.298632) (xy 109.261281 -412.245648) (xy 109.30883 -412.198492) (xy 109.362153 -412.157982)
			(xy 109.420329 -412.124815) (xy 109.45114 -412.111698) (xy 109.459549 -412.107898) (xy 109.473098 -412.095393)
			(xy 109.477556 -412.087314) (xy 109.491272 -412.059882) (xy 109.494982 -412.051359) (xy 109.496683 -412.032866)
			(xy 109.494574 -412.023814) (xy 109.486112 -411.99087) (xy 109.477065 -411.923457) (xy 109.47654 -411.889448)
			(xy 109.477042 -411.857487) (xy 109.485053 -411.794069) (xy 109.50095 -411.732155) (xy 109.524482 -411.672722)
			(xy 109.555276 -411.616707) (xy 109.592849 -411.564992) (xy 109.636606 -411.518395) (xy 109.685859 -411.47765)
			(xy 109.73983 -411.443399) (xy 109.797669 -411.416182) (xy 109.858462 -411.396429) (xy 109.921252 -411.384451)
			(xy 109.985048 -411.380438) (xy 110.048844 -411.384451) (xy 110.111634 -411.396429) (xy 110.172427 -411.416182)
			(xy 110.230266 -411.443399) (xy 110.284237 -411.47765) (xy 110.33349 -411.518395) (xy 110.377247 -411.564992)
			(xy 110.41482 -411.616707) (xy 110.445614 -411.672722) (xy 110.469146 -411.732155) (xy 110.485043 -411.794069)
			(xy 110.493054 -411.857487) (xy 110.493556 -411.889448) (xy 110.493032 -411.922931) (xy 110.484229 -411.989317)
			(xy 110.466794 -412.053974) (xy 110.441029 -412.115786) (xy 110.407379 -412.173685) (xy 110.366426 -412.226669)
			(xy 110.318876 -412.273824) (xy 110.265552 -412.314334) (xy 110.207376 -412.347501) (xy 110.176564 -412.360618)
			(xy 110.168152 -412.364413) (xy 110.154605 -412.376921) (xy 110.150148 -412.385002) (xy 110.136432 -412.412434)
			(xy 110.132713 -412.420953) (xy 110.13102 -412.439449) (xy 110.13313 -412.448502) (xy 110.141592 -412.481446)
			(xy 110.15064 -412.548859) (xy 110.151164 -412.582868) (xy 110.150572 -412.617695) (xy 110.14108 -412.686698)
			(xy 110.122256 -412.753759) (xy 110.094451 -412.817621) (xy 110.058188 -412.87709) (xy 110.03661 -412.904432)
			(xy 110.029498 -412.913068) (xy 110.02391 -412.934658) (xy 110.041436 -413.032448) (xy 110.054136 -413.050736)
			(xy 110.063534 -413.056324) (xy 110.087685 -413.071112) (xy 110.131706 -413.106735) (xy 110.169976 -413.148476)
			(xy 110.201653 -413.195417) (xy 110.226041 -413.246525) (xy 110.242604 -413.300679) (xy 110.250977 -413.356685)
			(xy 110.251494 -413.385) (xy 110.251008 -413.412251) (xy 110.243252 -413.466199) (xy 110.227897 -413.518494)
			(xy 110.205255 -413.568071) (xy 110.175789 -413.613921) (xy 110.140098 -413.655112) (xy 110.098907 -413.690803)
			(xy 110.053057 -413.720269) (xy 110.00348 -413.742911) (xy 109.951185 -413.758266) (xy 109.897237 -413.766022)
			(xy 109.842735 -413.766022) (xy 109.788787 -413.758266) (xy 109.736492 -413.742911) (xy 109.686915 -413.720269)
			(xy 109.641065 -413.690803) (xy 109.599874 -413.655112) (xy 109.564183 -413.613921) (xy 109.534717 -413.568071)
			(xy 109.512075 -413.518494) (xy 109.49672 -413.466199) (xy 109.488964 -413.412251) (xy 109.488478 -413.385)
			(xy 109.48907 -413.35406) (xy 109.499051 -413.29299) (xy 109.518752 -413.234329) (xy 109.532674 -413.206692)
			(xy 109.537754 -413.19704) (xy 109.539024 -413.174688) (xy 109.502702 -413.082232) (xy 109.4867 -413.066992)
			(xy 109.476032 -413.063436) (xy 109.446459 -413.052675) (xy 109.390004 -413.024865) (xy 109.337411 -412.990302)
			(xy 109.289484 -412.949515) (xy 109.246955 -412.903127) (xy 109.210473 -412.851847) (xy 109.180597 -412.796458)
			(xy 109.157781 -412.737806) (xy 109.142376 -412.676787) (xy 109.134616 -412.614335) (xy 109.134148 -412.582868)
			(xy 103.50093 -412.582868) (xy 103.48951 -412.603641) (xy 103.451937 -412.655356) (xy 103.40818 -412.701953)
			(xy 103.358927 -412.742698) (xy 103.304956 -412.776949) (xy 103.247117 -412.804166) (xy 103.186324 -412.823919)
			(xy 103.123534 -412.835897) (xy 103.059738 -412.839911) (xy 102.995942 -412.835897) (xy 102.933152 -412.823919)
			(xy 102.872359 -412.804166) (xy 102.81452 -412.776949) (xy 102.760549 -412.742698) (xy 102.711296 -412.701953)
			(xy 102.667539 -412.655356) (xy 102.629966 -412.603641) (xy 102.599172 -412.547626) (xy 102.57564 -412.488193)
			(xy 102.559743 -412.426279) (xy 102.551732 -412.362861) (xy 102.55123 -412.3309) (xy 102.551723 -412.298266)
			(xy 102.560075 -412.233535) (xy 102.57664 -412.170404) (xy 102.601148 -412.109912) (xy 102.633195 -412.053054)
			(xy 102.652322 -412.026608) (xy 102.657688 -412.018782) (xy 102.662787 -412.00052) (xy 102.662228 -411.991048)
			(xy 102.65918 -411.960314) (xy 102.657855 -411.950942) (xy 102.649244 -411.934102) (xy 102.642416 -411.927548)
			(xy 102.619868 -411.906834) (xy 102.579367 -411.860916) (xy 102.544677 -411.810462) (xy 102.516303 -411.756205)
			(xy 102.494655 -411.698932) (xy 102.480048 -411.639471) (xy 102.472692 -411.578686) (xy 102.472236 -411.548072)
			(xy 102.097095 -411.548072) (xy 102.126292 -411.588259) (xy 102.157086 -411.644274) (xy 102.180618 -411.703707)
			(xy 102.196515 -411.765621) (xy 102.204526 -411.829039) (xy 102.205028 -411.861) (xy 102.204526 -411.892961)
			(xy 102.196515 -411.956379) (xy 102.180618 -412.018293) (xy 102.157086 -412.077726) (xy 102.126292 -412.133741)
			(xy 102.088719 -412.185456) (xy 102.044962 -412.232053) (xy 101.995709 -412.272798) (xy 101.941738 -412.307049)
			(xy 101.883899 -412.334266) (xy 101.823106 -412.354019) (xy 101.760316 -412.365997) (xy 101.69652 -412.370011)
			(xy 101.632724 -412.365997) (xy 101.569934 -412.354019) (xy 101.509141 -412.334266) (xy 101.451302 -412.307049)
			(xy 101.397331 -412.272798) (xy 101.348078 -412.232053) (xy 101.304321 -412.185456) (xy 101.266748 -412.133741)
			(xy 101.235954 -412.077726) (xy 101.212422 -412.018293) (xy 101.196525 -411.956379) (xy 101.188514 -411.892961)
			(xy 100.584006 -411.892961) (xy 100.575995 -411.956379) (xy 100.560098 -412.018293) (xy 100.536566 -412.077726)
			(xy 100.505772 -412.133741) (xy 100.468199 -412.185456) (xy 100.424442 -412.232053) (xy 100.375189 -412.272798)
			(xy 100.321218 -412.307049) (xy 100.263379 -412.334266) (xy 100.202586 -412.354019) (xy 100.139796 -412.365997)
			(xy 100.076 -412.370011) (xy 100.012204 -412.365997) (xy 99.949414 -412.354019) (xy 99.888621 -412.334266)
			(xy 99.830782 -412.307049) (xy 99.776811 -412.272798) (xy 99.727558 -412.232053) (xy 99.683801 -412.185456)
			(xy 99.646228 -412.133741) (xy 99.615434 -412.077726) (xy 99.591902 -412.018293) (xy 99.576005 -411.956379)
			(xy 99.567994 -411.892961) (xy 99.314006 -411.892961) (xy 99.305995 -411.956379) (xy 99.290098 -412.018293)
			(xy 99.266566 -412.077726) (xy 99.235772 -412.133741) (xy 99.198199 -412.185456) (xy 99.154442 -412.232053)
			(xy 99.105189 -412.272798) (xy 99.051218 -412.307049) (xy 98.993379 -412.334266) (xy 98.932586 -412.354019)
			(xy 98.869796 -412.365997) (xy 98.806 -412.370011) (xy 98.742204 -412.365997) (xy 98.679414 -412.354019)
			(xy 98.618621 -412.334266) (xy 98.560782 -412.307049) (xy 98.506811 -412.272798) (xy 98.457558 -412.232053)
			(xy 98.413801 -412.185456) (xy 98.376228 -412.133741) (xy 98.345434 -412.077726) (xy 98.321902 -412.018293)
			(xy 98.306005 -411.956379) (xy 98.297994 -411.892961) (xy 96.535494 -411.892961) (xy 96.535494 -416.729926)
			(xy 96.536183 -416.742369) (xy 96.547893 -416.764337) (xy 96.557846 -416.771836) (xy 96.637856 -416.826192)
			(xy 96.663002 -416.828986) (xy 96.674686 -416.82416) (xy 96.704728 -416.812715) (xy 96.766975 -416.796637)
			(xy 96.830755 -416.788552) (xy 96.8629 -416.788092) (xy 96.863154 -416.788092) (xy 96.902271 -416.78881)
			(xy 96.979581 -416.800804) (xy 97.017078 -416.811968) (xy 97.028762 -416.815778) (xy 97.052638 -416.811968)
			(xy 97.128838 -416.756342) (xy 97.137392 -416.749332) (xy 97.148047 -416.729979) (xy 97.149412 -416.719004)
			(xy 97.149412 -414.27654) (xy 97.206308 -414.27654) (xy 97.27565 -414.173924) (xy 97.278444 -414.149032)
			(xy 97.273618 -414.137094) (xy 97.261966 -414.106789) (xy 97.245574 -414.043965) (xy 97.237311 -413.979566)
			(xy 97.236788 -413.947102) (xy 97.237252 -413.916371) (xy 97.24466 -413.855357) (xy 97.259369 -413.79568)
			(xy 97.281163 -413.738212) (xy 97.309726 -413.68379) (xy 97.34464 -413.633207) (xy 97.385397 -413.587201)
			(xy 97.431402 -413.546444) (xy 97.481984 -413.511529) (xy 97.536406 -413.482966) (xy 97.593874 -413.461171)
			(xy 97.653551 -413.446461) (xy 97.714565 -413.439052) (xy 97.745296 -413.438594) (xy 97.777791 -413.439108)
			(xy 97.84225 -413.447388) (xy 97.87382 -413.455104) (xy 97.886012 -413.458152) (xy 97.910142 -413.452818)
			(xy 97.992438 -413.382714) (xy 98.001836 -413.359854) (xy 98.00082 -413.347408) (xy 97.999042 -413.311848)
			(xy 97.999528 -413.284597) (xy 98.007284 -413.230649) (xy 98.022639 -413.178354) (xy 98.045281 -413.128777)
			(xy 98.074747 -413.082927) (xy 98.110438 -413.041736) (xy 98.151629 -413.006045) (xy 98.197479 -412.976579)
			(xy 98.247056 -412.953937) (xy 98.299351 -412.938582) (xy 98.353299 -412.930826) (xy 98.407801 -412.930826)
			(xy 98.461749 -412.938582) (xy 98.514044 -412.953937) (xy 98.563621 -412.976579) (xy 98.609471 -413.006045)
			(xy 98.650662 -413.041736) (xy 98.686353 -413.082927) (xy 98.715819 -413.128777) (xy 98.738461 -413.178354)
			(xy 98.753816 -413.230649) (xy 98.761572 -413.284597) (xy 98.762058 -413.311848) (xy 98.760534 -413.347154)
			(xy 98.759264 -413.3596) (xy 98.768662 -413.382714) (xy 98.850958 -413.452564) (xy 98.875088 -413.458152)
			(xy 98.88728 -413.455104) (xy 98.918725 -413.447414) (xy 98.982929 -413.439134) (xy 99.015296 -413.438594)
			(xy 99.046028 -413.439039) (xy 99.107045 -413.446448) (xy 99.166723 -413.461157) (xy 99.224193 -413.482952)
			(xy 99.278618 -413.511516) (xy 99.329202 -413.546431) (xy 99.375209 -413.58719) (xy 99.415967 -413.633196)
			(xy 99.450883 -413.683781) (xy 99.479447 -413.738205) (xy 99.501243 -413.795675) (xy 99.515952 -413.855353)
			(xy 99.52336 -413.91637) (xy 99.523804 -413.947102) (xy 99.523291 -413.979566) (xy 99.515024 -414.043966)
			(xy 99.498625 -414.106788) (xy 99.486974 -414.137094) (xy 99.482148 -414.149032) (xy 99.484942 -414.173924)
			(xy 99.539044 -414.254188) (xy 99.545932 -414.26349) (xy 99.565909 -414.275131) (xy 99.577398 -414.27654)
			(xy 99.723194 -414.27654) (xy 99.734674 -414.27511) (xy 99.75464 -414.263468) (xy 99.761548 -414.254188)
			(xy 99.81565 -414.173924) (xy 99.818444 -414.149032) (xy 99.813618 -414.137094) (xy 99.801966 -414.106789)
			(xy 99.785574 -414.043965) (xy 99.777311 -413.979566) (xy 99.776788 -413.947102) (xy 99.77729 -413.915141)
			(xy 99.785301 -413.851723) (xy 99.801198 -413.789809) (xy 99.82473 -413.730376) (xy 99.855524 -413.674361)
			(xy 99.893097 -413.622646) (xy 99.936854 -413.576049) (xy 99.986107 -413.535304) (xy 100.040078 -413.501053)
			(xy 100.097917 -413.473836) (xy 100.15871 -413.454083) (xy 100.2215 -413.442105) (xy 100.285296 -413.438092)
			(xy 100.349092 -413.442105) (xy 100.411882 -413.454083) (xy 100.472675 -413.473836) (xy 100.530514 -413.501053)
			(xy 100.584485 -413.535304) (xy 100.633738 -413.576049) (xy 100.677495 -413.622646) (xy 100.715068 -413.674361)
			(xy 100.745862 -413.730376) (xy 100.769394 -413.789809) (xy 100.785291 -413.851723) (xy 100.793302 -413.915141)
			(xy 100.793804 -413.947102) (xy 100.793291 -413.979566) (xy 100.785024 -414.043966) (xy 100.768625 -414.106788)
			(xy 100.756974 -414.137094) (xy 100.752148 -414.149032) (xy 100.754942 -414.173924) (xy 100.809044 -414.254188)
			(xy 100.815932 -414.26349) (xy 100.835909 -414.275131) (xy 100.847398 -414.27654) (xy 101.328474 -414.27654)
			(xy 101.340402 -414.274984) (xy 101.360933 -414.262512) (xy 101.367844 -414.252664) (xy 101.420422 -414.168336)
			(xy 101.421692 -414.142174) (xy 101.41585 -414.130236) (xy 101.403542 -414.10393) (xy 101.386131 -414.048525)
			(xy 101.377295 -413.991125) (xy 101.376734 -413.962088) (xy 101.37722 -413.934837) (xy 101.384976 -413.880889)
			(xy 101.400331 -413.828594) (xy 101.422973 -413.779017) (xy 101.452439 -413.733167) (xy 101.48813 -413.691976)
			(xy 101.529321 -413.656285) (xy 101.575171 -413.626819) (xy 101.624748 -413.604177) (xy 101.677043 -413.588822)
			(xy 101.730991 -413.581066) (xy 101.785493 -413.581066) (xy 101.839441 -413.588822) (xy 101.891736 -413.604177)
			(xy 101.941313 -413.626819) (xy 101.987163 -413.656285) (xy 102.028354 -413.691976) (xy 102.034574 -413.699155)
			(xy 102.448862 -413.699155) (xy 102.448862 -413.635233) (xy 102.456873 -413.571815) (xy 102.47277 -413.509901)
			(xy 102.496302 -413.450468) (xy 102.527096 -413.394453) (xy 102.564669 -413.342738) (xy 102.608426 -413.296141)
			(xy 102.657679 -413.255396) (xy 102.71165 -413.221145) (xy 102.769489 -413.193928) (xy 102.830282 -413.174175)
			(xy 102.893072 -413.162197) (xy 102.956868 -413.158184) (xy 103.020664 -413.162197) (xy 103.083454 -413.174175)
			(xy 103.144247 -413.193928) (xy 103.202086 -413.221145) (xy 103.256057 -413.255396) (xy 103.30531 -413.296141)
			(xy 103.349067 -413.342738) (xy 103.38664 -413.394453) (xy 103.408672 -413.43453) (xy 105.502202 -413.43453)
			(xy 105.502666 -413.403798) (xy 105.510071 -413.342782) (xy 105.524778 -413.283104) (xy 105.546571 -413.225633)
			(xy 105.575132 -413.171209) (xy 105.610046 -413.120624) (xy 105.650803 -413.074617) (xy 105.696809 -413.033859)
			(xy 105.747392 -412.998943) (xy 105.801815 -412.970379) (xy 105.859285 -412.948584) (xy 105.918963 -412.933875)
			(xy 105.979978 -412.926467) (xy 106.01071 -412.926022) (xy 106.045666 -412.926593) (xy 106.11492 -412.936156)
			(xy 106.182211 -412.955116) (xy 106.246271 -412.983113) (xy 106.305893 -413.019621) (xy 106.33329 -413.041338)
			(xy 106.340289 -413.046608) (xy 106.356792 -413.052454) (xy 106.365548 -413.052768) (xy 106.519472 -413.052768)
			(xy 106.528218 -413.052397) (xy 106.54471 -413.046566) (xy 106.55173 -413.041338) (xy 106.579123 -413.019617)
			(xy 106.63875 -412.983119) (xy 106.702812 -412.955128) (xy 106.770102 -412.936169) (xy 106.839355 -412.9266)
			(xy 106.87431 -412.926022) (xy 106.905043 -412.926428) (xy 106.966062 -412.933839) (xy 107.025743 -412.94855)
			(xy 107.083215 -412.970348) (xy 107.13764 -412.998915) (xy 107.188225 -413.033834) (xy 107.234232 -413.074596)
			(xy 107.27499 -413.120606) (xy 107.309905 -413.171194) (xy 107.338468 -413.225622) (xy 107.360262 -413.283096)
			(xy 107.374969 -413.342777) (xy 107.382374 -413.403796) (xy 107.382818 -413.43453) (xy 107.382278 -413.466454)
			(xy 107.374267 -413.529799) (xy 107.358386 -413.591642) (xy 107.334887 -413.651009) (xy 107.304138 -413.706967)
			(xy 107.266625 -413.758634) (xy 107.222937 -413.805196) (xy 107.198668 -413.825944) (xy 107.191557 -413.832383)
			(xy 107.182424 -413.849239) (xy 107.180888 -413.85871) (xy 107.176824 -413.889698) (xy 107.176082 -413.899142)
			(xy 107.180644 -413.91751) (xy 107.185714 -413.925512) (xy 107.202206 -413.949814) (xy 107.228383 -414.002383)
			(xy 107.246205 -414.058341) (xy 107.255251 -414.116367) (xy 107.255818 -414.14573) (xy 107.25535 -414.172982)
			(xy 107.24759 -414.226929) (xy 107.232231 -414.279224) (xy 107.209587 -414.328801) (xy 107.180119 -414.37465)
			(xy 107.144426 -414.41584) (xy 107.103234 -414.451531) (xy 107.057383 -414.480997) (xy 107.007805 -414.503638)
			(xy 106.95551 -414.518994) (xy 106.901562 -414.526752) (xy 106.87431 -414.527238) (xy 106.84793 -414.52682)
			(xy 106.795672 -414.519556) (xy 106.744913 -414.505165) (xy 106.696618 -414.483922) (xy 106.651709 -414.456231)
			(xy 106.611041 -414.422619) (xy 106.575389 -414.383727) (xy 106.545432 -414.340297) (xy 106.533188 -414.316926)
			(xy 106.526838 -414.303718) (xy 106.502454 -414.288732) (xy 106.382566 -414.288732) (xy 106.358182 -414.303718)
			(xy 106.351832 -414.316926) (xy 106.339594 -414.340298) (xy 106.30963 -414.383721) (xy 106.273974 -414.422606)
			(xy 106.233304 -414.456212) (xy 106.188395 -414.483898) (xy 106.140102 -414.505138) (xy 106.089344 -414.519528)
			(xy 106.037089 -414.526792) (xy 106.01071 -414.527238) (xy 105.98346 -414.526713) (xy 105.929516 -414.518958)
			(xy 105.877224 -414.503606) (xy 105.827648 -414.480968) (xy 105.781799 -414.451506) (xy 105.74061 -414.415818)
			(xy 105.704918 -414.374633) (xy 105.675451 -414.328787) (xy 105.652808 -414.279214) (xy 105.63745 -414.226923)
			(xy 105.62969 -414.17298) (xy 105.629202 -414.14573) (xy 105.629739 -414.116363) (xy 105.638761 -414.058326)
			(xy 105.656579 -414.00236) (xy 105.682774 -413.94979) (xy 105.699306 -413.925512) (xy 105.70446 -413.917545)
			(xy 105.709044 -413.899148) (xy 105.708196 -413.889698) (xy 105.704132 -413.85871) (xy 105.702544 -413.849259)
			(xy 105.693409 -413.832428) (xy 105.686352 -413.825944) (xy 105.6621 -413.805178) (xy 105.618418 -413.758612)
			(xy 105.580906 -413.706947) (xy 105.550154 -413.650993) (xy 105.526647 -413.591631) (xy 105.510752 -413.529794)
			(xy 105.502721 -413.466453) (xy 105.502202 -413.43453) (xy 103.408672 -413.43453) (xy 103.417434 -413.450468)
			(xy 103.440966 -413.509901) (xy 103.456863 -413.571815) (xy 103.464874 -413.635233) (xy 103.465376 -413.667194)
			(xy 103.464874 -413.699155) (xy 103.456863 -413.762573) (xy 103.440966 -413.824487) (xy 103.417434 -413.88392)
			(xy 103.38664 -413.939935) (xy 103.349067 -413.99165) (xy 103.30531 -414.038247) (xy 103.256057 -414.078992)
			(xy 103.202086 -414.113243) (xy 103.144247 -414.14046) (xy 103.083454 -414.160213) (xy 103.020664 -414.172191)
			(xy 102.956868 -414.176205) (xy 102.893072 -414.172191) (xy 102.830282 -414.160213) (xy 102.769489 -414.14046)
			(xy 102.71165 -414.113243) (xy 102.657679 -414.078992) (xy 102.608426 -414.038247) (xy 102.564669 -413.99165)
			(xy 102.527096 -413.939935) (xy 102.496302 -413.88392) (xy 102.47277 -413.824487) (xy 102.456873 -413.762573)
			(xy 102.448862 -413.699155) (xy 102.034574 -413.699155) (xy 102.064045 -413.733167) (xy 102.093511 -413.779017)
			(xy 102.116153 -413.828594) (xy 102.131508 -413.880889) (xy 102.139264 -413.934837) (xy 102.13975 -413.962088)
			(xy 102.13921 -413.991128) (xy 102.130399 -414.048536) (xy 102.112965 -414.103938) (xy 102.100634 -414.130236)
			(xy 102.094792 -414.142174) (xy 102.096062 -414.168336) (xy 102.143306 -414.244028) (xy 102.14692 -414.250168)
			(xy 102.150927 -414.263833) (xy 102.15118 -414.270952) (xy 102.15118 -414.27654) (xy 102.15118 -415.90595)
			(xy 102.270052 -415.90595) (xy 102.270549 -415.873746) (xy 102.27867 -415.809853) (xy 102.29479 -415.747495)
			(xy 102.31865 -415.687669) (xy 102.349868 -415.631333) (xy 102.387947 -415.579387) (xy 102.409752 -415.555684)
			(xy 102.41661 -415.548572) (xy 102.423722 -415.531046) (xy 102.42423 -415.441638) (xy 102.417372 -415.424112)
			(xy 102.410768 -415.416746) (xy 102.389629 -415.393173) (xy 102.352703 -415.341736) (xy 102.322451 -415.286111)
			(xy 102.299343 -415.227159) (xy 102.283735 -415.165794) (xy 102.27587 -415.102965) (xy 102.275386 -415.071306)
			(xy 102.275888 -415.039345) (xy 102.283899 -414.975927) (xy 102.299796 -414.914013) (xy 102.323328 -414.85458)
			(xy 102.354122 -414.798565) (xy 102.391695 -414.74685) (xy 102.435452 -414.700253) (xy 102.484705 -414.659508)
			(xy 102.538676 -414.625257) (xy 102.596515 -414.59804) (xy 102.657308 -414.578287) (xy 102.720098 -414.566309)
			(xy 102.783894 -414.562296) (xy 102.84769 -414.566309) (xy 102.91048 -414.578287) (xy 102.971273 -414.59804)
			(xy 103.029112 -414.625257) (xy 103.083083 -414.659508) (xy 103.132336 -414.700253) (xy 103.176093 -414.74685)
			(xy 103.213666 -414.798565) (xy 103.24446 -414.85458) (xy 103.267992 -414.914013) (xy 103.283889 -414.975927)
			(xy 103.2919 -415.039345) (xy 103.292402 -415.071306) (xy 103.29189 -415.10351) (xy 103.283773 -415.167403)
			(xy 103.267657 -415.229761) (xy 103.2438 -415.289586) (xy 103.212584 -415.345922) (xy 103.174507 -415.397868)
			(xy 103.152702 -415.421572) (xy 103.145844 -415.428684) (xy 103.138732 -415.44621) (xy 103.138224 -415.535618)
			(xy 103.145082 -415.553144) (xy 103.151686 -415.56051) (xy 103.172844 -415.584067) (xy 103.20977 -415.635507)
			(xy 103.212772 -415.641028) (xy 105.13949 -415.641028) (xy 105.13994 -415.614454) (xy 105.147339 -415.561823)
			(xy 105.161969 -415.510728) (xy 105.183548 -415.462157) (xy 105.211658 -415.41705) (xy 105.245754 -415.37628)
			(xy 105.285178 -415.340636) (xy 105.329167 -415.310807) (xy 105.376869 -415.28737) (xy 105.427362 -415.27078)
			(xy 105.453434 -415.265616) (xy 105.463848 -415.263584) (xy 105.480612 -415.252662) (xy 105.53319 -415.174938)
			(xy 105.537 -415.155126) (xy 105.534714 -415.144966) (xy 105.531016 -415.125748) (xy 105.527066 -415.086811)
			(xy 105.52684 -415.067242) (xy 105.527326 -415.039991) (xy 105.535082 -414.986043) (xy 105.550437 -414.933748)
			(xy 105.573079 -414.884171) (xy 105.602545 -414.838321) (xy 105.638236 -414.79713) (xy 105.679427 -414.761439)
			(xy 105.725277 -414.731973) (xy 105.774854 -414.709331) (xy 105.827149 -414.693976) (xy 105.881097 -414.68622)
			(xy 105.935599 -414.68622) (xy 105.989547 -414.693976) (xy 106.041842 -414.709331) (xy 106.091419 -414.731973)
			(xy 106.137269 -414.761439) (xy 106.17846 -414.79713) (xy 106.214151 -414.838321) (xy 106.243617 -414.884171)
			(xy 106.266259 -414.933748) (xy 106.281614 -414.986043) (xy 106.28937 -415.039991) (xy 106.289856 -415.067242)
			(xy 106.289422 -415.093817) (xy 106.282026 -415.146451) (xy 106.267398 -415.197549) (xy 106.245819 -415.246123)
			(xy 106.217708 -415.291231) (xy 106.183609 -415.332002) (xy 106.144181 -415.367646) (xy 106.100189 -415.397474)
			(xy 106.052482 -415.420907) (xy 106.001986 -415.437493) (xy 105.975912 -415.442654) (xy 105.965498 -415.444686)
			(xy 105.948734 -415.455608) (xy 105.896156 -415.533332) (xy 105.892346 -415.553144) (xy 105.894632 -415.563304)
			(xy 105.898341 -415.58252) (xy 105.902283 -415.621459) (xy 105.902506 -415.641028) (xy 105.90202 -415.668279)
			(xy 105.895494 -415.713672) (xy 106.64012 -415.713672) (xy 106.644191 -415.65805) (xy 106.656317 -415.603613)
			(xy 106.67624 -415.551522) (xy 106.703536 -415.502887) (xy 106.737622 -415.458744) (xy 106.777771 -415.420035)
			(xy 106.823129 -415.387584) (xy 106.872729 -415.362083) (xy 106.925513 -415.344076) (xy 106.980356 -415.333946)
			(xy 107.03609 -415.331909) (xy 107.091527 -415.338009) (xy 107.145484 -415.352115) (xy 107.196813 -415.373927)
			(xy 107.244419 -415.402981) (xy 107.287287 -415.438656) (xy 107.324504 -415.480193) (xy 107.355277 -415.526706)
			(xy 107.378949 -415.577203) (xy 107.395017 -415.63061) (xy 107.403137 -415.685786) (xy 107.403646 -415.713672)
			(xy 107.403137 -415.741558) (xy 107.395017 -415.796734) (xy 107.378949 -415.850141) (xy 107.355277 -415.900638)
			(xy 107.329244 -415.939986) (xy 114.552982 -415.939986) (xy 114.557053 -415.884364) (xy 114.569179 -415.829927)
			(xy 114.589102 -415.777836) (xy 114.616398 -415.729201) (xy 114.650484 -415.685058) (xy 114.690633 -415.646349)
			(xy 114.735991 -415.613898) (xy 114.785591 -415.588397) (xy 114.838375 -415.57039) (xy 114.893218 -415.56026)
			(xy 114.948952 -415.558223) (xy 115.004389 -415.564323) (xy 115.058346 -415.578429) (xy 115.109675 -415.600241)
			(xy 115.157281 -415.629295) (xy 115.200149 -415.66497) (xy 115.237366 -415.706507) (xy 115.268139 -415.75302)
			(xy 115.291811 -415.803517) (xy 115.307879 -415.856924) (xy 115.315999 -415.9121) (xy 115.316508 -415.939986)
			(xy 115.315999 -415.967872) (xy 115.307879 -416.023048) (xy 115.291811 -416.076455) (xy 115.268139 -416.126952)
			(xy 115.237366 -416.173465) (xy 115.200149 -416.215002) (xy 115.157281 -416.250677) (xy 115.109675 -416.279731)
			(xy 115.058346 -416.301543) (xy 115.004389 -416.315649) (xy 114.948952 -416.321749) (xy 114.893218 -416.319712)
			(xy 114.838375 -416.309582) (xy 114.785591 -416.291575) (xy 114.735991 -416.266074) (xy 114.690633 -416.233623)
			(xy 114.650484 -416.194914) (xy 114.616398 -416.150771) (xy 114.589102 -416.102136) (xy 114.569179 -416.050045)
			(xy 114.557053 -415.995608) (xy 114.552982 -415.939986) (xy 107.329244 -415.939986) (xy 107.324504 -415.947151)
			(xy 107.287287 -415.988688) (xy 107.244419 -416.024363) (xy 107.196813 -416.053417) (xy 107.145484 -416.075229)
			(xy 107.091527 -416.089335) (xy 107.03609 -416.095435) (xy 106.980356 -416.093398) (xy 106.925513 -416.083268)
			(xy 106.872729 -416.065261) (xy 106.823129 -416.03976) (xy 106.777771 -416.007309) (xy 106.737622 -415.9686)
			(xy 106.703536 -415.924457) (xy 106.67624 -415.875822) (xy 106.656317 -415.823731) (xy 106.644191 -415.769294)
			(xy 106.64012 -415.713672) (xy 105.895494 -415.713672) (xy 105.894264 -415.722227) (xy 105.878909 -415.774522)
			(xy 105.856267 -415.824099) (xy 105.826801 -415.869949) (xy 105.79111 -415.91114) (xy 105.749919 -415.946831)
			(xy 105.704069 -415.976297) (xy 105.654492 -415.998939) (xy 105.602197 -416.014294) (xy 105.548249 -416.02205)
			(xy 105.493747 -416.02205) (xy 105.439799 -416.014294) (xy 105.387504 -415.998939) (xy 105.337927 -415.976297)
			(xy 105.292077 -415.946831) (xy 105.250886 -415.91114) (xy 105.215195 -415.869949) (xy 105.185729 -415.824099)
			(xy 105.163087 -415.774522) (xy 105.147732 -415.722227) (xy 105.139976 -415.668279) (xy 105.13949 -415.641028)
			(xy 103.212772 -415.641028) (xy 103.24002 -415.691135) (xy 103.263125 -415.75009) (xy 103.278728 -415.811458)
			(xy 103.286588 -415.87429) (xy 103.287068 -415.90595) (xy 103.286523 -415.939079) (xy 103.277929 -416.004776)
			(xy 103.260867 -416.068799) (xy 103.235627 -416.130061) (xy 103.202638 -416.187522) (xy 103.162458 -416.240206)
			(xy 103.139494 -416.26409) (xy 103.12908 -416.274504) (xy 103.12273 -416.302444) (xy 103.16083 -416.415982)
			(xy 103.182674 -416.43427) (xy 103.197152 -416.436302) (xy 103.224074 -416.440632) (xy 103.276399 -416.455976)
			(xy 103.326006 -416.478612) (xy 103.371886 -416.508079) (xy 103.413104 -416.543778) (xy 103.448821 -416.58498)
			(xy 103.478308 -416.630848) (xy 103.500966 -416.680445) (xy 103.502891 -416.687) (xy 108.329982 -416.687)
			(xy 108.334053 -416.631378) (xy 108.346179 -416.576941) (xy 108.366102 -416.52485) (xy 108.393398 -416.476215)
			(xy 108.427484 -416.432072) (xy 108.467633 -416.393363) (xy 108.512991 -416.360912) (xy 108.562591 -416.335411)
			(xy 108.615375 -416.317404) (xy 108.670218 -416.307274) (xy 108.725952 -416.305237) (xy 108.781389 -416.311337)
			(xy 108.835346 -416.325443) (xy 108.886675 -416.347255) (xy 108.934281 -416.376309) (xy 108.977149 -416.411984)
			(xy 109.014366 -416.453521) (xy 109.045139 -416.500034) (xy 109.068811 -416.550531) (xy 109.084879 -416.603938)
			(xy 109.092999 -416.659114) (xy 109.093508 -416.687) (xy 109.092999 -416.714886) (xy 109.084879 -416.770062)
			(xy 109.068811 -416.823469) (xy 109.045139 -416.873966) (xy 109.014366 -416.920479) (xy 109.009407 -416.926014)
			(xy 113.25428 -416.926014) (xy 113.258351 -416.870392) (xy 113.270477 -416.815955) (xy 113.2904 -416.763864)
			(xy 113.317696 -416.715229) (xy 113.351782 -416.671086) (xy 113.391931 -416.632377) (xy 113.437289 -416.599926)
			(xy 113.486889 -416.574425) (xy 113.539673 -416.556418) (xy 113.594516 -416.546288) (xy 113.65025 -416.544251)
			(xy 113.705687 -416.550351) (xy 113.759644 -416.564457) (xy 113.810973 -416.586269) (xy 113.858579 -416.615323)
			(xy 113.901447 -416.650998) (xy 113.938664 -416.692535) (xy 113.969437 -416.739048) (xy 113.993109 -416.789545)
			(xy 114.009177 -416.842952) (xy 114.017297 -416.898128) (xy 114.017806 -416.926014) (xy 114.017297 -416.9539)
			(xy 114.009177 -417.009076) (xy 113.993109 -417.062483) (xy 113.969437 -417.11298) (xy 113.938664 -417.159493)
			(xy 113.901447 -417.20103) (xy 113.858579 -417.236705) (xy 113.810973 -417.265759) (xy 113.759644 -417.287571)
			(xy 113.705687 -417.301677) (xy 113.65025 -417.307777) (xy 113.594516 -417.30574) (xy 113.539673 -417.29561)
			(xy 113.486889 -417.277603) (xy 113.437289 -417.252102) (xy 113.391931 -417.219651) (xy 113.351782 -417.180942)
			(xy 113.317696 -417.136799) (xy 113.2904 -417.088164) (xy 113.270477 -417.036073) (xy 113.258351 -416.981636)
			(xy 113.25428 -416.926014) (xy 109.009407 -416.926014) (xy 108.977149 -416.962016) (xy 108.934281 -416.997691)
			(xy 108.886675 -417.026745) (xy 108.835346 -417.048557) (xy 108.781389 -417.062663) (xy 108.725952 -417.068763)
			(xy 108.670218 -417.066726) (xy 108.615375 -417.056596) (xy 108.562591 -417.038589) (xy 108.512991 -417.013088)
			(xy 108.467633 -416.980637) (xy 108.427484 -416.941928) (xy 108.393398 -416.897785) (xy 108.366102 -416.84915)
			(xy 108.346179 -416.797059) (xy 108.334053 -416.742622) (xy 108.329982 -416.687) (xy 103.502891 -416.687)
			(xy 103.516332 -416.732763) (xy 103.524094 -416.786736) (xy 103.524558 -416.814) (xy 103.524072 -416.841251)
			(xy 103.516316 -416.895199) (xy 103.500961 -416.947494) (xy 103.478319 -416.997071) (xy 103.448853 -417.042921)
			(xy 103.413162 -417.084112) (xy 103.371971 -417.119803) (xy 103.326121 -417.149269) (xy 103.276544 -417.171911)
			(xy 103.224249 -417.187266) (xy 103.170301 -417.195022) (xy 103.115799 -417.195022) (xy 103.061851 -417.187266)
			(xy 103.009556 -417.171911) (xy 102.959979 -417.149269) (xy 102.914129 -417.119803) (xy 102.872938 -417.084112)
			(xy 102.837247 -417.042921) (xy 102.807781 -416.997071) (xy 102.785139 -416.947494) (xy 102.769784 -416.895199)
			(xy 102.762028 -416.841251) (xy 102.761542 -416.814) (xy 102.76194 -416.788616) (xy 102.76868 -416.738298)
			(xy 102.782027 -416.689316) (xy 102.801747 -416.642534) (xy 102.827492 -416.598778) (xy 102.842822 -416.578542)
			(xy 102.851966 -416.567112) (xy 102.855014 -416.538664) (xy 102.80396 -416.430206) (xy 102.780084 -416.414712)
			(xy 102.765606 -416.414204) (xy 102.732877 -416.412853) (xy 102.668146 -416.402807) (xy 102.605243 -416.384528)
			(xy 102.545208 -416.358321) (xy 102.489037 -416.324619) (xy 102.437661 -416.283981) (xy 102.391931 -416.23708)
			(xy 102.352604 -416.184694) (xy 102.320332 -416.127689) (xy 102.29565 -416.067012) (xy 102.278966 -416.003666)
			(xy 102.270558 -415.938703) (xy 102.270052 -415.90595) (xy 102.15118 -415.90595) (xy 102.15118 -417.562284)
			(xy 105.647996 -417.562284) (xy 105.652067 -417.506662) (xy 105.664193 -417.452225) (xy 105.684116 -417.400134)
			(xy 105.711412 -417.351499) (xy 105.745498 -417.307356) (xy 105.785647 -417.268647) (xy 105.831005 -417.236196)
			(xy 105.880605 -417.210695) (xy 105.933389 -417.192688) (xy 105.988232 -417.182558) (xy 106.043966 -417.180521)
			(xy 106.099403 -417.186621) (xy 106.15336 -417.200727) (xy 106.204689 -417.222539) (xy 106.252295 -417.251593)
			(xy 106.295163 -417.287268) (xy 106.33238 -417.328805) (xy 106.363153 -417.375318) (xy 106.386825 -417.425815)
			(xy 106.402893 -417.479222) (xy 106.411013 -417.534398) (xy 106.411522 -417.562284) (xy 106.411013 -417.59017)
			(xy 106.402893 -417.645346) (xy 106.386825 -417.698753) (xy 106.363153 -417.74925) (xy 106.33238 -417.795763)
			(xy 106.295163 -417.8373) (xy 106.252295 -417.872975) (xy 106.204689 -417.902029) (xy 106.15336 -417.923841)
			(xy 106.099403 -417.937947) (xy 106.043966 -417.944047) (xy 105.988232 -417.94201) (xy 105.933389 -417.93188)
			(xy 105.880605 -417.913873) (xy 105.831005 -417.888372) (xy 105.785647 -417.855921) (xy 105.745498 -417.817212)
			(xy 105.711412 -417.773069) (xy 105.684116 -417.724434) (xy 105.664193 -417.672343) (xy 105.652067 -417.617906)
			(xy 105.647996 -417.562284) (xy 102.15118 -417.562284) (xy 102.15118 -418.414919) (xy 104.139994 -418.414919)
			(xy 104.139994 -418.350997) (xy 104.148005 -418.287579) (xy 104.163902 -418.225665) (xy 104.187434 -418.166232)
			(xy 104.218228 -418.110217) (xy 104.255801 -418.058502) (xy 104.299558 -418.011905) (xy 104.348811 -417.97116)
			(xy 104.402782 -417.936909) (xy 104.460621 -417.909692) (xy 104.521414 -417.889939) (xy 104.584204 -417.877961)
			(xy 104.648 -417.873948) (xy 104.711796 -417.877961) (xy 104.774586 -417.889939) (xy 104.835379 -417.909692)
			(xy 104.893218 -417.936909) (xy 104.947189 -417.97116) (xy 104.996442 -418.011905) (xy 105.040199 -418.058502)
			(xy 105.077772 -418.110217) (xy 105.108566 -418.166232) (xy 105.132098 -418.225665) (xy 105.147995 -418.287579)
			(xy 105.156006 -418.350997) (xy 105.156508 -418.382958) (xy 105.156006 -418.414919) (xy 105.147995 -418.478337)
			(xy 105.132098 -418.540251) (xy 105.108566 -418.599684) (xy 105.077772 -418.655699) (xy 105.040199 -418.707414)
			(xy 104.996442 -418.754011) (xy 104.947189 -418.794756) (xy 104.893218 -418.829007) (xy 104.835379 -418.856224)
			(xy 104.774586 -418.875977) (xy 104.711796 -418.887955) (xy 104.648 -418.891969) (xy 104.584204 -418.887955)
			(xy 104.521414 -418.875977) (xy 104.460621 -418.856224) (xy 104.402782 -418.829007) (xy 104.348811 -418.794756)
			(xy 104.299558 -418.754011) (xy 104.255801 -418.707414) (xy 104.218228 -418.655699) (xy 104.187434 -418.599684)
			(xy 104.163902 -418.540251) (xy 104.148005 -418.478337) (xy 104.139994 -418.414919) (xy 102.15118 -418.414919)
			(xy 102.15118 -419.127251) (xy 108.457978 -419.127251) (xy 108.457978 -419.072749) (xy 108.465734 -419.018801)
			(xy 108.481089 -418.966506) (xy 108.503731 -418.916929) (xy 108.533197 -418.871079) (xy 108.568888 -418.829888)
			(xy 108.610079 -418.794197) (xy 108.655929 -418.764731) (xy 108.705506 -418.742089) (xy 108.757801 -418.726734)
			(xy 108.811749 -418.718978) (xy 108.839 -418.718492) (xy 108.866379 -418.71895) (xy 108.920574 -418.726791)
			(xy 108.973091 -418.742297) (xy 109.022853 -418.76515) (xy 109.068838 -418.794881) (xy 109.110101 -418.830878)
			(xy 109.128306 -418.851334) (xy 109.136434 -418.860732) (xy 109.15904 -418.869876) (xy 109.265466 -418.860986)
			(xy 109.28604 -418.848032) (xy 109.29239 -418.837618) (xy 109.309679 -418.809851) (xy 109.350343 -418.758614)
			(xy 109.397241 -418.713013) (xy 109.449599 -418.673802) (xy 109.506551 -418.641627) (xy 109.567159 -418.617019)
			(xy 109.630421 -418.600384) (xy 109.695294 -418.591998) (xy 109.728 -418.591492) (xy 109.759961 -418.591994)
			(xy 109.823379 -418.600005) (xy 109.885293 -418.615902) (xy 109.944726 -418.639434) (xy 110.000741 -418.670228)
			(xy 110.052456 -418.707801) (xy 110.099053 -418.751558) (xy 110.139798 -418.800811) (xy 110.174049 -418.854782)
			(xy 110.201266 -418.912621) (xy 110.221019 -418.973414) (xy 110.224574 -418.99205) (xy 114.959128 -418.99205)
			(xy 114.963199 -418.936428) (xy 114.975325 -418.881991) (xy 114.995248 -418.8299) (xy 115.022544 -418.781265)
			(xy 115.05663 -418.737122) (xy 115.096779 -418.698413) (xy 115.142137 -418.665962) (xy 115.191737 -418.640461)
			(xy 115.244521 -418.622454) (xy 115.299364 -418.612324) (xy 115.355098 -418.610287) (xy 115.410535 -418.616387)
			(xy 115.464492 -418.630493) (xy 115.515821 -418.652305) (xy 115.563427 -418.681359) (xy 115.606295 -418.717034)
			(xy 115.643512 -418.758571) (xy 115.674285 -418.805084) (xy 115.697957 -418.855581) (xy 115.714025 -418.908988)
			(xy 115.722145 -418.964164) (xy 115.722654 -418.99205) (xy 115.722145 -419.019936) (xy 115.714025 -419.075112)
			(xy 115.706537 -419.1) (xy 116.711982 -419.1) (xy 116.716053 -419.044378) (xy 116.728179 -418.989941)
			(xy 116.748102 -418.93785) (xy 116.775398 -418.889215) (xy 116.809484 -418.845072) (xy 116.849633 -418.806363)
			(xy 116.894991 -418.773912) (xy 116.944591 -418.748411) (xy 116.997375 -418.730404) (xy 117.052218 -418.720274)
			(xy 117.107952 -418.718237) (xy 117.163389 -418.724337) (xy 117.217346 -418.738443) (xy 117.268675 -418.760255)
			(xy 117.316281 -418.789309) (xy 117.359149 -418.824984) (xy 117.396366 -418.866521) (xy 117.427139 -418.913034)
			(xy 117.450811 -418.963531) (xy 117.466879 -419.016938) (xy 117.474999 -419.072114) (xy 117.475508 -419.1)
			(xy 117.474999 -419.127886) (xy 117.466879 -419.183062) (xy 117.450811 -419.236469) (xy 117.427139 -419.286966)
			(xy 117.396366 -419.333479) (xy 117.359149 -419.375016) (xy 117.316281 -419.410691) (xy 117.268675 -419.439745)
			(xy 117.217346 -419.461557) (xy 117.163389 -419.475663) (xy 117.107952 -419.481763) (xy 117.052218 -419.479726)
			(xy 116.997375 -419.469596) (xy 116.944591 -419.451589) (xy 116.894991 -419.426088) (xy 116.849633 -419.393637)
			(xy 116.809484 -419.354928) (xy 116.775398 -419.310785) (xy 116.748102 -419.26215) (xy 116.728179 -419.210059)
			(xy 116.716053 -419.155622) (xy 116.711982 -419.1) (xy 115.706537 -419.1) (xy 115.697957 -419.128519)
			(xy 115.674285 -419.179016) (xy 115.643512 -419.225529) (xy 115.606295 -419.267066) (xy 115.563427 -419.302741)
			(xy 115.515821 -419.331795) (xy 115.464492 -419.353607) (xy 115.410535 -419.367713) (xy 115.355098 -419.373813)
			(xy 115.299364 -419.371776) (xy 115.244521 -419.361646) (xy 115.191737 -419.343639) (xy 115.142137 -419.318138)
			(xy 115.096779 -419.285687) (xy 115.05663 -419.246978) (xy 115.022544 -419.202835) (xy 114.995248 -419.1542)
			(xy 114.975325 -419.102109) (xy 114.963199 -419.047672) (xy 114.959128 -418.99205) (xy 110.224574 -418.99205)
			(xy 110.232997 -419.036204) (xy 110.237011 -419.1) (xy 110.232997 -419.163796) (xy 110.221019 -419.226586)
			(xy 110.201266 -419.287379) (xy 110.174049 -419.345218) (xy 110.139798 -419.399189) (xy 110.099053 -419.448442)
			(xy 110.052456 -419.492199) (xy 110.000741 -419.529772) (xy 109.944726 -419.560566) (xy 109.885293 -419.584098)
			(xy 109.823379 -419.599995) (xy 109.759961 -419.608006) (xy 109.728 -419.608508) (xy 109.695294 -419.60799)
			(xy 109.63042 -419.599613) (xy 109.567157 -419.582985) (xy 109.506549 -419.558379) (xy 109.449598 -419.526203)
			(xy 109.397244 -419.486988) (xy 109.350352 -419.441382) (xy 109.309697 -419.390138) (xy 109.29239 -419.362382)
			(xy 109.28604 -419.351968) (xy 109.265466 -419.339014) (xy 109.15904 -419.330124) (xy 109.136434 -419.339268)
			(xy 109.128306 -419.348666) (xy 109.110094 -419.369115) (xy 109.068837 -419.405119) (xy 109.022854 -419.434852)
			(xy 108.973092 -419.457704) (xy 108.920574 -419.473205) (xy 108.866379 -419.481035) (xy 108.839 -419.481508)
			(xy 108.811749 -419.481022) (xy 108.757801 -419.473266) (xy 108.705506 -419.457911) (xy 108.655929 -419.435269)
			(xy 108.610079 -419.405803) (xy 108.568888 -419.370112) (xy 108.533197 -419.328921) (xy 108.503731 -419.283071)
			(xy 108.481089 -419.233494) (xy 108.465734 -419.181199) (xy 108.457978 -419.127251) (xy 102.15118 -419.127251)
			(xy 102.15118 -419.989) (xy 104.138982 -419.989) (xy 104.143053 -419.933378) (xy 104.155179 -419.878941)
			(xy 104.175102 -419.82685) (xy 104.202398 -419.778215) (xy 104.236484 -419.734072) (xy 104.276633 -419.695363)
			(xy 104.321991 -419.662912) (xy 104.371591 -419.637411) (xy 104.424375 -419.619404) (xy 104.479218 -419.609274)
			(xy 104.534952 -419.607237) (xy 104.590389 -419.613337) (xy 104.644346 -419.627443) (xy 104.695675 -419.649255)
			(xy 104.743281 -419.678309) (xy 104.786149 -419.713984) (xy 104.823366 -419.755521) (xy 104.830935 -419.766961)
			(xy 107.060994 -419.766961) (xy 107.060994 -419.703039) (xy 107.069005 -419.639621) (xy 107.084902 -419.577707)
			(xy 107.108434 -419.518274) (xy 107.139228 -419.462259) (xy 107.176801 -419.410544) (xy 107.220558 -419.363947)
			(xy 107.269811 -419.323202) (xy 107.323782 -419.288951) (xy 107.381621 -419.261734) (xy 107.442414 -419.241981)
			(xy 107.505204 -419.230003) (xy 107.569 -419.22599) (xy 107.632796 -419.230003) (xy 107.695586 -419.241981)
			(xy 107.756379 -419.261734) (xy 107.814218 -419.288951) (xy 107.868189 -419.323202) (xy 107.917442 -419.363947)
			(xy 107.961199 -419.410544) (xy 107.998772 -419.462259) (xy 108.029566 -419.518274) (xy 108.053098 -419.577707)
			(xy 108.068995 -419.639621) (xy 108.077006 -419.703039) (xy 108.077508 -419.735) (xy 108.077006 -419.766961)
			(xy 108.068995 -419.830379) (xy 108.053098 -419.892293) (xy 108.029566 -419.951726) (xy 107.998772 -420.007741)
			(xy 107.961199 -420.059456) (xy 107.917442 -420.106053) (xy 107.868189 -420.146798) (xy 107.814218 -420.181049)
			(xy 107.756379 -420.208266) (xy 107.695586 -420.228019) (xy 107.632796 -420.239997) (xy 107.569 -420.244011)
			(xy 107.505204 -420.239997) (xy 107.442414 -420.228019) (xy 107.381621 -420.208266) (xy 107.323782 -420.181049)
			(xy 107.269811 -420.146798) (xy 107.220558 -420.106053) (xy 107.176801 -420.059456) (xy 107.139228 -420.007741)
			(xy 107.108434 -419.951726) (xy 107.084902 -419.892293) (xy 107.069005 -419.830379) (xy 107.060994 -419.766961)
			(xy 104.830935 -419.766961) (xy 104.854139 -419.802034) (xy 104.877811 -419.852531) (xy 104.893879 -419.905938)
			(xy 104.901999 -419.961114) (xy 104.902508 -419.989) (xy 104.901999 -420.016886) (xy 104.893879 -420.072062)
			(xy 104.877811 -420.125469) (xy 104.854139 -420.175966) (xy 104.823366 -420.222479) (xy 104.786149 -420.264016)
			(xy 104.743281 -420.299691) (xy 104.695675 -420.328745) (xy 104.644346 -420.350557) (xy 104.590389 -420.364663)
			(xy 104.534952 -420.370763) (xy 104.479218 -420.368726) (xy 104.424375 -420.358596) (xy 104.371591 -420.340589)
			(xy 104.321991 -420.315088) (xy 104.276633 -420.282637) (xy 104.236484 -420.243928) (xy 104.202398 -420.199785)
			(xy 104.175102 -420.15115) (xy 104.155179 -420.099059) (xy 104.143053 -420.044622) (xy 104.138982 -419.989)
			(xy 102.15118 -419.989) (xy 102.15118 -421.173656) (xy 97.149412 -421.173656) (xy 97.149412 -419.423596)
			(xy 97.148109 -419.4126) (xy 97.137445 -419.393222) (xy 97.128838 -419.386258) (xy 97.052638 -419.330632)
			(xy 97.028762 -419.326822) (xy 97.017078 -419.330632) (xy 96.979579 -419.341785) (xy 96.90227 -419.353771)
			(xy 96.863154 -419.354508) (xy 96.8629 -419.354508) (xy 96.830757 -419.354013) (xy 96.766983 -419.345917)
			(xy 96.704733 -419.329866) (xy 96.674686 -419.31844) (xy 96.663002 -419.313614) (xy 96.637856 -419.316408)
			(xy 96.557846 -419.370764) (xy 96.547877 -419.378248) (xy 96.536177 -419.400225) (xy 96.535494 -419.412674)
			(xy 96.535494 -420.307008) (xy 96.535069 -420.317077) (xy 96.527352 -420.335679) (xy 96.520508 -420.343076)
			(xy 95.770192 -421.093392) (xy 95.762826 -421.100504) (xy 95.755206 -421.1193) (xy 95.755206 -423.457116)
			(xy 97.53549 -423.457116) (xy 97.539561 -423.401494) (xy 97.551687 -423.347057) (xy 97.57161 -423.294966)
			(xy 97.598906 -423.246331) (xy 97.632992 -423.202188) (xy 97.673141 -423.163479) (xy 97.718499 -423.131028)
			(xy 97.768099 -423.105527) (xy 97.820883 -423.08752) (xy 97.875726 -423.07739) (xy 97.93146 -423.075353)
			(xy 97.986897 -423.081453) (xy 98.040854 -423.095559) (xy 98.092183 -423.117371) (xy 98.139789 -423.146425)
			(xy 98.182657 -423.1821) (xy 98.219874 -423.223637) (xy 98.250647 -423.27015) (xy 98.274319 -423.320647)
			(xy 98.290387 -423.374054) (xy 98.298507 -423.42923) (xy 98.298858 -423.44848) (xy 98.633278 -423.44848)
			(xy 98.637349 -423.392858) (xy 98.649475 -423.338421) (xy 98.669398 -423.28633) (xy 98.696694 -423.237695)
			(xy 98.73078 -423.193552) (xy 98.770929 -423.154843) (xy 98.816287 -423.122392) (xy 98.865887 -423.096891)
			(xy 98.918671 -423.078884) (xy 98.973514 -423.068754) (xy 99.029248 -423.066717) (xy 99.084685 -423.072817)
			(xy 99.138642 -423.086923) (xy 99.189971 -423.108735) (xy 99.237577 -423.137789) (xy 99.280445 -423.173464)
			(xy 99.317662 -423.215001) (xy 99.348435 -423.261514) (xy 99.372107 -423.312011) (xy 99.388175 -423.365418)
			(xy 99.396295 -423.420594) (xy 99.396804 -423.44848) (xy 99.903278 -423.44848) (xy 99.907349 -423.392858)
			(xy 99.919475 -423.338421) (xy 99.939398 -423.28633) (xy 99.966694 -423.237695) (xy 100.00078 -423.193552)
			(xy 100.040929 -423.154843) (xy 100.086287 -423.122392) (xy 100.135887 -423.096891) (xy 100.188671 -423.078884)
			(xy 100.243514 -423.068754) (xy 100.299248 -423.066717) (xy 100.354685 -423.072817) (xy 100.408642 -423.086923)
			(xy 100.459971 -423.108735) (xy 100.507577 -423.137789) (xy 100.550445 -423.173464) (xy 100.587662 -423.215001)
			(xy 100.618435 -423.261514) (xy 100.642107 -423.312011) (xy 100.658175 -423.365418) (xy 100.666295 -423.420594)
			(xy 100.666804 -423.44848) (xy 101.173278 -423.44848) (xy 101.177349 -423.392858) (xy 101.189475 -423.338421)
			(xy 101.209398 -423.28633) (xy 101.236694 -423.237695) (xy 101.27078 -423.193552) (xy 101.310929 -423.154843)
			(xy 101.356287 -423.122392) (xy 101.405887 -423.096891) (xy 101.458671 -423.078884) (xy 101.513514 -423.068754)
			(xy 101.569248 -423.066717) (xy 101.624685 -423.072817) (xy 101.678642 -423.086923) (xy 101.729971 -423.108735)
			(xy 101.776754 -423.137287) (xy 102.06837 -423.137287) (xy 102.06837 -423.073365) (xy 102.076381 -423.009947)
			(xy 102.092278 -422.948033) (xy 102.11581 -422.8886) (xy 102.146604 -422.832585) (xy 102.184177 -422.78087)
			(xy 102.227934 -422.734273) (xy 102.277187 -422.693528) (xy 102.331158 -422.659277) (xy 102.388997 -422.63206)
			(xy 102.44979 -422.612307) (xy 102.51258 -422.600329) (xy 102.576376 -422.596316) (xy 102.640172 -422.600329)
			(xy 102.702962 -422.612307) (xy 102.763755 -422.63206) (xy 102.821594 -422.659277) (xy 102.875565 -422.693528)
			(xy 102.924818 -422.734273) (xy 102.968575 -422.78087) (xy 103.006148 -422.832585) (xy 103.036942 -422.8886)
			(xy 103.060474 -422.948033) (xy 103.076371 -423.009947) (xy 103.084382 -423.073365) (xy 103.084884 -423.105326)
			(xy 103.084382 -423.137287) (xy 103.076371 -423.200705) (xy 103.060474 -423.262619) (xy 103.036942 -423.322052)
			(xy 103.006148 -423.378067) (xy 102.972522 -423.42435) (xy 103.503982 -423.42435) (xy 103.508053 -423.368728)
			(xy 103.520179 -423.314291) (xy 103.540102 -423.2622) (xy 103.567398 -423.213565) (xy 103.601484 -423.169422)
			(xy 103.641633 -423.130713) (xy 103.686991 -423.098262) (xy 103.736591 -423.072761) (xy 103.789375 -423.054754)
			(xy 103.844218 -423.044624) (xy 103.899952 -423.042587) (xy 103.955389 -423.048687) (xy 104.009346 -423.062793)
			(xy 104.060675 -423.084605) (xy 104.108281 -423.113659) (xy 104.151149 -423.149334) (xy 104.188366 -423.190871)
			(xy 104.219139 -423.237384) (xy 104.242811 -423.287881) (xy 104.258879 -423.341288) (xy 104.266999 -423.396464)
			(xy 104.267508 -423.42435) (xy 104.266999 -423.452236) (xy 104.258879 -423.507412) (xy 104.242811 -423.560819)
			(xy 104.219139 -423.611316) (xy 104.188366 -423.657829) (xy 104.1586 -423.69105) (xy 106.297982 -423.69105)
			(xy 106.302053 -423.635428) (xy 106.314179 -423.580991) (xy 106.334102 -423.5289) (xy 106.361398 -423.480265)
			(xy 106.395484 -423.436122) (xy 106.435633 -423.397413) (xy 106.480991 -423.364962) (xy 106.530591 -423.339461)
			(xy 106.583375 -423.321454) (xy 106.638218 -423.311324) (xy 106.693952 -423.309287) (xy 106.749389 -423.315387)
			(xy 106.803346 -423.329493) (xy 106.854675 -423.351305) (xy 106.902281 -423.380359) (xy 106.945149 -423.416034)
			(xy 106.982366 -423.457571) (xy 107.013139 -423.504084) (xy 107.036811 -423.554581) (xy 107.052879 -423.607988)
			(xy 107.060999 -423.663164) (xy 107.061508 -423.69105) (xy 107.060999 -423.718936) (xy 107.052879 -423.774112)
			(xy 107.036811 -423.827519) (xy 107.013139 -423.878016) (xy 106.982366 -423.924529) (xy 106.945149 -423.966066)
			(xy 106.902281 -424.001741) (xy 106.854675 -424.030795) (xy 106.803346 -424.052607) (xy 106.749389 -424.066713)
			(xy 106.693952 -424.072813) (xy 106.638218 -424.070776) (xy 106.583375 -424.060646) (xy 106.530591 -424.042639)
			(xy 106.480991 -424.017138) (xy 106.435633 -423.984687) (xy 106.395484 -423.945978) (xy 106.361398 -423.901835)
			(xy 106.334102 -423.8532) (xy 106.314179 -423.801109) (xy 106.302053 -423.746672) (xy 106.297982 -423.69105)
			(xy 104.1586 -423.69105) (xy 104.151149 -423.699366) (xy 104.108281 -423.735041) (xy 104.060675 -423.764095)
			(xy 104.009346 -423.785907) (xy 103.955389 -423.800013) (xy 103.899952 -423.806113) (xy 103.844218 -423.804076)
			(xy 103.789375 -423.793946) (xy 103.736591 -423.775939) (xy 103.686991 -423.750438) (xy 103.641633 -423.717987)
			(xy 103.601484 -423.679278) (xy 103.567398 -423.635135) (xy 103.540102 -423.5865) (xy 103.520179 -423.534409)
			(xy 103.508053 -423.479972) (xy 103.503982 -423.42435) (xy 102.972522 -423.42435) (xy 102.968575 -423.429782)
			(xy 102.924818 -423.476379) (xy 102.875565 -423.517124) (xy 102.821594 -423.551375) (xy 102.763755 -423.578592)
			(xy 102.702962 -423.598345) (xy 102.640172 -423.610323) (xy 102.576376 -423.614337) (xy 102.51258 -423.610323)
			(xy 102.44979 -423.598345) (xy 102.388997 -423.578592) (xy 102.331158 -423.551375) (xy 102.277187 -423.517124)
			(xy 102.227934 -423.476379) (xy 102.184177 -423.429782) (xy 102.146604 -423.378067) (xy 102.11581 -423.322052)
			(xy 102.092278 -423.262619) (xy 102.076381 -423.200705) (xy 102.06837 -423.137287) (xy 101.776754 -423.137287)
			(xy 101.777577 -423.137789) (xy 101.820445 -423.173464) (xy 101.857662 -423.215001) (xy 101.888435 -423.261514)
			(xy 101.912107 -423.312011) (xy 101.928175 -423.365418) (xy 101.936295 -423.420594) (xy 101.936804 -423.44848)
			(xy 101.936295 -423.476366) (xy 101.928175 -423.531542) (xy 101.912107 -423.584949) (xy 101.888435 -423.635446)
			(xy 101.857662 -423.681959) (xy 101.820445 -423.723496) (xy 101.777577 -423.759171) (xy 101.729971 -423.788225)
			(xy 101.678642 -423.810037) (xy 101.624685 -423.824143) (xy 101.569248 -423.830243) (xy 101.513514 -423.828206)
			(xy 101.458671 -423.818076) (xy 101.405887 -423.800069) (xy 101.356287 -423.774568) (xy 101.310929 -423.742117)
			(xy 101.27078 -423.703408) (xy 101.236694 -423.659265) (xy 101.209398 -423.61063) (xy 101.189475 -423.558539)
			(xy 101.177349 -423.504102) (xy 101.173278 -423.44848) (xy 100.666804 -423.44848) (xy 100.666295 -423.476366)
			(xy 100.658175 -423.531542) (xy 100.642107 -423.584949) (xy 100.618435 -423.635446) (xy 100.587662 -423.681959)
			(xy 100.550445 -423.723496) (xy 100.507577 -423.759171) (xy 100.459971 -423.788225) (xy 100.408642 -423.810037)
			(xy 100.354685 -423.824143) (xy 100.299248 -423.830243) (xy 100.243514 -423.828206) (xy 100.188671 -423.818076)
			(xy 100.135887 -423.800069) (xy 100.086287 -423.774568) (xy 100.040929 -423.742117) (xy 100.00078 -423.703408)
			(xy 99.966694 -423.659265) (xy 99.939398 -423.61063) (xy 99.919475 -423.558539) (xy 99.907349 -423.504102)
			(xy 99.903278 -423.44848) (xy 99.396804 -423.44848) (xy 99.396295 -423.476366) (xy 99.388175 -423.531542)
			(xy 99.372107 -423.584949) (xy 99.348435 -423.635446) (xy 99.317662 -423.681959) (xy 99.280445 -423.723496)
			(xy 99.237577 -423.759171) (xy 99.189971 -423.788225) (xy 99.138642 -423.810037) (xy 99.084685 -423.824143)
			(xy 99.029248 -423.830243) (xy 98.973514 -423.828206) (xy 98.918671 -423.818076) (xy 98.865887 -423.800069)
			(xy 98.816287 -423.774568) (xy 98.770929 -423.742117) (xy 98.73078 -423.703408) (xy 98.696694 -423.659265)
			(xy 98.669398 -423.61063) (xy 98.649475 -423.558539) (xy 98.637349 -423.504102) (xy 98.633278 -423.44848)
			(xy 98.298858 -423.44848) (xy 98.299016 -423.457116) (xy 98.298507 -423.485002) (xy 98.290387 -423.540178)
			(xy 98.274319 -423.593585) (xy 98.250647 -423.644082) (xy 98.219874 -423.690595) (xy 98.182657 -423.732132)
			(xy 98.139789 -423.767807) (xy 98.092183 -423.796861) (xy 98.040854 -423.818673) (xy 97.986897 -423.832779)
			(xy 97.93146 -423.838879) (xy 97.875726 -423.836842) (xy 97.820883 -423.826712) (xy 97.768099 -423.808705)
			(xy 97.718499 -423.783204) (xy 97.673141 -423.750753) (xy 97.632992 -423.712044) (xy 97.598906 -423.667901)
			(xy 97.57161 -423.619266) (xy 97.551687 -423.567175) (xy 97.539561 -423.512738) (xy 97.53549 -423.457116)
			(xy 95.755206 -423.457116) (xy 95.755206 -424.191684) (xy 96.111312 -424.191684) (xy 96.115383 -424.136062)
			(xy 96.127509 -424.081625) (xy 96.147432 -424.029534) (xy 96.174728 -423.980899) (xy 96.208814 -423.936756)
			(xy 96.248963 -423.898047) (xy 96.294321 -423.865596) (xy 96.343921 -423.840095) (xy 96.396705 -423.822088)
			(xy 96.451548 -423.811958) (xy 96.507282 -423.809921) (xy 96.562719 -423.816021) (xy 96.616676 -423.830127)
			(xy 96.668005 -423.851939) (xy 96.715611 -423.880993) (xy 96.758479 -423.916668) (xy 96.795696 -423.958205)
			(xy 96.826469 -424.004718) (xy 96.850141 -424.055215) (xy 96.866209 -424.108622) (xy 96.874329 -424.163798)
			(xy 96.874838 -424.191684) (xy 96.874329 -424.21957) (xy 96.866209 -424.274746) (xy 96.850141 -424.328153)
			(xy 96.826469 -424.37865) (xy 96.795696 -424.425163) (xy 96.758479 -424.4667) (xy 96.715611 -424.502375)
			(xy 96.668005 -424.531429) (xy 96.616676 -424.553241) (xy 96.562719 -424.567347) (xy 96.507282 -424.573447)
			(xy 96.451548 -424.57141) (xy 96.396705 -424.56128) (xy 96.343921 -424.543273) (xy 96.294321 -424.517772)
			(xy 96.248963 -424.485321) (xy 96.208814 -424.446612) (xy 96.174728 -424.402469) (xy 96.147432 -424.353834)
			(xy 96.127509 -424.301743) (xy 96.115383 -424.247306) (xy 96.111312 -424.191684) (xy 95.755206 -424.191684)
			(xy 95.755206 -425.481961) (xy 102.361994 -425.481961) (xy 102.361994 -425.418039) (xy 102.370005 -425.354621)
			(xy 102.385902 -425.292707) (xy 102.409434 -425.233274) (xy 102.440228 -425.177259) (xy 102.477801 -425.125544)
			(xy 102.521558 -425.078947) (xy 102.570811 -425.038202) (xy 102.624782 -425.003951) (xy 102.682621 -424.976734)
			(xy 102.743414 -424.956981) (xy 102.806204 -424.945003) (xy 102.87 -424.94099) (xy 102.933796 -424.945003)
			(xy 102.996586 -424.956981) (xy 103.057379 -424.976734) (xy 103.115218 -425.003951) (xy 103.169189 -425.038202)
			(xy 103.218442 -425.078947) (xy 103.262199 -425.125544) (xy 103.299772 -425.177259) (xy 103.330566 -425.233274)
			(xy 103.354098 -425.292707) (xy 103.369995 -425.354621) (xy 103.378006 -425.418039) (xy 103.378508 -425.45)
			(xy 103.378006 -425.481961) (xy 105.409994 -425.481961) (xy 105.409994 -425.418039) (xy 105.418005 -425.354621)
			(xy 105.433902 -425.292707) (xy 105.457434 -425.233274) (xy 105.488228 -425.177259) (xy 105.525801 -425.125544)
			(xy 105.569558 -425.078947) (xy 105.618811 -425.038202) (xy 105.672782 -425.003951) (xy 105.730621 -424.976734)
			(xy 105.791414 -424.956981) (xy 105.854204 -424.945003) (xy 105.918 -424.94099) (xy 105.981796 -424.945003)
			(xy 106.044586 -424.956981) (xy 106.105379 -424.976734) (xy 106.163218 -425.003951) (xy 106.217189 -425.038202)
			(xy 106.266442 -425.078947) (xy 106.310199 -425.125544) (xy 106.347772 -425.177259) (xy 106.378566 -425.233274)
			(xy 106.402098 -425.292707) (xy 106.417995 -425.354621) (xy 106.426006 -425.418039) (xy 106.426508 -425.45)
			(xy 106.426006 -425.481961) (xy 106.417995 -425.545379) (xy 106.402098 -425.607293) (xy 106.378566 -425.666726)
			(xy 106.347772 -425.722741) (xy 106.310199 -425.774456) (xy 106.266442 -425.821053) (xy 106.217189 -425.861798)
			(xy 106.163218 -425.896049) (xy 106.105379 -425.923266) (xy 106.044586 -425.943019) (xy 105.981796 -425.954997)
			(xy 105.918 -425.959011) (xy 105.854204 -425.954997) (xy 105.791414 -425.943019) (xy 105.730621 -425.923266)
			(xy 105.672782 -425.896049) (xy 105.618811 -425.861798) (xy 105.569558 -425.821053) (xy 105.525801 -425.774456)
			(xy 105.488228 -425.722741) (xy 105.457434 -425.666726) (xy 105.433902 -425.607293) (xy 105.418005 -425.545379)
			(xy 105.409994 -425.481961) (xy 103.378006 -425.481961) (xy 103.369995 -425.545379) (xy 103.354098 -425.607293)
			(xy 103.330566 -425.666726) (xy 103.299772 -425.722741) (xy 103.262199 -425.774456) (xy 103.218442 -425.821053)
			(xy 103.169189 -425.861798) (xy 103.115218 -425.896049) (xy 103.057379 -425.923266) (xy 102.996586 -425.943019)
			(xy 102.933796 -425.954997) (xy 102.87 -425.959011) (xy 102.806204 -425.954997) (xy 102.743414 -425.943019)
			(xy 102.682621 -425.923266) (xy 102.624782 -425.896049) (xy 102.570811 -425.861798) (xy 102.521558 -425.821053)
			(xy 102.477801 -425.774456) (xy 102.440228 -425.722741) (xy 102.409434 -425.666726) (xy 102.385902 -425.607293)
			(xy 102.370005 -425.545379) (xy 102.361994 -425.481961) (xy 95.755206 -425.481961) (xy 95.755206 -426.19295)
			(xy 101.641146 -426.19295) (xy 101.645217 -426.137328) (xy 101.657343 -426.082891) (xy 101.677266 -426.0308)
			(xy 101.704562 -425.982165) (xy 101.738648 -425.938022) (xy 101.778797 -425.899313) (xy 101.824155 -425.866862)
			(xy 101.873755 -425.841361) (xy 101.926539 -425.823354) (xy 101.981382 -425.813224) (xy 102.037116 -425.811187)
			(xy 102.092553 -425.817287) (xy 102.14651 -425.831393) (xy 102.197839 -425.853205) (xy 102.245445 -425.882259)
			(xy 102.288313 -425.917934) (xy 102.32553 -425.959471) (xy 102.356303 -426.005984) (xy 102.379975 -426.056481)
			(xy 102.396043 -426.109888) (xy 102.404163 -426.165064) (xy 102.404672 -426.19295) (xy 102.404163 -426.220836)
			(xy 102.396043 -426.276012) (xy 102.379975 -426.329419) (xy 102.356303 -426.379916) (xy 102.32553 -426.426429)
			(xy 102.288313 -426.467966) (xy 102.245445 -426.503641) (xy 102.197839 -426.532695) (xy 102.14651 -426.554507)
			(xy 102.092553 -426.568613) (xy 102.037116 -426.574713) (xy 101.981382 -426.572676) (xy 101.926539 -426.562546)
			(xy 101.873755 -426.544539) (xy 101.824155 -426.519038) (xy 101.778797 -426.486587) (xy 101.738648 -426.447878)
			(xy 101.704562 -426.403735) (xy 101.677266 -426.3551) (xy 101.657343 -426.303009) (xy 101.645217 -426.248572)
			(xy 101.641146 -426.19295) (xy 95.755206 -426.19295) (xy 95.755206 -427.641469) (xy 97.299266 -427.641469)
			(xy 97.299266 -427.577547) (xy 97.307277 -427.514129) (xy 97.323174 -427.452215) (xy 97.346706 -427.392782)
			(xy 97.3775 -427.336767) (xy 97.415073 -427.285052) (xy 97.45883 -427.238455) (xy 97.508083 -427.19771)
			(xy 97.562054 -427.163459) (xy 97.619893 -427.136242) (xy 97.680686 -427.116489) (xy 97.743476 -427.104511)
			(xy 97.807272 -427.100498) (xy 97.871068 -427.104511) (xy 97.933858 -427.116489) (xy 97.994651 -427.136242)
			(xy 98.05249 -427.163459) (xy 98.106461 -427.19771) (xy 98.155714 -427.238455) (xy 98.199471 -427.285052)
			(xy 98.237044 -427.336767) (xy 98.267838 -427.392782) (xy 98.29137 -427.452215) (xy 98.307267 -427.514129)
			(xy 98.315278 -427.577547) (xy 98.315772 -427.609) (xy 102.487982 -427.609) (xy 102.492053 -427.553378)
			(xy 102.504179 -427.498941) (xy 102.524102 -427.44685) (xy 102.551398 -427.398215) (xy 102.585484 -427.354072)
			(xy 102.625633 -427.315363) (xy 102.670991 -427.282912) (xy 102.720591 -427.257411) (xy 102.773375 -427.239404)
			(xy 102.828218 -427.229274) (xy 102.883952 -427.227237) (xy 102.939389 -427.233337) (xy 102.993346 -427.247443)
			(xy 103.044675 -427.269255) (xy 103.092281 -427.298309) (xy 103.135149 -427.333984) (xy 103.172366 -427.375521)
			(xy 103.203139 -427.422034) (xy 103.226811 -427.472531) (xy 103.242879 -427.525938) (xy 103.250999 -427.581114)
			(xy 103.251508 -427.609) (xy 105.535982 -427.609) (xy 105.540053 -427.553378) (xy 105.552179 -427.498941)
			(xy 105.572102 -427.44685) (xy 105.599398 -427.398215) (xy 105.633484 -427.354072) (xy 105.673633 -427.315363)
			(xy 105.718991 -427.282912) (xy 105.768591 -427.257411) (xy 105.821375 -427.239404) (xy 105.876218 -427.229274)
			(xy 105.931952 -427.227237) (xy 105.987389 -427.233337) (xy 106.041346 -427.247443) (xy 106.092675 -427.269255)
			(xy 106.140281 -427.298309) (xy 106.183149 -427.333984) (xy 106.220366 -427.375521) (xy 106.251139 -427.422034)
			(xy 106.274811 -427.472531) (xy 106.290879 -427.525938) (xy 106.298999 -427.581114) (xy 106.299508 -427.609)
			(xy 106.298999 -427.636886) (xy 106.290879 -427.692062) (xy 106.274811 -427.745469) (xy 106.251139 -427.795966)
			(xy 106.220366 -427.842479) (xy 106.183149 -427.884016) (xy 106.140281 -427.919691) (xy 106.092675 -427.948745)
			(xy 106.041346 -427.970557) (xy 105.987389 -427.984663) (xy 105.931952 -427.990763) (xy 105.876218 -427.988726)
			(xy 105.821375 -427.978596) (xy 105.768591 -427.960589) (xy 105.718991 -427.935088) (xy 105.673633 -427.902637)
			(xy 105.633484 -427.863928) (xy 105.599398 -427.819785) (xy 105.572102 -427.77115) (xy 105.552179 -427.719059)
			(xy 105.540053 -427.664622) (xy 105.535982 -427.609) (xy 103.251508 -427.609) (xy 103.250999 -427.636886)
			(xy 103.242879 -427.692062) (xy 103.226811 -427.745469) (xy 103.203139 -427.795966) (xy 103.172366 -427.842479)
			(xy 103.135149 -427.884016) (xy 103.092281 -427.919691) (xy 103.044675 -427.948745) (xy 102.993346 -427.970557)
			(xy 102.939389 -427.984663) (xy 102.883952 -427.990763) (xy 102.828218 -427.988726) (xy 102.773375 -427.978596)
			(xy 102.720591 -427.960589) (xy 102.670991 -427.935088) (xy 102.625633 -427.902637) (xy 102.585484 -427.863928)
			(xy 102.551398 -427.819785) (xy 102.524102 -427.77115) (xy 102.504179 -427.719059) (xy 102.492053 -427.664622)
			(xy 102.487982 -427.609) (xy 98.315772 -427.609) (xy 98.31578 -427.609508) (xy 98.315278 -427.641469)
			(xy 98.307267 -427.704887) (xy 98.29137 -427.766801) (xy 98.267838 -427.826234) (xy 98.237044 -427.882249)
			(xy 98.199471 -427.933964) (xy 98.155714 -427.980561) (xy 98.106461 -428.021306) (xy 98.05249 -428.055557)
			(xy 97.994651 -428.082774) (xy 97.933858 -428.102527) (xy 97.871068 -428.114505) (xy 97.807272 -428.118519)
			(xy 97.743476 -428.114505) (xy 97.680686 -428.102527) (xy 97.619893 -428.082774) (xy 97.562054 -428.055557)
			(xy 97.508083 -428.021306) (xy 97.45883 -427.980561) (xy 97.415073 -427.933964) (xy 97.3775 -427.882249)
			(xy 97.346706 -427.826234) (xy 97.323174 -427.766801) (xy 97.307277 -427.704887) (xy 97.299266 -427.641469)
			(xy 95.755206 -427.641469) (xy 95.755206 -428.977806) (xy 95.75563 -428.987876) (xy 95.763347 -429.006478)
			(xy 95.770192 -429.013874) (xy 95.826834 -429.070516) (xy 95.83423 -429.077366) (xy 95.852829 -429.085102)
			(xy 95.862902 -429.085502) (xy 106.485944 -429.085502) (xy 106.49458 -429.08474) (xy 106.502103 -429.083147)
			(xy 106.515805 -429.076185) (xy 106.521504 -429.071024) (xy 107.359196 -428.233332) (xy 107.366032 -428.22593)
			(xy 107.373743 -428.207332) (xy 107.374182 -428.197264) (xy 107.374182 -421.389556) (xy 107.374613 -421.379489)
			(xy 107.382336 -421.360894) (xy 107.389168 -421.353488) (xy 108.399834 -420.342822) (xy 108.407233 -420.335978)
			(xy 108.425832 -420.328253) (xy 108.435902 -420.327836) (xy 113.68278 -420.327836) (xy 113.692843 -420.328274)
			(xy 113.711423 -420.336013) (xy 113.718848 -420.342822) (xy 113.873026 -420.497) (xy 117.092982 -420.497)
			(xy 117.097053 -420.441378) (xy 117.109179 -420.386941) (xy 117.129102 -420.33485) (xy 117.156398 -420.286215)
			(xy 117.190484 -420.242072) (xy 117.230633 -420.203363) (xy 117.275991 -420.170912) (xy 117.325591 -420.145411)
			(xy 117.378375 -420.127404) (xy 117.433218 -420.117274) (xy 117.488952 -420.115237) (xy 117.544389 -420.121337)
			(xy 117.598346 -420.135443) (xy 117.649675 -420.157255) (xy 117.697281 -420.186309) (xy 117.740149 -420.221984)
			(xy 117.777366 -420.263521) (xy 117.808139 -420.310034) (xy 117.831811 -420.360531) (xy 117.847879 -420.413938)
			(xy 117.855999 -420.469114) (xy 117.856508 -420.497) (xy 117.855999 -420.524886) (xy 117.847879 -420.580062)
			(xy 117.831811 -420.633469) (xy 117.808139 -420.683966) (xy 117.777366 -420.730479) (xy 117.740149 -420.772016)
			(xy 117.697281 -420.807691) (xy 117.649675 -420.836745) (xy 117.598346 -420.858557) (xy 117.544389 -420.872663)
			(xy 117.488952 -420.878763) (xy 117.433218 -420.876726) (xy 117.378375 -420.866596) (xy 117.325591 -420.848589)
			(xy 117.275991 -420.823088) (xy 117.230633 -420.790637) (xy 117.190484 -420.751928) (xy 117.156398 -420.707785)
			(xy 117.129102 -420.65915) (xy 117.109179 -420.607059) (xy 117.097053 -420.552622) (xy 117.092982 -420.497)
			(xy 113.873026 -420.497) (xy 114.793987 -421.417961) (xy 116.204994 -421.417961) (xy 116.204994 -421.354039)
			(xy 116.213005 -421.290621) (xy 116.228902 -421.228707) (xy 116.252434 -421.169274) (xy 116.283228 -421.113259)
			(xy 116.320801 -421.061544) (xy 116.364558 -421.014947) (xy 116.413811 -420.974202) (xy 116.467782 -420.939951)
			(xy 116.525621 -420.912734) (xy 116.586414 -420.892981) (xy 116.649204 -420.881003) (xy 116.713 -420.87699)
			(xy 116.776796 -420.881003) (xy 116.839586 -420.892981) (xy 116.900379 -420.912734) (xy 116.958218 -420.939951)
			(xy 117.012189 -420.974202) (xy 117.061442 -421.014947) (xy 117.105199 -421.061544) (xy 117.142772 -421.113259)
			(xy 117.173566 -421.169274) (xy 117.197098 -421.228707) (xy 117.212995 -421.290621) (xy 117.221006 -421.354039)
			(xy 117.221508 -421.386) (xy 117.221006 -421.417961) (xy 117.212995 -421.481379) (xy 117.197098 -421.543293)
			(xy 117.173566 -421.602726) (xy 117.142772 -421.658741) (xy 117.105199 -421.710456) (xy 117.061442 -421.757053)
			(xy 117.012189 -421.797798) (xy 116.958218 -421.832049) (xy 116.900379 -421.859266) (xy 116.839586 -421.879019)
			(xy 116.776796 -421.890997) (xy 116.713 -421.895011) (xy 116.649204 -421.890997) (xy 116.586414 -421.879019)
			(xy 116.525621 -421.859266) (xy 116.467782 -421.832049) (xy 116.413811 -421.797798) (xy 116.364558 -421.757053)
			(xy 116.320801 -421.710456) (xy 116.283228 -421.658741) (xy 116.252434 -421.602726) (xy 116.228902 -421.543293)
			(xy 116.213005 -421.481379) (xy 116.204994 -421.417961) (xy 114.793987 -421.417961) (xy 115.683284 -422.307258)
			(xy 115.690123 -422.314659) (xy 115.697839 -422.333257) (xy 115.69827 -422.343326) (xy 115.69827 -422.887902)
			(xy 117.992906 -422.887902) (xy 117.9934 -422.861031) (xy 118.000955 -422.807822) (xy 118.015901 -422.7562)
			(xy 118.037943 -422.707186) (xy 118.066645 -422.661749) (xy 118.101438 -422.62079) (xy 118.141634 -422.585118)
			(xy 118.186438 -422.555439) (xy 118.234964 -422.53234) (xy 118.28625 -422.516279) (xy 118.312692 -422.511474)
			(xy 118.323106 -422.509696) (xy 118.340886 -422.498266) (xy 118.393972 -422.419272) (xy 118.397782 -422.398698)
			(xy 118.395242 -422.388538) (xy 118.389275 -422.360534) (xy 118.382907 -422.30363) (xy 118.382542 -422.275)
			(xy 118.382968 -422.24346) (xy 118.39077 -422.180863) (xy 118.406255 -422.119713) (xy 118.429185 -422.060947)
			(xy 118.459208 -422.005469) (xy 118.495862 -421.95413) (xy 118.538584 -421.907719) (xy 118.58672 -421.86695)
			(xy 118.639528 -421.832447) (xy 118.696199 -421.80474) (xy 118.755861 -421.784257) (xy 118.817599 -421.77131)
			(xy 118.880464 -421.766099) (xy 118.943491 -421.768703) (xy 119.005712 -421.779084) (xy 119.066171 -421.797081)
			(xy 119.123939 -421.822417) (xy 119.178131 -421.854705) (xy 119.227912 -421.893448) (xy 119.272519 -421.938051)
			(xy 119.311267 -421.987828) (xy 119.34356 -422.042016) (xy 119.368902 -422.099782) (xy 119.386905 -422.16024)
			(xy 119.397292 -422.222459) (xy 119.399902 -422.285486) (xy 119.398124 -422.306961) (xy 119.760994 -422.306961)
			(xy 119.760994 -422.243039) (xy 119.769005 -422.179621) (xy 119.784902 -422.117707) (xy 119.808434 -422.058274)
			(xy 119.839228 -422.002259) (xy 119.876801 -421.950544) (xy 119.920558 -421.903947) (xy 119.969811 -421.863202)
			(xy 120.023782 -421.828951) (xy 120.081621 -421.801734) (xy 120.142414 -421.781981) (xy 120.205204 -421.770003)
			(xy 120.269 -421.76599) (xy 120.332796 -421.770003) (xy 120.395586 -421.781981) (xy 120.456379 -421.801734)
			(xy 120.514218 -421.828951) (xy 120.568189 -421.863202) (xy 120.617442 -421.903947) (xy 120.661199 -421.950544)
			(xy 120.698772 -422.002259) (xy 120.729566 -422.058274) (xy 120.753098 -422.117707) (xy 120.768995 -422.179621)
			(xy 120.777006 -422.243039) (xy 120.777508 -422.275) (xy 120.777006 -422.306961) (xy 120.768995 -422.370379)
			(xy 120.753098 -422.432293) (xy 120.729566 -422.491726) (xy 120.698772 -422.547741) (xy 120.661199 -422.599456)
			(xy 120.617442 -422.646053) (xy 120.568189 -422.686798) (xy 120.514218 -422.721049) (xy 120.456379 -422.748266)
			(xy 120.395586 -422.768019) (xy 120.332796 -422.779997) (xy 120.269 -422.784011) (xy 120.205204 -422.779997)
			(xy 120.142414 -422.768019) (xy 120.081621 -422.748266) (xy 120.023782 -422.721049) (xy 119.969811 -422.686798)
			(xy 119.920558 -422.646053) (xy 119.876801 -422.599456) (xy 119.839228 -422.547741) (xy 119.808434 -422.491726)
			(xy 119.784902 -422.432293) (xy 119.769005 -422.370379) (xy 119.760994 -422.306961) (xy 119.398124 -422.306961)
			(xy 119.394698 -422.348352) (xy 119.381757 -422.410091) (xy 119.361279 -422.469755) (xy 119.333578 -422.526428)
			(xy 119.29908 -422.57924) (xy 119.258315 -422.627379) (xy 119.211909 -422.670107) (xy 119.160574 -422.706766)
			(xy 119.105098 -422.736794) (xy 119.046335 -422.75973) (xy 118.985186 -422.775221) (xy 118.92259 -422.783029)
			(xy 118.89105 -422.783508) (xy 118.86311 -422.782746) (xy 118.852442 -422.782238) (xy 118.832884 -422.78935)
			(xy 118.76405 -422.855136) (xy 118.755922 -422.87444) (xy 118.755922 -422.887902) (xy 118.755436 -422.915153)
			(xy 118.74768 -422.969101) (xy 118.732325 -423.021396) (xy 118.709683 -423.070973) (xy 118.680217 -423.116823)
			(xy 118.644526 -423.158014) (xy 118.603335 -423.193705) (xy 118.557485 -423.223171) (xy 118.507908 -423.245813)
			(xy 118.455613 -423.261168) (xy 118.401665 -423.268924) (xy 118.347163 -423.268924) (xy 118.293215 -423.261168)
			(xy 118.24092 -423.245813) (xy 118.191343 -423.223171) (xy 118.145493 -423.193705) (xy 118.104302 -423.158014)
			(xy 118.068611 -423.116823) (xy 118.039145 -423.070973) (xy 118.016503 -423.021396) (xy 118.001148 -422.969101)
			(xy 117.993392 -422.915153) (xy 117.992906 -422.887902) (xy 115.69827 -422.887902) (xy 115.69827 -423.322961)
			(xy 121.284994 -423.322961) (xy 121.284994 -423.259039) (xy 121.293005 -423.195621) (xy 121.308902 -423.133707)
			(xy 121.332434 -423.074274) (xy 121.363228 -423.018259) (xy 121.400801 -422.966544) (xy 121.444558 -422.919947)
			(xy 121.493811 -422.879202) (xy 121.547782 -422.844951) (xy 121.605621 -422.817734) (xy 121.666414 -422.797981)
			(xy 121.729204 -422.786003) (xy 121.793 -422.78199) (xy 121.856796 -422.786003) (xy 121.919586 -422.797981)
			(xy 121.980379 -422.817734) (xy 122.038218 -422.844951) (xy 122.092189 -422.879202) (xy 122.141442 -422.919947)
			(xy 122.185199 -422.966544) (xy 122.222772 -423.018259) (xy 122.253566 -423.074274) (xy 122.277098 -423.133707)
			(xy 122.292995 -423.195621) (xy 122.301006 -423.259039) (xy 122.301508 -423.291) (xy 122.301006 -423.322961)
			(xy 122.292995 -423.386379) (xy 122.277098 -423.448293) (xy 122.253566 -423.507726) (xy 122.222772 -423.563741)
			(xy 122.185199 -423.615456) (xy 122.141442 -423.662053) (xy 122.092189 -423.702798) (xy 122.038218 -423.737049)
			(xy 121.980379 -423.764266) (xy 121.919586 -423.784019) (xy 121.856796 -423.795997) (xy 121.793 -423.800011)
			(xy 121.729204 -423.795997) (xy 121.666414 -423.784019) (xy 121.605621 -423.764266) (xy 121.547782 -423.737049)
			(xy 121.493811 -423.702798) (xy 121.444558 -423.662053) (xy 121.400801 -423.615456) (xy 121.363228 -423.563741)
			(xy 121.332434 -423.507726) (xy 121.308902 -423.448293) (xy 121.293005 -423.386379) (xy 121.284994 -423.322961)
			(xy 115.69827 -423.322961) (xy 115.69827 -425.21505) (xy 119.124982 -425.21505) (xy 119.129053 -425.159428)
			(xy 119.141179 -425.104991) (xy 119.161102 -425.0529) (xy 119.188398 -425.004265) (xy 119.222484 -424.960122)
			(xy 119.262633 -424.921413) (xy 119.307991 -424.888962) (xy 119.357591 -424.863461) (xy 119.410375 -424.845454)
			(xy 119.465218 -424.835324) (xy 119.520952 -424.833287) (xy 119.576389 -424.839387) (xy 119.630346 -424.853493)
			(xy 119.681675 -424.875305) (xy 119.729281 -424.904359) (xy 119.772149 -424.940034) (xy 119.809366 -424.981571)
			(xy 119.840139 -425.028084) (xy 119.863811 -425.078581) (xy 119.879879 -425.131988) (xy 119.887999 -425.187164)
			(xy 119.888508 -425.21505) (xy 119.887999 -425.242936) (xy 119.879879 -425.298112) (xy 119.863811 -425.351519)
			(xy 119.840139 -425.402016) (xy 119.809366 -425.448529) (xy 119.772149 -425.490066) (xy 119.729281 -425.525741)
			(xy 119.681675 -425.554795) (xy 119.630346 -425.576607) (xy 119.576389 -425.590713) (xy 119.520952 -425.596813)
			(xy 119.465218 -425.594776) (xy 119.410375 -425.584646) (xy 119.357591 -425.566639) (xy 119.307991 -425.541138)
			(xy 119.262633 -425.508687) (xy 119.222484 -425.469978) (xy 119.188398 -425.425835) (xy 119.161102 -425.3772)
			(xy 119.141179 -425.325109) (xy 119.129053 -425.270672) (xy 119.124982 -425.21505) (xy 115.69827 -425.21505)
			(xy 115.69827 -426.72) (xy 120.521982 -426.72) (xy 120.526053 -426.664378) (xy 120.538179 -426.609941)
			(xy 120.558102 -426.55785) (xy 120.585398 -426.509215) (xy 120.619484 -426.465072) (xy 120.659633 -426.426363)
			(xy 120.704991 -426.393912) (xy 120.754591 -426.368411) (xy 120.807375 -426.350404) (xy 120.862218 -426.340274)
			(xy 120.917952 -426.338237) (xy 120.973389 -426.344337) (xy 121.027346 -426.358443) (xy 121.078675 -426.380255)
			(xy 121.126281 -426.409309) (xy 121.169149 -426.444984) (xy 121.206366 -426.486521) (xy 121.237139 -426.533034)
			(xy 121.260811 -426.583531) (xy 121.276879 -426.636938) (xy 121.284999 -426.692114) (xy 121.285508 -426.72)
			(xy 121.284999 -426.747886) (xy 121.276879 -426.803062) (xy 121.260811 -426.856469) (xy 121.237139 -426.906966)
			(xy 121.206366 -426.953479) (xy 121.169149 -426.995016) (xy 121.126281 -427.030691) (xy 121.078675 -427.059745)
			(xy 121.027346 -427.081557) (xy 120.973389 -427.095663) (xy 120.917952 -427.101763) (xy 120.862218 -427.099726)
			(xy 120.807375 -427.089596) (xy 120.754591 -427.071589) (xy 120.704991 -427.046088) (xy 120.659633 -427.013637)
			(xy 120.619484 -426.974928) (xy 120.585398 -426.930785) (xy 120.558102 -426.88215) (xy 120.538179 -426.830059)
			(xy 120.526053 -426.775622) (xy 120.521982 -426.72) (xy 115.69827 -426.72) (xy 115.69827 -429.006)
			(xy 119.076468 -429.006) (xy 119.080539 -428.950378) (xy 119.092665 -428.895941) (xy 119.112588 -428.84385)
			(xy 119.139884 -428.795215) (xy 119.17397 -428.751072) (xy 119.214119 -428.712363) (xy 119.259477 -428.679912)
			(xy 119.309077 -428.654411) (xy 119.361861 -428.636404) (xy 119.416704 -428.626274) (xy 119.472438 -428.624237)
			(xy 119.527875 -428.630337) (xy 119.581832 -428.644443) (xy 119.633161 -428.666255) (xy 119.680767 -428.695309)
			(xy 119.723635 -428.730984) (xy 119.760852 -428.772521) (xy 119.791625 -428.819034) (xy 119.815297 -428.869531)
			(xy 119.831365 -428.922938) (xy 119.839485 -428.978114) (xy 119.839994 -429.006) (xy 119.839485 -429.033886)
			(xy 119.831365 -429.089062) (xy 119.815297 -429.142469) (xy 119.791625 -429.192966) (xy 119.760852 -429.239479)
			(xy 119.723635 -429.281016) (xy 119.680767 -429.316691) (xy 119.633161 -429.345745) (xy 119.581832 -429.367557)
			(xy 119.527875 -429.381663) (xy 119.472438 -429.387763) (xy 119.416704 -429.385726) (xy 119.361861 -429.375596)
			(xy 119.309077 -429.357589) (xy 119.259477 -429.332088) (xy 119.214119 -429.299637) (xy 119.17397 -429.260928)
			(xy 119.139884 -429.216785) (xy 119.112588 -429.16815) (xy 119.092665 -429.116059) (xy 119.080539 -429.061622)
			(xy 119.076468 -429.006) (xy 115.69827 -429.006) (xy 115.69827 -432.054) (xy 117.092982 -432.054)
			(xy 117.097053 -431.998378) (xy 117.109179 -431.943941) (xy 117.129102 -431.89185) (xy 117.156398 -431.843215)
			(xy 117.190484 -431.799072) (xy 117.230633 -431.760363) (xy 117.275991 -431.727912) (xy 117.325591 -431.702411)
			(xy 117.378375 -431.684404) (xy 117.433218 -431.674274) (xy 117.488952 -431.672237) (xy 117.544389 -431.678337)
			(xy 117.598346 -431.692443) (xy 117.649675 -431.714255) (xy 117.697281 -431.743309) (xy 117.740149 -431.778984)
			(xy 117.777366 -431.820521) (xy 117.808139 -431.867034) (xy 117.831811 -431.917531) (xy 117.847879 -431.970938)
			(xy 117.855999 -432.026114) (xy 117.856508 -432.054) (xy 121.156982 -432.054) (xy 121.161053 -431.998378)
			(xy 121.173179 -431.943941) (xy 121.193102 -431.89185) (xy 121.220398 -431.843215) (xy 121.254484 -431.799072)
			(xy 121.294633 -431.760363) (xy 121.339991 -431.727912) (xy 121.389591 -431.702411) (xy 121.442375 -431.684404)
			(xy 121.497218 -431.674274) (xy 121.552952 -431.672237) (xy 121.608389 -431.678337) (xy 121.662346 -431.692443)
			(xy 121.713675 -431.714255) (xy 121.761281 -431.743309) (xy 121.804149 -431.778984) (xy 121.841366 -431.820521)
			(xy 121.872139 -431.867034) (xy 121.895811 -431.917531) (xy 121.911879 -431.970938) (xy 121.919999 -432.026114)
			(xy 121.920508 -432.054) (xy 121.919999 -432.081886) (xy 121.911879 -432.137062) (xy 121.895811 -432.190469)
			(xy 121.872139 -432.240966) (xy 121.841366 -432.287479) (xy 121.804149 -432.329016) (xy 121.761281 -432.364691)
			(xy 121.713675 -432.393745) (xy 121.662346 -432.415557) (xy 121.608389 -432.429663) (xy 121.552952 -432.435763)
			(xy 121.497218 -432.433726) (xy 121.442375 -432.423596) (xy 121.389591 -432.405589) (xy 121.339991 -432.380088)
			(xy 121.294633 -432.347637) (xy 121.254484 -432.308928) (xy 121.220398 -432.264785) (xy 121.193102 -432.21615)
			(xy 121.173179 -432.164059) (xy 121.161053 -432.109622) (xy 121.156982 -432.054) (xy 117.856508 -432.054)
			(xy 117.855999 -432.081886) (xy 117.847879 -432.137062) (xy 117.831811 -432.190469) (xy 117.808139 -432.240966)
			(xy 117.777366 -432.287479) (xy 117.740149 -432.329016) (xy 117.697281 -432.364691) (xy 117.649675 -432.393745)
			(xy 117.598346 -432.415557) (xy 117.544389 -432.429663) (xy 117.488952 -432.435763) (xy 117.433218 -432.433726)
			(xy 117.378375 -432.423596) (xy 117.325591 -432.405589) (xy 117.275991 -432.380088) (xy 117.230633 -432.347637)
			(xy 117.190484 -432.308928) (xy 117.156398 -432.264785) (xy 117.129102 -432.21615) (xy 117.109179 -432.164059)
			(xy 117.097053 -432.109622) (xy 117.092982 -432.054) (xy 115.69827 -432.054) (xy 115.69827 -432.847961)
			(xy 118.510044 -432.847961) (xy 118.510044 -432.784039) (xy 118.518055 -432.720621) (xy 118.533952 -432.658707)
			(xy 118.557484 -432.599274) (xy 118.588278 -432.543259) (xy 118.625851 -432.491544) (xy 118.669608 -432.444947)
			(xy 118.718861 -432.404202) (xy 118.772832 -432.369951) (xy 118.830671 -432.342734) (xy 118.891464 -432.322981)
			(xy 118.954254 -432.311003) (xy 119.01805 -432.30699) (xy 119.081846 -432.311003) (xy 119.144636 -432.322981)
			(xy 119.205429 -432.342734) (xy 119.263268 -432.369951) (xy 119.317239 -432.404202) (xy 119.366492 -432.444947)
			(xy 119.410249 -432.491544) (xy 119.447822 -432.543259) (xy 119.478616 -432.599274) (xy 119.502148 -432.658707)
			(xy 119.518045 -432.720621) (xy 119.526056 -432.784039) (xy 119.526558 -432.816) (xy 119.526056 -432.847961)
			(xy 119.887994 -432.847961) (xy 119.887994 -432.784039) (xy 119.896005 -432.720621) (xy 119.911902 -432.658707)
			(xy 119.935434 -432.599274) (xy 119.966228 -432.543259) (xy 120.003801 -432.491544) (xy 120.047558 -432.444947)
			(xy 120.096811 -432.404202) (xy 120.150782 -432.369951) (xy 120.208621 -432.342734) (xy 120.269414 -432.322981)
			(xy 120.332204 -432.311003) (xy 120.396 -432.30699) (xy 120.459796 -432.311003) (xy 120.522586 -432.322981)
			(xy 120.583379 -432.342734) (xy 120.641218 -432.369951) (xy 120.695189 -432.404202) (xy 120.744442 -432.444947)
			(xy 120.788199 -432.491544) (xy 120.825772 -432.543259) (xy 120.856566 -432.599274) (xy 120.880098 -432.658707)
			(xy 120.895995 -432.720621) (xy 120.904006 -432.784039) (xy 120.904508 -432.816) (xy 120.904006 -432.847961)
			(xy 120.895995 -432.911379) (xy 120.880098 -432.973293) (xy 120.856566 -433.032726) (xy 120.825772 -433.088741)
			(xy 120.788199 -433.140456) (xy 120.744442 -433.187053) (xy 120.695189 -433.227798) (xy 120.641218 -433.262049)
			(xy 120.583379 -433.289266) (xy 120.522586 -433.309019) (xy 120.459796 -433.320997) (xy 120.396 -433.325011)
			(xy 120.332204 -433.320997) (xy 120.269414 -433.309019) (xy 120.208621 -433.289266) (xy 120.150782 -433.262049)
			(xy 120.096811 -433.227798) (xy 120.047558 -433.187053) (xy 120.003801 -433.140456) (xy 119.966228 -433.088741)
			(xy 119.935434 -433.032726) (xy 119.911902 -432.973293) (xy 119.896005 -432.911379) (xy 119.887994 -432.847961)
			(xy 119.526056 -432.847961) (xy 119.518045 -432.911379) (xy 119.502148 -432.973293) (xy 119.478616 -433.032726)
			(xy 119.447822 -433.088741) (xy 119.410249 -433.140456) (xy 119.366492 -433.187053) (xy 119.317239 -433.227798)
			(xy 119.263268 -433.262049) (xy 119.205429 -433.289266) (xy 119.144636 -433.309019) (xy 119.081846 -433.320997)
			(xy 119.01805 -433.325011) (xy 118.954254 -433.320997) (xy 118.891464 -433.309019) (xy 118.830671 -433.289266)
			(xy 118.772832 -433.262049) (xy 118.718861 -433.227798) (xy 118.669608 -433.187053) (xy 118.625851 -433.140456)
			(xy 118.588278 -433.088741) (xy 118.557484 -433.032726) (xy 118.533952 -432.973293) (xy 118.518055 -432.911379)
			(xy 118.510044 -432.847961) (xy 115.69827 -432.847961) (xy 115.69827 -433.959) (xy 118.616982 -433.959)
			(xy 118.621053 -433.903378) (xy 118.633179 -433.848941) (xy 118.653102 -433.79685) (xy 118.680398 -433.748215)
			(xy 118.714484 -433.704072) (xy 118.754633 -433.665363) (xy 118.799991 -433.632912) (xy 118.849591 -433.607411)
			(xy 118.902375 -433.589404) (xy 118.957218 -433.579274) (xy 119.012952 -433.577237) (xy 119.068389 -433.583337)
			(xy 119.122346 -433.597443) (xy 119.173675 -433.619255) (xy 119.221281 -433.648309) (xy 119.264149 -433.683984)
			(xy 119.301366 -433.725521) (xy 119.332139 -433.772034) (xy 119.355811 -433.822531) (xy 119.371879 -433.875938)
			(xy 119.379999 -433.931114) (xy 119.380508 -433.959) (xy 119.379999 -433.986886) (xy 119.371879 -434.042062)
			(xy 119.355811 -434.095469) (xy 119.332139 -434.145966) (xy 119.301366 -434.192479) (xy 119.264149 -434.234016)
			(xy 119.221281 -434.269691) (xy 119.173675 -434.298745) (xy 119.122346 -434.320557) (xy 119.068389 -434.334663)
			(xy 119.012952 -434.340763) (xy 118.957218 -434.338726) (xy 118.902375 -434.328596) (xy 118.849591 -434.310589)
			(xy 118.799991 -434.285088) (xy 118.754633 -434.252637) (xy 118.714484 -434.213928) (xy 118.680398 -434.169785)
			(xy 118.653102 -434.12115) (xy 118.633179 -434.069059) (xy 118.621053 -434.014622) (xy 118.616982 -433.959)
			(xy 115.69827 -433.959) (xy 115.69827 -435.483) (xy 121.156982 -435.483) (xy 121.161053 -435.427378)
			(xy 121.173179 -435.372941) (xy 121.193102 -435.32085) (xy 121.220398 -435.272215) (xy 121.254484 -435.228072)
			(xy 121.294633 -435.189363) (xy 121.339991 -435.156912) (xy 121.389591 -435.131411) (xy 121.442375 -435.113404)
			(xy 121.497218 -435.103274) (xy 121.552952 -435.101237) (xy 121.608389 -435.107337) (xy 121.662346 -435.121443)
			(xy 121.713675 -435.143255) (xy 121.761281 -435.172309) (xy 121.804149 -435.207984) (xy 121.841366 -435.249521)
			(xy 121.872139 -435.296034) (xy 121.895811 -435.346531) (xy 121.911879 -435.399938) (xy 121.919999 -435.455114)
			(xy 121.920508 -435.483) (xy 121.919999 -435.510886) (xy 121.911879 -435.566062) (xy 121.895811 -435.619469)
			(xy 121.872139 -435.669966) (xy 121.841366 -435.716479) (xy 121.804149 -435.758016) (xy 121.761281 -435.793691)
			(xy 121.713675 -435.822745) (xy 121.662346 -435.844557) (xy 121.608389 -435.858663) (xy 121.552952 -435.864763)
			(xy 121.497218 -435.862726) (xy 121.442375 -435.852596) (xy 121.389591 -435.834589) (xy 121.339991 -435.809088)
			(xy 121.294633 -435.776637) (xy 121.254484 -435.737928) (xy 121.220398 -435.693785) (xy 121.193102 -435.64515)
			(xy 121.173179 -435.593059) (xy 121.161053 -435.538622) (xy 121.156982 -435.483) (xy 115.69827 -435.483)
			(xy 115.69827 -438.128447) (xy 118.34271 -438.128447) (xy 118.34271 -438.073953) (xy 118.350465 -438.020013)
			(xy 118.365817 -437.967725) (xy 118.388454 -437.918155) (xy 118.417914 -437.87231) (xy 118.453599 -437.831124)
			(xy 118.494781 -437.795436) (xy 118.540623 -437.765971) (xy 118.590192 -437.74333) (xy 118.642478 -437.727973)
			(xy 118.696417 -437.720213) (xy 118.723664 -437.719724) (xy 118.751821 -437.720264) (xy 118.80752 -437.728557)
			(xy 118.861393 -437.744954) (xy 118.912269 -437.769096) (xy 118.95904 -437.80046) (xy 118.980204 -437.819038)
			(xy 118.987316 -437.825388) (xy 119.005096 -437.832246) (xy 119.092218 -437.832246) (xy 119.109998 -437.825388)
			(xy 119.11711 -437.819038) (xy 119.138299 -437.80049) (xy 119.18507 -437.769133) (xy 119.235939 -437.744987)
			(xy 119.289804 -437.728575) (xy 119.345496 -437.720252) (xy 119.37365 -437.719724) (xy 119.400907 -437.72012)
			(xy 119.454868 -437.727871) (xy 119.507177 -437.743224) (xy 119.556767 -437.765866) (xy 119.602631 -437.795335)
			(xy 119.643833 -437.831032) (xy 119.679535 -437.872229) (xy 119.70901 -437.918089) (xy 119.731658 -437.967676)
			(xy 119.747018 -438.019983) (xy 119.754777 -438.073943) (xy 119.754777 -438.128457) (xy 119.747018 -438.182417)
			(xy 119.731658 -438.234724) (xy 119.70901 -438.284311) (xy 119.679535 -438.330171) (xy 119.643833 -438.371368)
			(xy 119.602631 -438.407065) (xy 119.556767 -438.436534) (xy 119.507177 -438.459176) (xy 119.454868 -438.474529)
			(xy 119.400908 -438.48228) (xy 119.37365 -438.48274) (xy 119.345491 -438.48226) (xy 119.289789 -438.473954)
			(xy 119.235914 -438.457544) (xy 119.185039 -438.433388) (xy 119.138272 -438.40201) (xy 119.11711 -438.383426)
			(xy 119.109998 -438.377076) (xy 119.092218 -438.370218) (xy 119.005096 -438.370218) (xy 118.987316 -438.377076)
			(xy 118.980204 -438.383426) (xy 118.959044 -438.402008) (xy 118.912266 -438.433361) (xy 118.861389 -438.457502)
			(xy 118.807517 -438.473906) (xy 118.75182 -438.482217) (xy 118.723664 -438.48274) (xy 118.696417 -438.482187)
			(xy 118.642478 -438.474427) (xy 118.590192 -438.45907) (xy 118.540623 -438.436429) (xy 118.494781 -438.406964)
			(xy 118.453599 -438.371276) (xy 118.417914 -438.33009) (xy 118.388454 -438.284245) (xy 118.365817 -438.234675)
			(xy 118.350465 -438.182387) (xy 118.34271 -438.128447) (xy 115.69827 -438.128447) (xy 115.69827 -439.209434)
			(xy 115.698699 -439.219502) (xy 115.706418 -439.2381) (xy 115.713256 -439.245502) (xy 116.046611 -439.578857)
			(xy 117.661327 -439.578857) (xy 117.661327 -439.524343) (xy 117.669086 -439.470385) (xy 117.684444 -439.418081)
			(xy 117.707091 -439.368495) (xy 117.736565 -439.322636) (xy 117.772265 -439.28144) (xy 117.813465 -439.245743)
			(xy 117.859326 -439.216274) (xy 117.908915 -439.193632) (xy 117.961221 -439.178278) (xy 118.015179 -439.170524)
			(xy 118.042436 -439.170064) (xy 118.070661 -439.170618) (xy 118.126495 -439.178935) (xy 118.180496 -439.195384)
			(xy 118.231487 -439.219604) (xy 118.278355 -439.251068) (xy 118.320079 -439.289091) (xy 118.35575 -439.332842)
			(xy 118.38459 -439.38137) (xy 118.39575 -439.4073) (xy 118.401489 -439.420274) (xy 118.419011 -439.442576)
			(xy 118.441996 -439.459192) (xy 118.468666 -439.468839) (xy 118.496962 -439.470772) (xy 118.524696 -439.464841)
			(xy 118.549727 -439.451505) (xy 118.570119 -439.431794) (xy 118.577614 -439.419746) (xy 118.594732 -439.391182)
			(xy 118.635281 -439.338359) (xy 118.682376 -439.291278) (xy 118.735212 -439.250745) (xy 118.792885 -439.217453)
			(xy 118.854409 -439.191971) (xy 118.918732 -439.174735) (xy 118.984754 -439.166039) (xy 119.01805 -439.165492)
			(xy 119.050014 -439.16597) (xy 119.11344 -439.173977) (xy 119.175361 -439.18987) (xy 119.234802 -439.213399)
			(xy 119.290826 -439.244193) (xy 119.342547 -439.281767) (xy 119.389152 -439.325526) (xy 119.429903 -439.374783)
			(xy 119.46416 -439.428758) (xy 119.491381 -439.486602) (xy 119.511137 -439.547401) (xy 119.523117 -439.610197)
			(xy 119.527132 -439.674) (xy 119.523117 -439.737803) (xy 119.511137 -439.800599) (xy 119.491381 -439.861398)
			(xy 119.46416 -439.919242) (xy 119.429903 -439.973217) (xy 119.389152 -440.022474) (xy 119.342547 -440.066233)
			(xy 119.290826 -440.103807) (xy 119.234802 -440.134601) (xy 119.175361 -440.15813) (xy 119.11344 -440.174023)
			(xy 119.050014 -440.18203) (xy 119.01805 -440.182508) (xy 118.985074 -440.181988) (xy 118.919677 -440.173444)
			(xy 118.855933 -440.156519) (xy 118.794912 -440.131496) (xy 118.737637 -440.098795) (xy 118.68507 -440.058966)
			(xy 118.638092 -440.012675) (xy 118.597491 -439.960701) (xy 118.563949 -439.903915) (xy 118.538028 -439.84327)
			(xy 118.528592 -439.811668) (xy 118.524249 -439.798136) (xy 118.50937 -439.773944) (xy 118.488401 -439.754787)
			(xy 118.462966 -439.742149) (xy 118.435033 -439.737007) (xy 118.406765 -439.739761) (xy 118.380349 -439.750196)
			(xy 118.357831 -439.767506) (xy 118.349014 -439.778648) (xy 118.330883 -439.802162) (xy 118.288577 -439.84382)
			(xy 118.240328 -439.878423) (xy 118.187302 -439.905134) (xy 118.130779 -439.92331) (xy 118.072123 -439.932512)
			(xy 118.042436 -439.93308) (xy 118.015179 -439.932676) (xy 117.961221 -439.924922) (xy 117.908915 -439.909568)
			(xy 117.859326 -439.886926) (xy 117.813465 -439.857457) (xy 117.772265 -439.82176) (xy 117.736565 -439.780564)
			(xy 117.707091 -439.734705) (xy 117.684444 -439.685119) (xy 117.669086 -439.632815) (xy 117.661327 -439.578857)
			(xy 116.046611 -439.578857) (xy 117.16512 -440.697366) (xy 117.171618 -440.703285) (xy 117.187535 -440.710714)
			(xy 117.205024 -440.712351) (xy 117.213634 -440.710574) (xy 117.226588 -440.707272) (xy 117.245638 -440.688984)
			(xy 117.251734 -440.668664) (xy 117.2541 -440.659538) (xy 117.252654 -440.640754) (xy 117.24894 -440.632088)
			(xy 117.239542 -440.61253) (xy 117.233192 -440.604402) (xy 117.228874 -440.600846) (xy 117.208015 -440.582615)
			(xy 117.171266 -440.541162) (xy 117.140895 -440.494831) (xy 117.11754 -440.444597) (xy 117.101692 -440.391515)
			(xy 117.093684 -440.336699) (xy 117.093238 -440.309) (xy 117.093724 -440.281731) (xy 117.101486 -440.227747)
			(xy 117.116851 -440.175417) (xy 117.139508 -440.125807) (xy 117.168994 -440.079926) (xy 117.204709 -440.038709)
			(xy 117.245926 -440.002994) (xy 117.291807 -439.973508) (xy 117.341417 -439.950851) (xy 117.393747 -439.935486)
			(xy 117.447731 -439.927724) (xy 117.502269 -439.927724) (xy 117.556253 -439.935486) (xy 117.608583 -439.950851)
			(xy 117.658193 -439.973508) (xy 117.704074 -440.002994) (xy 117.745291 -440.038709) (xy 117.781006 -440.079926)
			(xy 117.810492 -440.125807) (xy 117.833149 -440.175417) (xy 117.848514 -440.227747) (xy 117.856276 -440.281731)
			(xy 117.856762 -440.309) (xy 117.856301 -440.335594) (xy 117.848914 -440.388267) (xy 117.834283 -440.439403)
			(xy 117.812691 -440.488012) (xy 117.784558 -440.53315) (xy 117.767862 -440.553856) (xy 117.759473 -440.564601)
			(xy 117.748187 -440.589404) (xy 117.743865 -440.616309) (xy 117.746816 -440.643398) (xy 117.756829 -440.668742)
			(xy 117.773191 -440.690533) (xy 117.794735 -440.707218) (xy 117.819926 -440.717608) (xy 117.833394 -440.719718)
			(xy 117.839744 -440.719972)
		)
		(stroke
			(width 0)
			(type solid)
		)
		(fill yes)
		(layer "In15.Cu")
		(net "P3V3_AUX")
	)
	(gr_poly
		(pts
			(xy 301.969424 -409.497784) (xy 301.979492 -409.497356) (xy 301.998089 -409.489634) (xy 302.005492 -409.482798)
			(xy 302.253396 -409.234894) (xy 302.260242 -409.227495) (xy 302.267975 -409.208897) (xy 302.268382 -409.198826)
			(xy 302.268382 -400.978878) (xy 302.267914 -400.969246) (xy 302.26073 -400.951366) (xy 302.254412 -400.94408)
			(xy 302.237525 -400.925539) (xy 302.20897 -400.884313) (xy 302.186961 -400.839251) (xy 302.172 -400.791386)
			(xy 302.16443 -400.741811) (xy 302.164425 -400.691662) (xy 302.171984 -400.642085) (xy 302.186934 -400.594216)
			(xy 302.208934 -400.54915) (xy 302.237479 -400.507918) (xy 302.254412 -400.48942) (xy 302.26127 -400.482308)
			(xy 302.268382 -400.464274) (xy 302.268382 -400.410426) (xy 302.26127 -400.392392) (xy 302.254412 -400.38528)
			(xy 302.237527 -400.36674) (xy 302.208978 -400.325516) (xy 302.186976 -400.280457) (xy 302.172024 -400.232594)
			(xy 302.164465 -400.183022) (xy 302.163988 -400.15795) (xy 302.164467 -400.131958) (xy 302.172592 -400.080613)
			(xy 302.18865 -400.031172) (xy 302.212245 -399.984851) (xy 302.242796 -399.942793) (xy 302.279552 -399.906032)
			(xy 302.321605 -399.875473) (xy 302.367922 -399.851871) (xy 302.417361 -399.835805) (xy 302.468704 -399.827672)
			(xy 302.494696 -399.827242) (xy 302.52161 -399.827771) (xy 302.574727 -399.836491) (xy 302.625729 -399.853703)
			(xy 302.673268 -399.878951) (xy 302.716089 -399.911567) (xy 302.753059 -399.950691) (xy 302.783202 -399.995288)
			(xy 302.794924 -400.01952) (xy 302.801274 -400.032982) (xy 302.826166 -400.048984) (xy 303.532032 -400.048984)
			(xy 303.54385 -400.048426) (xy 303.565033 -400.037954) (xy 303.572672 -400.028918) (xy 303.588542 -400.008744)
			(xy 303.625863 -399.973509) (xy 303.668554 -399.945018) (xy 303.715412 -399.924072) (xy 303.765114 -399.911264)
			(xy 303.816258 -399.906954) (xy 303.867402 -399.911264) (xy 303.917104 -399.924072) (xy 303.963962 -399.945018)
			(xy 304.006653 -399.973509) (xy 304.043974 -400.008744) (xy 304.059844 -400.028918) (xy 304.067486 -400.037947)
			(xy 304.088669 -400.048413) (xy 304.100484 -400.048984) (xy 304.732182 -400.048984) (xy 304.744006 -400.048436)
			(xy 304.765206 -400.037977) (xy 304.772822 -400.028918) (xy 304.788692 -400.008744) (xy 304.826013 -399.973509)
			(xy 304.868704 -399.945018) (xy 304.915562 -399.924072) (xy 304.965264 -399.911264) (xy 305.016408 -399.906954)
			(xy 305.067552 -399.911264) (xy 305.117254 -399.924072) (xy 305.164112 -399.945018) (xy 305.206803 -399.973509)
			(xy 305.244124 -400.008744) (xy 305.259994 -400.028918) (xy 305.267639 -400.037939) (xy 305.288823 -400.048384)
			(xy 305.300634 -400.048984) (xy 305.932078 -400.048984) (xy 305.943902 -400.048437) (xy 305.965103 -400.037979)
			(xy 305.972718 -400.028918) (xy 305.988588 -400.008744) (xy 306.025909 -399.973509) (xy 306.0686 -399.945018)
			(xy 306.115458 -399.924072) (xy 306.16516 -399.911264) (xy 306.216304 -399.906954) (xy 306.267448 -399.911264)
			(xy 306.31715 -399.924072) (xy 306.364008 -399.945018) (xy 306.406699 -399.973509) (xy 306.44402 -400.008744)
			(xy 306.45989 -400.028918) (xy 306.467535 -400.03794) (xy 306.488719 -400.048387) (xy 306.50053 -400.048984)
			(xy 307.131974 -400.048984) (xy 307.143798 -400.048438) (xy 307.165001 -400.037981) (xy 307.172614 -400.028918)
			(xy 307.188484 -400.008744) (xy 307.225805 -399.973509) (xy 307.268496 -399.945018) (xy 307.315354 -399.924072)
			(xy 307.365056 -399.911264) (xy 307.4162 -399.906954) (xy 307.467344 -399.911264) (xy 307.517046 -399.924072)
			(xy 307.563904 -399.945018) (xy 307.606595 -399.973509) (xy 307.643916 -400.008744) (xy 307.659786 -400.028918)
			(xy 307.667431 -400.03794) (xy 307.688614 -400.048389) (xy 307.700426 -400.048984) (xy 308.332124 -400.048984)
			(xy 308.343943 -400.048427) (xy 308.365129 -400.037958) (xy 308.372764 -400.028918) (xy 308.388634 -400.008744)
			(xy 308.425955 -399.973509) (xy 308.468646 -399.945018) (xy 308.515504 -399.924072) (xy 308.565206 -399.911264)
			(xy 308.61635 -399.906954) (xy 308.667494 -399.911264) (xy 308.717196 -399.924072) (xy 308.764054 -399.945018)
			(xy 308.806745 -399.973509) (xy 308.844066 -400.008744) (xy 308.859936 -400.028918) (xy 308.867578 -400.037949)
			(xy 308.888761 -400.048418) (xy 308.900576 -400.048984) (xy 309.53202 -400.048984) (xy 309.543839 -400.048428)
			(xy 309.565026 -400.03796) (xy 309.57266 -400.028918) (xy 309.58853 -400.008744) (xy 309.625851 -399.973509)
			(xy 309.668542 -399.945018) (xy 309.7154 -399.924072) (xy 309.765102 -399.911264) (xy 309.816246 -399.906954)
			(xy 309.86739 -399.911264) (xy 309.917092 -399.924072) (xy 309.96395 -399.945018) (xy 310.006641 -399.973509)
			(xy 310.043962 -400.008744) (xy 310.059832 -400.028918) (xy 310.067473 -400.037949) (xy 310.088656 -400.04842)
			(xy 310.100472 -400.048984) (xy 310.73217 -400.048984) (xy 310.743995 -400.048439) (xy 310.765199 -400.037983)
			(xy 310.77281 -400.028918) (xy 310.78868 -400.008744) (xy 310.826001 -399.973509) (xy 310.868692 -399.945018)
			(xy 310.91555 -399.924072) (xy 310.965252 -399.911264) (xy 311.016396 -399.906954) (xy 311.06754 -399.911264)
			(xy 311.117242 -399.924072) (xy 311.1641 -399.945018) (xy 311.206791 -399.973509) (xy 311.244112 -400.008744)
			(xy 311.259982 -400.028918) (xy 311.267627 -400.037941) (xy 311.28881 -400.048391) (xy 311.300622 -400.048984)
			(xy 311.932066 -400.048984) (xy 311.943891 -400.04844) (xy 311.965097 -400.037984) (xy 311.972706 -400.028918)
			(xy 311.988576 -400.008744) (xy 312.025897 -399.973509) (xy 312.068588 -399.945018) (xy 312.115446 -399.924072)
			(xy 312.165148 -399.911264) (xy 312.216292 -399.906954) (xy 312.267436 -399.911264) (xy 312.317138 -399.924072)
			(xy 312.363996 -399.945018) (xy 312.406687 -399.973509) (xy 312.444008 -400.008744) (xy 312.459878 -400.028918)
			(xy 312.467522 -400.037942) (xy 312.488706 -400.048394) (xy 312.500518 -400.048984) (xy 313.131962 -400.048984)
			(xy 313.143788 -400.04844) (xy 313.164995 -400.037986) (xy 313.172602 -400.028918) (xy 313.188472 -400.008744)
			(xy 313.225793 -399.973509) (xy 313.268484 -399.945018) (xy 313.315342 -399.924072) (xy 313.365044 -399.911264)
			(xy 313.416188 -399.906954) (xy 313.467332 -399.911264) (xy 313.517034 -399.924072) (xy 313.563892 -399.945018)
			(xy 313.606583 -399.973509) (xy 313.643904 -400.008744) (xy 313.659774 -400.028918) (xy 313.667418 -400.037943)
			(xy 313.688601 -400.048396) (xy 313.700414 -400.048984) (xy 314.332112 -400.048984) (xy 314.343932 -400.04843)
			(xy 314.365122 -400.037963) (xy 314.372752 -400.028918) (xy 314.388622 -400.008744) (xy 314.425943 -399.973509)
			(xy 314.468634 -399.945018) (xy 314.515492 -399.924072) (xy 314.565194 -399.911264) (xy 314.616338 -399.906954)
			(xy 314.667482 -399.911264) (xy 314.717184 -399.924072) (xy 314.764042 -399.945018) (xy 314.806733 -399.973509)
			(xy 314.844054 -400.008744) (xy 314.859924 -400.028918) (xy 314.867565 -400.037951) (xy 314.888748 -400.048425)
			(xy 314.900564 -400.048984) (xy 315.532008 -400.048984) (xy 315.543829 -400.048431) (xy 315.56502 -400.037965)
			(xy 315.572648 -400.028918) (xy 315.588518 -400.008744) (xy 315.625839 -399.973509) (xy 315.66853 -399.945018)
			(xy 315.715388 -399.924072) (xy 315.76509 -399.911264) (xy 315.816234 -399.906954) (xy 315.867378 -399.911264)
			(xy 315.91708 -399.924072) (xy 315.963938 -399.945018) (xy 316.006629 -399.973509) (xy 316.04395 -400.008744)
			(xy 316.05982 -400.028918) (xy 316.06746 -400.037952) (xy 316.088643 -400.048427) (xy 316.10046 -400.048984)
			(xy 316.732158 -400.048984) (xy 316.743984 -400.048441) (xy 316.765192 -400.037988) (xy 316.772798 -400.028918)
			(xy 316.788668 -400.008744) (xy 316.825989 -399.973509) (xy 316.86868 -399.945018) (xy 316.915538 -399.924072)
			(xy 316.96524 -399.911264) (xy 317.016384 -399.906954) (xy 317.067528 -399.911264) (xy 317.11723 -399.924072)
			(xy 317.164088 -399.945018) (xy 317.206779 -399.973509) (xy 317.2441 -400.008744) (xy 317.25997 -400.028918)
			(xy 317.267614 -400.037943) (xy 317.288797 -400.048399) (xy 317.30061 -400.048984) (xy 317.932054 -400.048984)
			(xy 317.943881 -400.048442) (xy 317.96509 -400.03799) (xy 317.972694 -400.028918) (xy 317.988564 -400.008744)
			(xy 318.025885 -399.973509) (xy 318.068576 -399.945018) (xy 318.115434 -399.924072) (xy 318.165136 -399.911264)
			(xy 318.21628 -399.906954) (xy 318.267424 -399.911264) (xy 318.317126 -399.924072) (xy 318.363984 -399.945018)
			(xy 318.406675 -399.973509) (xy 318.443996 -400.008744) (xy 318.459866 -400.028918) (xy 318.467509 -400.037944)
			(xy 318.488693 -400.048401) (xy 318.500506 -400.048984) (xy 319.13195 -400.048984) (xy 319.143777 -400.048443)
			(xy 319.164988 -400.037992) (xy 319.17259 -400.028918) (xy 319.18846 -400.008744) (xy 319.225781 -399.973509)
			(xy 319.268472 -399.945018) (xy 319.31533 -399.924072) (xy 319.365032 -399.911264) (xy 319.416176 -399.906954)
			(xy 319.46732 -399.911264) (xy 319.517022 -399.924072) (xy 319.56388 -399.945018) (xy 319.606571 -399.973509)
			(xy 319.643892 -400.008744) (xy 319.659762 -400.028918) (xy 319.667405 -400.037944) (xy 319.688589 -400.048403)
			(xy 319.700402 -400.048984) (xy 320.3321 -400.048984) (xy 320.343922 -400.048432) (xy 320.365115 -400.037969)
			(xy 320.37274 -400.028918) (xy 320.38861 -400.008744) (xy 320.425931 -399.973509) (xy 320.468622 -399.945018)
			(xy 320.51548 -399.924072) (xy 320.565182 -399.911264) (xy 320.616326 -399.906954) (xy 320.66747 -399.911264)
			(xy 320.717172 -399.924072) (xy 320.76403 -399.945018) (xy 320.806721 -399.973509) (xy 320.844042 -400.008744)
			(xy 320.859912 -400.028918) (xy 320.867552 -400.037953) (xy 320.888735 -400.048432) (xy 320.900552 -400.048984)
			(xy 321.531996 -400.048984) (xy 321.543818 -400.048433) (xy 321.565013 -400.037971) (xy 321.572636 -400.028918)
			(xy 321.588506 -400.008744) (xy 321.625827 -399.973509) (xy 321.668518 -399.945018) (xy 321.715376 -399.924072)
			(xy 321.765078 -399.911264) (xy 321.816222 -399.906954) (xy 321.867366 -399.911264) (xy 321.917068 -399.924072)
			(xy 321.963926 -399.945018) (xy 322.006617 -399.973509) (xy 322.043938 -400.008744) (xy 322.059808 -400.028918)
			(xy 322.067448 -400.037953) (xy 322.088631 -400.048434) (xy 322.100448 -400.048984) (xy 323.319394 -400.048984)
			(xy 323.329464 -400.048562) (xy 323.348069 -400.040847) (xy 323.355462 -400.033998) (xy 323.466714 -399.922746)
			(xy 323.473561 -399.915349) (xy 323.481289 -399.896749) (xy 323.4817 -399.886678) (xy 323.4817 -399.471134)
			(xy 323.481169 -399.461144) (xy 323.473464 -399.442703) (xy 323.466714 -399.43532) (xy 323.448646 -399.416577)
			(xy 323.41804 -399.374468) (xy 323.394403 -399.328087) (xy 323.378317 -399.278578) (xy 323.370179 -399.227161)
			(xy 323.369686 -399.201132) (xy 323.370148 -399.1751) (xy 323.378264 -399.123673) (xy 323.394347 -399.074156)
			(xy 323.417998 -399.027775) (xy 323.448633 -398.985678) (xy 323.466714 -398.966944) (xy 323.473525 -398.9596)
			(xy 323.481251 -398.941136) (xy 323.4817 -398.93113) (xy 323.4817 -395.628622) (xy 323.481262 -395.618558)
			(xy 323.473528 -395.599974) (xy 323.466714 -395.592554) (xy 323.390006 -395.515846) (xy 323.38261 -395.508994)
			(xy 323.364012 -395.50125) (xy 323.353938 -395.50086) (xy 322.573142 -395.50086) (xy 322.563077 -395.500425)
			(xy 322.544492 -395.492691) (xy 322.537074 -395.485874) (xy 322.407026 -395.355826) (xy 322.399625 -395.348988)
			(xy 322.381026 -395.341277) (xy 322.370958 -395.34084) (xy 321.809872 -395.34084) (xy 321.799536 -395.34132)
			(xy 321.780524 -395.349441) (xy 321.773042 -395.356588) (xy 321.71513 -395.418056) (xy 321.708018 -395.43736)
			(xy 321.708526 -395.448028) (xy 321.709034 -395.466062) (xy 321.708601 -395.49018) (xy 321.701606 -395.537905)
			(xy 321.687758 -395.58411) (xy 321.667352 -395.627816) (xy 321.654424 -395.64818) (xy 321.648582 -395.65707)
			(xy 321.645026 -395.677136) (xy 321.666108 -395.769338) (xy 321.6783 -395.786102) (xy 321.68719 -395.791436)
			(xy 321.707994 -395.80429) (xy 321.745915 -395.835165) (xy 321.778869 -395.871295) (xy 321.806135 -395.911889)
			(xy 321.827117 -395.95606) (xy 321.841358 -396.002841) (xy 321.848544 -396.051211) (xy 321.848988 -396.075662)
			(xy 321.848551 -396.100033) (xy 321.841395 -396.148247) (xy 321.827248 -396.194891) (xy 321.806416 -396.238957)
			(xy 321.779347 -396.279492) (xy 321.746629 -396.315621) (xy 321.728084 -396.33144) (xy 321.719194 -396.338552)
			(xy 321.709796 -396.35811) (xy 321.707002 -396.457424) (xy 321.715638 -396.47749) (xy 321.72402 -396.48511)
			(xy 321.742441 -396.502598) (xy 321.773781 -396.542567) (xy 321.798076 -396.58717) (xy 321.814657 -396.635177)
			(xy 321.823066 -396.685267) (xy 321.823588 -396.710662) (xy 321.823516 -396.72002) (xy 321.82237 -396.738702)
			(xy 321.821302 -396.748) (xy 321.820286 -396.75689) (xy 321.824096 -396.773654) (xy 321.868038 -396.843504)
			(xy 321.881754 -396.853918) (xy 321.890136 -396.856712) (xy 321.91417 -396.865167) (xy 321.959349 -396.888715)
			(xy 322.000159 -396.919214) (xy 322.03554 -396.955871) (xy 322.064574 -396.997735) (xy 322.086508 -397.043719)
			(xy 322.094098 -397.06804) (xy 322.095622 -397.073882) (xy 322.415916 -397.627602) (xy 322.41998 -397.63192)
			(xy 322.436198 -397.649618) (xy 322.463632 -397.689006) (xy 322.484781 -397.732097) (xy 322.499155 -397.777896)
			(xy 322.506422 -397.825343) (xy 322.506848 -397.849344) (xy 322.506383 -397.874145) (xy 322.498613 -397.923136)
			(xy 322.483271 -397.970307) (xy 322.460736 -398.014495) (xy 322.431563 -398.054613) (xy 322.39647 -398.089669)
			(xy 322.356324 -398.118802) (xy 322.312113 -398.141293) (xy 322.264926 -398.156587) (xy 322.215928 -398.164308)
			(xy 322.191126 -398.164812) (xy 322.165731 -398.164306) (xy 322.115596 -398.156179) (xy 322.067408 -398.140131)
			(xy 322.022411 -398.116575) (xy 321.981766 -398.086118) (xy 321.946521 -398.049548) (xy 321.917585 -398.007807)
			(xy 321.895704 -397.961972) (xy 321.888104 -397.937736) (xy 321.88658 -397.931894) (xy 321.566286 -397.378174)
			(xy 321.562222 -397.373856) (xy 321.546032 -397.356147) (xy 321.518655 -397.316745) (xy 321.497564 -397.27365)
			(xy 321.483246 -397.227856) (xy 321.476032 -397.180422) (xy 321.475608 -397.156432) (xy 321.475694 -397.144384)
			(xy 321.477477 -397.120355) (xy 321.479164 -397.108426) (xy 321.480434 -397.099536) (xy 321.477386 -397.082518)
			(xy 321.435222 -397.011652) (xy 321.422014 -397.000476) (xy 321.413632 -396.997428) (xy 321.391894 -396.98902)
			(xy 321.351056 -396.966563) (xy 321.314103 -396.938162) (xy 321.281896 -396.904475) (xy 321.255182 -396.866285)
			(xy 321.234581 -396.824479) (xy 321.220573 -396.780028) (xy 321.213481 -396.733965) (xy 321.212972 -396.710662)
			(xy 321.213471 -396.685264) (xy 321.22187 -396.635166) (xy 321.238447 -396.587151) (xy 321.262744 -396.542542)
			(xy 321.29409 -396.502571) (xy 321.31254 -396.48511) (xy 321.320922 -396.47749) (xy 321.329558 -396.457424)
			(xy 321.326764 -396.35811) (xy 321.317366 -396.338552) (xy 321.308476 -396.33144) (xy 321.289916 -396.315637)
			(xy 321.257192 -396.279509) (xy 321.230121 -396.238972) (xy 321.209289 -396.194902) (xy 321.195148 -396.148253)
			(xy 321.188003 -396.100035) (xy 321.187572 -396.075662) (xy 321.188011 -396.051546) (xy 321.195016 -396.003825)
			(xy 321.208872 -395.957626) (xy 321.229286 -395.913928) (xy 321.242182 -395.893544) (xy 321.248024 -395.884654)
			(xy 321.25158 -395.864588) (xy 321.230498 -395.772386) (xy 321.218306 -395.755622) (xy 321.209416 -395.750288)
			(xy 321.188611 -395.737435) (xy 321.150687 -395.70656) (xy 321.11773 -395.670431) (xy 321.09046 -395.629838)
			(xy 321.069474 -395.585667) (xy 321.05523 -395.538885) (xy 321.04804 -395.490514) (xy 321.047618 -395.466062)
			(xy 321.048126 -395.448028) (xy 321.048634 -395.43736) (xy 321.041522 -395.418056) (xy 320.98361 -395.356588)
			(xy 320.976137 -395.349421) (xy 320.957123 -395.341275) (xy 320.94678 -395.34084) (xy 320.609976 -395.34084)
			(xy 320.599639 -395.34132) (xy 320.580626 -395.349439) (xy 320.573146 -395.356588) (xy 320.515234 -395.418056)
			(xy 320.508122 -395.43736) (xy 320.50863 -395.448028) (xy 320.509138 -395.466062) (xy 320.508705 -395.49018)
			(xy 320.50171 -395.537905) (xy 320.487863 -395.58411) (xy 320.467456 -395.627816) (xy 320.454528 -395.64818)
			(xy 320.448686 -395.65707) (xy 320.44513 -395.677136) (xy 320.466212 -395.769338) (xy 320.478404 -395.786102)
			(xy 320.487294 -395.791436) (xy 320.508098 -395.80429) (xy 320.546018 -395.835166) (xy 320.578972 -395.871296)
			(xy 320.606237 -395.91189) (xy 320.62722 -395.95606) (xy 320.64146 -396.002842) (xy 320.648646 -396.051211)
			(xy 320.649092 -396.075662) (xy 320.648655 -396.100033) (xy 320.641499 -396.148247) (xy 320.627353 -396.194891)
			(xy 320.60652 -396.238957) (xy 320.579452 -396.279493) (xy 320.546733 -396.315622) (xy 320.528188 -396.33144)
			(xy 320.519298 -396.338552) (xy 320.5099 -396.35811) (xy 320.507106 -396.457424) (xy 320.515742 -396.47749)
			(xy 320.524124 -396.48511) (xy 320.542545 -396.502599) (xy 320.573884 -396.542567) (xy 320.598179 -396.58717)
			(xy 320.614759 -396.635178) (xy 320.623169 -396.685267) (xy 320.623692 -396.710662) (xy 320.62362 -396.72002)
			(xy 320.622474 -396.738702) (xy 320.621406 -396.748) (xy 320.62039 -396.75689) (xy 320.6242 -396.773654)
			(xy 320.668142 -396.843504) (xy 320.681858 -396.853918) (xy 320.69024 -396.856712) (xy 320.714333 -396.865198)
			(xy 320.759615 -396.888832) (xy 320.800503 -396.919447) (xy 320.835929 -396.956244) (xy 320.86497 -396.998264)
			(xy 320.886869 -397.04441) (xy 320.894456 -397.068802) (xy 320.89598 -397.074644) (xy 321.215766 -397.627602)
			(xy 321.21983 -397.63192) (xy 321.236019 -397.649629) (xy 321.263395 -397.689032) (xy 321.284485 -397.732128)
			(xy 321.298804 -397.77792) (xy 321.30602 -397.825354) (xy 321.306444 -397.849344) (xy 321.305954 -397.874131)
			(xy 321.298193 -397.923093) (xy 321.282868 -397.970238) (xy 321.260357 -398.014405) (xy 321.231213 -398.054508)
			(xy 321.196156 -398.089558) (xy 321.156047 -398.118692) (xy 321.111875 -398.141194) (xy 321.064726 -398.156509)
			(xy 321.015763 -398.16426) (xy 320.990976 -398.164812) (xy 320.965583 -398.164302) (xy 320.915454 -398.156169)
			(xy 320.867272 -398.140115) (xy 320.822282 -398.116556) (xy 320.781643 -398.086099) (xy 320.746405 -398.049529)
			(xy 320.717474 -398.007789) (xy 320.695599 -397.961957) (xy 320.687954 -397.937736) (xy 320.68643 -397.931894)
			(xy 320.365882 -397.377412) (xy 320.361818 -397.373094) (xy 320.345741 -397.355415) (xy 320.318557 -397.316116)
			(xy 320.297602 -397.273171) (xy 320.283354 -397.22756) (xy 320.276138 -397.180324) (xy 320.275712 -397.156432)
			(xy 320.275798 -397.144384) (xy 320.277581 -397.120355) (xy 320.279268 -397.108426) (xy 320.280538 -397.099536)
			(xy 320.27749 -397.082518) (xy 320.235326 -397.011652) (xy 320.222118 -397.000476) (xy 320.213736 -396.997428)
			(xy 320.191998 -396.98902) (xy 320.151159 -396.966564) (xy 320.114206 -396.938162) (xy 320.081999 -396.904475)
			(xy 320.055284 -396.866285) (xy 320.034683 -396.824479) (xy 320.020674 -396.780029) (xy 320.013583 -396.733965)
			(xy 320.013076 -396.710662) (xy 320.013575 -396.685264) (xy 320.021975 -396.635167) (xy 320.038551 -396.587151)
			(xy 320.062848 -396.542542) (xy 320.094195 -396.502572) (xy 320.112644 -396.48511) (xy 320.121026 -396.47749)
			(xy 320.129662 -396.457424) (xy 320.126868 -396.35811) (xy 320.11747 -396.338552) (xy 320.10858 -396.33144)
			(xy 320.09002 -396.315637) (xy 320.057295 -396.27951) (xy 320.030224 -396.238972) (xy 320.009392 -396.194903)
			(xy 319.995251 -396.148254) (xy 319.988106 -396.100035) (xy 319.987676 -396.075662) (xy 319.988115 -396.051546)
			(xy 319.99512 -396.003825) (xy 320.008976 -395.957627) (xy 320.029391 -395.913928) (xy 320.042286 -395.893544)
			(xy 320.048128 -395.884654) (xy 320.051684 -395.864588) (xy 320.030602 -395.772386) (xy 320.01841 -395.755622)
			(xy 320.00952 -395.750288) (xy 319.988714 -395.737435) (xy 319.95079 -395.706561) (xy 319.917833 -395.670432)
			(xy 319.890563 -395.629838) (xy 319.869576 -395.585667) (xy 319.855332 -395.538885) (xy 319.848142 -395.490514)
			(xy 319.847722 -395.466062) (xy 319.84823 -395.448028) (xy 319.848738 -395.43736) (xy 319.841626 -395.418056)
			(xy 319.783714 -395.356588) (xy 319.776241 -395.349421) (xy 319.757228 -395.341273) (xy 319.746884 -395.34084)
			(xy 319.409826 -395.34084) (xy 319.399494 -395.341329) (xy 319.380495 -395.349461) (xy 319.372996 -395.356588)
			(xy 319.315084 -395.418056) (xy 319.307972 -395.43736) (xy 319.30848 -395.448028) (xy 319.308988 -395.466062)
			(xy 319.308555 -395.49018) (xy 319.301559 -395.537904) (xy 319.28771 -395.584108) (xy 319.267301 -395.627813)
			(xy 319.254378 -395.64818) (xy 319.248536 -395.65707) (xy 319.24498 -395.677136) (xy 319.266062 -395.769338)
			(xy 319.278254 -395.786102) (xy 319.287144 -395.791436) (xy 319.307945 -395.804292) (xy 319.34586 -395.835171)
			(xy 319.378809 -395.871302) (xy 319.40607 -395.911896) (xy 319.427049 -395.956065) (xy 319.441287 -396.002845)
			(xy 319.448472 -396.051213) (xy 319.448942 -396.075662) (xy 319.448504 -396.100033) (xy 319.441348 -396.148246)
			(xy 319.4272 -396.194888) (xy 319.406365 -396.238952) (xy 319.379295 -396.279485) (xy 319.346573 -396.31561)
			(xy 319.328038 -396.33144) (xy 319.319148 -396.338552) (xy 319.30975 -396.35811) (xy 319.306956 -396.457424)
			(xy 319.315592 -396.47749) (xy 319.323974 -396.48511) (xy 319.342397 -396.502597) (xy 319.373742 -396.542564)
			(xy 319.398041 -396.587167) (xy 319.414624 -396.635175) (xy 319.423035 -396.685266) (xy 319.423542 -396.710662)
			(xy 319.42347 -396.72002) (xy 319.422324 -396.738702) (xy 319.421256 -396.748) (xy 319.42024 -396.75689)
			(xy 319.42405 -396.773654) (xy 319.467992 -396.843504) (xy 319.481708 -396.853918) (xy 319.49009 -396.856712)
			(xy 319.514127 -396.865164) (xy 319.559311 -396.888708) (xy 319.600126 -396.919204) (xy 319.635512 -396.95586)
			(xy 319.664552 -396.997724) (xy 319.686489 -397.04371) (xy 319.694052 -397.06804) (xy 319.695576 -397.073882)
			(xy 320.01587 -397.627602) (xy 320.019934 -397.63192) (xy 320.036123 -397.649629) (xy 320.063498 -397.689032)
			(xy 320.084588 -397.732128) (xy 320.098907 -397.777921) (xy 320.106123 -397.825354) (xy 320.106548 -397.849344)
			(xy 320.106058 -397.874131) (xy 320.098297 -397.923093) (xy 320.082972 -397.970238) (xy 320.060461 -398.014406)
			(xy 320.031318 -398.054509) (xy 319.99626 -398.089559) (xy 319.956152 -398.118694) (xy 319.911979 -398.141196)
			(xy 319.864831 -398.156512) (xy 319.815867 -398.164263) (xy 319.79108 -398.164812) (xy 319.765687 -398.164303)
			(xy 319.715557 -398.15617) (xy 319.667375 -398.140117) (xy 319.622384 -398.116558) (xy 319.581745 -398.0861)
			(xy 319.546506 -398.04953) (xy 319.517575 -398.00779) (xy 319.495699 -397.961958) (xy 319.488058 -397.937736)
			(xy 319.486534 -397.931894) (xy 319.16624 -397.378174) (xy 319.162176 -397.373856) (xy 319.145962 -397.356157)
			(xy 319.118534 -397.316767) (xy 319.097392 -397.273675) (xy 319.083023 -397.227877) (xy 319.07576 -397.180431)
			(xy 319.075308 -397.156432) (xy 319.075466 -397.14438) (xy 319.077375 -397.120352) (xy 319.079118 -397.108426)
			(xy 319.080388 -397.099536) (xy 319.07734 -397.082518) (xy 319.035176 -397.011652) (xy 319.021968 -397.000476)
			(xy 319.013586 -396.997428) (xy 318.991845 -396.989023) (xy 318.951 -396.96657) (xy 318.914042 -396.938171)
			(xy 318.881829 -396.904485) (xy 318.855109 -396.866294) (xy 318.834505 -396.824487) (xy 318.820493 -396.780033)
			(xy 318.8134 -396.733967) (xy 318.812926 -396.710662) (xy 318.813426 -396.685264) (xy 318.821826 -396.635168)
			(xy 318.838405 -396.587155) (xy 318.862705 -396.542549) (xy 318.894054 -396.502582) (xy 318.912494 -396.48511)
			(xy 318.920876 -396.47749) (xy 318.929512 -396.457424) (xy 318.926718 -396.35811) (xy 318.91732 -396.338552)
			(xy 318.90843 -396.33144) (xy 318.889867 -396.315638) (xy 318.857138 -396.279513) (xy 318.830063 -396.238976)
			(xy 318.809228 -396.194906) (xy 318.795084 -396.148256) (xy 318.787938 -396.100036) (xy 318.787526 -396.075662)
			(xy 318.787965 -396.051546) (xy 318.794971 -396.003826) (xy 318.808829 -395.957628) (xy 318.829246 -395.913931)
			(xy 318.842136 -395.893544) (xy 318.847978 -395.884654) (xy 318.851534 -395.864588) (xy 318.830452 -395.772386)
			(xy 318.81826 -395.755622) (xy 318.80937 -395.750288) (xy 318.788567 -395.737433) (xy 318.750648 -395.706556)
			(xy 318.717696 -395.670426) (xy 318.69043 -395.629832) (xy 318.669447 -395.585662) (xy 318.655205 -395.538882)
			(xy 318.648016 -395.490512) (xy 318.647572 -395.466062) (xy 318.64808 -395.448028) (xy 318.648588 -395.43736)
			(xy 318.641476 -395.418056) (xy 318.583564 -395.356588) (xy 318.576088 -395.349429) (xy 318.557075 -395.3413)
			(xy 318.546734 -395.34084) (xy 318.20993 -395.34084) (xy 318.199597 -395.341328) (xy 318.180597 -395.34946)
			(xy 318.1731 -395.356588) (xy 318.115188 -395.418056) (xy 318.108076 -395.43736) (xy 318.108584 -395.448028)
			(xy 318.109092 -395.466062) (xy 318.108659 -395.49018) (xy 318.101663 -395.537904) (xy 318.087814 -395.584109)
			(xy 318.067405 -395.627813) (xy 318.054482 -395.64818) (xy 318.04864 -395.65707) (xy 318.045084 -395.677136)
			(xy 318.066166 -395.769338) (xy 318.078358 -395.786102) (xy 318.087248 -395.791436) (xy 318.108049 -395.804292)
			(xy 318.145964 -395.835171) (xy 318.178912 -395.871302) (xy 318.206173 -395.911896) (xy 318.227151 -395.956066)
			(xy 318.241389 -396.002845) (xy 318.248574 -396.051213) (xy 318.249046 -396.075662) (xy 318.248608 -396.100033)
			(xy 318.241452 -396.148246) (xy 318.227304 -396.194889) (xy 318.20647 -396.238953) (xy 318.179399 -396.279485)
			(xy 318.146678 -396.315611) (xy 318.128142 -396.33144) (xy 318.119252 -396.338552) (xy 318.109854 -396.35811)
			(xy 318.10706 -396.457424) (xy 318.115696 -396.47749) (xy 318.124078 -396.48511) (xy 318.142501 -396.502597)
			(xy 318.173845 -396.542564) (xy 318.198144 -396.587167) (xy 318.214727 -396.635175) (xy 318.223138 -396.685266)
			(xy 318.223646 -396.710662) (xy 318.223574 -396.72002) (xy 318.222428 -396.738702) (xy 318.22136 -396.748)
			(xy 318.220344 -396.75689) (xy 318.224154 -396.773654) (xy 318.268096 -396.843504) (xy 318.281812 -396.853918)
			(xy 318.290194 -396.856712) (xy 318.31429 -396.865195) (xy 318.359577 -396.888825) (xy 318.40047 -396.919438)
			(xy 318.435901 -396.956234) (xy 318.464947 -396.998253) (xy 318.48685 -397.044401) (xy 318.49441 -397.068802)
			(xy 318.495934 -397.074644) (xy 318.81572 -397.627602) (xy 318.819784 -397.63192) (xy 318.836002 -397.649618)
			(xy 318.863436 -397.689006) (xy 318.884584 -397.732098) (xy 318.898958 -397.777896) (xy 318.906225 -397.825343)
			(xy 318.906652 -397.849344) (xy 318.906187 -397.874146) (xy 318.898417 -397.923136) (xy 318.883075 -397.970308)
			(xy 318.86054 -398.014496) (xy 318.831367 -398.054614) (xy 318.796275 -398.089671) (xy 318.756128 -398.118804)
			(xy 318.711917 -398.141295) (xy 318.664731 -398.15659) (xy 318.615732 -398.164311) (xy 318.59093 -398.164812)
			(xy 318.565535 -398.164307) (xy 318.515399 -398.15618) (xy 318.467211 -398.140132) (xy 318.422213 -398.116576)
			(xy 318.381568 -398.08612) (xy 318.346322 -398.04955) (xy 318.317385 -398.007808) (xy 318.295505 -397.961973)
			(xy 318.287908 -397.937736) (xy 318.286384 -397.931894) (xy 317.965836 -397.377412) (xy 317.961772 -397.373094)
			(xy 317.945666 -397.355426) (xy 317.918424 -397.316142) (xy 317.897411 -397.273201) (xy 317.883108 -397.227585)
			(xy 317.87584 -397.180334) (xy 317.875412 -397.156432) (xy 317.87557 -397.14438) (xy 317.877479 -397.120352)
			(xy 317.879222 -397.108426) (xy 317.880492 -397.099536) (xy 317.877444 -397.082518) (xy 317.83528 -397.011652)
			(xy 317.822072 -397.000476) (xy 317.81369 -396.997428) (xy 317.791949 -396.989023) (xy 317.751104 -396.966571)
			(xy 317.714145 -396.938172) (xy 317.681931 -396.904486) (xy 317.655211 -396.866295) (xy 317.634606 -396.824487)
			(xy 317.620594 -396.780034) (xy 317.613501 -396.733967) (xy 317.61303 -396.710662) (xy 317.61353 -396.685264)
			(xy 317.62193 -396.635168) (xy 317.638509 -396.587155) (xy 317.662809 -396.542549) (xy 317.694159 -396.502582)
			(xy 317.712598 -396.48511) (xy 317.72098 -396.47749) (xy 317.729616 -396.457424) (xy 317.726822 -396.35811)
			(xy 317.717424 -396.338552) (xy 317.708534 -396.33144) (xy 317.689971 -396.315639) (xy 317.657241 -396.279513)
			(xy 317.630166 -396.238977) (xy 317.609331 -396.194906) (xy 317.595187 -396.148256) (xy 317.58804 -396.100036)
			(xy 317.58763 -396.075662) (xy 317.588069 -396.051546) (xy 317.595075 -396.003826) (xy 317.608933 -395.957628)
			(xy 317.629351 -395.913931) (xy 317.64224 -395.893544) (xy 317.648082 -395.884654) (xy 317.651638 -395.864588)
			(xy 317.630556 -395.772386) (xy 317.618364 -395.755622) (xy 317.609474 -395.750288) (xy 317.588671 -395.737433)
			(xy 317.550751 -395.706556) (xy 317.517799 -395.670426) (xy 317.490533 -395.629833) (xy 317.469549 -395.585663)
			(xy 317.455308 -395.538882) (xy 317.448118 -395.490513) (xy 317.447676 -395.466062) (xy 317.448444 -395.434132)
			(xy 317.460723 -395.371462) (xy 317.47206 -395.341602) (xy 317.477648 -395.327378) (xy 317.471806 -395.29766)
			(xy 317.435738 -395.261592) (xy 317.428336 -395.254756) (xy 317.409738 -395.247046) (xy 317.39967 -395.246606)
			(xy 315.9252 -395.246606) (xy 315.913784 -395.24707) (xy 315.893163 -395.256859) (xy 315.885576 -395.265402)
			(xy 315.82868 -395.336014) (xy 315.823346 -395.358366) (xy 315.825886 -395.369542) (xy 315.830684 -395.393382)
			(xy 315.835771 -395.441746) (xy 315.836046 -395.466062) (xy 315.835442 -395.499382) (xy 315.825772 -395.565316)
			(xy 315.806645 -395.629152) (xy 315.79312 -395.65961) (xy 315.78886 -395.67008) (xy 315.788936 -395.692654)
			(xy 315.798684 -395.713016) (xy 315.80709 -395.72057) (xy 315.829339 -395.739243) (xy 315.869406 -395.781297)
			(xy 315.903831 -395.828083) (xy 315.93206 -395.878848) (xy 315.95364 -395.932776) (xy 315.968224 -395.989001)
			(xy 315.975577 -396.046619) (xy 315.976 -396.075662) (xy 315.975549 -396.104666) (xy 315.968218 -396.162209)
			(xy 315.953682 -396.218366) (xy 315.932172 -396.272238) (xy 315.904033 -396.322964) (xy 315.869715 -396.369732)
			(xy 315.829768 -396.411793) (xy 315.807598 -396.4305) (xy 315.800486 -396.436088) (xy 315.791342 -396.451328)
			(xy 315.776102 -396.534132) (xy 315.778896 -396.551404) (xy 315.783468 -396.559532) (xy 315.796063 -396.58271)
			(xy 315.813951 -396.632331) (xy 315.823034 -396.684289) (xy 315.8236 -396.710662) (xy 316.41288 -396.710662)
			(xy 316.413402 -396.685407) (xy 316.421715 -396.635585) (xy 316.438116 -396.587811) (xy 316.462157 -396.543388)
			(xy 316.493181 -396.503528) (xy 316.530343 -396.469318) (xy 316.572629 -396.441692) (xy 316.618885 -396.421402)
			(xy 316.66785 -396.409002) (xy 316.718188 -396.404831) (xy 316.768526 -396.409002) (xy 316.817491 -396.421402)
			(xy 316.863747 -396.441692) (xy 316.906033 -396.469318) (xy 316.943195 -396.503528) (xy 316.974219 -396.543388)
			(xy 316.99826 -396.587811) (xy 317.014661 -396.635585) (xy 317.022974 -396.685407) (xy 317.023496 -396.710662)
			(xy 317.023428 -396.720021) (xy 317.022284 -396.738703) (xy 317.02121 -396.748) (xy 317.020194 -396.75689)
			(xy 317.024004 -396.773654) (xy 317.067946 -396.843504) (xy 317.081662 -396.853918) (xy 317.090044 -396.856712)
			(xy 317.114073 -396.865178) (xy 317.159245 -396.888731) (xy 317.20005 -396.919231) (xy 317.235429 -396.955886)
			(xy 317.264465 -396.997746) (xy 317.286403 -397.043724) (xy 317.294006 -397.06804) (xy 317.29553 -397.073882)
			(xy 317.615824 -397.627602) (xy 317.619888 -397.63192) (xy 317.636078 -397.64964) (xy 317.663504 -397.689028)
			(xy 317.68465 -397.732114) (xy 317.699027 -397.777906) (xy 317.706304 -397.825346) (xy 317.706756 -397.849344)
			(xy 317.706347 -397.87415) (xy 317.698575 -397.92315) (xy 317.683231 -397.97033) (xy 317.660692 -398.014527)
			(xy 317.631514 -398.054651) (xy 317.596415 -398.089715) (xy 317.556262 -398.118854) (xy 317.512043 -398.14135)
			(xy 317.464848 -398.156648) (xy 317.415841 -398.164371) (xy 317.391034 -398.164812) (xy 317.365641 -398.164282)
			(xy 317.315508 -398.156156) (xy 317.267324 -398.14011) (xy 317.222329 -398.116556) (xy 317.181686 -398.086103)
			(xy 317.146443 -398.049535) (xy 317.117508 -398.007797) (xy 317.095629 -397.961965) (xy 317.088012 -397.937736)
			(xy 317.086488 -397.931894) (xy 316.766194 -397.378174) (xy 316.76213 -397.373856) (xy 316.745967 -397.356126)
			(xy 316.7186 -397.316722) (xy 316.69751 -397.273631) (xy 316.683184 -397.227846) (xy 316.67595 -397.18042)
			(xy 316.675516 -397.156432) (xy 316.675597 -397.144384) (xy 316.677379 -397.120355) (xy 316.679072 -397.108426)
			(xy 316.680342 -397.099536) (xy 316.677294 -397.082518) (xy 316.63513 -397.011652) (xy 316.621922 -397.000476)
			(xy 316.61354 -396.997428) (xy 316.591786 -396.989049) (xy 316.550928 -396.966604) (xy 316.513959 -396.938208)
			(xy 316.481737 -396.90452) (xy 316.455013 -396.866324) (xy 316.434408 -396.824508) (xy 316.420401 -396.780046)
			(xy 316.413318 -396.73397) (xy 316.41288 -396.710662) (xy 315.8236 -396.710662) (xy 315.823528 -396.72002)
			(xy 315.822382 -396.738702) (xy 315.821314 -396.748) (xy 315.820298 -396.75689) (xy 315.824108 -396.773654)
			(xy 315.86805 -396.843504) (xy 315.881766 -396.853918) (xy 315.890148 -396.856712) (xy 315.914182 -396.865168)
			(xy 315.959359 -396.888717) (xy 316.000167 -396.919216) (xy 316.035547 -396.955874) (xy 316.06458 -396.997738)
			(xy 316.086513 -397.043721) (xy 316.09411 -397.06804) (xy 316.095634 -397.073882) (xy 316.415928 -397.627602)
			(xy 316.419992 -397.63192) (xy 316.436209 -397.649618) (xy 316.463643 -397.689007) (xy 316.48479 -397.732098)
			(xy 316.499164 -397.777896) (xy 316.506431 -397.825344) (xy 316.50686 -397.849344) (xy 316.506395 -397.874146)
			(xy 316.498625 -397.923137) (xy 316.483283 -397.970309) (xy 316.460748 -398.014498) (xy 316.431575 -398.054616)
			(xy 316.396483 -398.089674) (xy 316.356337 -398.118808) (xy 316.312126 -398.1413) (xy 316.264939 -398.156596)
			(xy 316.21594 -398.164319) (xy 316.191138 -398.164812) (xy 316.165742 -398.164307) (xy 316.115606 -398.156182)
			(xy 316.067416 -398.140134) (xy 316.022418 -398.116579) (xy 315.981771 -398.086123) (xy 315.946524 -398.049553)
			(xy 315.917587 -398.007811) (xy 315.895706 -397.961975) (xy 315.888116 -397.937736) (xy 315.886592 -397.931894)
			(xy 315.566298 -397.378174) (xy 315.562234 -397.373856) (xy 315.546043 -397.356148) (xy 315.518666 -397.316746)
			(xy 315.497574 -397.27365) (xy 315.483255 -397.227857) (xy 315.476041 -397.180422) (xy 315.47562 -397.156432)
			(xy 315.475706 -397.144384) (xy 315.477489 -397.120355) (xy 315.479176 -397.108426) (xy 315.480446 -397.099536)
			(xy 315.477398 -397.082518) (xy 315.435234 -397.011652) (xy 315.422026 -397.000476) (xy 315.413644 -396.997428)
			(xy 315.391906 -396.989021) (xy 315.351065 -396.966565) (xy 315.314112 -396.938164) (xy 315.281903 -396.904477)
			(xy 315.255188 -396.866287) (xy 315.234587 -396.824481) (xy 315.220577 -396.780029) (xy 315.213485 -396.733965)
			(xy 315.212984 -396.710662) (xy 315.213566 -396.684292) (xy 315.222669 -396.632341) (xy 315.240545 -396.582721)
			(xy 315.253116 -396.559532) (xy 315.257688 -396.551404) (xy 315.260482 -396.534132) (xy 315.245242 -396.451328)
			(xy 315.236098 -396.436088) (xy 315.228986 -396.4305) (xy 315.206795 -396.411816) (xy 315.166841 -396.369757)
			(xy 315.132521 -396.322988) (xy 315.104384 -396.272258) (xy 315.082882 -396.218379) (xy 315.068359 -396.162216)
			(xy 315.061048 -396.104668) (xy 315.060584 -396.075662) (xy 315.061187 -396.042342) (xy 315.070852 -395.976405)
			(xy 315.089972 -395.912566) (xy 315.10351 -395.882114) (xy 315.107779 -395.871644) (xy 315.107714 -395.849064)
			(xy 315.097959 -395.828698) (xy 315.08954 -395.821154) (xy 315.067298 -395.802478) (xy 315.027243 -395.760419)
			(xy 314.992831 -395.713631) (xy 314.964615 -395.662866) (xy 314.943047 -395.608938) (xy 314.928475 -395.552716)
			(xy 314.921132 -395.495102) (xy 314.92063 -395.466062) (xy 314.920927 -395.441747) (xy 314.926022 -395.393386)
			(xy 314.93079 -395.369542) (xy 314.93333 -395.358366) (xy 314.927996 -395.336014) (xy 314.8711 -395.265402)
			(xy 314.863431 -395.256966) (xy 314.842861 -395.247204) (xy 314.831476 -395.246606) (xy 314.593986 -395.246606)
			(xy 314.582226 -395.247194) (xy 314.561156 -395.257643) (xy 314.5536 -395.266672) (xy 314.497466 -395.341094)
			(xy 314.493148 -395.364208) (xy 314.49645 -395.375892) (xy 314.502291 -395.397975) (xy 314.508539 -395.443223)
			(xy 314.508896 -395.466062) (xy 314.508463 -395.49018) (xy 314.501467 -395.537905) (xy 314.487618 -395.584109)
			(xy 314.46721 -395.627813) (xy 314.454286 -395.64818) (xy 314.448444 -395.65707) (xy 314.444888 -395.677136)
			(xy 314.46597 -395.769338) (xy 314.478162 -395.786102) (xy 314.487052 -395.791436) (xy 314.507853 -395.804292)
			(xy 314.545767 -395.835171) (xy 314.578715 -395.871303) (xy 314.605975 -395.911897) (xy 314.626954 -395.956066)
			(xy 314.641191 -396.002845) (xy 314.648376 -396.051213) (xy 314.64885 -396.075662) (xy 314.648412 -396.100033)
			(xy 314.641257 -396.148246) (xy 314.627108 -396.194889) (xy 314.606274 -396.238953) (xy 314.579204 -396.279486)
			(xy 314.546483 -396.315612) (xy 314.527946 -396.33144) (xy 314.519056 -396.338552) (xy 314.509658 -396.35811)
			(xy 314.506864 -396.457424) (xy 314.5155 -396.47749) (xy 314.523882 -396.48511) (xy 314.542305 -396.502597)
			(xy 314.573648 -396.542565) (xy 314.597947 -396.587167) (xy 314.61453 -396.635176) (xy 314.62294 -396.685266)
			(xy 314.62345 -396.710662) (xy 314.623378 -396.72002) (xy 314.622232 -396.738702) (xy 314.621164 -396.748)
			(xy 314.620148 -396.75689) (xy 314.623958 -396.773654) (xy 314.6679 -396.843504) (xy 314.681616 -396.853918)
			(xy 314.689998 -396.856712) (xy 314.714034 -396.865165) (xy 314.759217 -396.888709) (xy 314.800031 -396.919206)
			(xy 314.835417 -396.955862) (xy 314.864456 -396.997726) (xy 314.886392 -397.043711) (xy 314.89396 -397.06804)
			(xy 314.895484 -397.073882) (xy 315.215778 -397.627602) (xy 315.219842 -397.63192) (xy 315.23603 -397.64963)
			(xy 315.263405 -397.689033) (xy 315.284495 -397.732128) (xy 315.298813 -397.777921) (xy 315.306029 -397.825354)
			(xy 315.306456 -397.849344) (xy 315.305966 -397.874131) (xy 315.298205 -397.923094) (xy 315.28288 -397.97024)
			(xy 315.260369 -398.014408) (xy 315.231226 -398.054511) (xy 315.196169 -398.089562) (xy 315.15606 -398.118698)
			(xy 315.111888 -398.141201) (xy 315.064739 -398.156518) (xy 315.015775 -398.164271) (xy 314.990988 -398.164812)
			(xy 314.965595 -398.164303) (xy 314.915464 -398.156171) (xy 314.867281 -398.140119) (xy 314.822289 -398.116561)
			(xy 314.781649 -398.086103) (xy 314.746408 -398.049533) (xy 314.717477 -398.007793) (xy 314.6956 -397.96196)
			(xy 314.687966 -397.937736) (xy 314.686442 -397.931894) (xy 314.366148 -397.378174) (xy 314.362084 -397.373856)
			(xy 314.345869 -397.356157) (xy 314.318441 -397.316767) (xy 314.297298 -397.273675) (xy 314.282929 -397.227878)
			(xy 314.275666 -397.180432) (xy 314.275216 -397.156432) (xy 314.275374 -397.14438) (xy 314.277283 -397.120352)
			(xy 314.279026 -397.108426) (xy 314.280296 -397.099536) (xy 314.277248 -397.082518) (xy 314.235084 -397.011652)
			(xy 314.221876 -397.000476) (xy 314.213494 -396.997428) (xy 314.191753 -396.989023) (xy 314.150907 -396.966571)
			(xy 314.113947 -396.938173) (xy 314.081734 -396.904486) (xy 314.055013 -396.866296) (xy 314.034408 -396.824488)
			(xy 314.020396 -396.780034) (xy 314.013303 -396.733967) (xy 314.012834 -396.710662) (xy 314.013334 -396.685264)
			(xy 314.021734 -396.635169) (xy 314.038313 -396.587155) (xy 314.062614 -396.54255) (xy 314.093964 -396.502583)
			(xy 314.112402 -396.48511) (xy 314.120784 -396.47749) (xy 314.12942 -396.457424) (xy 314.126626 -396.35811)
			(xy 314.117228 -396.338552) (xy 314.108338 -396.33144) (xy 314.089775 -396.315639) (xy 314.057045 -396.279513)
			(xy 314.029969 -396.238977) (xy 314.009133 -396.194907) (xy 313.994989 -396.148256) (xy 313.987843 -396.100036)
			(xy 313.987434 -396.075662) (xy 313.987873 -396.051546) (xy 313.994879 -396.003826) (xy 314.008738 -395.957629)
			(xy 314.029155 -395.913932) (xy 314.042044 -395.893544) (xy 314.047886 -395.884654) (xy 314.051442 -395.864588)
			(xy 314.03036 -395.772386) (xy 314.018168 -395.755622) (xy 314.009278 -395.750288) (xy 313.988475 -395.737434)
			(xy 313.950555 -395.706557) (xy 313.917602 -395.670427) (xy 313.890335 -395.629833) (xy 313.869352 -395.585663)
			(xy 313.85511 -395.538882) (xy 313.84792 -395.490513) (xy 313.84748 -395.466062) (xy 313.847851 -395.443224)
			(xy 313.854103 -395.397979) (xy 313.859926 -395.375892) (xy 313.863228 -395.364208) (xy 313.85891 -395.341094)
			(xy 313.802776 -395.266672) (xy 313.795184 -395.257682) (xy 313.77414 -395.247213) (xy 313.76239 -395.246606)
			(xy 313.39409 -395.246606) (xy 313.382329 -395.247193) (xy 313.361258 -395.257641) (xy 313.353704 -395.266672)
			(xy 313.29757 -395.341094) (xy 313.293252 -395.364208) (xy 313.296554 -395.375892) (xy 313.302395 -395.397975)
			(xy 313.308643 -395.443223) (xy 313.309 -395.466062) (xy 313.308567 -395.49018) (xy 313.301571 -395.537905)
			(xy 313.287723 -395.584109) (xy 313.267314 -395.627814) (xy 313.25439 -395.64818) (xy 313.248548 -395.65707)
			(xy 313.244992 -395.677136) (xy 313.266074 -395.769338) (xy 313.278266 -395.786102) (xy 313.287156 -395.791436)
			(xy 313.307957 -395.804292) (xy 313.34587 -395.835172) (xy 313.378818 -395.871303) (xy 313.406078 -395.911897)
			(xy 313.427056 -395.956066) (xy 313.441293 -396.002846) (xy 313.448478 -396.051213) (xy 313.448954 -396.075662)
			(xy 313.448516 -396.100033) (xy 313.441361 -396.148246) (xy 313.427213 -396.194889) (xy 313.406378 -396.238953)
			(xy 313.379308 -396.279487) (xy 313.346588 -396.315613) (xy 313.32805 -396.33144) (xy 313.31916 -396.338552)
			(xy 313.309762 -396.35811) (xy 313.306968 -396.457424) (xy 313.315604 -396.47749) (xy 313.323986 -396.48511)
			(xy 313.342409 -396.502597) (xy 313.373752 -396.542565) (xy 313.39805 -396.587167) (xy 313.414633 -396.635176)
			(xy 313.423043 -396.685266) (xy 313.423554 -396.710662) (xy 313.423482 -396.72002) (xy 313.422336 -396.738702)
			(xy 313.421268 -396.748) (xy 313.420252 -396.75689) (xy 313.424062 -396.773654) (xy 313.468004 -396.843504)
			(xy 313.48172 -396.853918) (xy 313.490102 -396.856712) (xy 313.514138 -396.865165) (xy 313.559321 -396.88871)
			(xy 313.600134 -396.919207) (xy 313.63552 -396.955863) (xy 313.664557 -396.997727) (xy 313.686494 -397.043712)
			(xy 313.694064 -397.06804) (xy 313.695588 -397.073882) (xy 314.015882 -397.627602) (xy 314.019946 -397.63192)
			(xy 314.036139 -397.649627) (xy 314.063521 -397.689028) (xy 314.084618 -397.732123) (xy 314.098941 -397.777917)
			(xy 314.106159 -397.825353) (xy 314.10656 -397.849344) (xy 314.10607 -397.874131) (xy 314.098309 -397.923094)
			(xy 314.082984 -397.97024) (xy 314.060473 -398.014409) (xy 314.03133 -398.054513) (xy 313.996273 -398.089564)
			(xy 313.956165 -398.1187) (xy 313.911992 -398.141204) (xy 313.864843 -398.156521) (xy 313.815879 -398.164274)
			(xy 313.791092 -398.164812) (xy 313.765699 -398.164304) (xy 313.715567 -398.156172) (xy 313.667384 -398.14012)
			(xy 313.622391 -398.116562) (xy 313.581751 -398.086105) (xy 313.54651 -398.049535) (xy 313.517578 -398.007795)
			(xy 313.495701 -397.961961) (xy 313.48807 -397.937736) (xy 313.486546 -397.931894) (xy 313.166252 -397.378174)
			(xy 313.162188 -397.373856) (xy 313.145973 -397.356157) (xy 313.118544 -397.316767) (xy 313.097401 -397.273676)
			(xy 313.083032 -397.227878) (xy 313.075769 -397.180432) (xy 313.07532 -397.156432) (xy 313.075478 -397.14438)
			(xy 313.077387 -397.120352) (xy 313.07913 -397.108426) (xy 313.0804 -397.099536) (xy 313.077352 -397.082518)
			(xy 313.035188 -397.011652) (xy 313.02198 -397.000476) (xy 313.013598 -396.997428) (xy 312.991857 -396.989023)
			(xy 312.95101 -396.966572) (xy 312.91405 -396.938173) (xy 312.881836 -396.904487) (xy 312.855115 -396.866297)
			(xy 312.83451 -396.824488) (xy 312.820497 -396.780034) (xy 312.813404 -396.733967) (xy 312.812938 -396.710662)
			(xy 312.813438 -396.685264) (xy 312.821839 -396.635169) (xy 312.838418 -396.587155) (xy 312.862718 -396.54255)
			(xy 312.894069 -396.502584) (xy 312.912506 -396.48511) (xy 312.920888 -396.47749) (xy 312.929524 -396.457424)
			(xy 312.92673 -396.35811) (xy 312.917332 -396.338552) (xy 312.908442 -396.33144) (xy 312.889879 -396.315639)
			(xy 312.857148 -396.279514) (xy 312.830072 -396.238977) (xy 312.809236 -396.194907) (xy 312.795092 -396.148257)
			(xy 312.787945 -396.100036) (xy 312.787538 -396.075662) (xy 312.787977 -396.051546) (xy 312.794983 -396.003826)
			(xy 312.808842 -395.957629) (xy 312.82926 -395.913932) (xy 312.842148 -395.893544) (xy 312.84799 -395.884654)
			(xy 312.851546 -395.864588) (xy 312.830464 -395.772386) (xy 312.818272 -395.755622) (xy 312.809382 -395.750288)
			(xy 312.788578 -395.737434) (xy 312.750658 -395.706557) (xy 312.717705 -395.670427) (xy 312.690438 -395.629833)
			(xy 312.669454 -395.585663) (xy 312.655212 -395.538882) (xy 312.648022 -395.490513) (xy 312.647584 -395.466062)
			(xy 312.648145 -395.438779) (xy 312.657106 -395.384955) (xy 312.674777 -395.33333) (xy 312.700681 -395.285305)
			(xy 312.734114 -395.242182) (xy 312.753756 -395.223238) (xy 312.76121 -395.215748) (xy 312.76976 -395.196453)
			(xy 312.770266 -395.1859) (xy 312.770266 -395.111224) (xy 312.769679 -395.10069) (xy 312.761147 -395.081417)
			(xy 312.753756 -395.073886) (xy 312.7341 -395.054954) (xy 312.700656 -395.011833) (xy 312.674746 -394.963807)
			(xy 312.657075 -394.912177) (xy 312.64812 -394.858347) (xy 312.647584 -394.831062) (xy 312.648346 -394.808964)
			(xy 312.649108 -394.797788) (xy 312.641488 -394.777468) (xy 312.587132 -394.723112) (xy 312.57113 -394.715492)
			(xy 312.561986 -394.71473) (xy 312.53769 -394.712146) (xy 312.490182 -394.700741) (xy 312.444866 -394.682477)
			(xy 312.402727 -394.65775) (xy 312.36468 -394.627097) (xy 312.331553 -394.591185) (xy 312.304064 -394.550793)
			(xy 312.282811 -394.506799) (xy 312.268256 -394.460159) (xy 312.264044 -394.436092) (xy 312.262774 -394.426694)
			(xy 312.227722 -394.366242) (xy 312.219594 -394.355574) (xy 312.023506 -394.159486) (xy 312.016661 -394.152087)
			(xy 312.008931 -394.133489) (xy 312.00852 -394.123418) (xy 312.00852 -394.000482) (xy 312.008323 -393.993815)
			(xy 312.004845 -393.980944) (xy 312.001662 -393.975082) (xy 311.990232 -393.95527) (xy 311.982866 -393.949428)
			(xy 311.964086 -393.933625) (xy 311.93095 -393.89742) (xy 311.903527 -393.856715) (xy 311.88242 -393.812406)
			(xy 311.868092 -393.765464) (xy 311.860858 -393.71692) (xy 311.860438 -393.69238) (xy 311.860909 -393.667226)
			(xy 311.868528 -393.617498) (xy 311.883588 -393.569496) (xy 311.905741 -393.524328) (xy 311.934477 -393.483034)
			(xy 311.969134 -393.446566) (xy 311.988708 -393.43076) (xy 311.99836 -393.423394) (xy 312.00852 -393.402566)
			(xy 312.00852 -393.369038) (xy 312.008107 -393.35901) (xy 312.000445 -393.340477) (xy 311.986272 -393.326288)
			(xy 311.967747 -393.318604) (xy 311.95772 -393.318238) (xy 311.95137 -393.318238) (xy 311.94502 -393.320016)
			(xy 311.924671 -393.324911) (xy 311.883143 -393.330132) (xy 311.862216 -393.33043) (xy 311.836224 -393.329948)
			(xy 311.78488 -393.321818) (xy 311.73544 -393.305756) (xy 311.689122 -393.282158) (xy 311.647065 -393.251604)
			(xy 311.610307 -393.214847) (xy 311.579751 -393.172792) (xy 311.55615 -393.126474) (xy 311.540086 -393.077035)
			(xy 311.531953 -393.025692) (xy 311.531953 -392.973708) (xy 311.540086 -392.922365) (xy 311.55615 -392.872926)
			(xy 311.579751 -392.826608) (xy 311.610307 -392.784553) (xy 311.647065 -392.747796) (xy 311.689122 -392.717242)
			(xy 311.73544 -392.693644) (xy 311.78488 -392.677582) (xy 311.836224 -392.669452) (xy 311.862216 -392.669014)
			(xy 311.896506 -392.670792) (xy 311.907174 -392.671808) (xy 311.927494 -392.665204) (xy 311.991756 -392.607546)
			(xy 311.999424 -392.600032) (xy 312.008126 -392.580427) (xy 312.00852 -392.5697) (xy 312.00852 -391.515346)
			(xy 312.008002 -391.50483) (xy 311.999618 -391.485541) (xy 311.992264 -391.478008) (xy 311.972534 -391.459084)
			(xy 311.93895 -391.41595) (xy 311.912921 -391.367879) (xy 311.895156 -391.31618) (xy 311.88614 -391.262263)
			(xy 311.885584 -391.23493) (xy 311.885584 -391.229342) (xy 311.885838 -391.218928) (xy 311.878218 -391.199878)
			(xy 311.784746 -391.106406) (xy 311.777345 -391.099567) (xy 311.758747 -391.091852) (xy 311.748678 -391.09142)
			(xy 311.446672 -391.09142) (xy 311.436016 -391.091885) (xy 311.416559 -391.100578) (xy 311.40908 -391.108184)
			(xy 311.351168 -391.171938) (xy 311.344564 -391.192004) (xy 311.34558 -391.202926) (xy 311.347104 -391.23493)
			(xy 311.346594 -391.260917) (xy 311.338464 -391.312252) (xy 311.322403 -391.361682) (xy 311.298807 -391.407992)
			(xy 311.268257 -391.45004) (xy 311.231506 -391.486791) (xy 311.189458 -391.517341) (xy 311.143148 -391.540937)
			(xy 311.093718 -391.556998) (xy 311.042383 -391.565128) (xy 310.990409 -391.565128) (xy 310.939074 -391.556998)
			(xy 310.889644 -391.540937) (xy 310.843334 -391.517341) (xy 310.801286 -391.486791) (xy 310.764535 -391.45004)
			(xy 310.733985 -391.407992) (xy 310.710389 -391.361682) (xy 310.694328 -391.312252) (xy 310.686198 -391.260917)
			(xy 310.685688 -391.23493) (xy 310.687212 -391.202926) (xy 310.688228 -391.192004) (xy 310.681624 -391.171938)
			(xy 310.623712 -391.108184) (xy 310.616165 -391.10068) (xy 310.596746 -391.092026) (xy 310.58612 -391.09142)
			(xy 310.246522 -391.09142) (xy 310.235862 -391.091876) (xy 310.21639 -391.100555) (xy 310.20893 -391.108184)
			(xy 310.151018 -391.171938) (xy 310.144414 -391.192004) (xy 310.14543 -391.202926) (xy 310.146954 -391.23493)
			(xy 310.146444 -391.260917) (xy 310.138314 -391.312252) (xy 310.122253 -391.361682) (xy 310.098657 -391.407992)
			(xy 310.068107 -391.45004) (xy 310.031356 -391.486791) (xy 309.989308 -391.517341) (xy 309.942998 -391.540937)
			(xy 309.893568 -391.556998) (xy 309.842233 -391.565128) (xy 309.790259 -391.565128) (xy 309.738924 -391.556998)
			(xy 309.689494 -391.540937) (xy 309.643184 -391.517341) (xy 309.601136 -391.486791) (xy 309.564385 -391.45004)
			(xy 309.533835 -391.407992) (xy 309.510239 -391.361682) (xy 309.494178 -391.312252) (xy 309.486048 -391.260917)
			(xy 309.485538 -391.23493) (xy 309.487062 -391.202926) (xy 309.488078 -391.192004) (xy 309.481474 -391.171938)
			(xy 309.423562 -391.108184) (xy 309.416012 -391.100688) (xy 309.396593 -391.092052) (xy 309.38597 -391.09142)
			(xy 309.046626 -391.09142) (xy 309.035965 -391.091875) (xy 309.016492 -391.100553) (xy 309.009034 -391.108184)
			(xy 308.951122 -391.171938) (xy 308.944518 -391.192004) (xy 308.945534 -391.202926) (xy 308.947058 -391.23493)
			(xy 308.946548 -391.260917) (xy 308.938418 -391.312252) (xy 308.922357 -391.361682) (xy 308.898761 -391.407992)
			(xy 308.868211 -391.45004) (xy 308.83146 -391.486791) (xy 308.789412 -391.517341) (xy 308.743102 -391.540937)
			(xy 308.693672 -391.556998) (xy 308.642337 -391.565128) (xy 308.590363 -391.565128) (xy 308.539028 -391.556998)
			(xy 308.489598 -391.540937) (xy 308.443288 -391.517341) (xy 308.40124 -391.486791) (xy 308.364489 -391.45004)
			(xy 308.333939 -391.407992) (xy 308.310343 -391.361682) (xy 308.294282 -391.312252) (xy 308.286152 -391.260917)
			(xy 308.285642 -391.23493) (xy 308.287166 -391.202926) (xy 308.288182 -391.192004) (xy 308.281578 -391.171938)
			(xy 308.223666 -391.108184) (xy 308.216116 -391.100687) (xy 308.196697 -391.09205) (xy 308.186074 -391.09142)
			(xy 307.846476 -391.09142) (xy 307.83582 -391.091885) (xy 307.816361 -391.100576) (xy 307.808884 -391.108184)
			(xy 307.750972 -391.171938) (xy 307.744368 -391.192004) (xy 307.745384 -391.202926) (xy 307.746908 -391.23493)
			(xy 307.746398 -391.260917) (xy 307.738268 -391.312252) (xy 307.722207 -391.361682) (xy 307.698611 -391.407992)
			(xy 307.668061 -391.45004) (xy 307.63131 -391.486791) (xy 307.589262 -391.517341) (xy 307.542952 -391.540937)
			(xy 307.493522 -391.556998) (xy 307.442187 -391.565128) (xy 307.390213 -391.565128) (xy 307.338878 -391.556998)
			(xy 307.289448 -391.540937) (xy 307.243138 -391.517341) (xy 307.20109 -391.486791) (xy 307.164339 -391.45004)
			(xy 307.133789 -391.407992) (xy 307.110193 -391.361682) (xy 307.094132 -391.312252) (xy 307.086002 -391.260917)
			(xy 307.085492 -391.23493) (xy 307.087016 -391.202926) (xy 307.088032 -391.192004) (xy 307.081428 -391.171938)
			(xy 307.023516 -391.108184) (xy 307.015969 -391.100679) (xy 306.996551 -391.092024) (xy 306.985924 -391.09142)
			(xy 306.64658 -391.09142) (xy 306.635923 -391.091884) (xy 306.616464 -391.100574) (xy 306.608988 -391.108184)
			(xy 306.551076 -391.171938) (xy 306.544472 -391.192004) (xy 306.545488 -391.202926) (xy 306.547012 -391.23493)
			(xy 306.546502 -391.260917) (xy 306.538372 -391.312252) (xy 306.522311 -391.361682) (xy 306.498715 -391.407992)
			(xy 306.468165 -391.45004) (xy 306.431414 -391.486791) (xy 306.389366 -391.517341) (xy 306.343056 -391.540937)
			(xy 306.293626 -391.556998) (xy 306.242291 -391.565128) (xy 306.190317 -391.565128) (xy 306.138982 -391.556998)
			(xy 306.089552 -391.540937) (xy 306.043242 -391.517341) (xy 306.001194 -391.486791) (xy 305.964443 -391.45004)
			(xy 305.933893 -391.407992) (xy 305.910297 -391.361682) (xy 305.894236 -391.312252) (xy 305.886106 -391.260917)
			(xy 305.885596 -391.23493) (xy 305.88712 -391.202926) (xy 305.888136 -391.192004) (xy 305.881532 -391.171938)
			(xy 305.82362 -391.108184) (xy 305.816073 -391.100678) (xy 305.796655 -391.092021) (xy 305.786028 -391.09142)
			(xy 305.446684 -391.09142) (xy 305.436027 -391.091883) (xy 305.416566 -391.100572) (xy 305.409092 -391.108184)
			(xy 305.35118 -391.171938) (xy 305.344576 -391.192004) (xy 305.345592 -391.202926) (xy 305.347116 -391.23493)
			(xy 305.346606 -391.260917) (xy 305.338476 -391.312252) (xy 305.322415 -391.361682) (xy 305.298819 -391.407992)
			(xy 305.268269 -391.45004) (xy 305.231518 -391.486791) (xy 305.18947 -391.517341) (xy 305.14316 -391.540937)
			(xy 305.09373 -391.556998) (xy 305.042395 -391.565128) (xy 304.990421 -391.565128) (xy 304.939086 -391.556998)
			(xy 304.889656 -391.540937) (xy 304.843346 -391.517341) (xy 304.801298 -391.486791) (xy 304.764547 -391.45004)
			(xy 304.733997 -391.407992) (xy 304.710401 -391.361682) (xy 304.69434 -391.312252) (xy 304.68621 -391.260917)
			(xy 304.6857 -391.23493) (xy 304.687224 -391.202926) (xy 304.68824 -391.192004) (xy 304.681636 -391.171938)
			(xy 304.623724 -391.108184) (xy 304.616178 -391.100678) (xy 304.596759 -391.092019) (xy 304.586132 -391.09142)
			(xy 304.246534 -391.09142) (xy 304.235872 -391.091873) (xy 304.216397 -391.10055) (xy 304.208942 -391.108184)
			(xy 304.15103 -391.171938) (xy 304.144426 -391.192004) (xy 304.145442 -391.202926) (xy 304.146966 -391.23493)
			(xy 304.146456 -391.260917) (xy 304.138326 -391.312252) (xy 304.122265 -391.361682) (xy 304.098669 -391.407992)
			(xy 304.068119 -391.45004) (xy 304.031368 -391.486791) (xy 303.98932 -391.517341) (xy 303.94301 -391.540937)
			(xy 303.89358 -391.556998) (xy 303.842245 -391.565128) (xy 303.790271 -391.565128) (xy 303.738936 -391.556998)
			(xy 303.689506 -391.540937) (xy 303.643196 -391.517341) (xy 303.601148 -391.486791) (xy 303.564397 -391.45004)
			(xy 303.533847 -391.407992) (xy 303.510251 -391.361682) (xy 303.49419 -391.312252) (xy 303.48606 -391.260917)
			(xy 303.48555 -391.23493) (xy 303.487074 -391.202926) (xy 303.48809 -391.192004) (xy 303.481486 -391.171938)
			(xy 303.423574 -391.108184) (xy 303.416025 -391.100686) (xy 303.396606 -391.092046) (xy 303.385982 -391.09142)
			(xy 302.889666 -391.09142) (xy 302.878159 -391.091904) (xy 302.8574 -391.101826) (xy 302.849788 -391.11047)
			(xy 302.792892 -391.182098) (xy 302.787812 -391.20445) (xy 302.790606 -391.21588) (xy 302.794533 -391.23417)
			(xy 302.798733 -391.271343) (xy 302.798988 -391.290048) (xy 302.798475 -391.316032) (xy 302.790338 -391.36736)
			(xy 302.774273 -391.416782) (xy 302.750674 -391.463084) (xy 302.720123 -391.505124) (xy 302.683372 -391.541867)
			(xy 302.641326 -391.57241) (xy 302.59502 -391.595999) (xy 302.545593 -391.612054) (xy 302.494264 -391.62018)
			(xy 302.46828 -391.620756) (xy 302.439683 -391.620157) (xy 302.383341 -391.610327) (xy 302.329531 -391.590948)
			(xy 302.279859 -391.562598) (xy 302.25746 -391.54481) (xy 302.250602 -391.539222) (xy 302.233838 -391.533126)
			(xy 302.151542 -391.533126) (xy 302.134778 -391.538968) (xy 302.12792 -391.544556) (xy 302.105565 -391.562207)
			(xy 302.056054 -391.590359) (xy 302.00245 -391.609607) (xy 301.946339 -391.619381) (xy 301.917862 -391.619994)
			(xy 301.894629 -391.619598) (xy 301.848621 -391.61309) (xy 301.803977 -391.600208) (xy 301.761575 -391.581205)
			(xy 301.722249 -391.556455) (xy 301.704248 -391.541762) (xy 301.697136 -391.535666) (xy 301.680626 -391.52957)
			(xy 301.596298 -391.52957) (xy 301.579788 -391.535666) (xy 301.572676 -391.541762) (xy 301.554686 -391.556471)
			(xy 301.515361 -391.581228) (xy 301.472956 -391.600234) (xy 301.428308 -391.613114) (xy 301.382297 -391.619616)
			(xy 301.359062 -391.619994) (xy 301.333077 -391.619482) (xy 301.281748 -391.611346) (xy 301.232324 -391.595282)
			(xy 301.18602 -391.571684) (xy 301.143979 -391.541133) (xy 301.107233 -391.504382) (xy 301.076689 -391.462335)
			(xy 301.053098 -391.416028) (xy 301.037042 -391.366601) (xy 301.028914 -391.315271) (xy 301.028354 -391.289286)
			(xy 301.028621 -391.270708) (xy 301.032824 -391.23379) (xy 301.036736 -391.215626) (xy 301.039276 -391.204196)
			(xy 301.034196 -391.181844) (xy 300.9773 -391.11047) (xy 300.96967 -391.101954) (xy 300.949092 -391.092058)
			(xy 300.937676 -391.09142) (xy 298.780962 -391.09142) (xy 298.770895 -391.091851) (xy 298.752303 -391.099577)
			(xy 298.744894 -391.106406) (xy 297.7261 -392.1252) (xy 299.683676 -392.1252) (xy 299.687747 -392.069578)
			(xy 299.699873 -392.015141) (xy 299.719796 -391.96305) (xy 299.747092 -391.914415) (xy 299.781178 -391.870272)
			(xy 299.821327 -391.831563) (xy 299.866685 -391.799112) (xy 299.916285 -391.773611) (xy 299.969069 -391.755604)
			(xy 300.023912 -391.745474) (xy 300.079646 -391.743437) (xy 300.135083 -391.749537) (xy 300.18904 -391.763643)
			(xy 300.240369 -391.785455) (xy 300.287975 -391.814509) (xy 300.330843 -391.850184) (xy 300.36806 -391.891721)
			(xy 300.398833 -391.938234) (xy 300.422505 -391.988731) (xy 300.438573 -392.042138) (xy 300.446693 -392.097314)
			(xy 300.447202 -392.1252) (xy 300.446693 -392.153086) (xy 300.438573 -392.208262) (xy 300.422505 -392.261669)
			(xy 300.398833 -392.312166) (xy 300.36806 -392.358679) (xy 300.330843 -392.400216) (xy 300.287975 -392.435891)
			(xy 300.240369 -392.464945) (xy 300.18904 -392.486757) (xy 300.135083 -392.500863) (xy 300.079646 -392.506963)
			(xy 300.023912 -392.504926) (xy 299.969069 -392.494796) (xy 299.916285 -392.476789) (xy 299.866685 -392.451288)
			(xy 299.821327 -392.418837) (xy 299.781178 -392.380128) (xy 299.747092 -392.335985) (xy 299.719796 -392.28735)
			(xy 299.699873 -392.235259) (xy 299.687747 -392.180822) (xy 299.683676 -392.1252) (xy 297.7261 -392.1252)
			(xy 297.657266 -392.194034) (xy 297.650418 -392.201431) (xy 297.642685 -392.22003) (xy 297.64228 -392.230102)
			(xy 297.64228 -393.04468) (xy 299.683676 -393.04468) (xy 299.687747 -392.989058) (xy 299.699873 -392.934621)
			(xy 299.719796 -392.88253) (xy 299.747092 -392.833895) (xy 299.781178 -392.789752) (xy 299.821327 -392.751043)
			(xy 299.866685 -392.718592) (xy 299.916285 -392.693091) (xy 299.969069 -392.675084) (xy 300.023912 -392.664954)
			(xy 300.079646 -392.662917) (xy 300.135083 -392.669017) (xy 300.18904 -392.683123) (xy 300.240369 -392.704935)
			(xy 300.287975 -392.733989) (xy 300.32567 -392.765359) (xy 301.070774 -392.765359) (xy 301.070774 -392.713385)
			(xy 301.078904 -392.66205) (xy 301.094965 -392.61262) (xy 301.118561 -392.56631) (xy 301.149111 -392.524262)
			(xy 301.185862 -392.487511) (xy 301.22791 -392.456961) (xy 301.27422 -392.433365) (xy 301.32365 -392.417304)
			(xy 301.374985 -392.409174) (xy 301.426959 -392.409174) (xy 301.478294 -392.417304) (xy 301.527724 -392.433365)
			(xy 301.574034 -392.456961) (xy 301.616082 -392.487511) (xy 301.652833 -392.524262) (xy 301.683383 -392.56631)
			(xy 301.706979 -392.61262) (xy 301.72304 -392.66205) (xy 301.73117 -392.713385) (xy 301.73168 -392.739372)
			(xy 301.73117 -392.765359) (xy 301.72304 -392.816694) (xy 301.706979 -392.866124) (xy 301.683383 -392.912434)
			(xy 301.652833 -392.954482) (xy 301.616082 -392.991233) (xy 301.574034 -393.021783) (xy 301.566329 -393.025709)
			(xy 303.131984 -393.025709) (xy 303.131984 -392.973735) (xy 303.140114 -392.9224) (xy 303.156175 -392.87297)
			(xy 303.179771 -392.82666) (xy 303.210321 -392.784612) (xy 303.247072 -392.747861) (xy 303.28912 -392.717311)
			(xy 303.33543 -392.693715) (xy 303.38486 -392.677654) (xy 303.436195 -392.669524) (xy 303.488169 -392.669524)
			(xy 303.539504 -392.677654) (xy 303.588934 -392.693715) (xy 303.635244 -392.717311) (xy 303.677292 -392.747861)
			(xy 303.714043 -392.784612) (xy 303.744593 -392.82666) (xy 303.768189 -392.87297) (xy 303.78425 -392.9224)
			(xy 303.79238 -392.973735) (xy 303.79289 -392.999722) (xy 303.79238 -393.025709) (xy 304.33188 -393.025709)
			(xy 304.33188 -392.973735) (xy 304.34001 -392.9224) (xy 304.356071 -392.87297) (xy 304.379667 -392.82666)
			(xy 304.410217 -392.784612) (xy 304.446968 -392.747861) (xy 304.489016 -392.717311) (xy 304.535326 -392.693715)
			(xy 304.584756 -392.677654) (xy 304.636091 -392.669524) (xy 304.688065 -392.669524) (xy 304.7394 -392.677654)
			(xy 304.78883 -392.693715) (xy 304.83514 -392.717311) (xy 304.877188 -392.747861) (xy 304.913939 -392.784612)
			(xy 304.944489 -392.82666) (xy 304.968085 -392.87297) (xy 304.984146 -392.9224) (xy 304.992276 -392.973735)
			(xy 304.992786 -392.999722) (xy 304.992276 -393.025709) (xy 305.53203 -393.025709) (xy 305.53203 -392.973735)
			(xy 305.54016 -392.9224) (xy 305.556221 -392.87297) (xy 305.579817 -392.82666) (xy 305.610367 -392.784612)
			(xy 305.647118 -392.747861) (xy 305.689166 -392.717311) (xy 305.735476 -392.693715) (xy 305.784906 -392.677654)
			(xy 305.836241 -392.669524) (xy 305.888215 -392.669524) (xy 305.93955 -392.677654) (xy 305.98898 -392.693715)
			(xy 306.03529 -392.717311) (xy 306.077338 -392.747861) (xy 306.114089 -392.784612) (xy 306.144639 -392.82666)
			(xy 306.168235 -392.87297) (xy 306.184296 -392.9224) (xy 306.192426 -392.973735) (xy 306.192936 -392.999722)
			(xy 306.192426 -393.025709) (xy 306.731926 -393.025709) (xy 306.731926 -392.973735) (xy 306.740056 -392.9224)
			(xy 306.756117 -392.87297) (xy 306.779713 -392.82666) (xy 306.810263 -392.784612) (xy 306.847014 -392.747861)
			(xy 306.889062 -392.717311) (xy 306.935372 -392.693715) (xy 306.984802 -392.677654) (xy 307.036137 -392.669524)
			(xy 307.088111 -392.669524) (xy 307.139446 -392.677654) (xy 307.188876 -392.693715) (xy 307.235186 -392.717311)
			(xy 307.277234 -392.747861) (xy 307.313985 -392.784612) (xy 307.344535 -392.82666) (xy 307.368131 -392.87297)
			(xy 307.384192 -392.9224) (xy 307.392322 -392.973735) (xy 307.392832 -392.999722) (xy 307.392322 -393.025709)
			(xy 307.932076 -393.025709) (xy 307.932076 -392.973735) (xy 307.940206 -392.9224) (xy 307.956267 -392.87297)
			(xy 307.979863 -392.82666) (xy 308.010413 -392.784612) (xy 308.047164 -392.747861) (xy 308.089212 -392.717311)
			(xy 308.135522 -392.693715) (xy 308.184952 -392.677654) (xy 308.236287 -392.669524) (xy 308.288261 -392.669524)
			(xy 308.339596 -392.677654) (xy 308.389026 -392.693715) (xy 308.435336 -392.717311) (xy 308.477384 -392.747861)
			(xy 308.514135 -392.784612) (xy 308.544685 -392.82666) (xy 308.568281 -392.87297) (xy 308.584342 -392.9224)
			(xy 308.592472 -392.973735) (xy 308.592982 -392.999722) (xy 308.592472 -393.025709) (xy 309.131972 -393.025709)
			(xy 309.131972 -392.973735) (xy 309.140102 -392.9224) (xy 309.156163 -392.87297) (xy 309.179759 -392.82666)
			(xy 309.210309 -392.784612) (xy 309.24706 -392.747861) (xy 309.289108 -392.717311) (xy 309.335418 -392.693715)
			(xy 309.384848 -392.677654) (xy 309.436183 -392.669524) (xy 309.488157 -392.669524) (xy 309.539492 -392.677654)
			(xy 309.588922 -392.693715) (xy 309.635232 -392.717311) (xy 309.67728 -392.747861) (xy 309.714031 -392.784612)
			(xy 309.744581 -392.82666) (xy 309.768177 -392.87297) (xy 309.784238 -392.9224) (xy 309.792368 -392.973735)
			(xy 309.792878 -392.999722) (xy 309.792368 -393.025709) (xy 310.331868 -393.025709) (xy 310.331868 -392.973735)
			(xy 310.339998 -392.9224) (xy 310.356059 -392.87297) (xy 310.379655 -392.82666) (xy 310.410205 -392.784612)
			(xy 310.446956 -392.747861) (xy 310.489004 -392.717311) (xy 310.535314 -392.693715) (xy 310.584744 -392.677654)
			(xy 310.636079 -392.669524) (xy 310.688053 -392.669524) (xy 310.739388 -392.677654) (xy 310.788818 -392.693715)
			(xy 310.835128 -392.717311) (xy 310.877176 -392.747861) (xy 310.913927 -392.784612) (xy 310.944477 -392.82666)
			(xy 310.968073 -392.87297) (xy 310.984134 -392.9224) (xy 310.992264 -392.973735) (xy 310.992774 -392.999722)
			(xy 310.992264 -393.025709) (xy 310.984134 -393.077044) (xy 310.968073 -393.126474) (xy 310.944477 -393.172784)
			(xy 310.913927 -393.214832) (xy 310.877176 -393.251583) (xy 310.835128 -393.282133) (xy 310.788818 -393.305729)
			(xy 310.739388 -393.32179) (xy 310.688053 -393.32992) (xy 310.636079 -393.32992) (xy 310.584744 -393.32179)
			(xy 310.535314 -393.305729) (xy 310.489004 -393.282133) (xy 310.446956 -393.251583) (xy 310.410205 -393.214832)
			(xy 310.379655 -393.172784) (xy 310.356059 -393.126474) (xy 310.339998 -393.077044) (xy 310.331868 -393.025709)
			(xy 309.792368 -393.025709) (xy 309.784238 -393.077044) (xy 309.768177 -393.126474) (xy 309.744581 -393.172784)
			(xy 309.714031 -393.214832) (xy 309.67728 -393.251583) (xy 309.635232 -393.282133) (xy 309.588922 -393.305729)
			(xy 309.539492 -393.32179) (xy 309.488157 -393.32992) (xy 309.436183 -393.32992) (xy 309.384848 -393.32179)
			(xy 309.335418 -393.305729) (xy 309.289108 -393.282133) (xy 309.24706 -393.251583) (xy 309.210309 -393.214832)
			(xy 309.179759 -393.172784) (xy 309.156163 -393.126474) (xy 309.140102 -393.077044) (xy 309.131972 -393.025709)
			(xy 308.592472 -393.025709) (xy 308.584342 -393.077044) (xy 308.568281 -393.126474) (xy 308.544685 -393.172784)
			(xy 308.514135 -393.214832) (xy 308.477384 -393.251583) (xy 308.435336 -393.282133) (xy 308.389026 -393.305729)
			(xy 308.339596 -393.32179) (xy 308.288261 -393.32992) (xy 308.236287 -393.32992) (xy 308.184952 -393.32179)
			(xy 308.135522 -393.305729) (xy 308.089212 -393.282133) (xy 308.047164 -393.251583) (xy 308.010413 -393.214832)
			(xy 307.979863 -393.172784) (xy 307.956267 -393.126474) (xy 307.940206 -393.077044) (xy 307.932076 -393.025709)
			(xy 307.392322 -393.025709) (xy 307.384192 -393.077044) (xy 307.368131 -393.126474) (xy 307.344535 -393.172784)
			(xy 307.313985 -393.214832) (xy 307.277234 -393.251583) (xy 307.235186 -393.282133) (xy 307.188876 -393.305729)
			(xy 307.139446 -393.32179) (xy 307.088111 -393.32992) (xy 307.036137 -393.32992) (xy 306.984802 -393.32179)
			(xy 306.935372 -393.305729) (xy 306.889062 -393.282133) (xy 306.847014 -393.251583) (xy 306.810263 -393.214832)
			(xy 306.779713 -393.172784) (xy 306.756117 -393.126474) (xy 306.740056 -393.077044) (xy 306.731926 -393.025709)
			(xy 306.192426 -393.025709) (xy 306.184296 -393.077044) (xy 306.168235 -393.126474) (xy 306.144639 -393.172784)
			(xy 306.114089 -393.214832) (xy 306.077338 -393.251583) (xy 306.03529 -393.282133) (xy 305.98898 -393.305729)
			(xy 305.93955 -393.32179) (xy 305.888215 -393.32992) (xy 305.836241 -393.32992) (xy 305.784906 -393.32179)
			(xy 305.735476 -393.305729) (xy 305.689166 -393.282133) (xy 305.647118 -393.251583) (xy 305.610367 -393.214832)
			(xy 305.579817 -393.172784) (xy 305.556221 -393.126474) (xy 305.54016 -393.077044) (xy 305.53203 -393.025709)
			(xy 304.992276 -393.025709) (xy 304.984146 -393.077044) (xy 304.968085 -393.126474) (xy 304.944489 -393.172784)
			(xy 304.913939 -393.214832) (xy 304.877188 -393.251583) (xy 304.83514 -393.282133) (xy 304.78883 -393.305729)
			(xy 304.7394 -393.32179) (xy 304.688065 -393.32992) (xy 304.636091 -393.32992) (xy 304.584756 -393.32179)
			(xy 304.535326 -393.305729) (xy 304.489016 -393.282133) (xy 304.446968 -393.251583) (xy 304.410217 -393.214832)
			(xy 304.379667 -393.172784) (xy 304.356071 -393.126474) (xy 304.34001 -393.077044) (xy 304.33188 -393.025709)
			(xy 303.79238 -393.025709) (xy 303.78425 -393.077044) (xy 303.768189 -393.126474) (xy 303.744593 -393.172784)
			(xy 303.714043 -393.214832) (xy 303.677292 -393.251583) (xy 303.635244 -393.282133) (xy 303.588934 -393.305729)
			(xy 303.539504 -393.32179) (xy 303.488169 -393.32992) (xy 303.436195 -393.32992) (xy 303.38486 -393.32179)
			(xy 303.33543 -393.305729) (xy 303.28912 -393.282133) (xy 303.247072 -393.251583) (xy 303.210321 -393.214832)
			(xy 303.179771 -393.172784) (xy 303.156175 -393.126474) (xy 303.140114 -393.077044) (xy 303.131984 -393.025709)
			(xy 301.566329 -393.025709) (xy 301.527724 -393.045379) (xy 301.478294 -393.06144) (xy 301.426959 -393.06957)
			(xy 301.374985 -393.06957) (xy 301.32365 -393.06144) (xy 301.27422 -393.045379) (xy 301.22791 -393.021783)
			(xy 301.185862 -392.991233) (xy 301.149111 -392.954482) (xy 301.118561 -392.912434) (xy 301.094965 -392.866124)
			(xy 301.078904 -392.816694) (xy 301.070774 -392.765359) (xy 300.32567 -392.765359) (xy 300.330843 -392.769664)
			(xy 300.36806 -392.811201) (xy 300.398833 -392.857714) (xy 300.422505 -392.908211) (xy 300.438573 -392.961618)
			(xy 300.446693 -393.016794) (xy 300.447202 -393.04468) (xy 300.446693 -393.072566) (xy 300.438573 -393.127742)
			(xy 300.422505 -393.181149) (xy 300.398833 -393.231646) (xy 300.36806 -393.278159) (xy 300.330843 -393.319696)
			(xy 300.287975 -393.355371) (xy 300.240369 -393.384425) (xy 300.18904 -393.406237) (xy 300.135083 -393.420343)
			(xy 300.079646 -393.426443) (xy 300.023912 -393.424406) (xy 299.969069 -393.414276) (xy 299.916285 -393.396269)
			(xy 299.866685 -393.370768) (xy 299.821327 -393.338317) (xy 299.781178 -393.299608) (xy 299.747092 -393.255465)
			(xy 299.719796 -393.20683) (xy 299.699873 -393.154739) (xy 299.687747 -393.100302) (xy 299.683676 -393.04468)
			(xy 297.64228 -393.04468) (xy 297.64228 -393.708636) (xy 297.642429 -393.714709) (xy 297.64526 -393.726517)
			(xy 297.647868 -393.732004) (xy 297.661231 -393.759029) (xy 297.68222 -393.815548) (xy 297.696387 -393.87415)
			(xy 297.703535 -393.934015) (xy 297.704002 -393.96416) (xy 299.683676 -393.96416) (xy 299.687747 -393.908538)
			(xy 299.699873 -393.854101) (xy 299.719796 -393.80201) (xy 299.747092 -393.753375) (xy 299.781178 -393.709232)
			(xy 299.821327 -393.670523) (xy 299.866685 -393.638072) (xy 299.916285 -393.612571) (xy 299.969069 -393.594564)
			(xy 300.023912 -393.584434) (xy 300.079646 -393.582397) (xy 300.135083 -393.588497) (xy 300.18904 -393.602603)
			(xy 300.240369 -393.624415) (xy 300.287975 -393.653469) (xy 300.330843 -393.689144) (xy 300.36806 -393.730681)
			(xy 300.398833 -393.777194) (xy 300.422505 -393.827691) (xy 300.438573 -393.881098) (xy 300.446693 -393.936274)
			(xy 300.447202 -393.96416) (xy 300.446693 -393.992046) (xy 300.443945 -394.010721) (xy 300.649388 -394.010721)
			(xy 300.649388 -393.958747) (xy 300.657518 -393.907412) (xy 300.673579 -393.857982) (xy 300.697175 -393.811672)
			(xy 300.727725 -393.769624) (xy 300.764476 -393.732873) (xy 300.806524 -393.702323) (xy 300.852834 -393.678727)
			(xy 300.902264 -393.662666) (xy 300.953599 -393.654536) (xy 301.005573 -393.654536) (xy 301.056908 -393.662666)
			(xy 301.106338 -393.678727) (xy 301.133134 -393.69238) (xy 303.460404 -393.69238) (xy 303.460883 -393.666392)
			(xy 303.469017 -393.615055) (xy 303.485082 -393.565623) (xy 303.508681 -393.519313) (xy 303.539234 -393.477265)
			(xy 303.575989 -393.440513) (xy 303.61804 -393.409964) (xy 303.664353 -393.386369) (xy 303.713787 -393.37031)
			(xy 303.765124 -393.362181) (xy 303.791112 -393.361672) (xy 303.817122 -393.362131) (xy 303.8685 -393.370291)
			(xy 303.917966 -393.386394) (xy 303.964302 -393.410041) (xy 304.006365 -393.44065) (xy 304.043118 -393.477466)
			(xy 304.073655 -393.519581) (xy 304.097223 -393.565958) (xy 304.113241 -393.615452) (xy 304.117756 -393.641072)
			(xy 304.11928 -393.65047) (xy 304.143506 -393.69238) (xy 304.6603 -393.69238) (xy 304.660783 -393.666392)
			(xy 304.668917 -393.615056) (xy 304.684981 -393.565624) (xy 304.70858 -393.519314) (xy 304.739133 -393.477266)
			(xy 304.775887 -393.440515) (xy 304.817938 -393.409966) (xy 304.86425 -393.38637) (xy 304.913683 -393.37031)
			(xy 304.96502 -393.362181) (xy 304.991008 -393.361672) (xy 305.017018 -393.362134) (xy 305.068395 -393.370294)
			(xy 305.117862 -393.386396) (xy 305.164198 -393.410043) (xy 305.206261 -393.440651) (xy 305.243014 -393.477467)
			(xy 305.273551 -393.519582) (xy 305.297119 -393.565958) (xy 305.313137 -393.615452) (xy 305.317652 -393.641072)
			(xy 305.319176 -393.65047) (xy 305.343402 -393.69238) (xy 305.86045 -393.69238) (xy 305.860983 -393.666394)
			(xy 305.869115 -393.615063) (xy 305.885176 -393.565636) (xy 305.908771 -393.519329) (xy 305.939318 -393.477283)
			(xy 305.976066 -393.440533) (xy 306.01811 -393.409983) (xy 306.064416 -393.386385) (xy 306.113842 -393.37032)
			(xy 306.165172 -393.362185) (xy 306.191158 -393.361672) (xy 306.21717 -393.362089) (xy 306.268549 -393.370256)
			(xy 306.318016 -393.386365) (xy 306.364352 -393.410018) (xy 306.406415 -393.440633) (xy 306.443167 -393.477453)
			(xy 306.473703 -393.519573) (xy 306.49727 -393.565953) (xy 306.513287 -393.61545) (xy 306.517802 -393.641072)
			(xy 306.519326 -393.65047) (xy 306.543548 -393.69238) (xy 307.060346 -393.69238) (xy 307.060883 -393.666395)
			(xy 307.069015 -393.615064) (xy 307.085076 -393.565637) (xy 307.10867 -393.51933) (xy 307.139217 -393.477285)
			(xy 307.175965 -393.440534) (xy 307.218008 -393.409984) (xy 307.264313 -393.386386) (xy 307.313739 -393.370321)
			(xy 307.365069 -393.362185) (xy 307.391054 -393.361672) (xy 307.417066 -393.362092) (xy 307.468445 -393.370259)
			(xy 307.517912 -393.386368) (xy 307.564248 -393.41002) (xy 307.606311 -393.440634) (xy 307.643063 -393.477455)
			(xy 307.673599 -393.519574) (xy 307.697166 -393.565953) (xy 307.713183 -393.61545) (xy 307.717698 -393.641072)
			(xy 307.719222 -393.65047) (xy 307.743448 -393.69238) (xy 308.260242 -393.69238) (xy 308.260657 -393.666388)
			(xy 308.268793 -393.615044) (xy 308.284861 -393.565605) (xy 308.308465 -393.519288) (xy 308.339025 -393.477234)
			(xy 308.375788 -393.44048) (xy 308.417848 -393.409929) (xy 308.464169 -393.386334) (xy 308.513612 -393.370276)
			(xy 308.564958 -393.362151) (xy 308.59095 -393.361672) (xy 308.616962 -393.362096) (xy 308.66834 -393.370262)
			(xy 308.717807 -393.38637) (xy 308.764143 -393.410022) (xy 308.806206 -393.440636) (xy 308.842959 -393.477456)
			(xy 308.873495 -393.519574) (xy 308.897062 -393.565954) (xy 308.913079 -393.61545) (xy 308.917594 -393.641072)
			(xy 308.919118 -393.65047) (xy 308.943344 -393.69238) (xy 309.460392 -393.69238) (xy 309.460883 -393.666392)
			(xy 309.469017 -393.615057) (xy 309.48508 -393.565626) (xy 309.508679 -393.519317) (xy 309.539231 -393.477269)
			(xy 309.575984 -393.440518) (xy 309.618034 -393.409968) (xy 309.664345 -393.386373) (xy 309.713777 -393.370312)
			(xy 309.765112 -393.362182) (xy 309.7911 -393.361672) (xy 309.81711 -393.362142) (xy 309.868487 -393.3703)
			(xy 309.917953 -393.386401) (xy 309.964289 -393.410047) (xy 310.006352 -393.440654) (xy 310.043105 -393.477469)
			(xy 310.073643 -393.519584) (xy 310.097211 -393.565959) (xy 310.113229 -393.615452) (xy 310.117744 -393.641072)
			(xy 310.119268 -393.65047) (xy 310.143494 -393.69238) (xy 310.660288 -393.69238) (xy 310.660783 -393.666392)
			(xy 310.668917 -393.615058) (xy 310.68498 -393.565627) (xy 310.708578 -393.519318) (xy 310.739129 -393.47727)
			(xy 310.775882 -393.440519) (xy 310.817932 -393.40997) (xy 310.864242 -393.386374) (xy 310.913673 -393.370313)
			(xy 310.965008 -393.362182) (xy 310.990996 -393.361672) (xy 311.017006 -393.362145) (xy 311.068383 -393.370303)
			(xy 311.117849 -393.386404) (xy 311.164185 -393.410049) (xy 311.206248 -393.440656) (xy 311.243001 -393.47747)
			(xy 311.273538 -393.519584) (xy 311.297107 -393.565959) (xy 311.313125 -393.615452) (xy 311.31764 -393.641072)
			(xy 311.319164 -393.65047) (xy 311.59196 -394.122402) (xy 311.599326 -394.128244) (xy 311.618113 -394.144035)
			(xy 311.651229 -394.180255) (xy 311.678637 -394.220966) (xy 311.699736 -394.265276) (xy 311.714065 -394.312214)
			(xy 311.721309 -394.360754) (xy 311.721754 -394.385292) (xy 311.7215 -394.397484) (xy 311.721246 -394.407136)
			(xy 311.727342 -394.42517) (xy 311.786016 -394.49248) (xy 311.80278 -394.501116) (xy 311.812686 -394.502132)
			(xy 311.839446 -394.505503) (xy 311.891469 -394.519723) (xy 311.940495 -394.542196) (xy 311.985225 -394.572326)
			(xy 312.024473 -394.609315) (xy 312.057199 -394.652182) (xy 312.082535 -394.699792) (xy 312.099811 -394.750881)
			(xy 312.108568 -394.804096) (xy 312.109104 -394.831062) (xy 312.108572 -394.858347) (xy 312.099617 -394.912178)
			(xy 312.081944 -394.963807) (xy 312.056034 -395.011834) (xy 312.022588 -395.054954) (xy 312.002932 -395.073886)
			(xy 311.995539 -395.081415) (xy 311.987009 -395.100689) (xy 311.986422 -395.111224) (xy 311.986422 -395.1859)
			(xy 311.986931 -395.196452) (xy 311.99548 -395.215748) (xy 312.002932 -395.223238) (xy 312.022571 -395.242184)
			(xy 312.056006 -395.285306) (xy 312.08191 -395.333331) (xy 312.099582 -395.384955) (xy 312.108543 -395.438779)
			(xy 312.109104 -395.466062) (xy 312.108661 -395.490179) (xy 312.101664 -395.537901) (xy 312.087813 -395.584102)
			(xy 312.0674 -395.627803) (xy 312.054494 -395.64818) (xy 312.048652 -395.65707) (xy 312.045096 -395.677136)
			(xy 312.066178 -395.769338) (xy 312.07837 -395.786102) (xy 312.08726 -395.791436) (xy 312.108067 -395.804282)
			(xy 312.145971 -395.835174) (xy 312.178912 -395.871311) (xy 312.206172 -395.911906) (xy 312.227157 -395.956073)
			(xy 312.241408 -396.002849) (xy 312.248615 -396.051213) (xy 312.249058 -396.075662) (xy 312.248652 -396.100036)
			(xy 312.241505 -396.148257) (xy 312.227361 -396.194907) (xy 312.206525 -396.238978) (xy 312.179448 -396.279514)
			(xy 312.146717 -396.315639) (xy 312.128154 -396.33144) (xy 312.119264 -396.338552) (xy 312.109866 -396.35811)
			(xy 312.107072 -396.457424) (xy 312.115708 -396.47749) (xy 312.12409 -396.48511) (xy 312.142546 -396.502565)
			(xy 312.17389 -396.542539) (xy 312.198185 -396.587149) (xy 312.21476 -396.635165) (xy 312.223159 -396.685263)
			(xy 312.223658 -396.710662) (xy 312.223589 -396.720021) (xy 312.222446 -396.738703) (xy 312.221372 -396.748)
			(xy 312.220356 -396.75689) (xy 312.224166 -396.773654) (xy 312.268108 -396.843504) (xy 312.281824 -396.853918)
			(xy 312.290206 -396.856712) (xy 312.314305 -396.865189) (xy 312.359596 -396.888815) (xy 312.40049 -396.919427)
			(xy 312.435922 -396.956225) (xy 312.464964 -396.998248) (xy 312.48686 -397.044401) (xy 312.494422 -397.068802)
			(xy 312.495946 -397.074644) (xy 312.815732 -397.627602) (xy 312.819796 -397.63192) (xy 312.835987 -397.649639)
			(xy 312.863413 -397.689027) (xy 312.884559 -397.732114) (xy 312.898935 -397.777905) (xy 312.906212 -397.825346)
			(xy 312.906664 -397.849344) (xy 312.906247 -397.87415) (xy 312.898476 -397.923149) (xy 312.883132 -397.970328)
			(xy 312.860593 -398.014524) (xy 312.831416 -398.054649) (xy 312.796319 -398.089713) (xy 312.756166 -398.118851)
			(xy 312.711948 -398.141347) (xy 312.664755 -398.156646) (xy 312.615748 -398.16437) (xy 312.590942 -398.164812)
			(xy 312.565549 -398.164275) (xy 312.515417 -398.15615) (xy 312.467232 -398.140105) (xy 312.422238 -398.116552)
			(xy 312.381595 -398.0861) (xy 312.346351 -398.049534) (xy 312.317417 -398.007796) (xy 312.295537 -397.961965)
			(xy 312.28792 -397.937736) (xy 312.286396 -397.931894) (xy 311.965848 -397.377412) (xy 311.961784 -397.373094)
			(xy 311.945686 -397.355419) (xy 311.918436 -397.316142) (xy 311.897424 -397.273203) (xy 311.88313 -397.227586)
			(xy 311.875883 -397.180334) (xy 311.875424 -397.156432) (xy 311.875566 -397.14438) (xy 311.877472 -397.12035)
			(xy 311.879234 -397.108426) (xy 311.880504 -397.099536) (xy 311.877456 -397.082518) (xy 311.835292 -397.011652)
			(xy 311.822084 -397.000476) (xy 311.813702 -396.997428) (xy 311.791961 -396.989015) (xy 311.751102 -396.966578)
			(xy 311.71413 -396.938189) (xy 311.681906 -396.904506) (xy 311.655179 -396.866314) (xy 311.634572 -396.824502)
			(xy 311.620564 -396.780042) (xy 311.61348 -396.733969) (xy 311.613042 -396.710662) (xy 311.613554 -396.685266)
			(xy 311.621965 -396.635176) (xy 311.638547 -396.587168) (xy 311.662845 -396.542565) (xy 311.694188 -396.502598)
			(xy 311.71261 -396.48511) (xy 311.720992 -396.47749) (xy 311.729628 -396.457424) (xy 311.726834 -396.35811)
			(xy 311.717436 -396.338552) (xy 311.708546 -396.33144) (xy 311.690007 -396.315614) (xy 311.657287 -396.279487)
			(xy 311.630217 -396.238954) (xy 311.609383 -396.194889) (xy 311.595235 -396.148246) (xy 311.58808 -396.100033)
			(xy 311.587642 -396.075662) (xy 311.588057 -396.051545) (xy 311.595064 -396.003821) (xy 311.608924 -395.95762)
			(xy 311.629343 -395.913921) (xy 311.642252 -395.893544) (xy 311.648094 -395.884654) (xy 311.65165 -395.864588)
			(xy 311.630568 -395.772386) (xy 311.618376 -395.755622) (xy 311.609486 -395.750288) (xy 311.5887 -395.737409)
			(xy 311.550794 -395.706524) (xy 311.51785 -395.670393) (xy 311.490586 -395.629804) (xy 311.469598 -395.585642)
			(xy 311.455344 -395.538871) (xy 311.448133 -395.49051) (xy 311.447688 -395.466062) (xy 311.448239 -395.438778)
			(xy 311.457189 -395.384948) (xy 311.474858 -395.333319) (xy 311.500764 -395.285292) (xy 311.534206 -395.242171)
			(xy 311.55386 -395.223238) (xy 311.561241 -395.215699) (xy 311.569778 -395.196432) (xy 311.57037 -395.1859)
			(xy 311.57037 -395.111224) (xy 311.56985 -395.100673) (xy 311.56131 -395.081377) (xy 311.55386 -395.073886)
			(xy 311.534231 -395.05493) (xy 311.500796 -395.01181) (xy 311.47489 -394.963788) (xy 311.457215 -394.912166)
			(xy 311.448251 -394.858344) (xy 311.447688 -394.831062) (xy 311.447942 -394.81887) (xy 311.448196 -394.809218)
			(xy 311.4421 -394.791184) (xy 311.383426 -394.723874) (xy 311.366662 -394.715238) (xy 311.356756 -394.714222)
			(xy 311.329849 -394.710854) (xy 311.277563 -394.696489) (xy 311.228319 -394.67379) (xy 311.183437 -394.643364)
			(xy 311.144117 -394.606027) (xy 311.111413 -394.562776) (xy 311.086199 -394.514772) (xy 311.069152 -394.463298)
			(xy 311.064402 -394.4366) (xy 311.062878 -394.427202) (xy 310.790082 -393.95527) (xy 310.782716 -393.949428)
			(xy 310.763973 -393.933587) (xy 310.730852 -393.897379) (xy 310.703438 -393.856679) (xy 310.682331 -393.812379)
			(xy 310.667993 -393.765448) (xy 310.660739 -393.716916) (xy 310.660288 -393.69238) (xy 310.143494 -393.69238)
			(xy 310.392064 -394.122402) (xy 310.39943 -394.128244) (xy 310.418218 -394.144034) (xy 310.451333 -394.180254)
			(xy 310.478741 -394.220965) (xy 310.49984 -394.265275) (xy 310.514169 -394.312214) (xy 310.521413 -394.360754)
			(xy 310.521858 -394.385292) (xy 310.521604 -394.397484) (xy 310.52135 -394.407136) (xy 310.527446 -394.42517)
			(xy 310.58612 -394.49248) (xy 310.602884 -394.501116) (xy 310.612536 -394.502132) (xy 310.639302 -394.505462)
			(xy 310.691325 -394.51969) (xy 310.740351 -394.54217) (xy 310.78508 -394.572306) (xy 310.824327 -394.6093)
			(xy 310.857052 -394.652171) (xy 310.882387 -394.699784) (xy 310.899662 -394.750877) (xy 310.908419 -394.804095)
			(xy 310.908954 -394.831062) (xy 310.908406 -394.858346) (xy 310.899453 -394.912175) (xy 310.881783 -394.963804)
			(xy 310.855876 -395.011831) (xy 310.822436 -395.054952) (xy 310.802782 -395.073886) (xy 310.795382 -395.081408)
			(xy 310.786857 -395.100688) (xy 310.786272 -395.111224) (xy 310.786272 -395.1859) (xy 310.786796 -395.19645)
			(xy 310.795336 -395.215745) (xy 310.802782 -395.223238) (xy 310.822431 -395.242175) (xy 310.855862 -395.285301)
			(xy 310.881763 -395.333328) (xy 310.899433 -395.384953) (xy 310.908393 -395.438779) (xy 310.908954 -395.466062)
			(xy 310.908503 -395.490178) (xy 310.901507 -395.5379) (xy 310.887658 -395.584101) (xy 310.867248 -395.627802)
			(xy 310.854344 -395.64818) (xy 310.848502 -395.65707) (xy 310.844946 -395.677136) (xy 310.866028 -395.769338)
			(xy 310.87822 -395.786102) (xy 310.88711 -395.791436) (xy 310.907905 -395.8043) (xy 310.945812 -395.835187)
			(xy 310.978756 -395.87132) (xy 311.006018 -395.911912) (xy 311.027005 -395.956077) (xy 311.041257 -396.002851)
			(xy 311.048465 -396.051213) (xy 311.048908 -396.075662) (xy 311.048484 -396.100035) (xy 311.041339 -396.148254)
			(xy 311.027196 -396.194904) (xy 311.006364 -396.238974) (xy 310.979291 -396.279511) (xy 310.946565 -396.315637)
			(xy 310.928004 -396.33144) (xy 310.919114 -396.338552) (xy 310.909716 -396.35811) (xy 310.906922 -396.457424)
			(xy 310.915558 -396.47749) (xy 310.92394 -396.48511) (xy 310.942386 -396.502575) (xy 310.973733 -396.542545)
			(xy 310.998031 -396.587152) (xy 311.014609 -396.635167) (xy 311.023008 -396.685264) (xy 311.023508 -396.710662)
			(xy 311.023439 -396.720021) (xy 311.022296 -396.738703) (xy 311.021222 -396.748) (xy 311.020206 -396.75689)
			(xy 311.024016 -396.773654) (xy 311.067958 -396.843504) (xy 311.081674 -396.853918) (xy 311.090056 -396.856712)
			(xy 311.114087 -396.865171) (xy 311.159259 -396.888726) (xy 311.200064 -396.919228) (xy 311.235442 -396.955884)
			(xy 311.264477 -396.997745) (xy 311.286415 -397.043724) (xy 311.294018 -397.06804) (xy 311.295542 -397.073882)
			(xy 311.615836 -397.627602) (xy 311.6199 -397.63192) (xy 311.636092 -397.649639) (xy 311.663518 -397.689027)
			(xy 311.684663 -397.732113) (xy 311.699039 -397.777905) (xy 311.706316 -397.825346) (xy 311.706768 -397.849344)
			(xy 311.706347 -397.874149) (xy 311.698576 -397.923148) (xy 311.683232 -397.970327) (xy 311.660694 -398.014523)
			(xy 311.631517 -398.054647) (xy 311.59642 -398.089711) (xy 311.556268 -398.11885) (xy 311.512051 -398.141346)
			(xy 311.464858 -398.156645) (xy 311.415852 -398.16437) (xy 311.391046 -398.164812) (xy 311.365653 -398.164271)
			(xy 311.315521 -398.156148) (xy 311.267337 -398.140103) (xy 311.222342 -398.116551) (xy 311.181699 -398.086099)
			(xy 311.146456 -398.049533) (xy 311.117521 -398.007796) (xy 311.095641 -397.961965) (xy 311.088024 -397.937736)
			(xy 311.0865 -397.931894) (xy 310.766206 -397.378174) (xy 310.762142 -397.373856) (xy 310.745981 -397.356124)
			(xy 310.718613 -397.316721) (xy 310.697523 -397.273631) (xy 310.683196 -397.227846) (xy 310.675962 -397.18042)
			(xy 310.675528 -397.156432) (xy 310.675609 -397.144384) (xy 310.677391 -397.120355) (xy 310.679084 -397.108426)
			(xy 310.680354 -397.099536) (xy 310.677306 -397.082518) (xy 310.635142 -397.011652) (xy 310.621934 -397.000476)
			(xy 310.613552 -396.997428) (xy 310.5918 -396.989043) (xy 310.550942 -396.966599) (xy 310.513972 -396.938204)
			(xy 310.48175 -396.904517) (xy 310.455026 -396.866322) (xy 310.43442 -396.824507) (xy 310.420413 -396.780045)
			(xy 310.41333 -396.73397) (xy 310.412892 -396.710662) (xy 310.41342 -396.685267) (xy 310.421829 -396.635178)
			(xy 310.438409 -396.587171) (xy 310.462702 -396.542568) (xy 310.49404 -396.502599) (xy 310.51246 -396.48511)
			(xy 310.520842 -396.47749) (xy 310.529478 -396.457424) (xy 310.526684 -396.35811) (xy 310.517286 -396.338552)
			(xy 310.508396 -396.33144) (xy 310.489868 -396.315602) (xy 310.457144 -396.27948) (xy 310.430072 -396.238949)
			(xy 310.409236 -396.194886) (xy 310.395086 -396.148245) (xy 310.38793 -396.100032) (xy 310.387492 -396.075662)
			(xy 310.387899 -396.051544) (xy 310.394907 -396.00382) (xy 310.408769 -395.957619) (xy 310.429191 -395.91392)
			(xy 310.442102 -395.893544) (xy 310.447944 -395.884654) (xy 310.4515 -395.864588) (xy 310.430418 -395.772386)
			(xy 310.418226 -395.755622) (xy 310.409336 -395.750288) (xy 310.388539 -395.737427) (xy 310.350635 -395.706537)
			(xy 310.317693 -395.670402) (xy 310.290432 -395.62981) (xy 310.269446 -395.585646) (xy 310.255193 -395.538873)
			(xy 310.247983 -395.49051) (xy 310.247538 -395.466062) (xy 310.248104 -395.438778) (xy 310.257054 -395.38495)
			(xy 310.274719 -395.333322) (xy 310.300622 -395.285295) (xy 310.334058 -395.242172) (xy 310.35371 -395.223238)
			(xy 310.361099 -395.215706) (xy 310.36963 -395.196434) (xy 310.37022 -395.1859) (xy 310.37022 -395.111224)
			(xy 310.369685 -395.100675) (xy 310.361153 -395.08138) (xy 310.35371 -395.073886) (xy 310.334071 -395.054939)
			(xy 310.30064 -395.011816) (xy 310.274736 -394.963791) (xy 310.257064 -394.912168) (xy 310.248101 -394.858344)
			(xy 310.247538 -394.831062) (xy 310.247792 -394.81887) (xy 310.248046 -394.809218) (xy 310.24195 -394.791184)
			(xy 310.183276 -394.723874) (xy 310.166512 -394.715238) (xy 310.15686 -394.714222) (xy 310.129953 -394.710851)
			(xy 310.077667 -394.696487) (xy 310.028424 -394.673788) (xy 309.983541 -394.643363) (xy 309.944221 -394.606025)
			(xy 309.911517 -394.562776) (xy 309.886303 -394.514771) (xy 309.869256 -394.463298) (xy 309.864506 -394.4366)
			(xy 309.862982 -394.427202) (xy 309.590186 -393.95527) (xy 309.58282 -393.949428) (xy 309.564078 -393.933586)
			(xy 309.530956 -393.897378) (xy 309.503542 -393.856678) (xy 309.482435 -393.812378) (xy 309.468097 -393.765448)
			(xy 309.460843 -393.716916) (xy 309.460392 -393.69238) (xy 308.943344 -393.69238) (xy 309.191914 -394.122402)
			(xy 309.19928 -394.128244) (xy 309.218057 -394.144047) (xy 309.251176 -394.180263) (xy 309.278586 -394.220971)
			(xy 309.299687 -394.265279) (xy 309.314017 -394.312216) (xy 309.321262 -394.360754) (xy 309.321708 -394.385292)
			(xy 309.321454 -394.397484) (xy 309.3212 -394.407136) (xy 309.327296 -394.42517) (xy 309.38597 -394.49248)
			(xy 309.402734 -394.501116) (xy 309.41264 -394.502132) (xy 309.439406 -394.505459) (xy 309.49143 -394.519687)
			(xy 309.540455 -394.542168) (xy 309.585184 -394.572304) (xy 309.624431 -394.609299) (xy 309.657156 -394.652171)
			(xy 309.682491 -394.699784) (xy 309.699766 -394.750876) (xy 309.708523 -394.804095) (xy 309.709058 -394.831062)
			(xy 309.70864 -394.855264) (xy 309.701565 -394.90315) (xy 309.687577 -394.949489) (xy 309.666975 -394.993291)
			(xy 309.65394 -395.013688) (xy 309.64915 -395.021643) (xy 309.645118 -395.039756) (xy 309.646066 -395.048994)
			(xy 309.650384 -395.079982) (xy 309.652071 -395.089277) (xy 309.661349 -395.105719) (xy 309.668418 -395.111986)
			(xy 309.690497 -395.130679) (xy 309.73027 -395.172688) (xy 309.764434 -395.219373) (xy 309.792444 -395.269991)
			(xy 309.813853 -395.323735) (xy 309.828319 -395.379748) (xy 309.835613 -395.437137) (xy 309.836058 -395.466062)
			(xy 309.835467 -395.499383) (xy 309.825804 -395.565322) (xy 309.806679 -395.629161) (xy 309.793132 -395.65961)
			(xy 309.788866 -395.67007) (xy 309.78898 -395.692636) (xy 309.798725 -395.712989) (xy 309.807102 -395.72057)
			(xy 309.829333 -395.739262) (xy 309.869397 -395.781315) (xy 309.903819 -395.828098) (xy 309.932046 -395.87886)
			(xy 309.953624 -395.932785) (xy 309.968206 -395.989006) (xy 309.975559 -396.046621) (xy 309.976012 -396.075662)
			(xy 309.97555 -396.104668) (xy 309.968238 -396.162216) (xy 309.953715 -396.218379) (xy 309.932213 -396.272258)
			(xy 309.904076 -396.322988) (xy 309.869755 -396.369758) (xy 309.829801 -396.411816) (xy 309.80761 -396.4305)
			(xy 309.800498 -396.436088) (xy 309.791354 -396.451328) (xy 309.776114 -396.534132) (xy 309.778908 -396.551404)
			(xy 309.78348 -396.559532) (xy 309.79605 -396.582721) (xy 309.813927 -396.632341) (xy 309.82303 -396.684292)
			(xy 309.823612 -396.710662) (xy 309.823543 -396.720021) (xy 309.8224 -396.738703) (xy 309.821326 -396.748)
			(xy 309.82031 -396.75689) (xy 309.82412 -396.773654) (xy 309.868062 -396.843504) (xy 309.881778 -396.853918)
			(xy 309.89016 -396.856712) (xy 309.914192 -396.865169) (xy 309.959364 -396.888725) (xy 310.000168 -396.919227)
			(xy 310.035547 -396.955884) (xy 310.064581 -396.997745) (xy 310.086519 -397.043724) (xy 310.094122 -397.06804)
			(xy 310.095646 -397.073882) (xy 310.41594 -397.627602) (xy 310.420004 -397.63192) (xy 310.436196 -397.649638)
			(xy 310.463622 -397.689026) (xy 310.484767 -397.732113) (xy 310.499143 -397.777905) (xy 310.50642 -397.825346)
			(xy 310.506872 -397.849344) (xy 310.506447 -397.874149) (xy 310.498676 -397.923148) (xy 310.483333 -397.970326)
			(xy 310.460795 -398.014522) (xy 310.431618 -398.054646) (xy 310.396522 -398.08971) (xy 310.356371 -398.118849)
			(xy 310.312154 -398.141345) (xy 310.264961 -398.156644) (xy 310.215956 -398.16437) (xy 310.19115 -398.164812)
			(xy 310.165757 -398.164268) (xy 310.115626 -398.156145) (xy 310.067441 -398.1401) (xy 310.022447 -398.116549)
			(xy 309.981803 -398.086097) (xy 309.94656 -398.049532) (xy 309.917625 -398.007795) (xy 309.895745 -397.961965)
			(xy 309.888128 -397.937736) (xy 309.886604 -397.931894) (xy 309.56631 -397.378174) (xy 309.562246 -397.373856)
			(xy 309.546085 -397.356123) (xy 309.518718 -397.316721) (xy 309.497627 -397.273631) (xy 309.4833 -397.227845)
			(xy 309.476066 -397.180419) (xy 309.475632 -397.156432) (xy 309.475713 -397.144384) (xy 309.477495 -397.120355)
			(xy 309.479188 -397.108426) (xy 309.480458 -397.099536) (xy 309.47741 -397.082518) (xy 309.435246 -397.011652)
			(xy 309.422038 -397.000476) (xy 309.413656 -396.997428) (xy 309.391905 -396.98904) (xy 309.351047 -396.966598)
			(xy 309.314077 -396.938203) (xy 309.281855 -396.904516) (xy 309.25513 -396.866321) (xy 309.234524 -396.824507)
			(xy 309.220517 -396.780045) (xy 309.213434 -396.73397) (xy 309.212996 -396.710662) (xy 309.213562 -396.684289)
			(xy 309.222645 -396.632331) (xy 309.240533 -396.58271) (xy 309.253128 -396.559532) (xy 309.2577 -396.551404)
			(xy 309.260494 -396.534132) (xy 309.245254 -396.451328) (xy 309.23611 -396.436088) (xy 309.228998 -396.4305)
			(xy 309.206827 -396.411794) (xy 309.16688 -396.369733) (xy 309.132563 -396.322965) (xy 309.104424 -396.272239)
			(xy 309.082914 -396.218366) (xy 309.068377 -396.162209) (xy 309.061047 -396.104666) (xy 309.060596 -396.075662)
			(xy 309.061191 -396.042341) (xy 309.070851 -395.976402) (xy 309.089975 -395.912563) (xy 309.103522 -395.882114)
			(xy 309.107747 -395.871642) (xy 309.107642 -395.849089) (xy 309.097918 -395.828739) (xy 309.089552 -395.821154)
			(xy 309.067296 -395.802491) (xy 309.027231 -395.760434) (xy 308.99281 -395.713647) (xy 308.964585 -395.66288)
			(xy 308.943012 -395.60895) (xy 308.928435 -395.552724) (xy 308.92109 -395.495105) (xy 308.920642 -395.466062)
			(xy 308.921097 -395.437136) (xy 308.928381 -395.379744) (xy 308.942839 -395.323727) (xy 308.964242 -395.26998)
			(xy 308.992249 -395.219358) (xy 309.026412 -395.17267) (xy 309.066187 -395.13066) (xy 309.088282 -395.111986)
			(xy 309.095257 -395.105642) (xy 309.104513 -395.089236) (xy 309.106316 -395.079982) (xy 309.110634 -395.048994)
			(xy 309.11154 -395.039757) (xy 309.107515 -395.021657) (xy 309.10276 -395.013688) (xy 309.089779 -394.993261)
			(xy 309.069195 -394.949461) (xy 309.055206 -394.903132) (xy 309.04811 -394.855259) (xy 309.047642 -394.831062)
			(xy 309.047896 -394.81887) (xy 309.04815 -394.809218) (xy 309.042054 -394.791184) (xy 308.98338 -394.723874)
			(xy 308.966616 -394.715238) (xy 308.95671 -394.714222) (xy 308.929809 -394.710811) (xy 308.877524 -394.696455)
			(xy 308.82828 -394.673763) (xy 308.783397 -394.643344) (xy 308.744076 -394.606012) (xy 308.71137 -394.562767)
			(xy 308.686155 -394.514766) (xy 308.669106 -394.463296) (xy 308.664356 -394.4366) (xy 308.662832 -394.427202)
			(xy 308.390036 -393.95527) (xy 308.38267 -393.949428) (xy 308.363917 -393.933598) (xy 308.330799 -393.897387)
			(xy 308.303387 -393.856684) (xy 308.282282 -393.812381) (xy 308.267946 -393.76545) (xy 308.260692 -393.716916)
			(xy 308.260242 -393.69238) (xy 307.743448 -393.69238) (xy 307.992018 -394.122402) (xy 307.999384 -394.128244)
			(xy 308.018162 -394.144046) (xy 308.05128 -394.180262) (xy 308.07869 -394.22097) (xy 308.099791 -394.265278)
			(xy 308.114121 -394.312216) (xy 308.121366 -394.360754) (xy 308.121812 -394.385292) (xy 308.121558 -394.397484)
			(xy 308.121304 -394.407136) (xy 308.1274 -394.42517) (xy 308.186074 -394.49248) (xy 308.202838 -394.501116)
			(xy 308.21249 -394.502132) (xy 308.239251 -394.5055) (xy 308.291274 -394.519721) (xy 308.340299 -394.542194)
			(xy 308.385029 -394.572325) (xy 308.424277 -394.609314) (xy 308.457003 -394.652182) (xy 308.482339 -394.699791)
			(xy 308.499615 -394.750881) (xy 308.508372 -394.804096) (xy 308.508908 -394.831062) (xy 308.508398 -394.857049)
			(xy 308.500268 -394.908384) (xy 308.484207 -394.957814) (xy 308.460611 -395.004124) (xy 308.430061 -395.046172)
			(xy 308.39331 -395.082923) (xy 308.351262 -395.113473) (xy 308.304952 -395.137069) (xy 308.255522 -395.15313)
			(xy 308.204187 -395.16126) (xy 308.152213 -395.16126) (xy 308.100878 -395.15313) (xy 308.051448 -395.137069)
			(xy 308.005138 -395.113473) (xy 307.96309 -395.082923) (xy 307.926339 -395.046172) (xy 307.895789 -395.004124)
			(xy 307.872193 -394.957814) (xy 307.856132 -394.908384) (xy 307.848002 -394.857049) (xy 307.847492 -394.831062)
			(xy 307.847746 -394.81887) (xy 307.848 -394.809218) (xy 307.841904 -394.791184) (xy 307.78323 -394.723874)
			(xy 307.766466 -394.715238) (xy 307.756814 -394.714222) (xy 307.729913 -394.710808) (xy 307.677628 -394.696452)
			(xy 307.628385 -394.673761) (xy 307.583501 -394.643343) (xy 307.54418 -394.606011) (xy 307.511474 -394.562766)
			(xy 307.486259 -394.514766) (xy 307.46921 -394.463296) (xy 307.46446 -394.4366) (xy 307.462936 -394.427202)
			(xy 307.19014 -393.95527) (xy 307.182774 -393.949428) (xy 307.164022 -393.933598) (xy 307.130903 -393.897386)
			(xy 307.103491 -393.856683) (xy 307.082386 -393.812381) (xy 307.06805 -393.76545) (xy 307.060796 -393.716916)
			(xy 307.060346 -393.69238) (xy 306.543548 -393.69238) (xy 306.792376 -394.12291) (xy 306.799488 -394.128752)
			(xy 306.818203 -394.144551) (xy 306.85126 -394.180688) (xy 306.878619 -394.22131) (xy 306.899681 -394.265525)
			(xy 306.913985 -394.312365) (xy 306.921217 -394.360804) (xy 306.921662 -394.385292) (xy 306.921408 -394.397484)
			(xy 306.921154 -394.407136) (xy 306.92725 -394.42517) (xy 306.985924 -394.49248) (xy 307.002688 -394.501116)
			(xy 307.012594 -394.502132) (xy 307.039355 -394.505496) (xy 307.091378 -394.519718) (xy 307.140404 -394.542192)
			(xy 307.185133 -394.572323) (xy 307.224381 -394.609313) (xy 307.257107 -394.652181) (xy 307.282443 -394.69979)
			(xy 307.299719 -394.75088) (xy 307.308476 -394.804096) (xy 307.309012 -394.831062) (xy 307.308477 -394.858347)
			(xy 307.299523 -394.912177) (xy 307.28185 -394.963807) (xy 307.25594 -395.011833) (xy 307.222496 -395.054954)
			(xy 307.20284 -395.073886) (xy 307.195449 -395.081416) (xy 307.186917 -395.10069) (xy 307.18633 -395.111224)
			(xy 307.18633 -395.1859) (xy 307.186837 -395.196453) (xy 307.195387 -395.215748) (xy 307.20284 -395.223238)
			(xy 307.222481 -395.242183) (xy 307.255915 -395.285306) (xy 307.281819 -395.33333) (xy 307.29949 -395.384955)
			(xy 307.308451 -395.438779) (xy 307.309012 -395.466062) (xy 307.308568 -395.490178) (xy 307.301571 -395.537901)
			(xy 307.28772 -395.584102) (xy 307.267308 -395.627803) (xy 307.254402 -395.64818) (xy 307.24856 -395.65707)
			(xy 307.245004 -395.677136) (xy 307.266086 -395.769338) (xy 307.278278 -395.786102) (xy 307.287168 -395.791436)
			(xy 307.307977 -395.804279) (xy 307.34588 -395.835172) (xy 307.378821 -395.87131) (xy 307.406081 -395.911905)
			(xy 307.427065 -395.956072) (xy 307.441316 -396.002848) (xy 307.448523 -396.051213) (xy 307.448966 -396.075662)
			(xy 307.448557 -396.100036) (xy 307.441411 -396.148256) (xy 307.427267 -396.194907) (xy 307.406431 -396.238977)
			(xy 307.379355 -396.279513) (xy 307.346625 -396.315639) (xy 307.328062 -396.33144) (xy 307.319172 -396.338552)
			(xy 307.309774 -396.35811) (xy 307.30698 -396.457424) (xy 307.315616 -396.47749) (xy 307.323998 -396.48511)
			(xy 307.342436 -396.502583) (xy 307.373786 -396.54255) (xy 307.398087 -396.587155) (xy 307.414666 -396.635169)
			(xy 307.423066 -396.685264) (xy 307.423566 -396.710662) (xy 308.012846 -396.710662) (xy 308.013368 -396.685407)
			(xy 308.021681 -396.635585) (xy 308.038082 -396.587811) (xy 308.062123 -396.543388) (xy 308.093147 -396.503528)
			(xy 308.130309 -396.469318) (xy 308.172595 -396.441692) (xy 308.218851 -396.421402) (xy 308.267816 -396.409002)
			(xy 308.318154 -396.404831) (xy 308.368492 -396.409002) (xy 308.417457 -396.421402) (xy 308.463713 -396.441692)
			(xy 308.505999 -396.469318) (xy 308.543161 -396.503528) (xy 308.574185 -396.543388) (xy 308.598226 -396.587811)
			(xy 308.614627 -396.635585) (xy 308.62294 -396.685407) (xy 308.623462 -396.710662) (xy 308.623393 -396.720021)
			(xy 308.62225 -396.738703) (xy 308.621176 -396.748) (xy 308.62016 -396.75689) (xy 308.62397 -396.773654)
			(xy 308.667912 -396.843504) (xy 308.681628 -396.853918) (xy 308.69001 -396.856712) (xy 308.714032 -396.865196)
			(xy 308.759205 -396.888744) (xy 308.800011 -396.91924) (xy 308.835392 -396.955892) (xy 308.864429 -396.997749)
			(xy 308.886368 -397.043725) (xy 308.893972 -397.06804) (xy 308.895496 -397.073882) (xy 309.21579 -397.627602)
			(xy 309.219854 -397.63192) (xy 309.236051 -397.649621) (xy 309.263414 -397.689032) (xy 309.284497 -397.73213)
			(xy 309.298816 -397.777923) (xy 309.30604 -397.825354) (xy 309.306468 -397.849344) (xy 309.306023 -397.874135)
			(xy 309.29826 -397.923105) (xy 309.282933 -397.970259) (xy 309.260419 -398.014434) (xy 309.231273 -398.054544)
			(xy 309.196211 -398.089601) (xy 309.156096 -398.118742) (xy 309.111918 -398.14125) (xy 309.064762 -398.15657)
			(xy 309.015791 -398.164326) (xy 308.991 -398.164812) (xy 308.965606 -398.164312) (xy 308.915472 -398.156181)
			(xy 308.867286 -398.140129) (xy 308.822292 -398.116571) (xy 308.781649 -398.086114) (xy 308.746407 -398.049543)
			(xy 308.717473 -398.007801) (xy 308.695595 -397.961967) (xy 308.687978 -397.937736) (xy 308.686454 -397.931894)
			(xy 308.36616 -397.378174) (xy 308.362096 -397.373856) (xy 308.345892 -397.356148) (xy 308.318468 -397.316757)
			(xy 308.297325 -397.273668) (xy 308.282952 -397.227873) (xy 308.275678 -397.18043) (xy 308.275228 -397.156432)
			(xy 308.27537 -397.14438) (xy 308.277276 -397.12035) (xy 308.279038 -397.108426) (xy 308.280308 -397.099536)
			(xy 308.27726 -397.082518) (xy 308.235096 -397.011652) (xy 308.221888 -397.000476) (xy 308.213506 -396.997428)
			(xy 308.191766 -396.989013) (xy 308.150906 -396.966577) (xy 308.113934 -396.938187) (xy 308.08171 -396.904505)
			(xy 308.054984 -396.866314) (xy 308.034376 -396.824502) (xy 308.020368 -396.780042) (xy 308.013284 -396.733969)
			(xy 308.012846 -396.710662) (xy 307.423566 -396.710662) (xy 307.423497 -396.720021) (xy 307.422354 -396.738703)
			(xy 307.42128 -396.748) (xy 307.420264 -396.75689) (xy 307.424074 -396.773654) (xy 307.468016 -396.843504)
			(xy 307.481732 -396.853918) (xy 307.490114 -396.856712) (xy 307.514137 -396.865194) (xy 307.55931 -396.888743)
			(xy 307.600116 -396.919239) (xy 307.635496 -396.955892) (xy 307.664533 -396.997749) (xy 307.686472 -397.043725)
			(xy 307.694076 -397.06804) (xy 307.6956 -397.073882) (xy 308.015894 -397.627602) (xy 308.019958 -397.63192)
			(xy 308.036156 -397.649621) (xy 308.063518 -397.689032) (xy 308.084601 -397.73213) (xy 308.09892 -397.777923)
			(xy 308.106144 -397.825354) (xy 308.106572 -397.849344) (xy 308.106123 -397.874135) (xy 308.09836 -397.923105)
			(xy 308.083034 -397.970258) (xy 308.06052 -398.014433) (xy 308.031374 -398.054543) (xy 307.996312 -398.0896)
			(xy 307.956199 -398.118741) (xy 307.912021 -398.141249) (xy 307.864866 -398.15657) (xy 307.815895 -398.164326)
			(xy 307.791104 -398.164812) (xy 307.76571 -398.164308) (xy 307.715576 -398.156178) (xy 307.667391 -398.140127)
			(xy 307.622396 -398.116569) (xy 307.581754 -398.086112) (xy 307.546511 -398.049542) (xy 307.517577 -398.007801)
			(xy 307.495699 -397.961966) (xy 307.488082 -397.937736) (xy 307.486558 -397.931894) (xy 307.166264 -397.378174)
			(xy 307.1622 -397.373856) (xy 307.145997 -397.356147) (xy 307.118572 -397.316757) (xy 307.09743 -397.273667)
			(xy 307.083056 -397.227873) (xy 307.075782 -397.18043) (xy 307.075332 -397.156432) (xy 307.075474 -397.14438)
			(xy 307.07738 -397.12035) (xy 307.079142 -397.108426) (xy 307.080412 -397.099536) (xy 307.077364 -397.082518)
			(xy 307.0352 -397.011652) (xy 307.021992 -397.000476) (xy 307.01361 -396.997428) (xy 306.991871 -396.989011)
			(xy 306.951011 -396.966575) (xy 306.914039 -396.938186) (xy 306.881815 -396.904504) (xy 306.855088 -396.866313)
			(xy 306.834481 -396.824501) (xy 306.820472 -396.780042) (xy 306.813388 -396.733969) (xy 306.81295 -396.710662)
			(xy 306.81346 -396.685266) (xy 306.82187 -396.635176) (xy 306.838453 -396.587167) (xy 306.862752 -396.542565)
			(xy 306.894095 -396.502597) (xy 306.912518 -396.48511) (xy 306.9209 -396.47749) (xy 306.929536 -396.457424)
			(xy 306.926742 -396.35811) (xy 306.917344 -396.338552) (xy 306.908454 -396.33144) (xy 306.889917 -396.315612)
			(xy 306.857196 -396.279486) (xy 306.830126 -396.238953) (xy 306.809292 -396.194889) (xy 306.795143 -396.148246)
			(xy 306.787988 -396.100033) (xy 306.78755 -396.075662) (xy 306.787964 -396.051544) (xy 306.794971 -396.003821)
			(xy 306.808831 -395.95762) (xy 306.829251 -395.91392) (xy 306.84216 -395.893544) (xy 306.848002 -395.884654)
			(xy 306.851558 -395.864588) (xy 306.830476 -395.772386) (xy 306.818284 -395.755622) (xy 306.809394 -395.750288)
			(xy 306.78861 -395.737406) (xy 306.750703 -395.706522) (xy 306.717759 -395.670392) (xy 306.690495 -395.629803)
			(xy 306.669507 -395.585642) (xy 306.655252 -395.53887) (xy 306.648041 -395.49051) (xy 306.647596 -395.466062)
			(xy 306.648144 -395.438777) (xy 306.657095 -395.384948) (xy 306.674764 -395.333318) (xy 306.700671 -395.285291)
			(xy 306.734113 -395.242171) (xy 306.753768 -395.223238) (xy 306.76115 -395.2157) (xy 306.769687 -395.196433)
			(xy 306.770278 -395.1859) (xy 306.770278 -395.111224) (xy 306.769756 -395.100673) (xy 306.761217 -395.081378)
			(xy 306.753768 -395.073886) (xy 306.73414 -395.054928) (xy 306.700704 -395.011809) (xy 306.674798 -394.963788)
			(xy 306.657123 -394.912166) (xy 306.648159 -394.858344) (xy 306.647596 -394.831062) (xy 306.64785 -394.81887)
			(xy 306.648104 -394.809218) (xy 306.642008 -394.791184) (xy 306.583334 -394.723874) (xy 306.56657 -394.715238)
			(xy 306.556664 -394.714222) (xy 306.529711 -394.710855) (xy 306.477328 -394.696507) (xy 306.427995 -394.673788)
			(xy 306.383039 -394.643311) (xy 306.343671 -394.605894) (xy 306.310949 -394.562545) (xy 306.285754 -394.51443)
			(xy 306.268763 -394.462843) (xy 306.264056 -394.436092) (xy 306.262786 -394.426694) (xy 305.990244 -393.95527)
			(xy 305.982878 -393.949428) (xy 305.964127 -393.933597) (xy 305.931008 -393.897385) (xy 305.903596 -393.856683)
			(xy 305.88249 -393.812381) (xy 305.868154 -393.765449) (xy 305.8609 -393.716916) (xy 305.86045 -393.69238)
			(xy 305.343402 -393.69238) (xy 305.591972 -394.122402) (xy 305.599338 -394.128244) (xy 305.618127 -394.144032)
			(xy 305.651243 -394.180253) (xy 305.67865 -394.220965) (xy 305.699748 -394.265275) (xy 305.714077 -394.312214)
			(xy 305.721321 -394.360753) (xy 305.721766 -394.385292) (xy 305.721512 -394.397484) (xy 305.721258 -394.407136)
			(xy 305.727354 -394.42517) (xy 305.786028 -394.49248) (xy 305.802792 -394.501116) (xy 305.812698 -394.502132)
			(xy 305.83946 -394.505493) (xy 305.891483 -394.519715) (xy 305.940508 -394.54219) (xy 305.985238 -394.572322)
			(xy 306.024485 -394.609312) (xy 306.057211 -394.65218) (xy 306.082548 -394.69979) (xy 306.099823 -394.75088)
			(xy 306.10858 -394.804096) (xy 306.109116 -394.831062) (xy 306.10858 -394.858347) (xy 306.099625 -394.912177)
			(xy 306.081954 -394.963807) (xy 306.056044 -395.011833) (xy 306.0226 -395.054954) (xy 306.002944 -395.073886)
			(xy 305.995553 -395.081417) (xy 305.987021 -395.10069) (xy 305.986434 -395.111224) (xy 305.986434 -395.1859)
			(xy 305.98694 -395.196453) (xy 305.99549 -395.215748) (xy 306.002944 -395.223238) (xy 306.022586 -395.242182)
			(xy 306.056019 -395.285305) (xy 306.081923 -395.33333) (xy 306.099594 -395.384955) (xy 306.108555 -395.438779)
			(xy 306.109116 -395.466062) (xy 306.108671 -395.490178) (xy 306.101675 -395.537901) (xy 306.087823 -395.584102)
			(xy 306.067412 -395.627803) (xy 306.054506 -395.64818) (xy 306.048664 -395.65707) (xy 306.045108 -395.677136)
			(xy 306.06619 -395.769338) (xy 306.078382 -395.786102) (xy 306.087272 -395.791436) (xy 306.108082 -395.804277)
			(xy 306.145985 -395.835171) (xy 306.178926 -395.871309) (xy 306.206185 -395.911905) (xy 306.227169 -395.956072)
			(xy 306.24142 -396.002848) (xy 306.248627 -396.051213) (xy 306.24907 -396.075662) (xy 306.24866 -396.100036)
			(xy 306.241513 -396.148256) (xy 306.227369 -396.194906) (xy 306.206534 -396.238977) (xy 306.179459 -396.279513)
			(xy 306.146729 -396.315639) (xy 306.128166 -396.33144) (xy 306.119276 -396.338552) (xy 306.109878 -396.35811)
			(xy 306.107084 -396.457424) (xy 306.11572 -396.47749) (xy 306.124102 -396.48511) (xy 306.142541 -396.502582)
			(xy 306.173891 -396.542549) (xy 306.198191 -396.587155) (xy 306.21477 -396.635168) (xy 306.22317 -396.685264)
			(xy 306.22367 -396.710662) (xy 306.223601 -396.720021) (xy 306.222458 -396.738703) (xy 306.221384 -396.748)
			(xy 306.220368 -396.75689) (xy 306.224178 -396.773654) (xy 306.26812 -396.843504) (xy 306.281836 -396.853918)
			(xy 306.290218 -396.856712) (xy 306.314319 -396.865182) (xy 306.35961 -396.88881) (xy 306.400504 -396.919423)
			(xy 306.435935 -396.956223) (xy 306.464977 -396.998247) (xy 306.486872 -397.0444) (xy 306.494434 -397.068802)
			(xy 306.495958 -397.074644) (xy 306.815744 -397.627602) (xy 306.819808 -397.63192) (xy 306.836001 -397.649637)
			(xy 306.863427 -397.689026) (xy 306.884571 -397.732113) (xy 306.898947 -397.777905) (xy 306.906224 -397.825346)
			(xy 306.906676 -397.849344) (xy 306.906247 -397.874149) (xy 306.898476 -397.923147) (xy 306.883133 -397.970325)
			(xy 306.860596 -398.014521) (xy 306.83142 -398.054645) (xy 306.796324 -398.089708) (xy 306.756173 -398.118847)
			(xy 306.711957 -398.141344) (xy 306.664764 -398.156644) (xy 306.615759 -398.164369) (xy 306.590954 -398.164812)
			(xy 306.565558 -398.164352) (xy 306.515423 -398.156214) (xy 306.467236 -398.140156) (xy 306.422242 -398.116592)
			(xy 306.3816 -398.086129) (xy 306.346358 -398.049553) (xy 306.317425 -398.007807) (xy 306.295548 -397.961968)
			(xy 306.287932 -397.937736) (xy 306.286408 -397.931894) (xy 305.96586 -397.377412) (xy 305.961796 -397.373094)
			(xy 305.9457 -397.355418) (xy 305.918449 -397.316141) (xy 305.897436 -397.273203) (xy 305.883143 -397.227586)
			(xy 305.875895 -397.180334) (xy 305.875436 -397.156432) (xy 305.875578 -397.14438) (xy 305.877484 -397.12035)
			(xy 305.879246 -397.108426) (xy 305.880516 -397.099536) (xy 305.877468 -397.082518) (xy 305.835304 -397.011652)
			(xy 305.822096 -397.000476) (xy 305.813714 -396.997428) (xy 305.791976 -396.989009) (xy 305.751116 -396.966573)
			(xy 305.714144 -396.938185) (xy 305.681919 -396.904503) (xy 305.655192 -396.866312) (xy 305.634585 -396.824501)
			(xy 305.620576 -396.780042) (xy 305.613492 -396.733969) (xy 305.613054 -396.710662) (xy 305.613562 -396.685266)
			(xy 305.621973 -396.635175) (xy 305.638556 -396.587167) (xy 305.662855 -396.542564) (xy 305.694199 -396.502597)
			(xy 305.712622 -396.48511) (xy 305.721004 -396.47749) (xy 305.72964 -396.457424) (xy 305.726846 -396.35811)
			(xy 305.717448 -396.338552) (xy 305.708558 -396.33144) (xy 305.690022 -396.315611) (xy 305.657301 -396.279485)
			(xy 305.63023 -396.238953) (xy 305.609396 -396.194889) (xy 305.595248 -396.148246) (xy 305.588092 -396.100033)
			(xy 305.587654 -396.075662) (xy 305.588067 -396.051544) (xy 305.595074 -396.003821) (xy 305.608935 -395.95762)
			(xy 305.629355 -395.91392) (xy 305.642264 -395.893544) (xy 305.648106 -395.884654) (xy 305.651662 -395.864588)
			(xy 305.63058 -395.772386) (xy 305.618388 -395.755622) (xy 305.609498 -395.750288) (xy 305.588715 -395.737405)
			(xy 305.550808 -395.706521) (xy 305.517863 -395.670391) (xy 305.490599 -395.629803) (xy 305.469611 -395.585641)
			(xy 305.455356 -395.53887) (xy 305.448145 -395.49051) (xy 305.4477 -395.466062) (xy 305.448247 -395.438777)
			(xy 305.457198 -395.384947) (xy 305.474867 -395.333318) (xy 305.500774 -395.285291) (xy 305.534217 -395.24217)
			(xy 305.553872 -395.223238) (xy 305.561255 -395.215701) (xy 305.569791 -395.196433) (xy 305.570382 -395.1859)
			(xy 305.570382 -395.111224) (xy 305.569859 -395.100673) (xy 305.56132 -395.081378) (xy 305.553872 -395.073886)
			(xy 305.534245 -395.054928) (xy 305.500809 -395.011809) (xy 305.474902 -394.963788) (xy 305.457227 -394.912166)
			(xy 305.448263 -394.858344) (xy 305.4477 -394.831062) (xy 305.447954 -394.81887) (xy 305.448208 -394.809218)
			(xy 305.442112 -394.791184) (xy 305.383438 -394.723874) (xy 305.366674 -394.715238) (xy 305.356768 -394.714222)
			(xy 305.329862 -394.710844) (xy 305.277576 -394.696481) (xy 305.228333 -394.673784) (xy 305.18345 -394.64336)
			(xy 305.14413 -394.606023) (xy 305.111425 -394.562774) (xy 305.086211 -394.514771) (xy 305.069164 -394.463298)
			(xy 305.064414 -394.4366) (xy 305.06289 -394.427202) (xy 304.790094 -393.95527) (xy 304.782728 -393.949428)
			(xy 304.763966 -393.933608) (xy 304.730851 -393.897393) (xy 304.703441 -393.856688) (xy 304.682338 -393.812384)
			(xy 304.668003 -393.765451) (xy 304.66075 -393.716917) (xy 304.6603 -393.69238) (xy 304.143506 -393.69238)
			(xy 304.392076 -394.122402) (xy 304.399442 -394.128244) (xy 304.418232 -394.144031) (xy 304.451347 -394.180252)
			(xy 304.478754 -394.220964) (xy 304.499853 -394.265275) (xy 304.514181 -394.312214) (xy 304.521425 -394.360753)
			(xy 304.52187 -394.385292) (xy 304.521616 -394.397484) (xy 304.521362 -394.407136) (xy 304.527458 -394.42517)
			(xy 304.586132 -394.49248) (xy 304.602896 -394.501116) (xy 304.612548 -394.502132) (xy 304.639315 -394.505452)
			(xy 304.691339 -394.519682) (xy 304.740364 -394.542164) (xy 304.785093 -394.572301) (xy 304.82434 -394.609296)
			(xy 304.857064 -394.652169) (xy 304.882399 -394.699783) (xy 304.899674 -394.750876) (xy 304.908431 -394.804095)
			(xy 304.908966 -394.831062) (xy 304.908414 -394.858346) (xy 304.899461 -394.912175) (xy 304.881792 -394.963803)
			(xy 304.855886 -395.01183) (xy 304.822447 -395.054952) (xy 304.802794 -395.073886) (xy 304.795396 -395.08141)
			(xy 304.78687 -395.100688) (xy 304.786284 -395.111224) (xy 304.786284 -395.1859) (xy 304.786804 -395.196451)
			(xy 304.795346 -395.215746) (xy 304.802794 -395.223238) (xy 304.822445 -395.242173) (xy 304.855875 -395.285299)
			(xy 304.881776 -395.333327) (xy 304.899446 -395.384953) (xy 304.908405 -395.438779) (xy 304.908966 -395.466062)
			(xy 304.908513 -395.490178) (xy 304.901518 -395.5379) (xy 304.887669 -395.584101) (xy 304.86726 -395.627802)
			(xy 304.854356 -395.64818) (xy 304.848514 -395.65707) (xy 304.844958 -395.677136) (xy 304.86604 -395.769338)
			(xy 304.878232 -395.786102) (xy 304.887122 -395.791436) (xy 304.90792 -395.804295) (xy 304.945826 -395.835184)
			(xy 304.97877 -395.871318) (xy 305.006031 -395.911911) (xy 305.027017 -395.956076) (xy 305.041269 -396.00285)
			(xy 305.048477 -396.051213) (xy 305.04892 -396.075662) (xy 305.048492 -396.100035) (xy 305.041346 -396.148254)
			(xy 305.027205 -396.194903) (xy 305.006373 -396.238973) (xy 304.979302 -396.27951) (xy 304.946576 -396.315637)
			(xy 304.928016 -396.33144) (xy 304.919126 -396.338552) (xy 304.909728 -396.35811) (xy 304.906934 -396.457424)
			(xy 304.91557 -396.47749) (xy 304.923952 -396.48511) (xy 304.942401 -396.502572) (xy 304.973747 -396.542543)
			(xy 304.998044 -396.587151) (xy 305.014621 -396.635167) (xy 305.023021 -396.685264) (xy 305.02352 -396.710662)
			(xy 305.023451 -396.720021) (xy 305.022308 -396.738703) (xy 305.021234 -396.748) (xy 305.020218 -396.75689)
			(xy 305.024028 -396.773654) (xy 305.06797 -396.843504) (xy 305.081686 -396.853918) (xy 305.090068 -396.856712)
			(xy 305.114082 -396.865218) (xy 305.159256 -396.888761) (xy 305.200064 -396.919252) (xy 305.235446 -396.9559)
			(xy 305.264484 -396.997753) (xy 305.286426 -397.043726) (xy 305.29403 -397.06804) (xy 305.295554 -397.073882)
			(xy 305.615848 -397.627602) (xy 305.619912 -397.63192) (xy 305.636106 -397.649637) (xy 305.663531 -397.689025)
			(xy 305.684675 -397.732113) (xy 305.699052 -397.777905) (xy 305.706328 -397.825346) (xy 305.70678 -397.849344)
			(xy 305.706347 -397.874149) (xy 305.698576 -397.923146) (xy 305.683233 -397.970324) (xy 305.660696 -398.014519)
			(xy 305.631521 -398.054643) (xy 305.596425 -398.089707) (xy 305.556275 -398.118846) (xy 305.512059 -398.141343)
			(xy 305.464868 -398.156643) (xy 305.415863 -398.164369) (xy 305.391058 -398.164812) (xy 305.365662 -398.164348)
			(xy 305.315527 -398.156211) (xy 305.267341 -398.140154) (xy 305.222346 -398.11659) (xy 305.181704 -398.086127)
			(xy 305.146462 -398.049552) (xy 305.117529 -398.007806) (xy 305.095652 -397.961968) (xy 305.088036 -397.937736)
			(xy 305.086512 -397.931894) (xy 304.766218 -397.378174) (xy 304.762154 -397.373856) (xy 304.745995 -397.356122)
			(xy 304.718626 -397.31672) (xy 304.697536 -397.27363) (xy 304.683208 -397.227845) (xy 304.675974 -397.180419)
			(xy 304.67554 -397.156432) (xy 304.675621 -397.144384) (xy 304.677403 -397.120355) (xy 304.679096 -397.108426)
			(xy 304.680366 -397.099536) (xy 304.677318 -397.082518) (xy 304.635154 -397.011652) (xy 304.621946 -397.000476)
			(xy 304.613564 -396.997428) (xy 304.591815 -396.989036) (xy 304.550957 -396.966594) (xy 304.513986 -396.9382)
			(xy 304.481764 -396.904514) (xy 304.455039 -396.86632) (xy 304.434433 -396.824506) (xy 304.420425 -396.780044)
			(xy 304.413342 -396.73397) (xy 304.412904 -396.710662) (xy 304.413429 -396.685267) (xy 304.421838 -396.635178)
			(xy 304.438418 -396.58717) (xy 304.462713 -396.542567) (xy 304.494052 -396.502599) (xy 304.512472 -396.48511)
			(xy 304.520854 -396.47749) (xy 304.52949 -396.457424) (xy 304.526696 -396.35811) (xy 304.517298 -396.338552)
			(xy 304.508408 -396.33144) (xy 304.489862 -396.315623) (xy 304.457143 -396.279493) (xy 304.430076 -396.238958)
			(xy 304.409243 -396.194892) (xy 304.395097 -396.148247) (xy 304.387941 -396.100033) (xy 304.387504 -396.075662)
			(xy 304.387909 -396.051544) (xy 304.394917 -396.00382) (xy 304.40878 -395.957619) (xy 304.429203 -395.91392)
			(xy 304.442114 -395.893544) (xy 304.447956 -395.884654) (xy 304.451512 -395.864588) (xy 304.43043 -395.772386)
			(xy 304.418238 -395.755622) (xy 304.409348 -395.750288) (xy 304.388554 -395.737423) (xy 304.350649 -395.706534)
			(xy 304.317707 -395.6704) (xy 304.290445 -395.629809) (xy 304.269459 -395.585645) (xy 304.255205 -395.538872)
			(xy 304.247995 -395.49051) (xy 304.24755 -395.466062) (xy 304.248113 -395.438778) (xy 304.257062 -395.38495)
			(xy 304.274728 -395.333321) (xy 304.300632 -395.285294) (xy 304.33407 -395.242172) (xy 304.353722 -395.223238)
			(xy 304.361112 -395.215707) (xy 304.369642 -395.196434) (xy 304.370232 -395.1859) (xy 304.370232 -395.111224)
			(xy 304.369694 -395.100676) (xy 304.361164 -395.081381) (xy 304.353722 -395.073886) (xy 304.334086 -395.054937)
			(xy 304.300653 -395.011814) (xy 304.274749 -394.963791) (xy 304.257076 -394.912168) (xy 304.248113 -394.858344)
			(xy 304.24755 -394.831062) (xy 304.247804 -394.81887) (xy 304.248058 -394.809218) (xy 304.241962 -394.791184)
			(xy 304.183288 -394.723874) (xy 304.166524 -394.715238) (xy 304.156872 -394.714222) (xy 304.129967 -394.710841)
			(xy 304.077681 -394.696479) (xy 304.028437 -394.673782) (xy 303.983555 -394.643358) (xy 303.944234 -394.606022)
			(xy 303.911529 -394.562774) (xy 303.886316 -394.51477) (xy 303.869268 -394.463297) (xy 303.864518 -394.4366)
			(xy 303.862994 -394.427202) (xy 303.590198 -393.95527) (xy 303.582832 -393.949428) (xy 303.564071 -393.933608)
			(xy 303.530955 -393.897393) (xy 303.503546 -393.856688) (xy 303.482442 -393.812384) (xy 303.468107 -393.765451)
			(xy 303.460854 -393.716917) (xy 303.460404 -393.69238) (xy 301.133134 -393.69238) (xy 301.152648 -393.702323)
			(xy 301.194696 -393.732873) (xy 301.231447 -393.769624) (xy 301.261997 -393.811672) (xy 301.285593 -393.857982)
			(xy 301.301654 -393.907412) (xy 301.309784 -393.958747) (xy 301.310294 -393.984734) (xy 301.309784 -394.010721)
			(xy 301.301654 -394.062056) (xy 301.285593 -394.111486) (xy 301.261997 -394.157796) (xy 301.231447 -394.199844)
			(xy 301.194696 -394.236595) (xy 301.165882 -394.25753) (xy 302.833786 -394.25753) (xy 302.834296 -394.231543)
			(xy 302.842426 -394.180208) (xy 302.858487 -394.130778) (xy 302.882083 -394.084468) (xy 302.912633 -394.04242)
			(xy 302.949384 -394.005669) (xy 302.991432 -393.975119) (xy 303.037742 -393.951523) (xy 303.087172 -393.935462)
			(xy 303.138507 -393.927332) (xy 303.190481 -393.927332) (xy 303.241816 -393.935462) (xy 303.291246 -393.951523)
			(xy 303.337556 -393.975119) (xy 303.379604 -394.005669) (xy 303.416355 -394.04242) (xy 303.446905 -394.084468)
			(xy 303.470501 -394.130778) (xy 303.486562 -394.180208) (xy 303.494692 -394.231543) (xy 303.495202 -394.25753)
			(xy 303.494814 -394.281206) (xy 303.488083 -394.328077) (xy 303.474719 -394.373503) (xy 303.46523 -394.395198)
			(xy 303.460912 -394.404596) (xy 303.46015 -394.424662) (xy 303.492408 -394.511022) (xy 303.506124 -394.525754)
			(xy 303.515522 -394.530072) (xy 303.539884 -394.541776) (xy 303.584756 -394.571899) (xy 303.624135 -394.608914)
			(xy 303.656975 -394.651837) (xy 303.682402 -394.699526) (xy 303.699741 -394.750714) (xy 303.70853 -394.80404)
			(xy 303.70907 -394.831062) (xy 303.708548 -394.858348) (xy 303.699593 -394.912179) (xy 303.681918 -394.96381)
			(xy 303.656005 -395.011836) (xy 303.622556 -395.054955) (xy 303.602898 -395.073886) (xy 303.5955 -395.081411)
			(xy 303.586974 -395.100688) (xy 303.586388 -395.111224) (xy 303.586388 -395.1859) (xy 303.586907 -395.196451)
			(xy 303.59545 -395.215746) (xy 303.602898 -395.223238) (xy 303.622531 -395.242191) (xy 303.655968 -395.28531)
			(xy 303.681874 -395.333333) (xy 303.699547 -395.384956) (xy 303.708509 -395.43878) (xy 303.70907 -395.466062)
			(xy 303.708617 -395.490178) (xy 303.701621 -395.5379) (xy 303.687772 -395.584101) (xy 303.667364 -395.627802)
			(xy 303.65446 -395.64818) (xy 303.648618 -395.65707) (xy 303.645062 -395.677136) (xy 303.666144 -395.769338)
			(xy 303.678336 -395.786102) (xy 303.687226 -395.791436) (xy 303.708025 -395.804294) (xy 303.745931 -395.835183)
			(xy 303.778874 -395.871317) (xy 303.806136 -395.91191) (xy 303.827121 -395.956075) (xy 303.841373 -396.00285)
			(xy 303.848581 -396.051213) (xy 303.849024 -396.075662) (xy 303.848594 -396.100035) (xy 303.841449 -396.148254)
			(xy 303.827308 -396.194903) (xy 303.806476 -396.238972) (xy 303.779405 -396.27951) (xy 303.74668 -396.315637)
			(xy 303.72812 -396.33144) (xy 303.71923 -396.338552) (xy 303.709832 -396.35811) (xy 303.707038 -396.457424)
			(xy 303.715674 -396.47749) (xy 303.724056 -396.48511) (xy 303.742505 -396.502572) (xy 303.773852 -396.542542)
			(xy 303.798149 -396.587151) (xy 303.814725 -396.635167) (xy 303.823125 -396.685264) (xy 303.823624 -396.710662)
			(xy 303.823555 -396.720021) (xy 303.822412 -396.738703) (xy 303.821338 -396.748) (xy 303.820322 -396.75689)
			(xy 303.824132 -396.773654) (xy 303.868074 -396.843504) (xy 303.88179 -396.853918) (xy 303.890172 -396.856712)
			(xy 303.914187 -396.865216) (xy 303.959361 -396.88876) (xy 304.000168 -396.919251) (xy 304.03555 -396.955899)
			(xy 304.064589 -396.997753) (xy 304.08653 -397.043726) (xy 304.094134 -397.06804) (xy 304.095658 -397.073882)
			(xy 304.415952 -397.627602) (xy 304.420016 -397.63192) (xy 304.43621 -397.649636) (xy 304.463635 -397.689025)
			(xy 304.48478 -397.732113) (xy 304.499156 -397.777905) (xy 304.506432 -397.825346) (xy 304.506884 -397.849344)
			(xy 304.506447 -397.874149) (xy 304.498676 -397.923146) (xy 304.483334 -397.970323) (xy 304.460797 -398.014518)
			(xy 304.431622 -398.054642) (xy 304.396527 -398.089705) (xy 304.356377 -398.118845) (xy 304.312162 -398.141342)
			(xy 304.264971 -398.156642) (xy 304.215967 -398.164369) (xy 304.191162 -398.164812) (xy 304.165766 -398.164345)
			(xy 304.115631 -398.156208) (xy 304.067445 -398.140151) (xy 304.022451 -398.116588) (xy 303.981808 -398.086126)
			(xy 303.946566 -398.049551) (xy 303.917633 -398.007806) (xy 303.895756 -397.961968) (xy 303.88814 -397.937736)
			(xy 303.886616 -397.931894) (xy 303.566322 -397.378174) (xy 303.562258 -397.373856) (xy 303.546099 -397.356121)
			(xy 303.518731 -397.31672) (xy 303.49764 -397.27363) (xy 303.483312 -397.227845) (xy 303.476078 -397.180419)
			(xy 303.475644 -397.156432) (xy 303.475725 -397.144384) (xy 303.477507 -397.120355) (xy 303.4792 -397.108426)
			(xy 303.48047 -397.099536) (xy 303.477422 -397.082518) (xy 303.435258 -397.011652) (xy 303.42205 -397.000476)
			(xy 303.413668 -396.997428) (xy 303.39192 -396.989034) (xy 303.351061 -396.966593) (xy 303.314091 -396.938199)
			(xy 303.281868 -396.904514) (xy 303.255143 -396.866319) (xy 303.234537 -396.824506) (xy 303.220529 -396.780044)
			(xy 303.213446 -396.73397) (xy 303.213008 -396.710662) (xy 303.213531 -396.685267) (xy 303.221941 -396.635178)
			(xy 303.238521 -396.58717) (xy 303.262816 -396.542567) (xy 303.294155 -396.502599) (xy 303.312576 -396.48511)
			(xy 303.320958 -396.47749) (xy 303.329594 -396.457424) (xy 303.3268 -396.35811) (xy 303.317402 -396.338552)
			(xy 303.308512 -396.33144) (xy 303.289967 -396.315622) (xy 303.257248 -396.279493) (xy 303.23018 -396.238957)
			(xy 303.209347 -396.194891) (xy 303.195201 -396.148247) (xy 303.188045 -396.100033) (xy 303.187608 -396.075662)
			(xy 303.188029 -396.051545) (xy 303.195035 -396.003822) (xy 303.208893 -395.957621) (xy 303.22931 -395.913921)
			(xy 303.242218 -395.893544) (xy 303.24806 -395.884654) (xy 303.251616 -395.864588) (xy 303.230534 -395.772386)
			(xy 303.218342 -395.755622) (xy 303.209452 -395.750288) (xy 303.188659 -395.737422) (xy 303.150754 -395.706533)
			(xy 303.117811 -395.670399) (xy 303.090549 -395.629808) (xy 303.069563 -395.585645) (xy 303.055309 -395.538872)
			(xy 303.048099 -395.49051) (xy 303.047654 -395.466062) (xy 303.048215 -395.438778) (xy 303.057165 -395.38495)
			(xy 303.074831 -395.333321) (xy 303.100735 -395.285294) (xy 303.134173 -395.242172) (xy 303.153826 -395.223238)
			(xy 303.161202 -395.215694) (xy 303.169744 -395.196432) (xy 303.170336 -395.1859) (xy 303.170336 -395.111224)
			(xy 303.169797 -395.100676) (xy 303.161268 -395.081381) (xy 303.153826 -395.073886) (xy 303.13419 -395.054936)
			(xy 303.100758 -395.011814) (xy 303.074853 -394.96379) (xy 303.05718 -394.912167) (xy 303.048217 -394.858344)
			(xy 303.047654 -394.831062) (xy 303.048034 -394.807386) (xy 303.054768 -394.760515) (xy 303.068135 -394.715088)
			(xy 303.077626 -394.693394) (xy 303.081944 -394.683996) (xy 303.082706 -394.66393) (xy 303.050448 -394.57757)
			(xy 303.036732 -394.562838) (xy 303.027334 -394.55852) (xy 303.002958 -394.546843) (xy 302.958089 -394.516713)
			(xy 302.918712 -394.479693) (xy 302.885874 -394.436765) (xy 302.860449 -394.389072) (xy 302.843112 -394.337881)
			(xy 302.834325 -394.284553) (xy 302.833786 -394.25753) (xy 301.165882 -394.25753) (xy 301.152648 -394.267145)
			(xy 301.106338 -394.290741) (xy 301.056908 -394.306802) (xy 301.005573 -394.314932) (xy 300.953599 -394.314932)
			(xy 300.902264 -394.306802) (xy 300.852834 -394.290741) (xy 300.806524 -394.267145) (xy 300.764476 -394.236595)
			(xy 300.727725 -394.199844) (xy 300.697175 -394.157796) (xy 300.673579 -394.111486) (xy 300.657518 -394.062056)
			(xy 300.649388 -394.010721) (xy 300.443945 -394.010721) (xy 300.438573 -394.047222) (xy 300.422505 -394.100629)
			(xy 300.398833 -394.151126) (xy 300.36806 -394.197639) (xy 300.330843 -394.239176) (xy 300.287975 -394.274851)
			(xy 300.240369 -394.303905) (xy 300.18904 -394.325717) (xy 300.135083 -394.339823) (xy 300.079646 -394.345923)
			(xy 300.023912 -394.343886) (xy 299.969069 -394.333756) (xy 299.916285 -394.315749) (xy 299.866685 -394.290248)
			(xy 299.821327 -394.257797) (xy 299.781178 -394.219088) (xy 299.747092 -394.174945) (xy 299.719796 -394.12631)
			(xy 299.699873 -394.074219) (xy 299.687747 -394.019782) (xy 299.683676 -393.96416) (xy 297.704002 -393.96416)
			(xy 297.703574 -393.994307) (xy 297.696438 -394.054178) (xy 297.682263 -394.112783) (xy 297.661248 -394.169297)
			(xy 297.647868 -394.196316) (xy 297.645074 -394.201904) (xy 297.64228 -394.213334) (xy 297.64228 -394.385292)
			(xy 297.642877 -394.396626) (xy 297.652624 -394.41709) (xy 297.661076 -394.424662) (xy 297.73118 -394.481812)
			(xy 297.75277 -394.487146) (xy 297.764454 -394.48486) (xy 297.783417 -394.481179) (xy 297.821846 -394.477232)
			(xy 297.841162 -394.476986) (xy 297.868417 -394.477447) (xy 297.922373 -394.485199) (xy 297.974676 -394.500552)
			(xy 298.024262 -394.523193) (xy 298.07012 -394.552661) (xy 298.111318 -394.588355) (xy 298.147017 -394.629549)
			(xy 298.176489 -394.675405) (xy 298.199134 -394.724988) (xy 298.214492 -394.77729) (xy 298.222251 -394.831245)
			(xy 298.222251 -394.871448) (xy 300.750732 -394.871448) (xy 300.751242 -394.845461) (xy 300.759372 -394.794126)
			(xy 300.775433 -394.744696) (xy 300.799029 -394.698386) (xy 300.829579 -394.656338) (xy 300.86633 -394.619587)
			(xy 300.908378 -394.589037) (xy 300.954688 -394.565441) (xy 301.004118 -394.54938) (xy 301.055453 -394.54125)
			(xy 301.107427 -394.54125) (xy 301.158762 -394.54938) (xy 301.208192 -394.565441) (xy 301.254502 -394.589037)
			(xy 301.29655 -394.619587) (xy 301.333301 -394.656338) (xy 301.363851 -394.698386) (xy 301.387447 -394.744696)
			(xy 301.403508 -394.794126) (xy 301.411638 -394.845461) (xy 301.412148 -394.871448) (xy 301.411601 -394.898777)
			(xy 301.402608 -394.95269) (xy 301.384873 -395.00439) (xy 301.35888 -395.052472) (xy 301.342552 -395.074394)
			(xy 301.336964 -395.08176) (xy 301.331376 -395.098524) (xy 301.334932 -395.182598) (xy 301.34179 -395.198854)
			(xy 301.347886 -395.205712) (xy 301.364263 -395.224117) (xy 301.391916 -395.264887) (xy 301.413219 -395.309307)
			(xy 301.427702 -395.356394) (xy 301.435044 -395.405108) (xy 301.435516 -395.42974) (xy 301.435006 -395.455727)
			(xy 301.426876 -395.507062) (xy 301.410815 -395.556492) (xy 301.387219 -395.602802) (xy 301.356669 -395.64485)
			(xy 301.319918 -395.681601) (xy 301.27787 -395.712151) (xy 301.23156 -395.735747) (xy 301.18213 -395.751808)
			(xy 301.130795 -395.759938) (xy 301.078821 -395.759938) (xy 301.027486 -395.751808) (xy 300.978056 -395.735747)
			(xy 300.931746 -395.712151) (xy 300.889698 -395.681601) (xy 300.852947 -395.64485) (xy 300.822397 -395.602802)
			(xy 300.798801 -395.556492) (xy 300.78274 -395.507062) (xy 300.77461 -395.455727) (xy 300.7741 -395.42974)
			(xy 300.774684 -395.402413) (xy 300.783665 -395.348501) (xy 300.801388 -395.2968) (xy 300.827372 -395.248717)
			(xy 300.843696 -395.226794) (xy 300.849284 -395.219428) (xy 300.854872 -395.202664) (xy 300.851316 -395.11859)
			(xy 300.844458 -395.102334) (xy 300.838362 -395.095476) (xy 300.822018 -395.077044) (xy 300.794362 -395.03628)
			(xy 300.773053 -394.991867) (xy 300.758563 -394.944786) (xy 300.75121 -394.896078) (xy 300.750732 -394.871448)
			(xy 298.222251 -394.871448) (xy 298.222251 -394.885755) (xy 298.214492 -394.93971) (xy 298.199134 -394.992012)
			(xy 298.176489 -395.041595) (xy 298.147017 -395.087451) (xy 298.111318 -395.128645) (xy 298.07012 -395.164339)
			(xy 298.024262 -395.193807) (xy 297.974676 -395.216448) (xy 297.922373 -395.231801) (xy 297.868417 -395.239553)
			(xy 297.841162 -395.240002) (xy 297.818656 -395.239645) (xy 297.773962 -395.234302) (xy 297.752008 -395.229334)
			(xy 297.740521 -395.227211) (xy 297.71776 -395.232361) (xy 297.70832 -395.23924) (xy 297.683174 -395.25956)
			(xy 297.674421 -395.26733) (xy 297.664501 -395.288501) (xy 297.664124 -395.3002) (xy 297.664124 -396.171674)
			(xy 297.663542 -396.202243) (xy 297.653849 -396.262606) (xy 297.64482 -396.291816) (xy 297.64228 -396.299436)
			(xy 297.64228 -396.359888) (xy 297.642787 -396.370968) (xy 297.652016 -396.391111) (xy 297.66006 -396.39875)
			(xy 297.727624 -396.456154) (xy 297.74896 -396.461996) (xy 297.760136 -396.460218) (xy 297.77521 -396.457951)
			(xy 297.805599 -396.455536) (xy 297.820842 -396.455392) (xy 297.848091 -396.455881) (xy 297.902034 -396.463642)
			(xy 297.954324 -396.479001) (xy 298.003896 -396.501644) (xy 298.049741 -396.531112) (xy 298.090926 -396.566803)
			(xy 298.126613 -396.607992) (xy 298.156076 -396.653841) (xy 298.167873 -396.679674) (xy 299.808644 -396.679674)
			(xy 299.812715 -396.624052) (xy 299.824841 -396.569615) (xy 299.844764 -396.517524) (xy 299.87206 -396.468889)
			(xy 299.906146 -396.424746) (xy 299.946295 -396.386037) (xy 299.991653 -396.353586) (xy 300.041253 -396.328085)
			(xy 300.094037 -396.310078) (xy 300.14888 -396.299948) (xy 300.204614 -396.297911) (xy 300.260051 -396.304011)
			(xy 300.314008 -396.318117) (xy 300.365337 -396.339929) (xy 300.412943 -396.368983) (xy 300.455811 -396.404658)
			(xy 300.493028 -396.446195) (xy 300.523801 -396.492708) (xy 300.547473 -396.543205) (xy 300.563541 -396.596612)
			(xy 300.571661 -396.651788) (xy 300.57217 -396.679674) (xy 300.571723 -396.704137) (xy 300.77461 -396.704137)
			(xy 300.77461 -396.652163) (xy 300.78274 -396.600828) (xy 300.798801 -396.551398) (xy 300.822397 -396.505088)
			(xy 300.852947 -396.46304) (xy 300.889698 -396.426289) (xy 300.931746 -396.395739) (xy 300.978056 -396.372143)
			(xy 301.027486 -396.356082) (xy 301.078821 -396.347952) (xy 301.130795 -396.347952) (xy 301.18213 -396.356082)
			(xy 301.23156 -396.372143) (xy 301.27787 -396.395739) (xy 301.319918 -396.426289) (xy 301.356669 -396.46304)
			(xy 301.387219 -396.505088) (xy 301.410815 -396.551398) (xy 301.426876 -396.600828) (xy 301.435006 -396.652163)
			(xy 301.435516 -396.67815) (xy 301.435006 -396.704137) (xy 301.426876 -396.755472) (xy 301.410815 -396.804902)
			(xy 301.387219 -396.851212) (xy 301.356669 -396.89326) (xy 301.319918 -396.930011) (xy 301.27787 -396.960561)
			(xy 301.23156 -396.984157) (xy 301.18213 -397.000218) (xy 301.130795 -397.008348) (xy 301.078821 -397.008348)
			(xy 301.027486 -397.000218) (xy 300.978056 -396.984157) (xy 300.931746 -396.960561) (xy 300.889698 -396.930011)
			(xy 300.852947 -396.89326) (xy 300.822397 -396.851212) (xy 300.798801 -396.804902) (xy 300.78274 -396.755472)
			(xy 300.77461 -396.704137) (xy 300.571723 -396.704137) (xy 300.571661 -396.70756) (xy 300.563541 -396.762736)
			(xy 300.547473 -396.816143) (xy 300.523801 -396.86664) (xy 300.493028 -396.913153) (xy 300.455811 -396.95469)
			(xy 300.412943 -396.990365) (xy 300.365337 -397.019419) (xy 300.314008 -397.041231) (xy 300.260051 -397.055337)
			(xy 300.204614 -397.061437) (xy 300.14888 -397.0594) (xy 300.094037 -397.04927) (xy 300.041253 -397.031263)
			(xy 299.991653 -397.005762) (xy 299.946295 -396.973311) (xy 299.906146 -396.934602) (xy 299.87206 -396.890459)
			(xy 299.844764 -396.841824) (xy 299.824841 -396.789733) (xy 299.812715 -396.735296) (xy 299.808644 -396.679674)
			(xy 298.167873 -396.679674) (xy 298.178714 -396.703415) (xy 298.194067 -396.755707) (xy 298.201822 -396.809651)
			(xy 298.201822 -396.864149) (xy 298.194067 -396.918093) (xy 298.178714 -396.970385) (xy 298.156076 -397.019959)
			(xy 298.126613 -397.065808) (xy 298.090926 -397.106997) (xy 298.049741 -397.142688) (xy 298.003896 -397.172156)
			(xy 297.954324 -397.194799) (xy 297.902034 -397.210158) (xy 297.848091 -397.217919) (xy 297.820842 -397.218408)
			(xy 297.805599 -397.218267) (xy 297.77521 -397.215847) (xy 297.760136 -397.213582) (xy 297.74896 -397.211804)
			(xy 297.727624 -397.217646) (xy 297.66006 -397.27505) (xy 297.651994 -397.282673) (xy 297.64276 -397.302826)
			(xy 297.64228 -397.313912) (xy 297.64228 -399.008092) (xy 300.762416 -399.008092) (xy 300.762823 -398.984859)
			(xy 300.769318 -398.938848) (xy 300.782191 -398.8942) (xy 300.801191 -398.851795) (xy 300.825942 -398.812469)
			(xy 300.840648 -398.794478) (xy 300.846744 -398.787366) (xy 300.85284 -398.770856) (xy 300.85284 -398.686528)
			(xy 300.846744 -398.670018) (xy 300.840648 -398.662906) (xy 300.825935 -398.64492) (xy 300.801188 -398.60559)
			(xy 300.782189 -398.563184) (xy 300.769311 -398.518537) (xy 300.762809 -398.472526) (xy 300.762416 -398.449292)
			(xy 300.762926 -398.423305) (xy 300.771056 -398.37197) (xy 300.787117 -398.32254) (xy 300.810713 -398.27623)
			(xy 300.841263 -398.234182) (xy 300.878014 -398.197431) (xy 300.920062 -398.166881) (xy 300.966372 -398.143285)
			(xy 301.015802 -398.127224) (xy 301.067137 -398.119094) (xy 301.119111 -398.119094) (xy 301.170446 -398.127224)
			(xy 301.219876 -398.143285) (xy 301.266186 -398.166881) (xy 301.308234 -398.197431) (xy 301.344985 -398.234182)
			(xy 301.375535 -398.27623) (xy 301.399131 -398.32254) (xy 301.415192 -398.37197) (xy 301.423322 -398.423305)
			(xy 301.423832 -398.449292) (xy 301.423463 -398.472527) (xy 301.416957 -398.518539) (xy 301.410187 -398.542002)
			(xy 303.085004 -398.542002) (xy 303.088964 -398.492948) (xy 303.100741 -398.445164) (xy 303.120032 -398.399888)
			(xy 303.146335 -398.358292) (xy 303.17897 -398.321455) (xy 303.217091 -398.29033) (xy 303.259712 -398.265723)
			(xy 303.305728 -398.248271) (xy 303.353947 -398.238427) (xy 303.403122 -398.236446) (xy 303.451977 -398.242378)
			(xy 303.499248 -398.25607) (xy 303.54371 -398.277168) (xy 303.584213 -398.305124) (xy 303.619706 -398.339216)
			(xy 303.649271 -398.37856) (xy 303.672142 -398.422137) (xy 303.687726 -398.468818) (xy 303.695621 -398.517395)
			(xy 303.696116 -398.542002) (xy 304.285154 -398.542002) (xy 304.289114 -398.492948) (xy 304.300891 -398.445164)
			(xy 304.320182 -398.399888) (xy 304.346485 -398.358292) (xy 304.37912 -398.321455) (xy 304.417241 -398.29033)
			(xy 304.459862 -398.265723) (xy 304.505878 -398.248271) (xy 304.554097 -398.238427) (xy 304.603272 -398.236446)
			(xy 304.652127 -398.242378) (xy 304.699398 -398.25607) (xy 304.74386 -398.277168) (xy 304.784363 -398.305124)
			(xy 304.819856 -398.339216) (xy 304.849421 -398.37856) (xy 304.872292 -398.422137) (xy 304.887876 -398.468818)
			(xy 304.895771 -398.517395) (xy 304.896266 -398.542002) (xy 305.485304 -398.542002) (xy 305.489264 -398.492948)
			(xy 305.501041 -398.445164) (xy 305.520332 -398.399888) (xy 305.546635 -398.358292) (xy 305.57927 -398.321455)
			(xy 305.617391 -398.29033) (xy 305.660012 -398.265723) (xy 305.706028 -398.248271) (xy 305.754247 -398.238427)
			(xy 305.803422 -398.236446) (xy 305.852277 -398.242378) (xy 305.899548 -398.25607) (xy 305.94401 -398.277168)
			(xy 305.984513 -398.305124) (xy 306.020006 -398.339216) (xy 306.049571 -398.37856) (xy 306.072442 -398.422137)
			(xy 306.088026 -398.468818) (xy 306.095921 -398.517395) (xy 306.096416 -398.542002) (xy 306.6852 -398.542002)
			(xy 306.68916 -398.492948) (xy 306.700937 -398.445164) (xy 306.720228 -398.399888) (xy 306.746531 -398.358292)
			(xy 306.779166 -398.321455) (xy 306.817287 -398.29033) (xy 306.859908 -398.265723) (xy 306.905924 -398.248271)
			(xy 306.954143 -398.238427) (xy 307.003318 -398.236446) (xy 307.052173 -398.242378) (xy 307.099444 -398.25607)
			(xy 307.143906 -398.277168) (xy 307.184409 -398.305124) (xy 307.219902 -398.339216) (xy 307.249467 -398.37856)
			(xy 307.272338 -398.422137) (xy 307.287922 -398.468818) (xy 307.295817 -398.517395) (xy 307.296312 -398.542002)
			(xy 307.88535 -398.542002) (xy 307.88931 -398.492948) (xy 307.901087 -398.445164) (xy 307.920378 -398.399888)
			(xy 307.946681 -398.358292) (xy 307.979316 -398.321455) (xy 308.017437 -398.29033) (xy 308.060058 -398.265723)
			(xy 308.106074 -398.248271) (xy 308.154293 -398.238427) (xy 308.203468 -398.236446) (xy 308.252323 -398.242378)
			(xy 308.299594 -398.25607) (xy 308.344056 -398.277168) (xy 308.384559 -398.305124) (xy 308.420052 -398.339216)
			(xy 308.449617 -398.37856) (xy 308.472488 -398.422137) (xy 308.488072 -398.468818) (xy 308.495967 -398.517395)
			(xy 308.496462 -398.542002) (xy 309.085246 -398.542002) (xy 309.089206 -398.492948) (xy 309.100983 -398.445164)
			(xy 309.120274 -398.399888) (xy 309.146577 -398.358292) (xy 309.179212 -398.321455) (xy 309.217333 -398.29033)
			(xy 309.259954 -398.265723) (xy 309.30597 -398.248271) (xy 309.354189 -398.238427) (xy 309.403364 -398.236446)
			(xy 309.452219 -398.242378) (xy 309.49949 -398.25607) (xy 309.543952 -398.277168) (xy 309.584455 -398.305124)
			(xy 309.619948 -398.339216) (xy 309.649513 -398.37856) (xy 309.672384 -398.422137) (xy 309.687968 -398.468818)
			(xy 309.695863 -398.517395) (xy 309.696358 -398.542002) (xy 310.285142 -398.542002) (xy 310.289102 -398.492948)
			(xy 310.300879 -398.445164) (xy 310.32017 -398.399888) (xy 310.346473 -398.358292) (xy 310.379108 -398.321455)
			(xy 310.417229 -398.29033) (xy 310.45985 -398.265723) (xy 310.505866 -398.248271) (xy 310.554085 -398.238427)
			(xy 310.60326 -398.236446) (xy 310.652115 -398.242378) (xy 310.699386 -398.25607) (xy 310.743848 -398.277168)
			(xy 310.784351 -398.305124) (xy 310.819844 -398.339216) (xy 310.849409 -398.37856) (xy 310.87228 -398.422137)
			(xy 310.887864 -398.468818) (xy 310.895759 -398.517395) (xy 310.896254 -398.542002) (xy 311.485292 -398.542002)
			(xy 311.489252 -398.492948) (xy 311.501029 -398.445164) (xy 311.52032 -398.399888) (xy 311.546623 -398.358292)
			(xy 311.579258 -398.321455) (xy 311.617379 -398.29033) (xy 311.66 -398.265723) (xy 311.706016 -398.248271)
			(xy 311.754235 -398.238427) (xy 311.80341 -398.236446) (xy 311.852265 -398.242378) (xy 311.899536 -398.25607)
			(xy 311.943998 -398.277168) (xy 311.984501 -398.305124) (xy 312.019994 -398.339216) (xy 312.049559 -398.37856)
			(xy 312.07243 -398.422137) (xy 312.088014 -398.468818) (xy 312.095909 -398.517395) (xy 312.096404 -398.542002)
			(xy 312.685188 -398.542002) (xy 312.689148 -398.492948) (xy 312.700925 -398.445164) (xy 312.720216 -398.399888)
			(xy 312.746519 -398.358292) (xy 312.779154 -398.321455) (xy 312.817275 -398.29033) (xy 312.859896 -398.265723)
			(xy 312.905912 -398.248271) (xy 312.954131 -398.238427) (xy 313.003306 -398.236446) (xy 313.052161 -398.242378)
			(xy 313.099432 -398.25607) (xy 313.143894 -398.277168) (xy 313.184397 -398.305124) (xy 313.21989 -398.339216)
			(xy 313.249455 -398.37856) (xy 313.272326 -398.422137) (xy 313.28791 -398.468818) (xy 313.295805 -398.517395)
			(xy 313.2963 -398.542002) (xy 313.885338 -398.542002) (xy 313.889298 -398.492948) (xy 313.901075 -398.445164)
			(xy 313.920366 -398.399888) (xy 313.946669 -398.358292) (xy 313.979304 -398.321455) (xy 314.017425 -398.29033)
			(xy 314.060046 -398.265723) (xy 314.106062 -398.248271) (xy 314.154281 -398.238427) (xy 314.203456 -398.236446)
			(xy 314.252311 -398.242378) (xy 314.299582 -398.25607) (xy 314.344044 -398.277168) (xy 314.384547 -398.305124)
			(xy 314.42004 -398.339216) (xy 314.449605 -398.37856) (xy 314.472476 -398.422137) (xy 314.48806 -398.468818)
			(xy 314.495955 -398.517395) (xy 314.49645 -398.542002) (xy 315.085234 -398.542002) (xy 315.089194 -398.492948)
			(xy 315.100971 -398.445164) (xy 315.120262 -398.399888) (xy 315.146565 -398.358292) (xy 315.1792 -398.321455)
			(xy 315.217321 -398.29033) (xy 315.259942 -398.265723) (xy 315.305958 -398.248271) (xy 315.354177 -398.238427)
			(xy 315.403352 -398.236446) (xy 315.452207 -398.242378) (xy 315.499478 -398.25607) (xy 315.54394 -398.277168)
			(xy 315.584443 -398.305124) (xy 315.619936 -398.339216) (xy 315.649501 -398.37856) (xy 315.672372 -398.422137)
			(xy 315.687956 -398.468818) (xy 315.695851 -398.517395) (xy 315.696346 -398.542002) (xy 316.28513 -398.542002)
			(xy 316.28909 -398.492948) (xy 316.300867 -398.445164) (xy 316.320158 -398.399888) (xy 316.346461 -398.358292)
			(xy 316.379096 -398.321455) (xy 316.417217 -398.29033) (xy 316.459838 -398.265723) (xy 316.505854 -398.248271)
			(xy 316.554073 -398.238427) (xy 316.603248 -398.236446) (xy 316.652103 -398.242378) (xy 316.699374 -398.25607)
			(xy 316.743836 -398.277168) (xy 316.784339 -398.305124) (xy 316.819832 -398.339216) (xy 316.849397 -398.37856)
			(xy 316.872268 -398.422137) (xy 316.887852 -398.468818) (xy 316.895747 -398.517395) (xy 316.896242 -398.542002)
			(xy 317.48528 -398.542002) (xy 317.48924 -398.492948) (xy 317.501017 -398.445164) (xy 317.520308 -398.399888)
			(xy 317.546611 -398.358292) (xy 317.579246 -398.321455) (xy 317.617367 -398.29033) (xy 317.659988 -398.265723)
			(xy 317.706004 -398.248271) (xy 317.754223 -398.238427) (xy 317.803398 -398.236446) (xy 317.852253 -398.242378)
			(xy 317.899524 -398.25607) (xy 317.943986 -398.277168) (xy 317.984489 -398.305124) (xy 318.019982 -398.339216)
			(xy 318.049547 -398.37856) (xy 318.072418 -398.422137) (xy 318.088002 -398.468818) (xy 318.095897 -398.517395)
			(xy 318.096392 -398.542002) (xy 318.685176 -398.542002) (xy 318.689136 -398.492948) (xy 318.700913 -398.445164)
			(xy 318.720204 -398.399888) (xy 318.746507 -398.358292) (xy 318.779142 -398.321455) (xy 318.817263 -398.29033)
			(xy 318.859884 -398.265723) (xy 318.9059 -398.248271) (xy 318.954119 -398.238427) (xy 319.003294 -398.236446)
			(xy 319.052149 -398.242378) (xy 319.09942 -398.25607) (xy 319.143882 -398.277168) (xy 319.184385 -398.305124)
			(xy 319.219878 -398.339216) (xy 319.249443 -398.37856) (xy 319.272314 -398.422137) (xy 319.287898 -398.468818)
			(xy 319.295793 -398.517395) (xy 319.296288 -398.542002) (xy 319.885326 -398.542002) (xy 319.889286 -398.492948)
			(xy 319.901063 -398.445164) (xy 319.920354 -398.399888) (xy 319.946657 -398.358292) (xy 319.979292 -398.321455)
			(xy 320.017413 -398.29033) (xy 320.060034 -398.265723) (xy 320.10605 -398.248271) (xy 320.154269 -398.238427)
			(xy 320.203444 -398.236446) (xy 320.252299 -398.242378) (xy 320.29957 -398.25607) (xy 320.344032 -398.277168)
			(xy 320.384535 -398.305124) (xy 320.420028 -398.339216) (xy 320.449593 -398.37856) (xy 320.472464 -398.422137)
			(xy 320.488048 -398.468818) (xy 320.495943 -398.517395) (xy 320.496438 -398.542002) (xy 321.085222 -398.542002)
			(xy 321.089182 -398.492948) (xy 321.100959 -398.445164) (xy 321.12025 -398.399888) (xy 321.146553 -398.358292)
			(xy 321.179188 -398.321455) (xy 321.217309 -398.29033) (xy 321.25993 -398.265723) (xy 321.305946 -398.248271)
			(xy 321.354165 -398.238427) (xy 321.40334 -398.236446) (xy 321.452195 -398.242378) (xy 321.499466 -398.25607)
			(xy 321.543928 -398.277168) (xy 321.584431 -398.305124) (xy 321.619924 -398.339216) (xy 321.649489 -398.37856)
			(xy 321.67236 -398.422137) (xy 321.687944 -398.468818) (xy 321.695839 -398.517395) (xy 321.696334 -398.542002)
			(xy 321.695839 -398.566609) (xy 321.695615 -398.567989) (xy 322.414902 -398.567989) (xy 322.414902 -398.516015)
			(xy 322.423032 -398.46468) (xy 322.439093 -398.41525) (xy 322.462689 -398.36894) (xy 322.493239 -398.326892)
			(xy 322.52999 -398.290141) (xy 322.572038 -398.259591) (xy 322.618348 -398.235995) (xy 322.667778 -398.219934)
			(xy 322.719113 -398.211804) (xy 322.771087 -398.211804) (xy 322.822422 -398.219934) (xy 322.871852 -398.235995)
			(xy 322.918162 -398.259591) (xy 322.96021 -398.290141) (xy 322.996961 -398.326892) (xy 323.027511 -398.36894)
			(xy 323.051107 -398.41525) (xy 323.067168 -398.46468) (xy 323.075298 -398.516015) (xy 323.075808 -398.542002)
			(xy 323.075298 -398.567989) (xy 323.067168 -398.619324) (xy 323.051107 -398.668754) (xy 323.027511 -398.715064)
			(xy 322.996961 -398.757112) (xy 322.96021 -398.793863) (xy 322.918162 -398.824413) (xy 322.871852 -398.848009)
			(xy 322.822422 -398.86407) (xy 322.771087 -398.8722) (xy 322.719113 -398.8722) (xy 322.667778 -398.86407)
			(xy 322.618348 -398.848009) (xy 322.572038 -398.824413) (xy 322.52999 -398.793863) (xy 322.493239 -398.757112)
			(xy 322.462689 -398.715064) (xy 322.439093 -398.668754) (xy 322.423032 -398.619324) (xy 322.414902 -398.567989)
			(xy 321.695615 -398.567989) (xy 321.687944 -398.615186) (xy 321.67236 -398.661867) (xy 321.649489 -398.705444)
			(xy 321.619924 -398.744788) (xy 321.584431 -398.77888) (xy 321.543928 -398.806836) (xy 321.499466 -398.827934)
			(xy 321.452195 -398.841626) (xy 321.40334 -398.847558) (xy 321.354165 -398.845577) (xy 321.305946 -398.835733)
			(xy 321.25993 -398.818281) (xy 321.217309 -398.793674) (xy 321.179188 -398.762549) (xy 321.146553 -398.725712)
			(xy 321.12025 -398.684116) (xy 321.100959 -398.63884) (xy 321.089182 -398.591056) (xy 321.085222 -398.542002)
			(xy 320.496438 -398.542002) (xy 320.495943 -398.566609) (xy 320.488048 -398.615186) (xy 320.472464 -398.661867)
			(xy 320.449593 -398.705444) (xy 320.420028 -398.744788) (xy 320.384535 -398.77888) (xy 320.344032 -398.806836)
			(xy 320.29957 -398.827934) (xy 320.252299 -398.841626) (xy 320.203444 -398.847558) (xy 320.154269 -398.845577)
			(xy 320.10605 -398.835733) (xy 320.060034 -398.818281) (xy 320.017413 -398.793674) (xy 319.979292 -398.762549)
			(xy 319.946657 -398.725712) (xy 319.920354 -398.684116) (xy 319.901063 -398.63884) (xy 319.889286 -398.591056)
			(xy 319.885326 -398.542002) (xy 319.296288 -398.542002) (xy 319.295793 -398.566609) (xy 319.287898 -398.615186)
			(xy 319.272314 -398.661867) (xy 319.249443 -398.705444) (xy 319.219878 -398.744788) (xy 319.184385 -398.77888)
			(xy 319.143882 -398.806836) (xy 319.09942 -398.827934) (xy 319.052149 -398.841626) (xy 319.003294 -398.847558)
			(xy 318.954119 -398.845577) (xy 318.9059 -398.835733) (xy 318.859884 -398.818281) (xy 318.817263 -398.793674)
			(xy 318.779142 -398.762549) (xy 318.746507 -398.725712) (xy 318.720204 -398.684116) (xy 318.700913 -398.63884)
			(xy 318.689136 -398.591056) (xy 318.685176 -398.542002) (xy 318.096392 -398.542002) (xy 318.095897 -398.566609)
			(xy 318.088002 -398.615186) (xy 318.072418 -398.661867) (xy 318.049547 -398.705444) (xy 318.019982 -398.744788)
			(xy 317.984489 -398.77888) (xy 317.943986 -398.806836) (xy 317.899524 -398.827934) (xy 317.852253 -398.841626)
			(xy 317.803398 -398.847558) (xy 317.754223 -398.845577) (xy 317.706004 -398.835733) (xy 317.659988 -398.818281)
			(xy 317.617367 -398.793674) (xy 317.579246 -398.762549) (xy 317.546611 -398.725712) (xy 317.520308 -398.684116)
			(xy 317.501017 -398.63884) (xy 317.48924 -398.591056) (xy 317.48528 -398.542002) (xy 316.896242 -398.542002)
			(xy 316.895747 -398.566609) (xy 316.887852 -398.615186) (xy 316.872268 -398.661867) (xy 316.849397 -398.705444)
			(xy 316.819832 -398.744788) (xy 316.784339 -398.77888) (xy 316.743836 -398.806836) (xy 316.699374 -398.827934)
			(xy 316.652103 -398.841626) (xy 316.603248 -398.847558) (xy 316.554073 -398.845577) (xy 316.505854 -398.835733)
			(xy 316.459838 -398.818281) (xy 316.417217 -398.793674) (xy 316.379096 -398.762549) (xy 316.346461 -398.725712)
			(xy 316.320158 -398.684116) (xy 316.300867 -398.63884) (xy 316.28909 -398.591056) (xy 316.28513 -398.542002)
			(xy 315.696346 -398.542002) (xy 315.695851 -398.566609) (xy 315.687956 -398.615186) (xy 315.672372 -398.661867)
			(xy 315.649501 -398.705444) (xy 315.619936 -398.744788) (xy 315.584443 -398.77888) (xy 315.54394 -398.806836)
			(xy 315.499478 -398.827934) (xy 315.452207 -398.841626) (xy 315.403352 -398.847558) (xy 315.354177 -398.845577)
			(xy 315.305958 -398.835733) (xy 315.259942 -398.818281) (xy 315.217321 -398.793674) (xy 315.1792 -398.762549)
			(xy 315.146565 -398.725712) (xy 315.120262 -398.684116) (xy 315.100971 -398.63884) (xy 315.089194 -398.591056)
			(xy 315.085234 -398.542002) (xy 314.49645 -398.542002) (xy 314.495955 -398.566609) (xy 314.48806 -398.615186)
			(xy 314.472476 -398.661867) (xy 314.449605 -398.705444) (xy 314.42004 -398.744788) (xy 314.384547 -398.77888)
			(xy 314.344044 -398.806836) (xy 314.299582 -398.827934) (xy 314.252311 -398.841626) (xy 314.203456 -398.847558)
			(xy 314.154281 -398.845577) (xy 314.106062 -398.835733) (xy 314.060046 -398.818281) (xy 314.017425 -398.793674)
			(xy 313.979304 -398.762549) (xy 313.946669 -398.725712) (xy 313.920366 -398.684116) (xy 313.901075 -398.63884)
			(xy 313.889298 -398.591056) (xy 313.885338 -398.542002) (xy 313.2963 -398.542002) (xy 313.295805 -398.566609)
			(xy 313.28791 -398.615186) (xy 313.272326 -398.661867) (xy 313.249455 -398.705444) (xy 313.21989 -398.744788)
			(xy 313.184397 -398.77888) (xy 313.143894 -398.806836) (xy 313.099432 -398.827934) (xy 313.052161 -398.841626)
			(xy 313.003306 -398.847558) (xy 312.954131 -398.845577) (xy 312.905912 -398.835733) (xy 312.859896 -398.818281)
			(xy 312.817275 -398.793674) (xy 312.779154 -398.762549) (xy 312.746519 -398.725712) (xy 312.720216 -398.684116)
			(xy 312.700925 -398.63884) (xy 312.689148 -398.591056) (xy 312.685188 -398.542002) (xy 312.096404 -398.542002)
			(xy 312.095909 -398.566609) (xy 312.088014 -398.615186) (xy 312.07243 -398.661867) (xy 312.049559 -398.705444)
			(xy 312.019994 -398.744788) (xy 311.984501 -398.77888) (xy 311.943998 -398.806836) (xy 311.899536 -398.827934)
			(xy 311.852265 -398.841626) (xy 311.80341 -398.847558) (xy 311.754235 -398.845577) (xy 311.706016 -398.835733)
			(xy 311.66 -398.818281) (xy 311.617379 -398.793674) (xy 311.579258 -398.762549) (xy 311.546623 -398.725712)
			(xy 311.52032 -398.684116) (xy 311.501029 -398.63884) (xy 311.489252 -398.591056) (xy 311.485292 -398.542002)
			(xy 310.896254 -398.542002) (xy 310.895759 -398.566609) (xy 310.887864 -398.615186) (xy 310.87228 -398.661867)
			(xy 310.849409 -398.705444) (xy 310.819844 -398.744788) (xy 310.784351 -398.77888) (xy 310.743848 -398.806836)
			(xy 310.699386 -398.827934) (xy 310.652115 -398.841626) (xy 310.60326 -398.847558) (xy 310.554085 -398.845577)
			(xy 310.505866 -398.835733) (xy 310.45985 -398.818281) (xy 310.417229 -398.793674) (xy 310.379108 -398.762549)
			(xy 310.346473 -398.725712) (xy 310.32017 -398.684116) (xy 310.300879 -398.63884) (xy 310.289102 -398.591056)
			(xy 310.285142 -398.542002) (xy 309.696358 -398.542002) (xy 309.695863 -398.566609) (xy 309.687968 -398.615186)
			(xy 309.672384 -398.661867) (xy 309.649513 -398.705444) (xy 309.619948 -398.744788) (xy 309.584455 -398.77888)
			(xy 309.543952 -398.806836) (xy 309.49949 -398.827934) (xy 309.452219 -398.841626) (xy 309.403364 -398.847558)
			(xy 309.354189 -398.845577) (xy 309.30597 -398.835733) (xy 309.259954 -398.818281) (xy 309.217333 -398.793674)
			(xy 309.179212 -398.762549) (xy 309.146577 -398.725712) (xy 309.120274 -398.684116) (xy 309.100983 -398.63884)
			(xy 309.089206 -398.591056) (xy 309.085246 -398.542002) (xy 308.496462 -398.542002) (xy 308.495967 -398.566609)
			(xy 308.488072 -398.615186) (xy 308.472488 -398.661867) (xy 308.449617 -398.705444) (xy 308.420052 -398.744788)
			(xy 308.384559 -398.77888) (xy 308.344056 -398.806836) (xy 308.299594 -398.827934) (xy 308.252323 -398.841626)
			(xy 308.203468 -398.847558) (xy 308.154293 -398.845577) (xy 308.106074 -398.835733) (xy 308.060058 -398.818281)
			(xy 308.017437 -398.793674) (xy 307.979316 -398.762549) (xy 307.946681 -398.725712) (xy 307.920378 -398.684116)
			(xy 307.901087 -398.63884) (xy 307.88931 -398.591056) (xy 307.88535 -398.542002) (xy 307.296312 -398.542002)
			(xy 307.295817 -398.566609) (xy 307.287922 -398.615186) (xy 307.272338 -398.661867) (xy 307.249467 -398.705444)
			(xy 307.219902 -398.744788) (xy 307.184409 -398.77888) (xy 307.143906 -398.806836) (xy 307.099444 -398.827934)
			(xy 307.052173 -398.841626) (xy 307.003318 -398.847558) (xy 306.954143 -398.845577) (xy 306.905924 -398.835733)
			(xy 306.859908 -398.818281) (xy 306.817287 -398.793674) (xy 306.779166 -398.762549) (xy 306.746531 -398.725712)
			(xy 306.720228 -398.684116) (xy 306.700937 -398.63884) (xy 306.68916 -398.591056) (xy 306.6852 -398.542002)
			(xy 306.096416 -398.542002) (xy 306.095921 -398.566609) (xy 306.088026 -398.615186) (xy 306.072442 -398.661867)
			(xy 306.049571 -398.705444) (xy 306.020006 -398.744788) (xy 305.984513 -398.77888) (xy 305.94401 -398.806836)
			(xy 305.899548 -398.827934) (xy 305.852277 -398.841626) (xy 305.803422 -398.847558) (xy 305.754247 -398.845577)
			(xy 305.706028 -398.835733) (xy 305.660012 -398.818281) (xy 305.617391 -398.793674) (xy 305.57927 -398.762549)
			(xy 305.546635 -398.725712) (xy 305.520332 -398.684116) (xy 305.501041 -398.63884) (xy 305.489264 -398.591056)
			(xy 305.485304 -398.542002) (xy 304.896266 -398.542002) (xy 304.895771 -398.566609) (xy 304.887876 -398.615186)
			(xy 304.872292 -398.661867) (xy 304.849421 -398.705444) (xy 304.819856 -398.744788) (xy 304.784363 -398.77888)
			(xy 304.74386 -398.806836) (xy 304.699398 -398.827934) (xy 304.652127 -398.841626) (xy 304.603272 -398.847558)
			(xy 304.554097 -398.845577) (xy 304.505878 -398.835733) (xy 304.459862 -398.818281) (xy 304.417241 -398.793674)
			(xy 304.37912 -398.762549) (xy 304.346485 -398.725712) (xy 304.320182 -398.684116) (xy 304.300891 -398.63884)
			(xy 304.289114 -398.591056) (xy 304.285154 -398.542002) (xy 303.696116 -398.542002) (xy 303.695621 -398.566609)
			(xy 303.687726 -398.615186) (xy 303.672142 -398.661867) (xy 303.649271 -398.705444) (xy 303.619706 -398.744788)
			(xy 303.584213 -398.77888) (xy 303.54371 -398.806836) (xy 303.499248 -398.827934) (xy 303.451977 -398.841626)
			(xy 303.403122 -398.847558) (xy 303.353947 -398.845577) (xy 303.305728 -398.835733) (xy 303.259712 -398.818281)
			(xy 303.217091 -398.793674) (xy 303.17897 -398.762549) (xy 303.146335 -398.725712) (xy 303.120032 -398.684116)
			(xy 303.100741 -398.63884) (xy 303.088964 -398.591056) (xy 303.085004 -398.542002) (xy 301.410187 -398.542002)
			(xy 301.404074 -398.563186) (xy 301.385067 -398.605591) (xy 301.360309 -398.644916) (xy 301.3456 -398.662906)
			(xy 301.339504 -398.670018) (xy 301.333408 -398.686528) (xy 301.333408 -398.770856) (xy 301.339504 -398.787366)
			(xy 301.3456 -398.794478) (xy 301.360313 -398.812464) (xy 301.385058 -398.851794) (xy 301.404057 -398.894201)
			(xy 301.416935 -398.938848) (xy 301.423438 -398.984858) (xy 301.423832 -399.008092) (xy 301.423416 -399.032184)
			(xy 301.416437 -399.079862) (xy 301.402627 -399.126025) (xy 301.392844 -399.148046) (xy 301.38751 -399.159476)
			(xy 301.38878 -399.184622) (xy 301.444914 -399.278602) (xy 301.466504 -399.291556) (xy 301.479204 -399.292318)
			(xy 301.504203 -399.294126) (xy 301.553249 -399.304464) (xy 301.600173 -399.322083) (xy 301.643901 -399.346581)
			(xy 301.683433 -399.377396) (xy 301.717863 -399.413822) (xy 301.746403 -399.455026) (xy 301.7684 -399.500065)
			(xy 301.783349 -399.547907) (xy 301.790908 -399.597456) (xy 301.79137 -399.622518) (xy 301.79086 -399.648505)
			(xy 301.78273 -399.69984) (xy 301.766669 -399.74927) (xy 301.743073 -399.79558) (xy 301.712523 -399.837628)
			(xy 301.675772 -399.874379) (xy 301.633724 -399.904929) (xy 301.587414 -399.928525) (xy 301.537984 -399.944586)
			(xy 301.486649 -399.952716) (xy 301.434675 -399.952716) (xy 301.38334 -399.944586) (xy 301.33391 -399.928525)
			(xy 301.2876 -399.904929) (xy 301.245552 -399.874379) (xy 301.208801 -399.837628) (xy 301.178251 -399.79558)
			(xy 301.154655 -399.74927) (xy 301.138594 -399.69984) (xy 301.130464 -399.648505) (xy 301.129954 -399.622518)
			(xy 301.130375 -399.598426) (xy 301.137352 -399.550749) (xy 301.15116 -399.504585) (xy 301.160942 -399.482564)
			(xy 301.166276 -399.471134) (xy 301.165006 -399.445988) (xy 301.108872 -399.352008) (xy 301.087282 -399.339054)
			(xy 301.074582 -399.338292) (xy 301.04959 -399.3364) (xy 301.000547 -399.326075) (xy 300.953625 -399.308467)
			(xy 300.909896 -399.283981) (xy 300.870363 -399.253176) (xy 300.835932 -399.216758) (xy 300.80739 -399.175562)
			(xy 300.785391 -399.13053) (xy 300.77044 -399.082695) (xy 300.762878 -399.033151) (xy 300.762416 -399.008092)
			(xy 297.64228 -399.008092) (xy 297.64228 -399.128488) (xy 297.642787 -399.139568) (xy 297.652016 -399.159711)
			(xy 297.66006 -399.16735) (xy 297.727624 -399.224754) (xy 297.74896 -399.230596) (xy 297.760136 -399.228818)
			(xy 297.77521 -399.226551) (xy 297.805599 -399.224136) (xy 297.820842 -399.223992) (xy 297.848091 -399.224481)
			(xy 297.902034 -399.232242) (xy 297.954324 -399.247601) (xy 298.003896 -399.270244) (xy 298.049741 -399.299712)
			(xy 298.090926 -399.335403) (xy 298.126613 -399.376592) (xy 298.156076 -399.422441) (xy 298.178714 -399.472015)
			(xy 298.194067 -399.524307) (xy 298.201822 -399.578251) (xy 298.201822 -399.632749) (xy 298.194067 -399.686693)
			(xy 298.178714 -399.738985) (xy 298.156076 -399.788559) (xy 298.126613 -399.834408) (xy 298.090926 -399.875597)
			(xy 298.049741 -399.911288) (xy 298.003896 -399.940756) (xy 297.954324 -399.963399) (xy 297.902034 -399.978758)
			(xy 297.848091 -399.986519) (xy 297.820842 -399.987008) (xy 297.805599 -399.986867) (xy 297.77521 -399.984447)
			(xy 297.760136 -399.982182) (xy 297.74896 -399.980404) (xy 297.727624 -399.986246) (xy 297.66006 -400.04365)
			(xy 297.651994 -400.051273) (xy 297.64276 -400.071426) (xy 297.64228 -400.082512) (xy 297.64228 -400.524218)
			(xy 297.642706 -400.534287) (xy 297.650423 -400.552889) (xy 297.657266 -400.560286) (xy 299.021754 -401.924774)
			(xy 299.052742 -401.930616) (xy 299.066966 -401.924012) (xy 299.091467 -401.913647) (xy 299.14262 -401.899038)
			(xy 299.195307 -401.891677) (xy 299.221906 -401.891246) (xy 299.249158 -401.891732) (xy 299.303108 -401.899489)
			(xy 299.355404 -401.914844) (xy 299.404984 -401.937485) (xy 299.450837 -401.966951) (xy 299.49203 -402.002642)
			(xy 299.527725 -402.043831) (xy 299.557196 -402.089681) (xy 299.579842 -402.139258) (xy 299.595202 -402.191553)
			(xy 299.602965 -402.245502) (xy 299.603414 -402.272754) (xy 299.602938 -402.300123) (xy 299.595108 -402.354297)
			(xy 299.579615 -402.406797) (xy 299.556779 -402.456543) (xy 299.527067 -402.502516) (xy 299.509434 -402.523452)
			(xy 299.503338 -402.530564) (xy 299.496988 -402.547582) (xy 299.496988 -402.632926) (xy 299.503338 -402.649944)
			(xy 299.509434 -402.657056) (xy 299.511212 -402.659088) (xy 299.518769 -402.66699) (xy 299.538645 -402.676052)
			(xy 299.549566 -402.676614) (xy 299.626782 -402.676614) (xy 299.637711 -402.676094) (xy 299.657593 -402.667013)
			(xy 299.665136 -402.659088) (xy 299.68334 -402.638632) (xy 299.724603 -402.602634) (xy 299.770588 -402.572904)
			(xy 299.82035 -402.550053) (xy 299.872868 -402.53455) (xy 299.927063 -402.526714) (xy 299.954442 -402.526246)
			(xy 299.981692 -402.526735) (xy 300.035638 -402.534496) (xy 300.08793 -402.549854) (xy 300.137505 -402.572497)
			(xy 300.183354 -402.601964) (xy 300.224543 -402.637654) (xy 300.260234 -402.678843) (xy 300.289701 -402.724691)
			(xy 300.312345 -402.774266) (xy 300.327703 -402.826558) (xy 300.335465 -402.880504) (xy 300.33595 -402.907754)
			(xy 300.335474 -402.935122) (xy 300.327643 -402.989296) (xy 300.312148 -403.041794) (xy 300.289309 -403.091538)
			(xy 300.259594 -403.137507) (xy 300.24197 -403.158452) (xy 300.235874 -403.165564) (xy 300.229524 -403.182582)
			(xy 300.229524 -403.267926) (xy 300.235874 -403.284944) (xy 300.24197 -403.292056) (xy 300.25961 -403.312988)
			(xy 300.289332 -403.358955) (xy 300.312169 -403.408702) (xy 300.327653 -403.461206) (xy 300.335464 -403.515384)
			(xy 300.33595 -403.542754) (xy 300.33549 -403.57001) (xy 300.327739 -403.623968) (xy 300.312387 -403.676274)
			(xy 300.289748 -403.725863) (xy 300.260282 -403.771725) (xy 300.224589 -403.812926) (xy 300.183395 -403.848629)
			(xy 300.13754 -403.878106) (xy 300.087957 -403.900756) (xy 300.035654 -403.91612) (xy 299.981698 -403.923884)
			(xy 299.954442 -403.924262) (xy 299.927062 -403.923792) (xy 299.872865 -403.915966) (xy 299.820344 -403.900468)
			(xy 299.770579 -403.877618) (xy 299.724595 -403.847885) (xy 299.683336 -403.811881) (xy 299.665136 -403.79142)
			(xy 299.657582 -403.783509) (xy 299.637707 -403.774427) (xy 299.626782 -403.773894) (xy 299.549566 -403.773894)
			(xy 299.538633 -403.774405) (xy 299.518737 -403.783475) (xy 299.511212 -403.79142) (xy 299.492973 -403.811906)
			(xy 299.451631 -403.847953) (xy 299.405558 -403.877715) (xy 299.355701 -403.900581) (xy 299.303086 -403.91608)
			(xy 299.276008 -403.920452) (xy 299.256958 -403.923246) (xy 299.23232 -403.95144) (xy 299.23232 -404.751286)
			(xy 299.257974 -404.780242) (xy 299.277532 -404.782274) (xy 299.308265 -404.78612) (xy 299.368552 -404.800324)
			(xy 299.426667 -404.821747) (xy 299.481749 -404.85007) (xy 299.532983 -404.884874) (xy 299.579611 -404.925644)
			(xy 299.620941 -404.971775) (xy 299.656361 -405.022586) (xy 299.685347 -405.077322) (xy 299.70747 -405.135174)
			(xy 299.722401 -405.195285) (xy 299.72992 -405.256765) (xy 299.730414 -405.287734) (xy 299.729933 -405.318429)
			(xy 299.72251 -405.379368) (xy 299.70781 -405.438972) (xy 299.686048 -405.496376) (xy 299.65754 -405.550745)
			(xy 299.640498 -405.576278) (xy 299.635033 -405.58503) (xy 299.630917 -405.605228) (xy 299.635055 -405.625422)
			(xy 299.640498 -405.63419) (xy 299.657553 -405.659717) (xy 299.686082 -405.71408) (xy 299.707852 -405.771483)
			(xy 299.722547 -405.831092) (xy 299.729953 -405.892037) (xy 299.730414 -405.922734) (xy 299.729933 -405.953429)
			(xy 299.72251 -406.014368) (xy 299.70781 -406.073972) (xy 299.686048 -406.131376) (xy 299.65754 -406.185745)
			(xy 299.640498 -406.211278) (xy 299.635033 -406.22003) (xy 299.630917 -406.240228) (xy 299.635055 -406.260422)
			(xy 299.640498 -406.26919) (xy 299.657553 -406.294717) (xy 299.686082 -406.34908) (xy 299.707852 -406.406483)
			(xy 299.722547 -406.466092) (xy 299.729953 -406.527037) (xy 299.730414 -406.557734) (xy 299.729834 -406.59263)
			(xy 299.720282 -406.661764) (xy 299.70136 -406.728942) (xy 299.673426 -406.7929) (xy 299.637005 -406.852434)
			(xy 299.615352 -406.879806) (xy 299.609174 -406.888071) (xy 299.603428 -406.90787) (xy 299.605985 -406.928326)
			(xy 299.61078 -406.937464) (xy 299.62713 -406.966647) (xy 299.652873 -407.028389) (xy 299.670294 -407.092974)
			(xy 299.679092 -407.159287) (xy 299.679614 -407.192734) (xy 299.679129 -407.224389) (xy 299.671266 -407.287208)
			(xy 299.655665 -407.348566) (xy 299.632569 -407.407512) (xy 299.602334 -407.463135) (xy 299.565428 -407.514575)
			(xy 299.522421 -407.561036) (xy 299.47398 -407.601798) (xy 299.420854 -407.636232) (xy 299.363864 -407.663805)
			(xy 299.303892 -407.68409) (xy 299.27296 -407.690828) (xy 299.254926 -407.694638) (xy 299.23232 -407.722324)
			(xy 299.23232 -409.183078) (xy 299.232758 -409.193141) (xy 299.240494 -409.211723) (xy 299.247306 -409.219146)
			(xy 299.304456 -409.276296) (xy 299.312838 -409.280106) (xy 299.417702 -409.327934) (xy 299.622666 -409.433401)
			(xy 299.72254 -409.490926) (xy 299.728476 -409.494095) (xy 299.741469 -409.497571) (xy 299.748194 -409.497784)
		)
		(stroke
			(width 0)
			(type solid)
		)
		(fill yes)
		(layer "In15.Cu")
		(net "P0V9_CPU0_RT0_2A_2D")
	)
	(gr_poly
		(pts
			(xy 352.749358 -407.34234) (xy 352.759422 -407.341905) (xy 352.778006 -407.334169) (xy 352.785426 -407.327354)
			(xy 354.618036 -405.494744) (xy 354.625982 -405.485987) (xy 354.633513 -405.463603) (xy 354.632514 -405.451818)
			(xy 354.619814 -405.35987) (xy 354.606606 -405.340312) (xy 354.596192 -405.334216) (xy 354.567144 -405.317252)
			(xy 354.513378 -405.276827) (xy 354.465414 -405.229663) (xy 354.424089 -405.176584) (xy 354.390128 -405.118518)
			(xy 354.364121 -405.05648) (xy 354.346526 -404.991554) (xy 354.337647 -404.924874) (xy 354.337112 -404.89124)
			(xy 354.337555 -404.860507) (xy 354.34496 -404.799488) (xy 354.359666 -404.739807) (xy 354.38146 -404.682334)
			(xy 354.410022 -404.627907) (xy 354.444937 -404.577319) (xy 354.485696 -404.53131) (xy 354.531704 -404.49055)
			(xy 354.582289 -404.455633) (xy 354.636715 -404.427068) (xy 354.694188 -404.405272) (xy 354.753868 -404.390564)
			(xy 354.814887 -404.383157) (xy 354.84562 -404.382732) (xy 354.868988 -404.38324) (xy 354.879402 -404.383748)
			(xy 354.898706 -404.376636) (xy 354.959412 -404.31847) (xy 354.966536 -404.311047) (xy 354.974665 -404.29217)
			(xy 354.97516 -404.281894) (xy 354.97516 -402.260562) (xy 354.95738 -402.234654) (xy 354.942648 -402.229066)
			(xy 354.926562 -402.222563) (xy 354.895528 -402.207042) (xy 354.880672 -402.198078) (xy 354.868734 -402.190712)
			(xy 354.841556 -402.190204) (xy 354.739702 -402.2471) (xy 354.725986 -402.270722) (xy 354.725732 -402.284692)
			(xy 354.725223 -402.312094) (xy 354.717386 -402.366335) (xy 354.701915 -402.41891) (xy 354.679122 -402.46875)
			(xy 354.649471 -402.514841) (xy 354.613567 -402.556247) (xy 354.572138 -402.592124) (xy 354.526027 -402.621744)
			(xy 354.476172 -402.644503) (xy 354.423587 -402.659941) (xy 354.36934 -402.667741) (xy 354.341938 -402.668232)
			(xy 354.314521 -402.667746) (xy 354.260244 -402.659947) (xy 354.207629 -402.644504) (xy 354.157747 -402.62173)
			(xy 354.111615 -402.592088) (xy 354.07017 -402.556184) (xy 354.034257 -402.514746) (xy 354.004607 -402.468619)
			(xy 353.981823 -402.418742) (xy 353.966369 -402.366131) (xy 353.95856 -402.311855) (xy 353.958144 -402.284438)
			(xy 353.958624 -402.25616) (xy 353.966882 -402.200211) (xy 353.983268 -402.146081) (xy 354.007427 -402.094945)
			(xy 354.038835 -402.047913) (xy 354.057458 -402.026628) (xy 354.063425 -402.019479) (xy 354.07019 -402.002147)
			(xy 354.070666 -401.992846) (xy 354.07092 -401.961604) (xy 354.070602 -401.95225) (xy 354.06394 -401.934773)
			(xy 354.057966 -401.927568) (xy 354.040041 -401.906529) (xy 354.009807 -401.860262) (xy 353.98655 -401.810124)
			(xy 353.970753 -401.757159) (xy 353.962747 -401.702472) (xy 353.962208 -401.674838) (xy 353.962208 -400.811238)
			(xy 353.962651 -400.784879) (xy 353.969906 -400.732664) (xy 353.984283 -400.681946) (xy 354.005509 -400.633691)
			(xy 354.033178 -400.588819) (xy 354.066764 -400.548185) (xy 354.085906 -400.53006) (xy 354.093018 -400.52371)
			(xy 354.101146 -400.506946) (xy 354.109528 -400.420332) (xy 354.104448 -400.402552) (xy 354.09886 -400.394678)
			(xy 354.084702 -400.374833) (xy 354.062215 -400.331585) (xy 354.046897 -400.28531) (xy 354.039138 -400.237186)
			(xy 354.038662 -400.212814) (xy 354.039184 -400.187559) (xy 354.047497 -400.137737) (xy 354.063898 -400.089963)
			(xy 354.087939 -400.04554) (xy 354.118963 -400.00568) (xy 354.156125 -399.97147) (xy 354.198411 -399.943844)
			(xy 354.244667 -399.923554) (xy 354.293632 -399.911154) (xy 354.34397 -399.906983) (xy 354.394308 -399.911154)
			(xy 354.443273 -399.923554) (xy 354.489529 -399.943844) (xy 354.531815 -399.97147) (xy 354.568977 -400.00568)
			(xy 354.600001 -400.04554) (xy 354.624042 -400.089963) (xy 354.640443 -400.137737) (xy 354.648756 -400.187559)
			(xy 354.649278 -400.212814) (xy 354.64878 -400.237184) (xy 354.641001 -400.2853) (xy 354.62569 -400.331574)
			(xy 354.603234 -400.374834) (xy 354.58908 -400.394678) (xy 354.583492 -400.402552) (xy 354.578412 -400.420332)
			(xy 354.586794 -400.506946) (xy 354.594922 -400.52371) (xy 354.602034 -400.53006) (xy 354.621158 -400.548202)
			(xy 354.654732 -400.588838) (xy 354.682394 -400.633709) (xy 354.703618 -400.68196) (xy 354.717998 -400.732673)
			(xy 354.725261 -400.784882) (xy 354.725732 -400.811238) (xy 354.725732 -401.461986) (xy 354.726072 -401.470976)
			(xy 354.732272 -401.487852) (xy 354.743943 -401.501529) (xy 354.75164 -401.506182) (xy 354.841048 -401.55622)
			(xy 354.868734 -401.555712) (xy 354.880418 -401.548346) (xy 354.895335 -401.539373) (xy 354.926498 -401.523855)
			(xy 354.942648 -401.517358) (xy 354.95738 -401.51177) (xy 354.97516 -401.485862) (xy 354.97516 -398.686528)
			(xy 354.970842 -398.676622) (xy 354.961763 -398.655354) (xy 354.948978 -398.610914) (xy 354.942529 -398.565123)
			(xy 354.94214 -398.542002) (xy 354.942568 -398.518885) (xy 354.949043 -398.473105) (xy 354.961812 -398.428667)
			(xy 354.970842 -398.407382) (xy 354.97516 -398.397476) (xy 354.97516 -398.236694) (xy 354.974473 -398.224251)
			(xy 354.962761 -398.202283) (xy 354.952808 -398.194784) (xy 354.872798 -398.140428) (xy 354.847652 -398.137634)
			(xy 354.835968 -398.14246) (xy 354.807824 -398.152885) (xy 354.748879 -398.164128) (xy 354.718874 -398.164812)
			(xy 354.693481 -398.164302) (xy 354.643352 -398.156168) (xy 354.595171 -398.140115) (xy 354.550181 -398.116555)
			(xy 354.509543 -398.086098) (xy 354.474304 -398.049528) (xy 354.445374 -398.007788) (xy 354.423498 -397.961956)
			(xy 354.415852 -397.937736) (xy 354.414328 -397.931894) (xy 354.094034 -397.378174) (xy 354.08997 -397.373856)
			(xy 354.073782 -397.356146) (xy 354.04641 -397.316743) (xy 354.025323 -397.273647) (xy 354.011007 -397.227854)
			(xy 354.003794 -397.180422) (xy 354.003356 -397.156432) (xy 354.003442 -397.144384) (xy 354.005225 -397.120355)
			(xy 354.006912 -397.108426) (xy 354.008182 -397.099536) (xy 354.005134 -397.082518) (xy 353.96297 -397.011652)
			(xy 353.949762 -397.000476) (xy 353.94138 -396.997428) (xy 353.918321 -396.988496) (xy 353.875215 -396.964271)
			(xy 353.836569 -396.933424) (xy 353.803392 -396.896759) (xy 353.776548 -396.855232) (xy 353.756738 -396.809926)
			(xy 353.750118 -396.7861) (xy 353.7458 -396.769082) (xy 353.718622 -396.748) (xy 353.40163 -396.748)
			(xy 353.391453 -396.748448) (xy 353.372699 -396.756356) (xy 353.3585 -396.770939) (xy 353.354386 -396.780258)
			(xy 353.314 -396.883382) (xy 353.321112 -396.913608) (xy 353.332796 -396.924276) (xy 353.353476 -396.944185)
			(xy 353.387971 -396.990061) (xy 353.413621 -397.041409) (xy 353.422204 -397.068802) (xy 353.423728 -397.074644)
			(xy 353.743514 -397.627602) (xy 353.747578 -397.63192) (xy 353.763769 -397.649628) (xy 353.791149 -397.68903)
			(xy 353.812243 -397.732125) (xy 353.826565 -397.777918) (xy 353.833783 -397.825353) (xy 353.834192 -397.849344)
			(xy 353.833703 -397.874132) (xy 353.825942 -397.923097) (xy 353.810617 -397.970245) (xy 353.788107 -398.014416)
			(xy 353.758964 -398.054523) (xy 353.723908 -398.089577) (xy 353.683799 -398.118717) (xy 353.639627 -398.141225)
			(xy 353.592478 -398.156546) (xy 353.543512 -398.164304) (xy 353.518724 -398.164812) (xy 353.493329 -398.164306)
			(xy 353.443194 -398.156179) (xy 353.395006 -398.14013) (xy 353.35001 -398.116574) (xy 353.309365 -398.086118)
			(xy 353.27412 -398.049547) (xy 353.245184 -398.007806) (xy 353.223304 -397.961971) (xy 353.215702 -397.937736)
			(xy 353.214178 -397.931894) (xy 352.89363 -397.377412) (xy 352.889566 -397.373094) (xy 352.873487 -397.355416)
			(xy 352.846299 -397.316118) (xy 352.825341 -397.273174) (xy 352.811091 -397.227562) (xy 352.803873 -397.180325)
			(xy 352.80346 -397.156432) (xy 352.803546 -397.144384) (xy 352.805329 -397.120355) (xy 352.807016 -397.108426)
			(xy 352.808286 -397.099536) (xy 352.805238 -397.082518) (xy 352.763074 -397.011652) (xy 352.749866 -397.000476)
			(xy 352.741484 -396.997428) (xy 352.718425 -396.988496) (xy 352.675318 -396.964271) (xy 352.636672 -396.933424)
			(xy 352.603494 -396.89676) (xy 352.57665 -396.855233) (xy 352.55684 -396.809927) (xy 352.550222 -396.7861)
			(xy 352.545904 -396.769082) (xy 352.518726 -396.748) (xy 352.20148 -396.748) (xy 352.191297 -396.748439)
			(xy 352.172527 -396.756337) (xy 352.158313 -396.770919) (xy 352.154236 -396.780258) (xy 352.11385 -396.883382)
			(xy 352.120962 -396.913608) (xy 352.132646 -396.924276) (xy 352.153237 -396.944084) (xy 352.187605 -396.989719)
			(xy 352.213204 -397.040792) (xy 352.2218 -397.06804) (xy 352.223324 -397.073882) (xy 352.543618 -397.627602)
			(xy 352.547682 -397.63192) (xy 352.563873 -397.649628) (xy 352.591253 -397.68903) (xy 352.612347 -397.732125)
			(xy 352.626668 -397.777919) (xy 352.633885 -397.825353) (xy 352.634296 -397.849344) (xy 352.633807 -397.874132)
			(xy 352.626046 -397.923097) (xy 352.610721 -397.970246) (xy 352.588211 -398.014417) (xy 352.559069 -398.054524)
			(xy 352.524012 -398.089579) (xy 352.483904 -398.118719) (xy 352.439731 -398.141227) (xy 352.392582 -398.156549)
			(xy 352.343616 -398.164308) (xy 352.318828 -398.164812) (xy 352.293433 -398.164306) (xy 352.243297 -398.15618)
			(xy 352.195109 -398.140131) (xy 352.150112 -398.116575) (xy 352.109467 -398.086119) (xy 352.074221 -398.049549)
			(xy 352.045285 -398.007808) (xy 352.023405 -397.961972) (xy 352.015806 -397.937736) (xy 352.014282 -397.931894)
			(xy 351.693988 -397.378174) (xy 351.689924 -397.373856) (xy 351.673707 -397.356158) (xy 351.646276 -397.316769)
			(xy 351.62513 -397.273677) (xy 351.610759 -397.227879) (xy 351.603495 -397.180432) (xy 351.603056 -397.156432)
			(xy 351.603214 -397.14438) (xy 351.605123 -397.120352) (xy 351.606866 -397.108426) (xy 351.608136 -397.099536)
			(xy 351.605088 -397.082518) (xy 351.562924 -397.011652) (xy 351.549716 -397.000476) (xy 351.541334 -396.997428)
			(xy 351.518278 -396.988493) (xy 351.475176 -396.964264) (xy 351.436536 -396.933415) (xy 351.403364 -396.896749)
			(xy 351.376525 -396.855222) (xy 351.356719 -396.809918) (xy 351.350072 -396.7861) (xy 351.345754 -396.769082)
			(xy 351.318576 -396.748) (xy 351.001584 -396.748) (xy 350.991401 -396.748438) (xy 350.97263 -396.756335)
			(xy 350.958414 -396.770918) (xy 350.95434 -396.780258) (xy 350.913954 -396.883382) (xy 350.921066 -396.913608)
			(xy 350.93275 -396.924276) (xy 350.953432 -396.944183) (xy 350.987932 -396.990058) (xy 351.013586 -397.041405)
			(xy 351.022158 -397.068802) (xy 351.023682 -397.074644) (xy 351.343468 -397.627602) (xy 351.347532 -397.63192)
			(xy 351.363747 -397.649619) (xy 351.391177 -397.689009) (xy 351.412322 -397.7321) (xy 351.426694 -397.777898)
			(xy 351.43396 -397.825344) (xy 351.4344 -397.849344) (xy 351.433935 -397.874147) (xy 351.426165 -397.923141)
			(xy 351.410824 -397.970315) (xy 351.38829 -398.014507) (xy 351.359117 -398.054629) (xy 351.324026 -398.08969)
			(xy 351.28388 -398.118829) (xy 351.239669 -398.141326) (xy 351.192482 -398.156627) (xy 351.143481 -398.164356)
			(xy 351.118678 -398.164812) (xy 351.093285 -398.164303) (xy 351.043155 -398.156169) (xy 350.994974 -398.140116)
			(xy 350.949983 -398.116557) (xy 350.909344 -398.0861) (xy 350.874105 -398.049529) (xy 350.845175 -398.00779)
			(xy 350.823299 -397.961957) (xy 350.815656 -397.937736) (xy 350.814132 -397.931894) (xy 350.493584 -397.377412)
			(xy 350.48952 -397.373094) (xy 350.473416 -397.355425) (xy 350.446178 -397.316139) (xy 350.425169 -397.273199)
			(xy 350.410868 -397.227583) (xy 350.403602 -397.180334) (xy 350.40316 -397.156432) (xy 350.403318 -397.14438)
			(xy 350.405227 -397.120352) (xy 350.40697 -397.108426) (xy 350.40824 -397.099536) (xy 350.405192 -397.082518)
			(xy 350.363028 -397.011652) (xy 350.34982 -397.000476) (xy 350.341438 -396.997428) (xy 350.3197 -396.98902)
			(xy 350.27886 -396.966564) (xy 350.241908 -396.938163) (xy 350.2097 -396.904476) (xy 350.182985 -396.866286)
			(xy 350.162384 -396.82448) (xy 350.148375 -396.780029) (xy 350.141283 -396.733965) (xy 350.140778 -396.710662)
			(xy 350.141261 -396.686127) (xy 350.149094 -396.637687) (xy 350.164569 -396.591121) (xy 350.187287 -396.547628)
			(xy 350.216665 -396.508324) (xy 350.233996 -396.490952) (xy 350.241362 -396.48384) (xy 350.24949 -396.465298)
			(xy 350.249998 -396.382494) (xy 350.249665 -396.372384) (xy 350.242078 -396.353649) (xy 350.235266 -396.346172)
			(xy 350.06788 -396.178786) (xy 350.061027 -396.171391) (xy 350.053285 -396.152792) (xy 350.052894 -396.142718)
			(xy 350.052894 -395.69644) (xy 350.052567 -395.688162) (xy 350.04724 -395.672488) (xy 350.04248 -395.665706)
			(xy 350.026712 -395.644019) (xy 350.001667 -395.596612) (xy 349.984598 -395.545785) (xy 349.975954 -395.49287)
			(xy 349.975424 -395.466062) (xy 349.976192 -395.434132) (xy 349.988469 -395.371461) (xy 349.999808 -395.341602)
			(xy 350.005396 -395.327378) (xy 349.999554 -395.29766) (xy 349.963486 -395.261592) (xy 349.956086 -395.254748)
			(xy 349.937489 -395.24702) (xy 349.927418 -395.246606) (xy 348.452948 -395.246606) (xy 348.441527 -395.24706)
			(xy 348.420891 -395.256837) (xy 348.413324 -395.265402) (xy 348.356428 -395.336014) (xy 348.351094 -395.358366)
			(xy 348.353634 -395.369542) (xy 348.358431 -395.393382) (xy 348.363518 -395.441746) (xy 348.363794 -395.466062)
			(xy 348.36319 -395.499382) (xy 348.353521 -395.565317) (xy 348.334396 -395.629154) (xy 348.320868 -395.65961)
			(xy 348.316606 -395.670079) (xy 348.31668 -395.692653) (xy 348.326436 -395.713011) (xy 348.334838 -395.72057)
			(xy 348.357085 -395.739244) (xy 348.397148 -395.7813) (xy 348.431569 -395.828087) (xy 348.459796 -395.878851)
			(xy 348.481373 -395.932779) (xy 348.495955 -395.989003) (xy 348.503308 -396.04662) (xy 348.503748 -396.075662)
			(xy 348.503297 -396.104666) (xy 348.495967 -396.16221) (xy 348.481432 -396.218368) (xy 348.459923 -396.272242)
			(xy 348.431786 -396.32297) (xy 348.397471 -396.369741) (xy 348.357526 -396.411805) (xy 348.335346 -396.4305)
			(xy 348.328234 -396.436088) (xy 348.31909 -396.451328) (xy 348.30385 -396.534132) (xy 348.306644 -396.551404)
			(xy 348.311216 -396.559532) (xy 348.323809 -396.582711) (xy 348.341695 -396.632331) (xy 348.350776 -396.684289)
			(xy 348.351348 -396.710662) (xy 348.940628 -396.710662) (xy 348.94115 -396.685407) (xy 348.949463 -396.635585)
			(xy 348.965864 -396.587811) (xy 348.989905 -396.543388) (xy 349.020929 -396.503528) (xy 349.058091 -396.469318)
			(xy 349.100377 -396.441692) (xy 349.146633 -396.421402) (xy 349.195598 -396.409002) (xy 349.245936 -396.404831)
			(xy 349.296274 -396.409002) (xy 349.345239 -396.421402) (xy 349.391495 -396.441692) (xy 349.433781 -396.469318)
			(xy 349.470943 -396.503528) (xy 349.501967 -396.543388) (xy 349.526008 -396.587811) (xy 349.542409 -396.635585)
			(xy 349.550722 -396.685407) (xy 349.551244 -396.710662) (xy 349.551175 -396.720021) (xy 349.550032 -396.738703)
			(xy 349.548958 -396.748) (xy 349.547942 -396.75689) (xy 349.551752 -396.773654) (xy 349.595694 -396.843504)
			(xy 349.60941 -396.853918) (xy 349.617792 -396.856712) (xy 349.641811 -396.865205) (xy 349.686984 -396.888752)
			(xy 349.727791 -396.919245) (xy 349.763172 -396.955896) (xy 349.79221 -396.997751) (xy 349.81415 -397.043726)
			(xy 349.821754 -397.06804) (xy 349.823278 -397.073882) (xy 350.143572 -397.627602) (xy 350.147636 -397.63192)
			(xy 350.163834 -397.649633) (xy 350.191258 -397.689023) (xy 350.212401 -397.732112) (xy 350.226776 -397.777904)
			(xy 350.234052 -397.825346) (xy 350.234504 -397.849344) (xy 350.234047 -397.874148) (xy 350.226277 -397.923143)
			(xy 350.210936 -397.970319) (xy 350.188401 -398.014512) (xy 350.159228 -398.054635) (xy 350.124135 -398.089698)
			(xy 350.083988 -398.118838) (xy 350.039776 -398.141336) (xy 349.992588 -398.156638) (xy 349.943586 -398.164367)
			(xy 349.918782 -398.164812) (xy 349.893387 -398.164327) (xy 349.843253 -398.156194) (xy 349.795067 -398.14014)
			(xy 349.750072 -398.116579) (xy 349.70943 -398.08612) (xy 349.674187 -398.049547) (xy 349.645254 -398.007804)
			(xy 349.623376 -397.961967) (xy 349.61576 -397.937736) (xy 349.614236 -397.931894) (xy 349.293942 -397.378174)
			(xy 349.289878 -397.373856) (xy 349.273723 -397.356118) (xy 349.246353 -397.316718) (xy 349.225261 -397.273629)
			(xy 349.210933 -397.227845) (xy 349.203698 -397.180419) (xy 349.203264 -397.156432) (xy 349.203344 -397.144384)
			(xy 349.205127 -397.120355) (xy 349.20682 -397.108426) (xy 349.20809 -397.099536) (xy 349.205042 -397.082518)
			(xy 349.162878 -397.011652) (xy 349.14967 -397.000476) (xy 349.141288 -396.997428) (xy 349.119544 -396.989023)
			(xy 349.078685 -396.966584) (xy 349.041714 -396.938193) (xy 349.00949 -396.904509) (xy 348.982764 -396.866316)
			(xy 348.962158 -396.824504) (xy 348.94815 -396.780043) (xy 348.941066 -396.73397) (xy 348.940628 -396.710662)
			(xy 348.351348 -396.710662) (xy 348.351276 -396.72002) (xy 348.35013 -396.738702) (xy 348.349062 -396.748)
			(xy 348.348046 -396.75689) (xy 348.351856 -396.773654) (xy 348.395798 -396.843504) (xy 348.409514 -396.853918)
			(xy 348.417896 -396.856712) (xy 348.441932 -396.865165) (xy 348.487116 -396.888709) (xy 348.52793 -396.919205)
			(xy 348.563316 -396.955862) (xy 348.592355 -396.997726) (xy 348.614291 -397.043711) (xy 348.621858 -397.06804)
			(xy 348.623382 -397.073882) (xy 348.943676 -397.627602) (xy 348.94774 -397.63192) (xy 348.963955 -397.649619)
			(xy 348.991384 -397.689009) (xy 349.012529 -397.7321) (xy 349.0269 -397.777898) (xy 349.034166 -397.825344)
			(xy 349.034608 -397.849344) (xy 349.034143 -397.874147) (xy 349.026373 -397.923141) (xy 349.011032 -397.970316)
			(xy 348.988498 -398.014509) (xy 348.959326 -398.054631) (xy 348.924234 -398.089694) (xy 348.884089 -398.118833)
			(xy 348.839877 -398.141331) (xy 348.79269 -398.156633) (xy 348.74369 -398.164363) (xy 348.718886 -398.164812)
			(xy 348.693493 -398.164303) (xy 348.643362 -398.156171) (xy 348.595179 -398.140118) (xy 348.550188 -398.11656)
			(xy 348.509548 -398.086103) (xy 348.474308 -398.049533) (xy 348.445376 -398.007793) (xy 348.4235 -397.96196)
			(xy 348.415864 -397.937736) (xy 348.41434 -397.931894) (xy 348.094046 -397.378174) (xy 348.089982 -397.373856)
			(xy 348.073794 -397.356146) (xy 348.04642 -397.316743) (xy 348.025332 -397.273648) (xy 348.011016 -397.227855)
			(xy 348.003803 -397.180422) (xy 348.003368 -397.156432) (xy 348.003454 -397.144384) (xy 348.005237 -397.120355)
			(xy 348.006924 -397.108426) (xy 348.008194 -397.099536) (xy 348.005146 -397.082518) (xy 347.962982 -397.011652)
			(xy 347.949774 -397.000476) (xy 347.941392 -396.997428) (xy 347.91848 -396.988545) (xy 347.875614 -396.964526)
			(xy 347.837149 -396.93395) (xy 347.80408 -396.897606) (xy 347.790262 -396.877286) (xy 347.783912 -396.867634)
			(xy 347.764354 -396.855696) (xy 347.674438 -396.846298) (xy 347.663091 -396.84578) (xy 347.641736 -396.853434)
			(xy 347.63329 -396.86103) (xy 347.562424 -396.931896) (xy 347.555021 -396.938731) (xy 347.536423 -396.946438)
			(xy 347.526356 -396.946882) (xy 347.448886 -396.946882) (xy 347.438879 -396.947372) (xy 347.420389 -396.955033)
			(xy 347.406236 -396.969185) (xy 347.398573 -396.987675) (xy 347.398086 -396.997682) (xy 347.398086 -397.009366)
			(xy 347.403166 -397.01978) (xy 347.408657 -397.031499) (xy 347.417939 -397.055659) (xy 347.421708 -397.06804)
			(xy 347.423232 -397.073882) (xy 347.743526 -397.627602) (xy 347.74759 -397.63192) (xy 347.763781 -397.649628)
			(xy 347.79116 -397.68903) (xy 347.812253 -397.732125) (xy 347.826574 -397.777919) (xy 347.833791 -397.825353)
			(xy 347.834204 -397.849344) (xy 347.833715 -397.874132) (xy 347.825954 -397.923098) (xy 347.810629 -397.970247)
			(xy 347.788119 -398.014419) (xy 347.758977 -398.054526) (xy 347.72392 -398.089582) (xy 347.683812 -398.118723)
			(xy 347.63964 -398.141232) (xy 347.59249 -398.156556) (xy 347.543524 -398.164315) (xy 347.518736 -398.164812)
			(xy 347.493341 -398.164307) (xy 347.443204 -398.156181) (xy 347.395015 -398.140134) (xy 347.350017 -398.116578)
			(xy 347.30937 -398.086122) (xy 347.274124 -398.049552) (xy 347.245187 -398.007811) (xy 347.223306 -397.961975)
			(xy 347.215714 -397.937736) (xy 347.21419 -397.931894) (xy 346.893896 -397.378174) (xy 346.889832 -397.373856)
			(xy 346.873615 -397.356158) (xy 346.846183 -397.316769) (xy 346.825037 -397.273678) (xy 346.810665 -397.22788)
			(xy 346.803401 -397.180432) (xy 346.802964 -397.156432) (xy 346.803122 -397.14438) (xy 346.805031 -397.120352)
			(xy 346.806774 -397.108426) (xy 346.808044 -397.099536) (xy 346.804996 -397.082518) (xy 346.762832 -397.011652)
			(xy 346.749624 -397.000476) (xy 346.741242 -396.997428) (xy 346.721065 -396.989665) (xy 346.682949 -396.969267)
			(xy 346.665296 -396.956788) (xy 346.6586 -396.952198) (xy 346.643184 -396.947141) (xy 346.63507 -396.946882)
			(xy 346.24899 -396.946882) (xy 346.238982 -396.947371) (xy 346.220491 -396.955032) (xy 346.206337 -396.969184)
			(xy 346.198673 -396.987674) (xy 346.19819 -396.997682) (xy 346.19819 -397.009366) (xy 346.20327 -397.01978)
			(xy 346.208761 -397.031499) (xy 346.218043 -397.055659) (xy 346.221812 -397.06804) (xy 346.223336 -397.073882)
			(xy 346.54363 -397.627602) (xy 346.547694 -397.63192) (xy 346.563885 -397.649628) (xy 346.591263 -397.689031)
			(xy 346.612356 -397.732126) (xy 346.626677 -397.777919) (xy 346.633894 -397.825353) (xy 346.634308 -397.849344)
			(xy 346.633819 -397.874132) (xy 346.626058 -397.923098) (xy 346.610733 -397.970248) (xy 346.588223 -398.01442)
			(xy 346.559081 -398.054528) (xy 346.524025 -398.089584) (xy 346.483917 -398.118725) (xy 346.439744 -398.141235)
			(xy 346.392594 -398.156559) (xy 346.343629 -398.164319) (xy 346.31884 -398.164812) (xy 346.293444 -398.164307)
			(xy 346.243307 -398.156182) (xy 346.195118 -398.140135) (xy 346.150119 -398.11658) (xy 346.109472 -398.086124)
			(xy 346.074225 -398.049554) (xy 346.045288 -398.007812) (xy 346.023406 -397.961976) (xy 346.015818 -397.937736)
			(xy 346.014294 -397.931894) (xy 345.694 -397.378174) (xy 345.689936 -397.373856) (xy 345.673719 -397.356158)
			(xy 345.646286 -397.316769) (xy 345.62514 -397.273678) (xy 345.610768 -397.22788) (xy 345.603504 -397.180432)
			(xy 345.603068 -397.156432) (xy 345.603226 -397.14438) (xy 345.605135 -397.120352) (xy 345.606878 -397.108426)
			(xy 345.608148 -397.099536) (xy 345.6051 -397.082518) (xy 345.562936 -397.011652) (xy 345.549728 -397.000476)
			(xy 345.541346 -396.997428) (xy 345.521169 -396.989665) (xy 345.483053 -396.969268) (xy 345.4654 -396.956788)
			(xy 345.458704 -396.952198) (xy 345.443288 -396.947139) (xy 345.435174 -396.946882) (xy 345.049094 -396.946882)
			(xy 345.039086 -396.947371) (xy 345.020593 -396.955031) (xy 345.006437 -396.969183) (xy 344.998773 -396.987674)
			(xy 344.998294 -396.997682) (xy 344.998294 -397.009366) (xy 345.003374 -397.01978) (xy 345.008967 -397.031674)
			(xy 345.01838 -397.056217) (xy 345.02217 -397.068802) (xy 345.023694 -397.074644) (xy 345.34348 -397.627602)
			(xy 345.347544 -397.63192) (xy 345.363763 -397.649617) (xy 345.391201 -397.689004) (xy 345.412352 -397.732095)
			(xy 345.426728 -397.777894) (xy 345.433996 -397.825343) (xy 345.434412 -397.849344) (xy 345.433947 -397.874147)
			(xy 345.426177 -397.923142) (xy 345.410836 -397.970317) (xy 345.388302 -398.01451) (xy 345.35913 -398.054632)
			(xy 345.324039 -398.089695) (xy 345.283893 -398.118835) (xy 345.239682 -398.141334) (xy 345.192494 -398.156636)
			(xy 345.143494 -398.164367) (xy 345.11869 -398.164812) (xy 345.093297 -398.164303) (xy 345.043165 -398.156172)
			(xy 344.994982 -398.14012) (xy 344.94999 -398.116561) (xy 344.90935 -398.086104) (xy 344.874109 -398.049534)
			(xy 344.845177 -398.007794) (xy 344.8233 -397.961961) (xy 344.815668 -397.937736) (xy 344.814144 -397.931894)
			(xy 344.493596 -397.377412) (xy 344.489532 -397.373094) (xy 344.473428 -397.355425) (xy 344.446189 -397.31614)
			(xy 344.425179 -397.273199) (xy 344.410877 -397.227584) (xy 344.403611 -397.180334) (xy 344.403172 -397.156432)
			(xy 344.40333 -397.14438) (xy 344.405239 -397.120352) (xy 344.406982 -397.108426) (xy 344.408252 -397.099536)
			(xy 344.405204 -397.082518) (xy 344.36304 -397.011652) (xy 344.349832 -397.000476) (xy 344.34145 -396.997428)
			(xy 344.321273 -396.989665) (xy 344.283156 -396.969269) (xy 344.265504 -396.956788) (xy 344.258808 -396.952197)
			(xy 344.243392 -396.947138) (xy 344.235278 -396.946882) (xy 343.848944 -396.946882) (xy 343.838916 -396.947294)
			(xy 343.820381 -396.954955) (xy 343.80619 -396.969128) (xy 343.798506 -396.987654) (xy 343.798144 -396.997682)
			(xy 343.798144 -397.009366) (xy 343.803224 -397.01978) (xy 343.808715 -397.031499) (xy 343.817999 -397.055659)
			(xy 343.821766 -397.06804) (xy 343.82329 -397.073882) (xy 344.143584 -397.627602) (xy 344.147648 -397.63192)
			(xy 344.163867 -397.649617) (xy 344.191304 -397.689005) (xy 344.212455 -397.732096) (xy 344.226831 -397.777894)
			(xy 344.234099 -397.825343) (xy 344.234516 -397.849344) (xy 344.234051 -397.874147) (xy 344.226281 -397.923142)
			(xy 344.21094 -397.970317) (xy 344.188406 -398.014511) (xy 344.159234 -398.054633) (xy 344.124143 -398.089697)
			(xy 344.083997 -398.118837) (xy 344.039786 -398.141336) (xy 343.992599 -398.15664) (xy 343.943598 -398.16437)
			(xy 343.918794 -398.164812) (xy 343.893401 -398.164304) (xy 343.843269 -398.156173) (xy 343.795085 -398.140121)
			(xy 343.750092 -398.116563) (xy 343.709451 -398.086106) (xy 343.67421 -398.049536) (xy 343.645278 -398.007796)
			(xy 343.623401 -397.961962) (xy 343.615772 -397.937736) (xy 343.614248 -397.931894) (xy 343.293954 -397.378174)
			(xy 343.28989 -397.373856) (xy 343.273701 -397.356147) (xy 343.246327 -397.316744) (xy 343.225239 -397.273648)
			(xy 343.210922 -397.227855) (xy 343.203709 -397.180422) (xy 343.203276 -397.156432) (xy 343.203362 -397.144384)
			(xy 343.205145 -397.120355) (xy 343.206832 -397.108426) (xy 343.208102 -397.099536) (xy 343.205054 -397.082518)
			(xy 343.16289 -397.011652) (xy 343.149682 -397.000476) (xy 343.1413 -396.997428) (xy 343.121122 -396.989668)
			(xy 343.083001 -396.969276) (xy 343.065354 -396.956788) (xy 343.058656 -396.952204) (xy 343.04324 -396.94716)
			(xy 343.035128 -396.946882) (xy 342.649048 -396.946882) (xy 342.639019 -396.947293) (xy 342.620483 -396.954954)
			(xy 342.606291 -396.969127) (xy 342.598606 -396.987654) (xy 342.598248 -396.997682) (xy 342.598248 -397.009366)
			(xy 342.603328 -397.01978) (xy 342.608819 -397.031499) (xy 342.618103 -397.055659) (xy 342.62187 -397.06804)
			(xy 342.623394 -397.073882) (xy 342.943688 -397.627602) (xy 342.947752 -397.63192) (xy 342.963971 -397.649617)
			(xy 342.991408 -397.689005) (xy 343.012558 -397.732096) (xy 343.026934 -397.777895) (xy 343.034202 -397.825343)
			(xy 343.03462 -397.849344) (xy 343.034155 -397.874145) (xy 343.026384 -397.923134) (xy 343.011042 -397.970303)
			(xy 342.988507 -398.014489) (xy 342.959333 -398.054604) (xy 342.92424 -398.089658) (xy 342.884094 -398.118788)
			(xy 342.839883 -398.141275) (xy 342.792697 -398.156565) (xy 342.743699 -398.164282) (xy 342.718898 -398.164812)
			(xy 342.693504 -398.164304) (xy 342.643372 -398.156173) (xy 342.595188 -398.140122) (xy 342.550195 -398.116564)
			(xy 342.509553 -398.086107) (xy 342.474312 -398.049537) (xy 342.445379 -398.007797) (xy 342.423501 -397.961963)
			(xy 342.415876 -397.937736) (xy 342.414352 -397.931894) (xy 342.094058 -397.378174) (xy 342.089994 -397.373856)
			(xy 342.073805 -397.356147) (xy 342.046431 -397.316744) (xy 342.025342 -397.273648) (xy 342.011025 -397.227855)
			(xy 342.003812 -397.180422) (xy 342.00338 -397.156432) (xy 342.003466 -397.144384) (xy 342.005249 -397.120355)
			(xy 342.006936 -397.108426) (xy 342.008206 -397.099536) (xy 342.005158 -397.082518) (xy 341.962994 -397.011652)
			(xy 341.949786 -397.000476) (xy 341.941404 -396.997428) (xy 341.919662 -396.989024) (xy 341.878815 -396.966573)
			(xy 341.841855 -396.938174) (xy 341.80964 -396.904488) (xy 341.782918 -396.866298) (xy 341.762312 -396.824489)
			(xy 341.7483 -396.780035) (xy 341.741206 -396.733967) (xy 341.740744 -396.710662) (xy 341.741247 -396.685654)
			(xy 341.749399 -396.636305) (xy 341.76548 -396.588944) (xy 341.776812 -396.566644) (xy 341.784686 -396.551658)
			(xy 341.77986 -396.518638) (xy 341.656416 -396.395194) (xy 341.649569 -396.387796) (xy 341.641834 -396.369198)
			(xy 341.64143 -396.359126) (xy 341.64143 -396.29588) (xy 341.63889 -396.284704) (xy 341.636096 -396.27937)
			(xy 341.621026 -396.24755) (xy 341.599744 -396.18044) (xy 341.588971 -396.110864) (xy 341.588344 -396.075662)
			(xy 341.588966 -396.040458) (xy 341.599712 -395.970876) (xy 341.621007 -395.903766) (xy 341.636096 -395.871954)
			(xy 341.638557 -395.866628) (xy 341.641249 -395.855212) (xy 341.64143 -395.849348) (xy 341.64143 -395.839442)
			(xy 341.616276 -395.820965) (xy 341.570731 -395.77829) (xy 341.531406 -395.729825) (xy 341.499028 -395.676466)
			(xy 341.474199 -395.619204) (xy 341.457379 -395.5591) (xy 341.448878 -395.497268) (xy 341.44839 -395.466062)
			(xy 341.448788 -395.438157) (xy 341.455532 -395.382755) (xy 341.461852 -395.355572) (xy 341.465154 -395.342364)
			(xy 341.458042 -395.31671) (xy 341.402924 -395.261592) (xy 341.395521 -395.254758) (xy 341.376923 -395.247053)
			(xy 341.366856 -395.246606) (xy 339.92185 -395.246606) (xy 339.910094 -395.247201) (xy 339.889036 -395.25766)
			(xy 339.881464 -395.266672) (xy 339.82533 -395.341094) (xy 339.821012 -395.364208) (xy 339.824314 -395.375892)
			(xy 339.830156 -395.397975) (xy 339.836405 -395.443223) (xy 339.83676 -395.466062) (xy 339.836327 -395.490179)
			(xy 339.82933 -395.537904) (xy 339.81548 -395.584107) (xy 339.79507 -395.627811) (xy 339.78215 -395.64818)
			(xy 339.776308 -395.65707) (xy 339.772752 -395.677136) (xy 339.793834 -395.769338) (xy 339.806026 -395.786102)
			(xy 339.814916 -395.791436) (xy 339.835719 -395.804291) (xy 339.873637 -395.835168) (xy 339.906588 -395.871298)
			(xy 339.933852 -395.911892) (xy 339.954833 -395.956062) (xy 339.969072 -396.002843) (xy 339.976258 -396.051212)
			(xy 339.976714 -396.075662) (xy 339.976276 -396.100032) (xy 339.96912 -396.148245) (xy 339.954971 -396.194887)
			(xy 339.934135 -396.238949) (xy 339.907063 -396.27948) (xy 339.87434 -396.315603) (xy 339.85581 -396.33144)
			(xy 339.84692 -396.338552) (xy 339.837522 -396.35811) (xy 339.834728 -396.457424) (xy 339.843364 -396.47749)
			(xy 339.851746 -396.48511) (xy 339.870165 -396.502599) (xy 339.901503 -396.542569) (xy 339.925796 -396.587171)
			(xy 339.942375 -396.635179) (xy 339.950784 -396.685267) (xy 339.951314 -396.710662) (xy 340.540594 -396.710662)
			(xy 340.541116 -396.685407) (xy 340.549429 -396.635585) (xy 340.56583 -396.587811) (xy 340.589871 -396.543388)
			(xy 340.620895 -396.503528) (xy 340.658057 -396.469318) (xy 340.700343 -396.441692) (xy 340.746599 -396.421402)
			(xy 340.795564 -396.409002) (xy 340.845902 -396.404831) (xy 340.89624 -396.409002) (xy 340.945205 -396.421402)
			(xy 340.991461 -396.441692) (xy 341.033747 -396.469318) (xy 341.070909 -396.503528) (xy 341.101933 -396.543388)
			(xy 341.125974 -396.587811) (xy 341.142375 -396.635585) (xy 341.150688 -396.685407) (xy 341.15121 -396.710662)
			(xy 341.151141 -396.720021) (xy 341.149998 -396.738703) (xy 341.148924 -396.748) (xy 341.147908 -396.75689)
			(xy 341.151718 -396.773654) (xy 341.19566 -396.843504) (xy 341.209376 -396.853918) (xy 341.217758 -396.856712)
			(xy 341.24179 -396.86517) (xy 341.286962 -396.888725) (xy 341.327766 -396.919227) (xy 341.363145 -396.955884)
			(xy 341.392179 -396.997745) (xy 341.414117 -397.043724) (xy 341.42172 -397.06804) (xy 341.423244 -397.073882)
			(xy 341.743538 -397.627602) (xy 341.747602 -397.63192) (xy 341.76379 -397.649629) (xy 341.791156 -397.689037)
			(xy 341.812242 -397.732133) (xy 341.826562 -397.777924) (xy 341.833787 -397.825355) (xy 341.834216 -397.849344)
			(xy 341.833723 -397.874132) (xy 341.825962 -397.923098) (xy 341.810638 -397.970247) (xy 341.788128 -398.01442)
			(xy 341.758987 -398.054528) (xy 341.723931 -398.089584) (xy 341.683823 -398.118726) (xy 341.639651 -398.141236)
			(xy 341.592502 -398.156561) (xy 341.543536 -398.164322) (xy 341.518748 -398.164812) (xy 341.493355 -398.164269)
			(xy 341.443223 -398.156146) (xy 341.395039 -398.140102) (xy 341.350045 -398.11655) (xy 341.309401 -398.086098)
			(xy 341.274158 -398.049532) (xy 341.245223 -398.007796) (xy 341.223343 -397.961965) (xy 341.215726 -397.937736)
			(xy 341.214202 -397.931894) (xy 340.893908 -397.378174) (xy 340.889844 -397.373856) (xy 340.873631 -397.356156)
			(xy 340.846211 -397.316762) (xy 340.82507 -397.27367) (xy 340.810699 -397.227875) (xy 340.803426 -397.180431)
			(xy 340.802976 -397.156432) (xy 340.803118 -397.14438) (xy 340.805024 -397.12035) (xy 340.806786 -397.108426)
			(xy 340.808056 -397.099536) (xy 340.805008 -397.082518) (xy 340.762844 -397.011652) (xy 340.749636 -397.000476)
			(xy 340.741254 -396.997428) (xy 340.719503 -396.989042) (xy 340.678645 -396.966599) (xy 340.641675 -396.938203)
			(xy 340.609453 -396.904517) (xy 340.582728 -396.866322) (xy 340.562122 -396.824507) (xy 340.548115 -396.780045)
			(xy 340.541032 -396.73397) (xy 340.540594 -396.710662) (xy 339.951314 -396.710662) (xy 339.951242 -396.72002)
			(xy 339.950096 -396.738702) (xy 339.949028 -396.748) (xy 339.948012 -396.75689) (xy 339.951822 -396.773654)
			(xy 339.995764 -396.843504) (xy 340.00948 -396.853918) (xy 340.017862 -396.856712) (xy 340.041895 -396.865169)
			(xy 340.08707 -396.888719) (xy 340.127877 -396.919219) (xy 340.163256 -396.955877) (xy 340.192287 -396.997741)
			(xy 340.214219 -397.043724) (xy 340.221824 -397.06804) (xy 340.223348 -397.073882) (xy 340.543642 -397.627602)
			(xy 340.547706 -397.63192) (xy 340.563896 -397.649629) (xy 340.591274 -397.689031) (xy 340.612366 -397.732126)
			(xy 340.626686 -397.777919) (xy 340.633903 -397.825354) (xy 340.63432 -397.849344) (xy 340.633856 -397.874132)
			(xy 340.626093 -397.923097) (xy 340.610767 -397.970244) (xy 340.588253 -398.014413) (xy 340.559108 -398.054517)
			(xy 340.524047 -398.089567) (xy 340.483935 -398.118702) (xy 340.439759 -398.141202) (xy 340.392607 -398.156515)
			(xy 340.34364 -398.164263) (xy 340.318852 -398.164812) (xy 340.29346 -398.164301) (xy 340.243333 -398.156164)
			(xy 340.195155 -398.140108) (xy 340.150168 -398.116547) (xy 340.109533 -398.086089) (xy 340.074297 -398.049519)
			(xy 340.045369 -398.00778) (xy 340.023496 -397.961949) (xy 340.01583 -397.937736) (xy 340.014306 -397.931894)
			(xy 339.694012 -397.378174) (xy 339.689948 -397.373856) (xy 339.67373 -397.356158) (xy 339.646297 -397.31677)
			(xy 339.625149 -397.273679) (xy 339.610777 -397.22788) (xy 339.603513 -397.180432) (xy 339.60308 -397.156432)
			(xy 339.603238 -397.14438) (xy 339.605147 -397.120352) (xy 339.60689 -397.108426) (xy 339.60816 -397.099536)
			(xy 339.605112 -397.082518) (xy 339.562948 -397.011652) (xy 339.54974 -397.000476) (xy 339.541358 -396.997428)
			(xy 339.519619 -396.989021) (xy 339.478777 -396.966567) (xy 339.441822 -396.938166) (xy 339.409612 -396.90448)
			(xy 339.382895 -396.866289) (xy 339.362293 -396.824483) (xy 339.348282 -396.780031) (xy 339.34119 -396.733966)
			(xy 339.340698 -396.710662) (xy 339.341198 -396.685264) (xy 339.349598 -396.635167) (xy 339.366175 -396.587153)
			(xy 339.390473 -396.542545) (xy 339.421821 -396.502576) (xy 339.440266 -396.48511) (xy 339.448648 -396.47749)
			(xy 339.457284 -396.457424) (xy 339.45449 -396.35811) (xy 339.445092 -396.338552) (xy 339.436202 -396.33144)
			(xy 339.417641 -396.315638) (xy 339.384914 -396.279511) (xy 339.357841 -396.238974) (xy 339.337008 -396.194904)
			(xy 339.322865 -396.148255) (xy 339.31572 -396.100035) (xy 339.315298 -396.075662) (xy 339.315737 -396.051546)
			(xy 339.322742 -396.003826) (xy 339.3366 -395.957627) (xy 339.357015 -395.913929) (xy 339.369908 -395.893544)
			(xy 339.37575 -395.884654) (xy 339.379306 -395.864588) (xy 339.358224 -395.772386) (xy 339.346032 -395.755622)
			(xy 339.337142 -395.750288) (xy 339.31634 -395.737432) (xy 339.278424 -395.706553) (xy 339.245475 -395.670422)
			(xy 339.218212 -395.629829) (xy 339.197231 -395.585659) (xy 339.18299 -395.53888) (xy 339.175802 -395.490512)
			(xy 339.175344 -395.466062) (xy 339.175715 -395.443224) (xy 339.181967 -395.397978) (xy 339.18779 -395.375892)
			(xy 339.191092 -395.364208) (xy 339.186774 -395.341094) (xy 339.13064 -395.266672) (xy 339.123046 -395.257688)
			(xy 339.102001 -395.247233) (xy 339.090254 -395.246606) (xy 338.721954 -395.246606) (xy 338.710197 -395.2472)
			(xy 338.689138 -395.257658) (xy 338.681568 -395.266672) (xy 338.625434 -395.341094) (xy 338.621116 -395.364208)
			(xy 338.624418 -395.375892) (xy 338.63026 -395.397975) (xy 338.636508 -395.443223) (xy 338.636864 -395.466062)
			(xy 338.636431 -395.490179) (xy 338.629434 -395.537904) (xy 338.615584 -395.584108) (xy 338.595174 -395.627811)
			(xy 338.582254 -395.64818) (xy 338.576412 -395.65707) (xy 338.572856 -395.677136) (xy 338.593938 -395.769338)
			(xy 338.60613 -395.786102) (xy 338.61502 -395.791436) (xy 338.635822 -395.804291) (xy 338.67374 -395.835168)
			(xy 338.706691 -395.871299) (xy 338.733954 -395.911893) (xy 338.754935 -395.956063) (xy 338.769174 -396.002843)
			(xy 338.77636 -396.051212) (xy 338.776818 -396.075662) (xy 338.77638 -396.100032) (xy 338.769224 -396.148245)
			(xy 338.755075 -396.194887) (xy 338.734239 -396.23895) (xy 338.707167 -396.279481) (xy 338.674444 -396.315604)
			(xy 338.655914 -396.33144) (xy 338.647024 -396.338552) (xy 338.637626 -396.35811) (xy 338.634832 -396.457424)
			(xy 338.643468 -396.47749) (xy 338.65185 -396.48511) (xy 338.670269 -396.502599) (xy 338.701606 -396.542569)
			(xy 338.725899 -396.587172) (xy 338.742478 -396.635179) (xy 338.750886 -396.685267) (xy 338.751418 -396.710662)
			(xy 338.751346 -396.72002) (xy 338.7502 -396.738702) (xy 338.749132 -396.748) (xy 338.748116 -396.75689)
			(xy 338.751926 -396.773654) (xy 338.795868 -396.843504) (xy 338.809584 -396.853918) (xy 338.817966 -396.856712)
			(xy 338.842063 -396.865193) (xy 338.887354 -396.888821) (xy 338.92825 -396.919432) (xy 338.963685 -396.956227)
			(xy 338.992733 -396.998247) (xy 339.014639 -397.044395) (xy 339.022182 -397.068802) (xy 339.023706 -397.074644)
			(xy 339.343492 -397.627602) (xy 339.347556 -397.63192) (xy 339.363775 -397.649617) (xy 339.391211 -397.689005)
			(xy 339.412362 -397.732096) (xy 339.426737 -397.777895) (xy 339.434005 -397.825343) (xy 339.434424 -397.849344)
			(xy 339.433959 -397.874145) (xy 339.426188 -397.923134) (xy 339.410847 -397.970303) (xy 339.388311 -398.01449)
			(xy 339.359137 -398.054605) (xy 339.324045 -398.08966) (xy 339.283898 -398.11879) (xy 339.239687 -398.141278)
			(xy 339.192501 -398.156568) (xy 339.143503 -398.164285) (xy 339.118702 -398.164812) (xy 339.093308 -398.164304)
			(xy 339.043175 -398.156174) (xy 338.994991 -398.140123) (xy 338.949997 -398.116566) (xy 338.909355 -398.086109)
			(xy 338.874113 -398.049539) (xy 338.84518 -398.007798) (xy 338.823302 -397.961965) (xy 338.81568 -397.937736)
			(xy 338.814156 -397.931894) (xy 338.493608 -397.377412) (xy 338.489544 -397.373094) (xy 338.473439 -397.355426)
			(xy 338.446199 -397.31614) (xy 338.425188 -397.2732) (xy 338.410887 -397.227584) (xy 338.40362 -397.180334)
			(xy 338.403184 -397.156432) (xy 338.403342 -397.14438) (xy 338.405251 -397.120352) (xy 338.406994 -397.108426)
			(xy 338.408264 -397.099536) (xy 338.405216 -397.082518) (xy 338.363052 -397.011652) (xy 338.349844 -397.000476)
			(xy 338.341462 -396.997428) (xy 338.319723 -396.989022) (xy 338.27888 -396.966567) (xy 338.241925 -396.938167)
			(xy 338.209714 -396.90448) (xy 338.182997 -396.86629) (xy 338.162394 -396.824483) (xy 338.148384 -396.780031)
			(xy 338.141292 -396.733966) (xy 338.140802 -396.710662) (xy 338.141302 -396.685264) (xy 338.149702 -396.635168)
			(xy 338.166279 -396.587153) (xy 338.190578 -396.542546) (xy 338.221926 -396.502577) (xy 338.24037 -396.48511)
			(xy 338.248752 -396.47749) (xy 338.257388 -396.457424) (xy 338.254594 -396.35811) (xy 338.245196 -396.338552)
			(xy 338.236306 -396.33144) (xy 338.217745 -396.315638) (xy 338.185017 -396.279511) (xy 338.157944 -396.238974)
			(xy 338.137111 -396.194904) (xy 338.122968 -396.148255) (xy 338.115822 -396.100035) (xy 338.115402 -396.075662)
			(xy 338.115841 -396.051546) (xy 338.122846 -396.003826) (xy 338.136704 -395.957627) (xy 338.15712 -395.91393)
			(xy 338.170012 -395.893544) (xy 338.175854 -395.884654) (xy 338.17941 -395.864588) (xy 338.158328 -395.772386)
			(xy 338.146136 -395.755622) (xy 338.137246 -395.750288) (xy 338.116444 -395.737432) (xy 338.078528 -395.706554)
			(xy 338.045578 -395.670423) (xy 338.018314 -395.629829) (xy 337.997333 -395.58566) (xy 337.983092 -395.53888)
			(xy 337.975904 -395.490512) (xy 337.975448 -395.466062) (xy 337.975819 -395.443224) (xy 337.982071 -395.397978)
			(xy 337.987894 -395.375892) (xy 337.991196 -395.364208) (xy 337.986878 -395.341094) (xy 337.930744 -395.266672)
			(xy 337.92315 -395.257687) (xy 337.902106 -395.247231) (xy 337.890358 -395.246606) (xy 337.521804 -395.246606)
			(xy 337.510042 -395.24719) (xy 337.488966 -395.257635) (xy 337.481418 -395.266672) (xy 337.425284 -395.341094)
			(xy 337.420966 -395.364208) (xy 337.424268 -395.375892) (xy 337.430109 -395.397975) (xy 337.436357 -395.443223)
			(xy 337.436714 -395.466062) (xy 337.436281 -395.49018) (xy 337.429285 -395.537905) (xy 337.415437 -395.584109)
			(xy 337.39503 -395.627815) (xy 337.382104 -395.64818) (xy 337.376262 -395.65707) (xy 337.372706 -395.677136)
			(xy 337.393788 -395.769338) (xy 337.40598 -395.786102) (xy 337.41487 -395.791436) (xy 337.43567 -395.804293)
			(xy 337.473582 -395.835173) (xy 337.506528 -395.871305) (xy 337.533787 -395.911899) (xy 337.554764 -395.956068)
			(xy 337.569001 -396.002847) (xy 337.576185 -396.051213) (xy 337.576668 -396.075662) (xy 337.57623 -396.100033)
			(xy 337.569075 -396.148246) (xy 337.554927 -396.19489) (xy 337.534094 -396.238955) (xy 337.507024 -396.279489)
			(xy 337.474305 -396.315616) (xy 337.455764 -396.33144) (xy 337.446874 -396.338552) (xy 337.437476 -396.35811)
			(xy 337.434682 -396.457424) (xy 337.443318 -396.47749) (xy 337.4517 -396.48511) (xy 337.470122 -396.502598)
			(xy 337.501464 -396.542566) (xy 337.52576 -396.587168) (xy 337.542342 -396.635177) (xy 337.550753 -396.685267)
			(xy 337.551268 -396.710662) (xy 337.551196 -396.72002) (xy 337.55005 -396.738702) (xy 337.548982 -396.748)
			(xy 337.547966 -396.75689) (xy 337.551776 -396.773654) (xy 337.595718 -396.843504) (xy 337.609434 -396.853918)
			(xy 337.617816 -396.856712) (xy 337.641851 -396.865166) (xy 337.687032 -396.888712) (xy 337.727844 -396.919209)
			(xy 337.763228 -396.955866) (xy 337.792264 -396.99773) (xy 337.8142 -397.043715) (xy 337.821778 -397.06804)
			(xy 337.823302 -397.073882) (xy 338.143596 -397.627602) (xy 338.14766 -397.63192) (xy 338.163879 -397.649617)
			(xy 338.191315 -397.689005) (xy 338.212465 -397.732096) (xy 338.22684 -397.777895) (xy 338.234108 -397.825343)
			(xy 338.234528 -397.849344) (xy 338.234063 -397.874145) (xy 338.226292 -397.923134) (xy 338.210951 -397.970304)
			(xy 338.188415 -398.014491) (xy 338.159242 -398.054606) (xy 338.124149 -398.089661) (xy 338.084002 -398.118792)
			(xy 338.039791 -398.14128) (xy 337.992605 -398.156571) (xy 337.943607 -398.164289) (xy 337.918806 -398.164812)
			(xy 337.893412 -398.164305) (xy 337.843279 -398.156175) (xy 337.795094 -398.140125) (xy 337.750099 -398.116567)
			(xy 337.709457 -398.086111) (xy 337.674214 -398.04954) (xy 337.64528 -398.0078) (xy 337.623402 -397.961966)
			(xy 337.615784 -397.937736) (xy 337.61426 -397.931894) (xy 337.293966 -397.378174) (xy 337.289902 -397.373856)
			(xy 337.273713 -397.356147) (xy 337.246338 -397.316744) (xy 337.225248 -397.273649) (xy 337.210931 -397.227856)
			(xy 337.203718 -397.180422) (xy 337.203288 -397.156432) (xy 337.203374 -397.144384) (xy 337.205156 -397.120355)
			(xy 337.206844 -397.108426) (xy 337.208114 -397.099536) (xy 337.205066 -397.082518) (xy 337.162902 -397.011652)
			(xy 337.149694 -397.000476) (xy 337.141312 -396.997428) (xy 337.11957 -396.989024) (xy 337.078722 -396.966574)
			(xy 337.04176 -396.938176) (xy 337.009544 -396.90449) (xy 336.982823 -396.866299) (xy 336.962216 -396.82449)
			(xy 336.948203 -396.780036) (xy 336.941109 -396.733967) (xy 336.940652 -396.710662) (xy 336.941151 -396.685263)
			(xy 336.94955 -396.635166) (xy 336.966126 -396.58715) (xy 336.990421 -396.54254) (xy 337.021766 -396.502567)
			(xy 337.04022 -396.48511) (xy 337.048602 -396.47749) (xy 337.057238 -396.457424) (xy 337.054444 -396.35811)
			(xy 337.045046 -396.338552) (xy 337.036156 -396.33144) (xy 337.017592 -396.315639) (xy 336.98486 -396.279515)
			(xy 336.957783 -396.238978) (xy 336.936946 -396.194908) (xy 336.922801 -396.148257) (xy 336.915654 -396.100036)
			(xy 336.915252 -396.075662) (xy 336.915691 -396.051546) (xy 336.922697 -396.003827) (xy 336.936557 -395.957629)
			(xy 336.956975 -395.913933) (xy 336.969862 -395.893544) (xy 336.975704 -395.884654) (xy 336.97926 -395.864588)
			(xy 336.958178 -395.772386) (xy 336.945986 -395.755622) (xy 336.937096 -395.750288) (xy 336.916292 -395.737434)
			(xy 336.87837 -395.706558) (xy 336.845415 -395.670429) (xy 336.818147 -395.629835) (xy 336.797162 -395.585665)
			(xy 336.782919 -395.538883) (xy 336.77573 -395.490513) (xy 336.775298 -395.466062) (xy 336.775669 -395.443224)
			(xy 336.78192 -395.397978) (xy 336.787744 -395.375892) (xy 336.791046 -395.364208) (xy 336.786728 -395.341094)
			(xy 336.730594 -395.266672) (xy 336.722997 -395.257695) (xy 336.701952 -395.24726) (xy 336.690208 -395.246606)
			(xy 336.321908 -395.246606) (xy 336.310156 -395.24721) (xy 336.289113 -395.257679) (xy 336.281522 -395.266672)
			(xy 336.225388 -395.341094) (xy 336.22107 -395.364208) (xy 336.224372 -395.375892) (xy 336.230213 -395.397975)
			(xy 336.236461 -395.443223) (xy 336.236818 -395.466062) (xy 336.236385 -395.49018) (xy 336.229389 -395.537905)
			(xy 336.215542 -395.584109) (xy 336.195134 -395.627815) (xy 336.182208 -395.64818) (xy 336.176366 -395.65707)
			(xy 336.17281 -395.677136) (xy 336.193892 -395.769338) (xy 336.206084 -395.786102) (xy 336.214974 -395.791436)
			(xy 336.235774 -395.804293) (xy 336.273686 -395.835173) (xy 336.306631 -395.871305) (xy 336.33389 -395.911899)
			(xy 336.354867 -395.956068) (xy 336.369103 -396.002847) (xy 336.376288 -396.051213) (xy 336.376772 -396.075662)
			(xy 336.376334 -396.100033) (xy 336.369179 -396.148247) (xy 336.355032 -396.19489) (xy 336.334198 -396.238955)
			(xy 336.307129 -396.27949) (xy 336.274409 -396.315617) (xy 336.255868 -396.33144) (xy 336.246978 -396.338552)
			(xy 336.23758 -396.35811) (xy 336.234786 -396.457424) (xy 336.243422 -396.47749) (xy 336.251804 -396.48511)
			(xy 336.270226 -396.502598) (xy 336.301567 -396.542566) (xy 336.325863 -396.587169) (xy 336.342445 -396.635177)
			(xy 336.350855 -396.685267) (xy 336.351372 -396.710662) (xy 336.3513 -396.72002) (xy 336.350154 -396.738702)
			(xy 336.349086 -396.748) (xy 336.34807 -396.75689) (xy 336.35188 -396.773654) (xy 336.395822 -396.843504)
			(xy 336.409538 -396.853918) (xy 336.41792 -396.856712) (xy 336.441955 -396.865166) (xy 336.487135 -396.888713)
			(xy 336.527947 -396.91921) (xy 336.56333 -396.955867) (xy 336.592366 -396.997731) (xy 336.614301 -397.043716)
			(xy 336.621882 -397.06804) (xy 336.623406 -397.073882) (xy 336.9437 -397.627602) (xy 336.947764 -397.63192)
			(xy 336.963983 -397.649617) (xy 336.991418 -397.689005) (xy 337.012568 -397.732097) (xy 337.026943 -397.777895)
			(xy 337.034211 -397.825343) (xy 337.034632 -397.849344) (xy 337.034167 -397.874145) (xy 337.026396 -397.923135)
			(xy 337.011055 -397.970305) (xy 336.988519 -398.014492) (xy 336.959346 -398.054608) (xy 336.924253 -398.089663)
			(xy 336.884107 -398.118794) (xy 336.839895 -398.141283) (xy 336.792709 -398.156574) (xy 336.743712 -398.164293)
			(xy 336.71891 -398.164812) (xy 336.693516 -398.164305) (xy 336.643382 -398.156176) (xy 336.595196 -398.140126)
			(xy 336.550202 -398.116569) (xy 336.509559 -398.086112) (xy 336.474315 -398.049542) (xy 336.445381 -398.007801)
			(xy 336.423503 -397.961967) (xy 336.415888 -397.937736) (xy 336.414364 -397.931894) (xy 336.09407 -397.378174)
			(xy 336.090006 -397.373856) (xy 336.073817 -397.356147) (xy 336.046441 -397.316744) (xy 336.025351 -397.273649)
			(xy 336.011034 -397.227856) (xy 336.003821 -397.180422) (xy 336.003392 -397.156432) (xy 336.003478 -397.144384)
			(xy 336.00526 -397.120355) (xy 336.006948 -397.108426) (xy 336.008218 -397.099536) (xy 336.00517 -397.082518)
			(xy 335.963006 -397.011652) (xy 335.949798 -397.000476) (xy 335.941416 -396.997428) (xy 335.919674 -396.989024)
			(xy 335.878825 -396.966574) (xy 335.841863 -396.938176) (xy 335.809647 -396.904491) (xy 335.782925 -396.8663)
			(xy 335.762317 -396.824491) (xy 335.748304 -396.780036) (xy 335.74121 -396.733968) (xy 335.740756 -396.710662)
			(xy 335.741255 -396.685264) (xy 335.749654 -396.635166) (xy 335.76623 -396.58715) (xy 335.790526 -396.54254)
			(xy 335.821871 -396.502568) (xy 335.840324 -396.48511) (xy 335.848706 -396.47749) (xy 335.857342 -396.457424)
			(xy 335.854548 -396.35811) (xy 335.84515 -396.338552) (xy 335.83626 -396.33144) (xy 335.817701 -396.315636)
			(xy 335.784978 -396.279508) (xy 335.757908 -396.238971) (xy 335.737078 -396.194901) (xy 335.722938 -396.148253)
			(xy 335.715793 -396.100034) (xy 335.715356 -396.075662) (xy 335.715795 -396.051546) (xy 335.722799 -396.003825)
			(xy 335.736655 -395.957626) (xy 335.757069 -395.913926) (xy 335.769966 -395.893544) (xy 335.775808 -395.884654)
			(xy 335.779364 -395.864588) (xy 335.758282 -395.772386) (xy 335.74609 -395.755622) (xy 335.7372 -395.750288)
			(xy 335.716395 -395.737434) (xy 335.678473 -395.706559) (xy 335.645518 -395.670429) (xy 335.61825 -395.629836)
			(xy 335.597265 -395.585665) (xy 335.583022 -395.538884) (xy 335.575832 -395.490513) (xy 335.575402 -395.466062)
			(xy 335.575773 -395.443224) (xy 335.582024 -395.397978) (xy 335.587848 -395.375892) (xy 335.59115 -395.364208)
			(xy 335.586832 -395.341094) (xy 335.530698 -395.266672) (xy 335.523101 -395.257695) (xy 335.502056 -395.247258)
			(xy 335.490312 -395.246606) (xy 334.05699 -395.246606) (xy 334.045753 -395.247194) (xy 334.02545 -395.256827)
			(xy 334.017874 -395.265148) (xy 333.960724 -395.334236) (xy 333.955136 -395.35608) (xy 333.957422 -395.367256)
			(xy 333.960192 -395.382727) (xy 333.963121 -395.414023) (xy 333.963264 -395.42974) (xy 333.962754 -395.455727)
			(xy 333.954624 -395.507062) (xy 333.938563 -395.556492) (xy 333.914967 -395.602802) (xy 333.884417 -395.64485)
			(xy 333.847666 -395.681601) (xy 333.805618 -395.712151) (xy 333.759308 -395.735747) (xy 333.709878 -395.751808)
			(xy 333.658543 -395.759938) (xy 333.606569 -395.759938) (xy 333.555234 -395.751808) (xy 333.505804 -395.735747)
			(xy 333.459494 -395.712151) (xy 333.417446 -395.681601) (xy 333.380695 -395.64485) (xy 333.350145 -395.602802)
			(xy 333.326549 -395.556492) (xy 333.310488 -395.507062) (xy 333.302358 -395.455727) (xy 333.301848 -395.42974)
			(xy 333.30201 -395.414024) (xy 333.304933 -395.382729) (xy 333.30769 -395.367256) (xy 333.309976 -395.35608)
			(xy 333.304388 -395.334236) (xy 333.247238 -395.265148) (xy 333.239637 -395.256864) (xy 333.219346 -395.247243)
			(xy 333.208122 -395.246606) (xy 331.69987 -395.246606) (xy 331.689802 -395.247035) (xy 331.671206 -395.254758)
			(xy 331.663802 -395.261592) (xy 330.53909 -396.386304) (xy 330.531691 -396.393149) (xy 330.513093 -396.400879)
			(xy 330.503022 -396.40129) (xy 330.400152 -396.40129) (xy 330.390075 -396.40172) (xy 330.371482 -396.409497)
			(xy 330.357346 -396.42386) (xy 330.353162 -396.43304) (xy 330.312014 -396.534894) (xy 330.318364 -396.564866)
			(xy 330.32954 -396.575788) (xy 330.351949 -396.598341) (xy 330.389705 -396.649489) (xy 330.418484 -396.706175)
			(xy 330.4286 -396.736316) (xy 330.43241 -396.749016) (xy 330.451206 -396.766796) (xy 330.559918 -396.795752)
			(xy 330.58481 -396.789656) (xy 330.594462 -396.780512) (xy 330.618047 -396.759311) (xy 330.669556 -396.722313)
			(xy 330.725264 -396.692005) (xy 330.784308 -396.668856) (xy 330.845771 -396.653225) (xy 330.9087 -396.645356)
			(xy 330.94041 -396.644876) (xy 330.972372 -396.645379) (xy 331.035791 -396.653391) (xy 331.097705 -396.66929)
			(xy 331.123932 -396.679674) (xy 332.336392 -396.679674) (xy 332.340463 -396.624052) (xy 332.352589 -396.569615)
			(xy 332.372512 -396.517524) (xy 332.399808 -396.468889) (xy 332.433894 -396.424746) (xy 332.474043 -396.386037)
			(xy 332.519401 -396.353586) (xy 332.569001 -396.328085) (xy 332.621785 -396.310078) (xy 332.676628 -396.299948)
			(xy 332.732362 -396.297911) (xy 332.787799 -396.304011) (xy 332.841756 -396.318117) (xy 332.893085 -396.339929)
			(xy 332.940691 -396.368983) (xy 332.983559 -396.404658) (xy 333.020776 -396.446195) (xy 333.051549 -396.492708)
			(xy 333.075221 -396.543205) (xy 333.091289 -396.596612) (xy 333.099409 -396.651788) (xy 333.099918 -396.679674)
			(xy 333.099471 -396.704137) (xy 333.302358 -396.704137) (xy 333.302358 -396.652163) (xy 333.310488 -396.600828)
			(xy 333.326549 -396.551398) (xy 333.350145 -396.505088) (xy 333.380695 -396.46304) (xy 333.417446 -396.426289)
			(xy 333.459494 -396.395739) (xy 333.505804 -396.372143) (xy 333.555234 -396.356082) (xy 333.606569 -396.347952)
			(xy 333.658543 -396.347952) (xy 333.709878 -396.356082) (xy 333.759308 -396.372143) (xy 333.805618 -396.395739)
			(xy 333.847666 -396.426289) (xy 333.884417 -396.46304) (xy 333.914967 -396.505088) (xy 333.938563 -396.551398)
			(xy 333.954624 -396.600828) (xy 333.962754 -396.652163) (xy 333.963264 -396.67815) (xy 333.962754 -396.704137)
			(xy 333.954624 -396.755472) (xy 333.938563 -396.804902) (xy 333.914967 -396.851212) (xy 333.884417 -396.89326)
			(xy 333.847666 -396.930011) (xy 333.805618 -396.960561) (xy 333.759308 -396.984157) (xy 333.709878 -397.000218)
			(xy 333.658543 -397.008348) (xy 333.606569 -397.008348) (xy 333.555234 -397.000218) (xy 333.505804 -396.984157)
			(xy 333.459494 -396.960561) (xy 333.417446 -396.930011) (xy 333.380695 -396.89326) (xy 333.350145 -396.851212)
			(xy 333.326549 -396.804902) (xy 333.310488 -396.755472) (xy 333.302358 -396.704137) (xy 333.099471 -396.704137)
			(xy 333.099409 -396.70756) (xy 333.091289 -396.762736) (xy 333.075221 -396.816143) (xy 333.051549 -396.86664)
			(xy 333.020776 -396.913153) (xy 332.983559 -396.95469) (xy 332.940691 -396.990365) (xy 332.893085 -397.019419)
			(xy 332.841756 -397.041231) (xy 332.787799 -397.055337) (xy 332.732362 -397.061437) (xy 332.676628 -397.0594)
			(xy 332.621785 -397.04927) (xy 332.569001 -397.031263) (xy 332.519401 -397.005762) (xy 332.474043 -396.973311)
			(xy 332.433894 -396.934602) (xy 332.399808 -396.890459) (xy 332.372512 -396.841824) (xy 332.352589 -396.789733)
			(xy 332.340463 -396.735296) (xy 332.336392 -396.679674) (xy 331.123932 -396.679674) (xy 331.157139 -396.692822)
			(xy 331.213155 -396.723618) (xy 331.26487 -396.761192) (xy 331.311468 -396.804951) (xy 331.352213 -396.854205)
			(xy 331.386465 -396.908177) (xy 331.413682 -396.966017) (xy 331.433435 -397.026812) (xy 331.445413 -397.089603)
			(xy 331.449427 -397.1534) (xy 331.445413 -397.217197) (xy 331.433435 -397.279988) (xy 331.413682 -397.340783)
			(xy 331.386465 -397.398623) (xy 331.352213 -397.452595) (xy 331.311468 -397.501849) (xy 331.26487 -397.545608)
			(xy 331.213155 -397.583182) (xy 331.157139 -397.613978) (xy 331.097705 -397.63751) (xy 331.035791 -397.653409)
			(xy 330.972372 -397.661421) (xy 330.94041 -397.661892) (xy 330.909321 -397.661425) (xy 330.847607 -397.65384)
			(xy 330.78728 -397.638782) (xy 330.729241 -397.616477) (xy 330.674357 -397.587257) (xy 330.623448 -397.551559)
			(xy 330.60005 -397.531082) (xy 330.590144 -397.522192) (xy 330.564236 -397.51635) (xy 330.455524 -397.548862)
			(xy 330.436982 -397.568166) (xy 330.43368 -397.58112) (xy 330.426187 -397.608022) (xy 330.404414 -397.659446)
			(xy 330.375375 -397.707145) (xy 330.339691 -397.750101) (xy 330.298126 -397.787395) (xy 330.251567 -397.81823)
			(xy 330.20101 -397.841946) (xy 330.147536 -397.858038) (xy 330.092286 -397.86616) (xy 330.064364 -397.866616)
			(xy 330.037114 -397.866128) (xy 329.98317 -397.858367) (xy 329.930879 -397.843009) (xy 329.881306 -397.820366)
			(xy 329.835459 -397.790899) (xy 329.794273 -397.755207) (xy 329.758584 -397.714018) (xy 329.729121 -397.66817)
			(xy 329.706481 -397.618595) (xy 329.691127 -397.566303) (xy 329.68337 -397.512358) (xy 329.682856 -397.485108)
			(xy 329.683327 -397.457738) (xy 329.691151 -397.40356) (xy 329.706639 -397.351057) (xy 329.729473 -397.301307)
			(xy 329.759184 -397.255332) (xy 329.776836 -397.23441) (xy 329.782932 -397.227298) (xy 329.789282 -397.21028)
			(xy 329.789282 -397.124936) (xy 329.782932 -397.107918) (xy 329.776836 -397.100806) (xy 329.759192 -397.079875)
			(xy 329.729463 -397.03391) (xy 329.706616 -396.984163) (xy 329.691124 -396.931659) (xy 329.683304 -396.877479)
			(xy 329.682856 -396.850108) (xy 329.683474 -396.818979) (xy 329.693571 -396.757544) (xy 329.713483 -396.698555)
			(xy 329.72756 -396.670784) (xy 329.73264 -396.661132) (xy 329.734164 -396.639542) (xy 329.699874 -396.547594)
			(xy 329.68438 -396.5321) (xy 329.67422 -396.52829) (xy 329.644675 -396.516304) (xy 329.589736 -396.483956)
			(xy 329.540929 -396.442936) (xy 329.519788 -396.41907) (xy 329.512214 -396.411052) (xy 329.492197 -396.401842)
			(xy 329.48118 -396.40129) (xy 328.671936 -396.40129) (xy 328.660694 -396.401868) (xy 328.640374 -396.411487)
			(xy 328.63282 -396.419832) (xy 328.614605 -396.441062) (xy 328.573022 -396.478477) (xy 328.526421 -396.509419)
			(xy 328.475802 -396.533225) (xy 328.422249 -396.549385) (xy 328.366911 -396.557553) (xy 328.310973 -396.557553)
			(xy 328.255635 -396.549385) (xy 328.202082 -396.533225) (xy 328.151463 -396.509419) (xy 328.104862 -396.478477)
			(xy 328.063279 -396.441062) (xy 328.045064 -396.419832) (xy 328.037464 -396.411546) (xy 328.017173 -396.401918)
			(xy 328.005948 -396.40129) (xy 325.871332 -396.40129) (xy 325.861267 -396.401725) (xy 325.842679 -396.409456)
			(xy 325.835264 -396.416276) (xy 325.499476 -396.752064) (xy 325.491058 -396.76152) (xy 325.483891 -396.785768)
			(xy 325.48576 -396.798292) (xy 325.50608 -396.894558) (xy 325.52259 -396.913862) (xy 325.534782 -396.918688)
			(xy 325.565641 -396.931281) (xy 325.622746 -396.96564) (xy 325.64832 -396.987014) (xy 325.655432 -396.99311)
			(xy 325.67245 -396.99946) (xy 325.757794 -396.99946) (xy 325.774812 -396.99311) (xy 325.781924 -396.987014)
			(xy 325.802856 -396.969373) (xy 325.848822 -396.939649) (xy 325.898569 -396.916808) (xy 325.951073 -396.90132)
			(xy 326.005252 -396.893505) (xy 326.032622 -396.893034) (xy 326.059869 -396.893522) (xy 326.113809 -396.90128)
			(xy 326.166095 -396.916635) (xy 326.215664 -396.939275) (xy 326.261506 -396.968739) (xy 326.302689 -397.004426)
			(xy 326.338375 -397.045611) (xy 326.367835 -397.091456) (xy 326.390473 -397.141026) (xy 326.40202 -397.180352)
			(xy 327.740985 -397.180352) (xy 327.740985 -397.125848) (xy 327.748742 -397.071899) (xy 327.764099 -397.019603)
			(xy 327.786741 -396.970025) (xy 327.816209 -396.924175) (xy 327.851903 -396.882984) (xy 327.893095 -396.847294)
			(xy 327.938948 -396.817829) (xy 327.988528 -396.795189) (xy 328.040825 -396.779837) (xy 328.094774 -396.772083)
			(xy 328.122026 -396.771622) (xy 328.149397 -396.772067) (xy 328.203577 -396.779889) (xy 328.256081 -396.795383)
			(xy 328.305827 -396.818229) (xy 328.351793 -396.847959) (xy 328.372724 -396.865602) (xy 328.379836 -396.871698)
			(xy 328.396854 -396.878048) (xy 328.482198 -396.878048) (xy 328.499216 -396.871698) (xy 328.506328 -396.865602)
			(xy 328.527277 -396.847984) (xy 328.573245 -396.818269) (xy 328.622988 -396.795429) (xy 328.675485 -396.779933)
			(xy 328.729658 -396.772099) (xy 328.757026 -396.771622) (xy 328.784278 -396.77205) (xy 328.838227 -396.77981)
			(xy 328.890523 -396.795168) (xy 328.940101 -396.817813) (xy 328.985952 -396.847282) (xy 329.027142 -396.882976)
			(xy 329.062834 -396.924169) (xy 329.0923 -396.970022) (xy 329.114941 -397.019601) (xy 329.130296 -397.071898)
			(xy 329.138052 -397.125848) (xy 329.138052 -397.180352) (xy 329.130296 -397.234302) (xy 329.114941 -397.286599)
			(xy 329.0923 -397.336178) (xy 329.062834 -397.382031) (xy 329.027142 -397.423224) (xy 328.985952 -397.458918)
			(xy 328.940101 -397.488387) (xy 328.890523 -397.511032) (xy 328.838227 -397.52639) (xy 328.784278 -397.53415)
			(xy 328.757026 -397.534638) (xy 328.729656 -397.534172) (xy 328.675476 -397.526356) (xy 328.622972 -397.510868)
			(xy 328.573225 -397.488026) (xy 328.527259 -397.4583) (xy 328.506328 -397.440658) (xy 328.499216 -397.434562)
			(xy 328.482198 -397.428212) (xy 328.396854 -397.428212) (xy 328.379836 -397.434562) (xy 328.372724 -397.440658)
			(xy 328.351788 -397.458293) (xy 328.305817 -397.488007) (xy 328.256071 -397.510844) (xy 328.203571 -397.526336)
			(xy 328.149395 -397.534164) (xy 328.122026 -397.534638) (xy 328.094774 -397.534117) (xy 328.040825 -397.526363)
			(xy 327.988528 -397.511011) (xy 327.938948 -397.488371) (xy 327.893095 -397.458906) (xy 327.851903 -397.423216)
			(xy 327.816209 -397.382025) (xy 327.786741 -397.336175) (xy 327.764099 -397.286597) (xy 327.748742 -397.234301)
			(xy 327.740985 -397.180352) (xy 326.40202 -397.180352) (xy 326.405825 -397.193313) (xy 326.41358 -397.247253)
			(xy 326.41358 -397.301747) (xy 326.405825 -397.355687) (xy 326.390473 -397.407974) (xy 326.367835 -397.457544)
			(xy 326.338375 -397.503389) (xy 326.302689 -397.544574) (xy 326.261506 -397.580261) (xy 326.215664 -397.609725)
			(xy 326.166095 -397.632365) (xy 326.113809 -397.64772) (xy 326.059869 -397.655478) (xy 326.032622 -397.65605)
			(xy 326.005254 -397.655573) (xy 325.951082 -397.647738) (xy 325.898586 -397.632241) (xy 325.848844 -397.609399)
			(xy 325.802878 -397.579682) (xy 325.781924 -397.56207) (xy 325.774812 -397.555974) (xy 325.757794 -397.549624)
			(xy 325.67245 -397.549624) (xy 325.655432 -397.555974) (xy 325.64832 -397.56207) (xy 325.627387 -397.579711)
			(xy 325.581419 -397.609435) (xy 325.531673 -397.632281) (xy 325.479171 -397.647777) (xy 325.424993 -397.655606)
			(xy 325.370251 -397.655606) (xy 325.316073 -397.647777) (xy 325.263571 -397.632281) (xy 325.213825 -397.609435)
			(xy 325.167857 -397.579711) (xy 325.146924 -397.56207) (xy 325.139812 -397.555974) (xy 325.122794 -397.549624)
			(xy 325.03745 -397.549624) (xy 325.020432 -397.555974) (xy 325.01332 -397.56207) (xy 324.99239 -397.579714)
			(xy 324.946424 -397.609445) (xy 324.896678 -397.632293) (xy 324.844174 -397.647787) (xy 324.789993 -397.655609)
			(xy 324.762622 -397.65605) (xy 324.734187 -397.655545) (xy 324.677946 -397.647125) (xy 324.650608 -397.639286)
			(xy 324.636892 -397.634968) (xy 324.609714 -397.641826) (xy 324.18147 -398.07007) (xy 324.174104 -398.09293)
			(xy 324.175882 -398.105122) (xy 324.177669 -398.117554) (xy 324.179579 -398.142601) (xy 324.179692 -398.15516)
			(xy 324.179276 -398.178932) (xy 324.172458 -398.225986) (xy 324.158972 -398.271578) (xy 324.139096 -398.314769)
			(xy 324.113239 -398.354668) (xy 324.097904 -398.372838) (xy 324.092224 -398.37996) (xy 324.085847 -398.397011)
			(xy 324.085458 -398.406112) (xy 324.085458 -398.437608) (xy 324.085838 -398.44671) (xy 324.092225 -398.463757)
			(xy 324.097904 -398.470882) (xy 324.11325 -398.489043) (xy 324.139111 -398.52894) (xy 324.158984 -398.572133)
			(xy 324.172457 -398.61773) (xy 324.179252 -398.664787) (xy 324.179692 -398.68856) (xy 324.179135 -398.716149)
			(xy 324.173929 -398.747054) (xy 326.121957 -398.747054) (xy 326.121957 -398.692546) (xy 326.129715 -398.638593)
			(xy 326.145073 -398.586293) (xy 326.167717 -398.536711) (xy 326.197188 -398.490857) (xy 326.232885 -398.449663)
			(xy 326.274081 -398.41397) (xy 326.319937 -398.384503) (xy 326.369521 -398.361862) (xy 326.421822 -398.346509)
			(xy 326.475776 -398.338755) (xy 326.50303 -398.338294) (xy 326.530401 -398.338744) (xy 326.584581 -398.346566)
			(xy 326.637084 -398.362059) (xy 326.68683 -398.384904) (xy 326.732797 -398.414632) (xy 326.753728 -398.432274)
			(xy 326.76084 -398.43837) (xy 326.777858 -398.44472) (xy 326.863202 -398.44472) (xy 326.88022 -398.43837)
			(xy 326.887332 -398.432274) (xy 326.908276 -398.414649) (xy 326.954246 -398.384936) (xy 327.00399 -398.362098)
			(xy 327.056488 -398.346603) (xy 327.110662 -398.338771) (xy 327.13803 -398.338294) (xy 327.16528 -398.338778)
			(xy 327.219225 -398.346538) (xy 327.271516 -398.361896) (xy 327.32109 -398.384539) (xy 327.366937 -398.414006)
			(xy 327.408124 -398.449698) (xy 327.443812 -398.490887) (xy 327.473276 -398.536736) (xy 327.495915 -398.586312)
			(xy 327.511269 -398.638605) (xy 327.519024 -398.69255) (xy 327.519024 -398.74705) (xy 327.511269 -398.800995)
			(xy 327.495915 -398.853288) (xy 327.473276 -398.902864) (xy 327.443812 -398.948713) (xy 327.408124 -398.989902)
			(xy 327.366937 -399.025594) (xy 327.32109 -399.055061) (xy 327.271516 -399.077704) (xy 327.219225 -399.093062)
			(xy 327.16528 -399.100822) (xy 327.13803 -399.10131) (xy 327.110661 -399.100824) (xy 327.056482 -399.093011)
			(xy 327.00398 -399.077526) (xy 326.954232 -399.054689) (xy 326.908265 -399.024969) (xy 326.887332 -399.00733)
			(xy 326.88022 -399.001234) (xy 326.863202 -398.994884) (xy 326.777858 -398.994884) (xy 326.76084 -399.001234)
			(xy 326.753728 -399.00733) (xy 326.7328 -399.024974) (xy 326.686826 -399.054684) (xy 326.637077 -399.077519)
			(xy 326.584576 -399.093009) (xy 326.530399 -399.100836) (xy 326.50303 -399.10131) (xy 326.475776 -399.100845)
			(xy 326.421822 -399.093091) (xy 326.369521 -399.077738) (xy 326.319937 -399.055097) (xy 326.274081 -399.02563)
			(xy 326.232885 -398.989937) (xy 326.197188 -398.948743) (xy 326.167717 -398.902889) (xy 326.145073 -398.853307)
			(xy 326.129715 -398.801007) (xy 326.121957 -398.747054) (xy 324.173929 -398.747054) (xy 324.169969 -398.77056)
			(xy 324.151903 -398.822696) (xy 324.125437 -398.871111) (xy 324.091303 -398.914464) (xy 324.05045 -398.951553)
			(xy 324.027546 -398.966944) (xy 324.019982 -398.972204) (xy 324.008924 -398.986923) (xy 324.005956 -398.995646)
			(xy 323.99732 -399.025618) (xy 323.995126 -399.034568) (xy 323.99657 -399.052924) (xy 324.000114 -399.061432)
			(xy 324.009889 -399.083411) (xy 324.023693 -399.129489) (xy 324.030673 -399.177081) (xy 324.031102 -399.201132)
			(xy 324.030698 -399.224857) (xy 324.023924 -399.27182) (xy 324.010505 -399.317333) (xy 323.990718 -399.36046)
			(xy 323.964968 -399.400315) (xy 323.933785 -399.436079) (xy 323.91604 -399.45183) (xy 323.908029 -399.459408)
			(xy 323.898832 -399.479424) (xy 323.89826 -399.490438) (xy 323.89826 -400.788378) (xy 323.923406 -400.81708)
			(xy 323.942456 -400.81962) (xy 323.96966 -400.823648) (xy 324.022607 -400.83851) (xy 324.07287 -400.860822)
			(xy 324.119407 -400.890122) (xy 324.161254 -400.925802) (xy 324.197542 -400.967123) (xy 324.227518 -401.013228)
			(xy 324.250562 -401.06316) (xy 324.266195 -401.115884) (xy 324.274093 -401.170307) (xy 324.274093 -401.2253)
			(xy 324.266194 -401.279722) (xy 324.25056 -401.332446) (xy 324.227515 -401.382378) (xy 324.197538 -401.428482)
			(xy 324.161249 -401.469802) (xy 324.119402 -401.505482) (xy 324.072864 -401.534781) (xy 324.0226 -401.557092)
			(xy 323.969653 -401.571953) (xy 323.942456 -401.576032) (xy 323.923406 -401.578572) (xy 323.89826 -401.607274)
			(xy 323.89826 -401.717002) (xy 324.23303 -401.717002) (xy 324.237101 -401.66138) (xy 324.249227 -401.606943)
			(xy 324.26915 -401.554852) (xy 324.296446 -401.506217) (xy 324.330532 -401.462074) (xy 324.370681 -401.423365)
			(xy 324.416039 -401.390914) (xy 324.465639 -401.365413) (xy 324.518423 -401.347406) (xy 324.573266 -401.337276)
			(xy 324.629 -401.335239) (xy 324.684437 -401.341339) (xy 324.738394 -401.355445) (xy 324.789723 -401.377257)
			(xy 324.837329 -401.406311) (xy 324.880197 -401.441986) (xy 324.917414 -401.483523) (xy 324.948187 -401.530036)
			(xy 324.971859 -401.580533) (xy 324.987927 -401.63394) (xy 324.996047 -401.689116) (xy 324.996556 -401.717002)
			(xy 324.996047 -401.744888) (xy 324.987927 -401.800064) (xy 324.971859 -401.853471) (xy 324.948674 -401.90293)
			(xy 325.225918 -401.90293) (xy 325.226372 -401.872233) (xy 325.233778 -401.811287) (xy 325.248475 -401.751678)
			(xy 325.270247 -401.694275) (xy 325.298778 -401.639913) (xy 325.315834 -401.614386) (xy 325.321278 -401.60562)
			(xy 325.325412 -401.585425) (xy 325.321297 -401.565226) (xy 325.315834 -401.556474) (xy 325.298794 -401.530939)
			(xy 325.270285 -401.476571) (xy 325.248522 -401.419168) (xy 325.233822 -401.359564) (xy 325.226398 -401.298625)
			(xy 325.225918 -401.26793) (xy 325.226366 -401.237198) (xy 325.233772 -401.17618) (xy 325.248479 -401.116501)
			(xy 325.270272 -401.05903) (xy 325.298835 -401.004604) (xy 325.33375 -400.954019) (xy 325.374509 -400.908012)
			(xy 325.420516 -400.867253) (xy 325.471101 -400.832337) (xy 325.525526 -400.803774) (xy 325.582997 -400.78198)
			(xy 325.642676 -400.767272) (xy 325.703694 -400.759866) (xy 325.734426 -400.759422) (xy 325.765122 -400.759897)
			(xy 325.826067 -400.767299) (xy 325.885676 -400.78199) (xy 325.94308 -400.803758) (xy 325.997443 -400.832284)
			(xy 326.02297 -400.849338) (xy 326.031722 -400.854809) (xy 326.051926 -400.858937) (xy 326.07213 -400.854809)
			(xy 326.080882 -400.849338) (xy 326.106429 -400.832317) (xy 326.160794 -400.803805) (xy 326.218194 -400.782038)
			(xy 326.277795 -400.767334) (xy 326.338732 -400.759905) (xy 326.369426 -400.759422) (xy 326.400122 -400.759897)
			(xy 326.461067 -400.767299) (xy 326.520676 -400.78199) (xy 326.57808 -400.803758) (xy 326.632443 -400.832284)
			(xy 326.65797 -400.849338) (xy 326.666722 -400.854809) (xy 326.686926 -400.858937) (xy 326.70713 -400.854809)
			(xy 326.715882 -400.849338) (xy 326.741429 -400.832317) (xy 326.795794 -400.803805) (xy 326.853194 -400.782038)
			(xy 326.912795 -400.767334) (xy 326.973732 -400.759905) (xy 327.004426 -400.759422) (xy 327.025508 -400.75993)
			(xy 327.03643 -400.760438) (xy 327.055988 -400.752818) (xy 327.124314 -400.684492) (xy 327.131934 -400.664934)
			(xy 327.131426 -400.654012) (xy 327.130918 -400.63293) (xy 327.131372 -400.602233) (xy 327.138778 -400.541287)
			(xy 327.153475 -400.481678) (xy 327.175247 -400.424275) (xy 327.203778 -400.369913) (xy 327.220834 -400.344386)
			(xy 327.226278 -400.33562) (xy 327.230412 -400.315425) (xy 327.226297 -400.295226) (xy 327.220834 -400.286474)
			(xy 327.203794 -400.260939) (xy 327.175285 -400.206571) (xy 327.153522 -400.149168) (xy 327.138822 -400.089564)
			(xy 327.131398 -400.028625) (xy 327.130918 -399.99793) (xy 327.131521 -399.964696) (xy 327.14019 -399.898797)
			(xy 327.157371 -399.834588) (xy 327.182771 -399.773165) (xy 327.215957 -399.715575) (xy 327.256364 -399.6628)
			(xy 327.303303 -399.615739) (xy 327.355972 -399.575195) (xy 327.413475 -399.541859) (xy 327.474832 -399.516298)
			(xy 327.538995 -399.49895) (xy 327.571862 -399.493994) (xy 327.583292 -399.49247) (xy 327.601834 -399.480532)
			(xy 327.655682 -399.395188) (xy 327.658476 -399.373344) (xy 327.65492 -399.362168) (xy 327.643621 -399.324435)
			(xy 327.631505 -399.24661) (xy 327.63079 -399.207228) (xy 327.631264 -399.176497) (xy 327.638669 -399.115481)
			(xy 327.653376 -399.055804) (xy 327.675168 -398.998334) (xy 327.703729 -398.94391) (xy 327.738642 -398.893326)
			(xy 327.779398 -398.847319) (xy 327.825403 -398.806561) (xy 327.875985 -398.771645) (xy 327.930407 -398.74308)
			(xy 327.987875 -398.721284) (xy 328.047552 -398.706575) (xy 328.108567 -398.699166) (xy 328.139298 -398.69872)
			(xy 328.169995 -398.699159) (xy 328.230942 -398.706569) (xy 328.290551 -398.721269) (xy 328.347954 -398.743044)
			(xy 328.402316 -398.771579) (xy 328.427842 -398.788636) (xy 328.436594 -398.794107) (xy 328.456798 -398.798235)
			(xy 328.477002 -398.794107) (xy 328.485754 -398.788636) (xy 328.511281 -398.771584) (xy 328.565652 -398.743077)
			(xy 328.623057 -398.721317) (xy 328.682662 -398.706619) (xy 328.743603 -398.699199) (xy 328.774298 -398.69872)
			(xy 328.805031 -398.69914) (xy 328.866049 -398.706549) (xy 328.925729 -398.721259) (xy 328.983201 -398.743056)
			(xy 329.037626 -398.771621) (xy 329.088212 -398.806539) (xy 329.134219 -398.8473) (xy 329.174977 -398.893309)
			(xy 329.209892 -398.943896) (xy 329.238455 -398.998323) (xy 329.260249 -399.055795) (xy 329.274956 -399.115476)
			(xy 329.282362 -399.176495) (xy 329.282806 -399.207228) (xy 329.282236 -399.242074) (xy 329.272721 -399.311114)
			(xy 329.253871 -399.378209) (xy 329.226041 -399.442103) (xy 329.208384 -399.47215) (xy 329.203304 -399.480278)
			(xy 329.200002 -399.498058) (xy 329.21448 -399.582386) (xy 329.223624 -399.59788) (xy 329.230736 -399.603976)
			(xy 329.255363 -399.62474) (xy 329.299742 -399.67143) (xy 329.337874 -399.723347) (xy 329.369147 -399.779663)
			(xy 329.393063 -399.839475) (xy 329.409239 -399.901827) (xy 329.417415 -399.965722) (xy 329.417934 -399.99793)
			(xy 329.417451 -400.028626) (xy 329.41005 -400.08957) (xy 329.39536 -400.149179) (xy 329.373594 -400.206583)
			(xy 329.34507 -400.260946) (xy 329.328018 -400.286474) (xy 329.322519 -400.295211) (xy 329.318397 -400.315425)
			(xy 329.322538 -400.335634) (xy 329.328018 -400.344386) (xy 329.345035 -400.369936) (xy 329.37355 -400.424299)
			(xy 329.395317 -400.481699) (xy 329.410022 -400.541299) (xy 329.417451 -400.602236) (xy 329.417934 -400.63293)
			(xy 329.417472 -400.663661) (xy 329.410061 -400.724673) (xy 329.39535 -400.784348) (xy 329.373553 -400.841815)
			(xy 329.344989 -400.896235) (xy 329.310074 -400.946816) (xy 329.269318 -400.992821) (xy 329.223313 -401.033577)
			(xy 329.172732 -401.068491) (xy 329.118311 -401.097055) (xy 329.060844 -401.118851) (xy 329.00117 -401.133561)
			(xy 328.940157 -401.140972) (xy 328.909426 -401.141438) (xy 328.888344 -401.14093) (xy 328.877422 -401.140422)
			(xy 328.857864 -401.148042) (xy 328.789538 -401.216368) (xy 328.781918 -401.235926) (xy 328.782426 -401.246848)
			(xy 328.782934 -401.26793) (xy 328.782451 -401.298626) (xy 328.77505 -401.35957) (xy 328.76036 -401.419179)
			(xy 328.738594 -401.476583) (xy 328.71007 -401.530946) (xy 328.693018 -401.556474) (xy 328.687519 -401.565211)
			(xy 328.683397 -401.585425) (xy 328.687538 -401.605634) (xy 328.693018 -401.614386) (xy 328.710035 -401.639936)
			(xy 328.73855 -401.694299) (xy 328.760317 -401.751699) (xy 328.775022 -401.811299) (xy 328.782451 -401.872236)
			(xy 328.782934 -401.90293) (xy 329.637898 -401.90293) (xy 329.638382 -401.87556) (xy 329.646196 -401.821382)
			(xy 329.661681 -401.768879) (xy 329.684518 -401.719132) (xy 329.714239 -401.673164) (xy 329.731878 -401.652232)
			(xy 329.737974 -401.64512) (xy 329.744324 -401.628102) (xy 329.744324 -401.542758) (xy 329.737974 -401.52574)
			(xy 329.731878 -401.518628) (xy 329.714269 -401.49767) (xy 329.684546 -401.451706) (xy 329.661702 -401.401963)
			(xy 329.646206 -401.349465) (xy 329.638376 -401.295291) (xy 329.638372 -401.240554) (xy 329.646196 -401.186379)
			(xy 329.661686 -401.133879) (xy 329.684525 -401.084134) (xy 329.714241 -401.038166) (xy 329.731878 -401.017232)
			(xy 329.737974 -401.01012) (xy 329.744324 -400.993102) (xy 329.744324 -400.907758) (xy 329.737974 -400.89074)
			(xy 329.731878 -400.883628) (xy 329.714269 -400.86267) (xy 329.684546 -400.816706) (xy 329.661702 -400.766963)
			(xy 329.646206 -400.714465) (xy 329.638376 -400.660291) (xy 329.638372 -400.605554) (xy 329.646196 -400.551379)
			(xy 329.661686 -400.498879) (xy 329.684525 -400.449134) (xy 329.714241 -400.403166) (xy 329.731878 -400.382232)
			(xy 329.737974 -400.37512) (xy 329.744324 -400.358102) (xy 329.744324 -400.272758) (xy 329.737974 -400.25574)
			(xy 329.731878 -400.248628) (xy 329.714235 -400.227699) (xy 329.684525 -400.181725) (xy 329.66169 -400.131977)
			(xy 329.6462 -400.079475) (xy 329.638372 -400.025299) (xy 329.637898 -399.99793) (xy 329.638403 -399.970461)
			(xy 329.646285 -399.916091) (xy 329.661878 -399.863412) (xy 329.684858 -399.813511) (xy 329.714752 -399.767419)
			(xy 329.750942 -399.726085) (xy 329.771502 -399.707862) (xy 329.779122 -399.701258) (xy 329.788266 -399.683478)
			(xy 329.795378 -399.591276) (xy 329.789028 -399.571972) (xy 329.78217 -399.564352) (xy 329.764777 -399.543446)
			(xy 329.735469 -399.497637) (xy 329.71295 -399.448137) (xy 329.697673 -399.395945) (xy 329.689948 -399.342115)
			(xy 329.68946 -399.314924) (xy 329.689926 -399.287554) (xy 329.697741 -399.233374) (xy 329.71323 -399.18087)
			(xy 329.736072 -399.131123) (xy 329.765798 -399.085157) (xy 329.78344 -399.064226) (xy 329.789536 -399.057114)
			(xy 329.795886 -399.040096) (xy 329.795886 -398.954752) (xy 329.789536 -398.937734) (xy 329.78344 -398.930622)
			(xy 329.765804 -398.909687) (xy 329.73609 -398.863716) (xy 329.713253 -398.813969) (xy 329.697761 -398.761469)
			(xy 329.689934 -398.707293) (xy 329.68946 -398.679924) (xy 329.689946 -398.652673) (xy 329.697702 -398.598725)
			(xy 329.713057 -398.54643) (xy 329.735699 -398.496853) (xy 329.765165 -398.451003) (xy 329.800856 -398.409812)
			(xy 329.842047 -398.374121) (xy 329.887897 -398.344655) (xy 329.937474 -398.322013) (xy 329.989769 -398.306658)
			(xy 330.043717 -398.298902) (xy 330.098219 -398.298902) (xy 330.152167 -398.306658) (xy 330.204462 -398.322013)
			(xy 330.254039 -398.344655) (xy 330.299889 -398.374121) (xy 330.34108 -398.409812) (xy 330.376771 -398.451003)
			(xy 330.406237 -398.496853) (xy 330.428879 -398.54643) (xy 330.444234 -398.598725) (xy 330.45199 -398.652673)
			(xy 330.452476 -398.679924) (xy 330.45203 -398.707295) (xy 330.444208 -398.761475) (xy 330.428715 -398.813979)
			(xy 330.405868 -398.863725) (xy 330.376139 -398.909691) (xy 330.358496 -398.930622) (xy 330.3524 -398.937734)
			(xy 330.34605 -398.954752) (xy 330.34605 -399.008092) (xy 333.290164 -399.008092) (xy 333.290583 -398.984859)
			(xy 333.297077 -398.938849) (xy 333.309948 -398.894202) (xy 333.328945 -398.851797) (xy 333.353692 -398.81247)
			(xy 333.368396 -398.794478) (xy 333.374492 -398.787366) (xy 333.380588 -398.770856) (xy 333.380588 -398.686528)
			(xy 333.374492 -398.670018) (xy 333.368396 -398.662906) (xy 333.353675 -398.644926) (xy 333.328931 -398.605594)
			(xy 333.309934 -398.563186) (xy 333.297058 -398.518538) (xy 333.290557 -398.472526) (xy 333.290164 -398.449292)
			(xy 333.290674 -398.423305) (xy 333.298804 -398.37197) (xy 333.314865 -398.32254) (xy 333.338461 -398.27623)
			(xy 333.369011 -398.234182) (xy 333.405762 -398.197431) (xy 333.44781 -398.166881) (xy 333.49412 -398.143285)
			(xy 333.54355 -398.127224) (xy 333.594885 -398.119094) (xy 333.646859 -398.119094) (xy 333.698194 -398.127224)
			(xy 333.747624 -398.143285) (xy 333.793934 -398.166881) (xy 333.835982 -398.197431) (xy 333.872733 -398.234182)
			(xy 333.903283 -398.27623) (xy 333.926879 -398.32254) (xy 333.94294 -398.37197) (xy 333.95107 -398.423305)
			(xy 333.95158 -398.449292) (xy 333.951223 -398.472527) (xy 333.944717 -398.51854) (xy 333.937946 -398.542002)
			(xy 335.612752 -398.542002) (xy 335.616712 -398.492948) (xy 335.628489 -398.445164) (xy 335.64778 -398.399888)
			(xy 335.674083 -398.358292) (xy 335.706718 -398.321455) (xy 335.744839 -398.29033) (xy 335.78746 -398.265723)
			(xy 335.833476 -398.248271) (xy 335.881695 -398.238427) (xy 335.93087 -398.236446) (xy 335.979725 -398.242378)
			(xy 336.026996 -398.25607) (xy 336.071458 -398.277168) (xy 336.111961 -398.305124) (xy 336.147454 -398.339216)
			(xy 336.177019 -398.37856) (xy 336.19989 -398.422137) (xy 336.215474 -398.468818) (xy 336.223369 -398.517395)
			(xy 336.223864 -398.542002) (xy 336.812902 -398.542002) (xy 336.816862 -398.492948) (xy 336.828639 -398.445164)
			(xy 336.84793 -398.399888) (xy 336.874233 -398.358292) (xy 336.906868 -398.321455) (xy 336.944989 -398.29033)
			(xy 336.98761 -398.265723) (xy 337.033626 -398.248271) (xy 337.081845 -398.238427) (xy 337.13102 -398.236446)
			(xy 337.179875 -398.242378) (xy 337.227146 -398.25607) (xy 337.271608 -398.277168) (xy 337.312111 -398.305124)
			(xy 337.347604 -398.339216) (xy 337.377169 -398.37856) (xy 337.40004 -398.422137) (xy 337.415624 -398.468818)
			(xy 337.423519 -398.517395) (xy 337.424014 -398.542002) (xy 338.013052 -398.542002) (xy 338.017012 -398.492948)
			(xy 338.028789 -398.445164) (xy 338.04808 -398.399888) (xy 338.074383 -398.358292) (xy 338.107018 -398.321455)
			(xy 338.145139 -398.29033) (xy 338.18776 -398.265723) (xy 338.233776 -398.248271) (xy 338.281995 -398.238427)
			(xy 338.33117 -398.236446) (xy 338.380025 -398.242378) (xy 338.427296 -398.25607) (xy 338.471758 -398.277168)
			(xy 338.512261 -398.305124) (xy 338.547754 -398.339216) (xy 338.577319 -398.37856) (xy 338.60019 -398.422137)
			(xy 338.615774 -398.468818) (xy 338.623669 -398.517395) (xy 338.624164 -398.542002) (xy 339.212948 -398.542002)
			(xy 339.216908 -398.492948) (xy 339.228685 -398.445164) (xy 339.247976 -398.399888) (xy 339.274279 -398.358292)
			(xy 339.306914 -398.321455) (xy 339.345035 -398.29033) (xy 339.387656 -398.265723) (xy 339.433672 -398.248271)
			(xy 339.481891 -398.238427) (xy 339.531066 -398.236446) (xy 339.579921 -398.242378) (xy 339.627192 -398.25607)
			(xy 339.671654 -398.277168) (xy 339.712157 -398.305124) (xy 339.74765 -398.339216) (xy 339.777215 -398.37856)
			(xy 339.800086 -398.422137) (xy 339.81567 -398.468818) (xy 339.823565 -398.517395) (xy 339.82406 -398.542002)
			(xy 340.413098 -398.542002) (xy 340.417058 -398.492948) (xy 340.428835 -398.445164) (xy 340.448126 -398.399888)
			(xy 340.474429 -398.358292) (xy 340.507064 -398.321455) (xy 340.545185 -398.29033) (xy 340.587806 -398.265723)
			(xy 340.633822 -398.248271) (xy 340.682041 -398.238427) (xy 340.731216 -398.236446) (xy 340.780071 -398.242378)
			(xy 340.827342 -398.25607) (xy 340.871804 -398.277168) (xy 340.912307 -398.305124) (xy 340.9478 -398.339216)
			(xy 340.977365 -398.37856) (xy 341.000236 -398.422137) (xy 341.01582 -398.468818) (xy 341.023715 -398.517395)
			(xy 341.02421 -398.542002) (xy 341.612994 -398.542002) (xy 341.616954 -398.492948) (xy 341.628731 -398.445164)
			(xy 341.648022 -398.399888) (xy 341.674325 -398.358292) (xy 341.70696 -398.321455) (xy 341.745081 -398.29033)
			(xy 341.787702 -398.265723) (xy 341.833718 -398.248271) (xy 341.881937 -398.238427) (xy 341.931112 -398.236446)
			(xy 341.979967 -398.242378) (xy 342.027238 -398.25607) (xy 342.0717 -398.277168) (xy 342.112203 -398.305124)
			(xy 342.147696 -398.339216) (xy 342.177261 -398.37856) (xy 342.200132 -398.422137) (xy 342.215716 -398.468818)
			(xy 342.223611 -398.517395) (xy 342.224106 -398.542002) (xy 342.81289 -398.542002) (xy 342.81685 -398.492948)
			(xy 342.828627 -398.445164) (xy 342.847918 -398.399888) (xy 342.874221 -398.358292) (xy 342.906856 -398.321455)
			(xy 342.944977 -398.29033) (xy 342.987598 -398.265723) (xy 343.033614 -398.248271) (xy 343.081833 -398.238427)
			(xy 343.131008 -398.236446) (xy 343.179863 -398.242378) (xy 343.227134 -398.25607) (xy 343.271596 -398.277168)
			(xy 343.312099 -398.305124) (xy 343.347592 -398.339216) (xy 343.377157 -398.37856) (xy 343.400028 -398.422137)
			(xy 343.415612 -398.468818) (xy 343.423507 -398.517395) (xy 343.424002 -398.542002) (xy 344.01304 -398.542002)
			(xy 344.017 -398.492948) (xy 344.028777 -398.445164) (xy 344.048068 -398.399888) (xy 344.074371 -398.358292)
			(xy 344.107006 -398.321455) (xy 344.145127 -398.29033) (xy 344.187748 -398.265723) (xy 344.233764 -398.248271)
			(xy 344.281983 -398.238427) (xy 344.331158 -398.236446) (xy 344.380013 -398.242378) (xy 344.427284 -398.25607)
			(xy 344.471746 -398.277168) (xy 344.512249 -398.305124) (xy 344.547742 -398.339216) (xy 344.577307 -398.37856)
			(xy 344.600178 -398.422137) (xy 344.615762 -398.468818) (xy 344.623657 -398.517395) (xy 344.624152 -398.542002)
			(xy 345.212936 -398.542002) (xy 345.216896 -398.492948) (xy 345.228673 -398.445164) (xy 345.247964 -398.399888)
			(xy 345.274267 -398.358292) (xy 345.306902 -398.321455) (xy 345.345023 -398.29033) (xy 345.387644 -398.265723)
			(xy 345.43366 -398.248271) (xy 345.481879 -398.238427) (xy 345.531054 -398.236446) (xy 345.579909 -398.242378)
			(xy 345.62718 -398.25607) (xy 345.671642 -398.277168) (xy 345.712145 -398.305124) (xy 345.747638 -398.339216)
			(xy 345.777203 -398.37856) (xy 345.800074 -398.422137) (xy 345.815658 -398.468818) (xy 345.823553 -398.517395)
			(xy 345.824048 -398.542002) (xy 346.413086 -398.542002) (xy 346.417046 -398.492948) (xy 346.428823 -398.445164)
			(xy 346.448114 -398.399888) (xy 346.474417 -398.358292) (xy 346.507052 -398.321455) (xy 346.545173 -398.29033)
			(xy 346.587794 -398.265723) (xy 346.63381 -398.248271) (xy 346.682029 -398.238427) (xy 346.731204 -398.236446)
			(xy 346.780059 -398.242378) (xy 346.82733 -398.25607) (xy 346.871792 -398.277168) (xy 346.912295 -398.305124)
			(xy 346.947788 -398.339216) (xy 346.977353 -398.37856) (xy 347.000224 -398.422137) (xy 347.015808 -398.468818)
			(xy 347.023703 -398.517395) (xy 347.024198 -398.542002) (xy 347.612982 -398.542002) (xy 347.616942 -398.492948)
			(xy 347.628719 -398.445164) (xy 347.64801 -398.399888) (xy 347.674313 -398.358292) (xy 347.706948 -398.321455)
			(xy 347.745069 -398.29033) (xy 347.78769 -398.265723) (xy 347.833706 -398.248271) (xy 347.881925 -398.238427)
			(xy 347.9311 -398.236446) (xy 347.979955 -398.242378) (xy 348.027226 -398.25607) (xy 348.071688 -398.277168)
			(xy 348.112191 -398.305124) (xy 348.147684 -398.339216) (xy 348.177249 -398.37856) (xy 348.20012 -398.422137)
			(xy 348.215704 -398.468818) (xy 348.223599 -398.517395) (xy 348.224094 -398.542002) (xy 348.812878 -398.542002)
			(xy 348.816838 -398.492948) (xy 348.828615 -398.445164) (xy 348.847906 -398.399888) (xy 348.874209 -398.358292)
			(xy 348.906844 -398.321455) (xy 348.944965 -398.29033) (xy 348.987586 -398.265723) (xy 349.033602 -398.248271)
			(xy 349.081821 -398.238427) (xy 349.130996 -398.236446) (xy 349.179851 -398.242378) (xy 349.227122 -398.25607)
			(xy 349.271584 -398.277168) (xy 349.312087 -398.305124) (xy 349.34758 -398.339216) (xy 349.377145 -398.37856)
			(xy 349.400016 -398.422137) (xy 349.4156 -398.468818) (xy 349.423495 -398.517395) (xy 349.42399 -398.542002)
			(xy 350.013028 -398.542002) (xy 350.016988 -398.492948) (xy 350.028765 -398.445164) (xy 350.048056 -398.399888)
			(xy 350.074359 -398.358292) (xy 350.106994 -398.321455) (xy 350.145115 -398.29033) (xy 350.187736 -398.265723)
			(xy 350.233752 -398.248271) (xy 350.281971 -398.238427) (xy 350.331146 -398.236446) (xy 350.380001 -398.242378)
			(xy 350.427272 -398.25607) (xy 350.471734 -398.277168) (xy 350.512237 -398.305124) (xy 350.54773 -398.339216)
			(xy 350.577295 -398.37856) (xy 350.600166 -398.422137) (xy 350.61575 -398.468818) (xy 350.623645 -398.517395)
			(xy 350.62414 -398.542002) (xy 351.212924 -398.542002) (xy 351.216884 -398.492948) (xy 351.228661 -398.445164)
			(xy 351.247952 -398.399888) (xy 351.274255 -398.358292) (xy 351.30689 -398.321455) (xy 351.345011 -398.29033)
			(xy 351.387632 -398.265723) (xy 351.433648 -398.248271) (xy 351.481867 -398.238427) (xy 351.531042 -398.236446)
			(xy 351.579897 -398.242378) (xy 351.627168 -398.25607) (xy 351.67163 -398.277168) (xy 351.712133 -398.305124)
			(xy 351.747626 -398.339216) (xy 351.777191 -398.37856) (xy 351.800062 -398.422137) (xy 351.815646 -398.468818)
			(xy 351.823541 -398.517395) (xy 351.824036 -398.542002) (xy 352.413074 -398.542002) (xy 352.417034 -398.492948)
			(xy 352.428811 -398.445164) (xy 352.448102 -398.399888) (xy 352.474405 -398.358292) (xy 352.50704 -398.321455)
			(xy 352.545161 -398.29033) (xy 352.587782 -398.265723) (xy 352.633798 -398.248271) (xy 352.682017 -398.238427)
			(xy 352.731192 -398.236446) (xy 352.780047 -398.242378) (xy 352.827318 -398.25607) (xy 352.87178 -398.277168)
			(xy 352.912283 -398.305124) (xy 352.947776 -398.339216) (xy 352.977341 -398.37856) (xy 353.000212 -398.422137)
			(xy 353.015796 -398.468818) (xy 353.023691 -398.517395) (xy 353.024186 -398.542002) (xy 353.61297 -398.542002)
			(xy 353.61693 -398.492948) (xy 353.628707 -398.445164) (xy 353.647998 -398.399888) (xy 353.674301 -398.358292)
			(xy 353.706936 -398.321455) (xy 353.745057 -398.29033) (xy 353.787678 -398.265723) (xy 353.833694 -398.248271)
			(xy 353.881913 -398.238427) (xy 353.931088 -398.236446) (xy 353.979943 -398.242378) (xy 354.027214 -398.25607)
			(xy 354.071676 -398.277168) (xy 354.112179 -398.305124) (xy 354.147672 -398.339216) (xy 354.177237 -398.37856)
			(xy 354.200108 -398.422137) (xy 354.215692 -398.468818) (xy 354.223587 -398.517395) (xy 354.224082 -398.542002)
			(xy 354.223587 -398.566609) (xy 354.215692 -398.615186) (xy 354.200108 -398.661867) (xy 354.177237 -398.705444)
			(xy 354.147672 -398.744788) (xy 354.112179 -398.77888) (xy 354.071676 -398.806836) (xy 354.027214 -398.827934)
			(xy 353.979943 -398.841626) (xy 353.931088 -398.847558) (xy 353.881913 -398.845577) (xy 353.833694 -398.835733)
			(xy 353.787678 -398.818281) (xy 353.745057 -398.793674) (xy 353.706936 -398.762549) (xy 353.674301 -398.725712)
			(xy 353.647998 -398.684116) (xy 353.628707 -398.63884) (xy 353.61693 -398.591056) (xy 353.61297 -398.542002)
			(xy 353.024186 -398.542002) (xy 353.023691 -398.566609) (xy 353.015796 -398.615186) (xy 353.000212 -398.661867)
			(xy 352.977341 -398.705444) (xy 352.947776 -398.744788) (xy 352.912283 -398.77888) (xy 352.87178 -398.806836)
			(xy 352.827318 -398.827934) (xy 352.780047 -398.841626) (xy 352.731192 -398.847558) (xy 352.682017 -398.845577)
			(xy 352.633798 -398.835733) (xy 352.587782 -398.818281) (xy 352.545161 -398.793674) (xy 352.50704 -398.762549)
			(xy 352.474405 -398.725712) (xy 352.448102 -398.684116) (xy 352.428811 -398.63884) (xy 352.417034 -398.591056)
			(xy 352.413074 -398.542002) (xy 351.824036 -398.542002) (xy 351.823541 -398.566609) (xy 351.815646 -398.615186)
			(xy 351.800062 -398.661867) (xy 351.777191 -398.705444) (xy 351.747626 -398.744788) (xy 351.712133 -398.77888)
			(xy 351.67163 -398.806836) (xy 351.627168 -398.827934) (xy 351.579897 -398.841626) (xy 351.531042 -398.847558)
			(xy 351.481867 -398.845577) (xy 351.433648 -398.835733) (xy 351.387632 -398.818281) (xy 351.345011 -398.793674)
			(xy 351.30689 -398.762549) (xy 351.274255 -398.725712) (xy 351.247952 -398.684116) (xy 351.228661 -398.63884)
			(xy 351.216884 -398.591056) (xy 351.212924 -398.542002) (xy 350.62414 -398.542002) (xy 350.623645 -398.566609)
			(xy 350.61575 -398.615186) (xy 350.600166 -398.661867) (xy 350.577295 -398.705444) (xy 350.54773 -398.744788)
			(xy 350.512237 -398.77888) (xy 350.471734 -398.806836) (xy 350.427272 -398.827934) (xy 350.380001 -398.841626)
			(xy 350.331146 -398.847558) (xy 350.281971 -398.845577) (xy 350.233752 -398.835733) (xy 350.187736 -398.818281)
			(xy 350.145115 -398.793674) (xy 350.106994 -398.762549) (xy 350.074359 -398.725712) (xy 350.048056 -398.684116)
			(xy 350.028765 -398.63884) (xy 350.016988 -398.591056) (xy 350.013028 -398.542002) (xy 349.42399 -398.542002)
			(xy 349.423495 -398.566609) (xy 349.4156 -398.615186) (xy 349.400016 -398.661867) (xy 349.377145 -398.705444)
			(xy 349.34758 -398.744788) (xy 349.312087 -398.77888) (xy 349.271584 -398.806836) (xy 349.227122 -398.827934)
			(xy 349.179851 -398.841626) (xy 349.130996 -398.847558) (xy 349.081821 -398.845577) (xy 349.033602 -398.835733)
			(xy 348.987586 -398.818281) (xy 348.944965 -398.793674) (xy 348.906844 -398.762549) (xy 348.874209 -398.725712)
			(xy 348.847906 -398.684116) (xy 348.828615 -398.63884) (xy 348.816838 -398.591056) (xy 348.812878 -398.542002)
			(xy 348.224094 -398.542002) (xy 348.223599 -398.566609) (xy 348.215704 -398.615186) (xy 348.20012 -398.661867)
			(xy 348.177249 -398.705444) (xy 348.147684 -398.744788) (xy 348.112191 -398.77888) (xy 348.071688 -398.806836)
			(xy 348.027226 -398.827934) (xy 347.979955 -398.841626) (xy 347.9311 -398.847558) (xy 347.881925 -398.845577)
			(xy 347.833706 -398.835733) (xy 347.78769 -398.818281) (xy 347.745069 -398.793674) (xy 347.706948 -398.762549)
			(xy 347.674313 -398.725712) (xy 347.64801 -398.684116) (xy 347.628719 -398.63884) (xy 347.616942 -398.591056)
			(xy 347.612982 -398.542002) (xy 347.024198 -398.542002) (xy 347.023703 -398.566609) (xy 347.015808 -398.615186)
			(xy 347.000224 -398.661867) (xy 346.977353 -398.705444) (xy 346.947788 -398.744788) (xy 346.912295 -398.77888)
			(xy 346.871792 -398.806836) (xy 346.82733 -398.827934) (xy 346.780059 -398.841626) (xy 346.731204 -398.847558)
			(xy 346.682029 -398.845577) (xy 346.63381 -398.835733) (xy 346.587794 -398.818281) (xy 346.545173 -398.793674)
			(xy 346.507052 -398.762549) (xy 346.474417 -398.725712) (xy 346.448114 -398.684116) (xy 346.428823 -398.63884)
			(xy 346.417046 -398.591056) (xy 346.413086 -398.542002) (xy 345.824048 -398.542002) (xy 345.823553 -398.566609)
			(xy 345.815658 -398.615186) (xy 345.800074 -398.661867) (xy 345.777203 -398.705444) (xy 345.747638 -398.744788)
			(xy 345.712145 -398.77888) (xy 345.671642 -398.806836) (xy 345.62718 -398.827934) (xy 345.579909 -398.841626)
			(xy 345.531054 -398.847558) (xy 345.481879 -398.845577) (xy 345.43366 -398.835733) (xy 345.387644 -398.818281)
			(xy 345.345023 -398.793674) (xy 345.306902 -398.762549) (xy 345.274267 -398.725712) (xy 345.247964 -398.684116)
			(xy 345.228673 -398.63884) (xy 345.216896 -398.591056) (xy 345.212936 -398.542002) (xy 344.624152 -398.542002)
			(xy 344.623657 -398.566609) (xy 344.615762 -398.615186) (xy 344.600178 -398.661867) (xy 344.577307 -398.705444)
			(xy 344.547742 -398.744788) (xy 344.512249 -398.77888) (xy 344.471746 -398.806836) (xy 344.427284 -398.827934)
			(xy 344.380013 -398.841626) (xy 344.331158 -398.847558) (xy 344.281983 -398.845577) (xy 344.233764 -398.835733)
			(xy 344.187748 -398.818281) (xy 344.145127 -398.793674) (xy 344.107006 -398.762549) (xy 344.074371 -398.725712)
			(xy 344.048068 -398.684116) (xy 344.028777 -398.63884) (xy 344.017 -398.591056) (xy 344.01304 -398.542002)
			(xy 343.424002 -398.542002) (xy 343.423507 -398.566609) (xy 343.415612 -398.615186) (xy 343.400028 -398.661867)
			(xy 343.377157 -398.705444) (xy 343.347592 -398.744788) (xy 343.312099 -398.77888) (xy 343.271596 -398.806836)
			(xy 343.227134 -398.827934) (xy 343.179863 -398.841626) (xy 343.131008 -398.847558) (xy 343.081833 -398.845577)
			(xy 343.033614 -398.835733) (xy 342.987598 -398.818281) (xy 342.944977 -398.793674) (xy 342.906856 -398.762549)
			(xy 342.874221 -398.725712) (xy 342.847918 -398.684116) (xy 342.828627 -398.63884) (xy 342.81685 -398.591056)
			(xy 342.81289 -398.542002) (xy 342.224106 -398.542002) (xy 342.223611 -398.566609) (xy 342.215716 -398.615186)
			(xy 342.200132 -398.661867) (xy 342.177261 -398.705444) (xy 342.147696 -398.744788) (xy 342.112203 -398.77888)
			(xy 342.0717 -398.806836) (xy 342.027238 -398.827934) (xy 341.979967 -398.841626) (xy 341.931112 -398.847558)
			(xy 341.881937 -398.845577) (xy 341.833718 -398.835733) (xy 341.787702 -398.818281) (xy 341.745081 -398.793674)
			(xy 341.70696 -398.762549) (xy 341.674325 -398.725712) (xy 341.648022 -398.684116) (xy 341.628731 -398.63884)
			(xy 341.616954 -398.591056) (xy 341.612994 -398.542002) (xy 341.02421 -398.542002) (xy 341.023715 -398.566609)
			(xy 341.01582 -398.615186) (xy 341.000236 -398.661867) (xy 340.977365 -398.705444) (xy 340.9478 -398.744788)
			(xy 340.912307 -398.77888) (xy 340.871804 -398.806836) (xy 340.827342 -398.827934) (xy 340.780071 -398.841626)
			(xy 340.731216 -398.847558) (xy 340.682041 -398.845577) (xy 340.633822 -398.835733) (xy 340.587806 -398.818281)
			(xy 340.545185 -398.793674) (xy 340.507064 -398.762549) (xy 340.474429 -398.725712) (xy 340.448126 -398.684116)
			(xy 340.428835 -398.63884) (xy 340.417058 -398.591056) (xy 340.413098 -398.542002) (xy 339.82406 -398.542002)
			(xy 339.823565 -398.566609) (xy 339.81567 -398.615186) (xy 339.800086 -398.661867) (xy 339.777215 -398.705444)
			(xy 339.74765 -398.744788) (xy 339.712157 -398.77888) (xy 339.671654 -398.806836) (xy 339.627192 -398.827934)
			(xy 339.579921 -398.841626) (xy 339.531066 -398.847558) (xy 339.481891 -398.845577) (xy 339.433672 -398.835733)
			(xy 339.387656 -398.818281) (xy 339.345035 -398.793674) (xy 339.306914 -398.762549) (xy 339.274279 -398.725712)
			(xy 339.247976 -398.684116) (xy 339.228685 -398.63884) (xy 339.216908 -398.591056) (xy 339.212948 -398.542002)
			(xy 338.624164 -398.542002) (xy 338.623669 -398.566609) (xy 338.615774 -398.615186) (xy 338.60019 -398.661867)
			(xy 338.577319 -398.705444) (xy 338.547754 -398.744788) (xy 338.512261 -398.77888) (xy 338.471758 -398.806836)
			(xy 338.427296 -398.827934) (xy 338.380025 -398.841626) (xy 338.33117 -398.847558) (xy 338.281995 -398.845577)
			(xy 338.233776 -398.835733) (xy 338.18776 -398.818281) (xy 338.145139 -398.793674) (xy 338.107018 -398.762549)
			(xy 338.074383 -398.725712) (xy 338.04808 -398.684116) (xy 338.028789 -398.63884) (xy 338.017012 -398.591056)
			(xy 338.013052 -398.542002) (xy 337.424014 -398.542002) (xy 337.423519 -398.566609) (xy 337.415624 -398.615186)
			(xy 337.40004 -398.661867) (xy 337.377169 -398.705444) (xy 337.347604 -398.744788) (xy 337.312111 -398.77888)
			(xy 337.271608 -398.806836) (xy 337.227146 -398.827934) (xy 337.179875 -398.841626) (xy 337.13102 -398.847558)
			(xy 337.081845 -398.845577) (xy 337.033626 -398.835733) (xy 336.98761 -398.818281) (xy 336.944989 -398.793674)
			(xy 336.906868 -398.762549) (xy 336.874233 -398.725712) (xy 336.84793 -398.684116) (xy 336.828639 -398.63884)
			(xy 336.816862 -398.591056) (xy 336.812902 -398.542002) (xy 336.223864 -398.542002) (xy 336.223369 -398.566609)
			(xy 336.215474 -398.615186) (xy 336.19989 -398.661867) (xy 336.177019 -398.705444) (xy 336.147454 -398.744788)
			(xy 336.111961 -398.77888) (xy 336.071458 -398.806836) (xy 336.026996 -398.827934) (xy 335.979725 -398.841626)
			(xy 335.93087 -398.847558) (xy 335.881695 -398.845577) (xy 335.833476 -398.835733) (xy 335.78746 -398.818281)
			(xy 335.744839 -398.793674) (xy 335.706718 -398.762549) (xy 335.674083 -398.725712) (xy 335.64778 -398.684116)
			(xy 335.628489 -398.63884) (xy 335.616712 -398.591056) (xy 335.612752 -398.542002) (xy 333.937946 -398.542002)
			(xy 333.931831 -398.563188) (xy 333.912821 -398.605593) (xy 333.888059 -398.644917) (xy 333.873348 -398.662906)
			(xy 333.867252 -398.670018) (xy 333.861156 -398.686528) (xy 333.861156 -398.770856) (xy 333.867252 -398.787366)
			(xy 333.873348 -398.794478) (xy 333.888053 -398.81247) (xy 333.912801 -398.851798) (xy 333.931802 -398.894203)
			(xy 333.944682 -398.938849) (xy 333.951186 -398.984859) (xy 333.95158 -399.008092) (xy 333.951168 -399.032185)
			(xy 333.944189 -399.079862) (xy 333.930377 -399.126025) (xy 333.920592 -399.148046) (xy 333.915258 -399.159476)
			(xy 333.916528 -399.184622) (xy 333.972662 -399.278602) (xy 333.994252 -399.291556) (xy 334.006952 -399.292318)
			(xy 334.031948 -399.294171) (xy 334.080992 -399.304501) (xy 334.127916 -399.322114) (xy 334.171645 -399.346605)
			(xy 334.211177 -399.377415) (xy 334.245608 -399.413837) (xy 334.274149 -399.455037) (xy 334.296146 -399.500072)
			(xy 334.311096 -399.547911) (xy 334.318656 -399.597458) (xy 334.319118 -399.622518) (xy 334.318608 -399.648505)
			(xy 334.310478 -399.69984) (xy 334.294417 -399.74927) (xy 334.270821 -399.79558) (xy 334.240271 -399.837628)
			(xy 334.20352 -399.874379) (xy 334.161472 -399.904929) (xy 334.115162 -399.928525) (xy 334.065732 -399.944586)
			(xy 334.014397 -399.952716) (xy 333.962423 -399.952716) (xy 333.911088 -399.944586) (xy 333.861658 -399.928525)
			(xy 333.815348 -399.904929) (xy 333.7733 -399.874379) (xy 333.736549 -399.837628) (xy 333.705999 -399.79558)
			(xy 333.682403 -399.74927) (xy 333.666342 -399.69984) (xy 333.658212 -399.648505) (xy 333.657702 -399.622518)
			(xy 333.658119 -399.598425) (xy 333.665096 -399.550748) (xy 333.678907 -399.504585) (xy 333.68869 -399.482564)
			(xy 333.694024 -399.471134) (xy 333.692754 -399.445988) (xy 333.63662 -399.352008) (xy 333.61503 -399.339054)
			(xy 333.60233 -399.338292) (xy 333.577334 -399.336445) (xy 333.52829 -399.326112) (xy 333.481367 -399.308498)
			(xy 333.437639 -399.284005) (xy 333.398107 -399.253195) (xy 333.363676 -399.216773) (xy 333.335136 -399.175573)
			(xy 333.313138 -399.130537) (xy 333.298188 -399.082699) (xy 333.290626 -399.033152) (xy 333.290164 -399.008092)
			(xy 330.34605 -399.008092) (xy 330.34605 -399.040096) (xy 330.3524 -399.057114) (xy 330.358496 -399.064226)
			(xy 330.376113 -399.085176) (xy 330.405829 -399.131144) (xy 330.428669 -399.180887) (xy 330.444165 -399.233383)
			(xy 330.451999 -399.287556) (xy 330.452476 -399.314924) (xy 330.451874 -399.344533) (xy 330.442715 -399.403039)
			(xy 330.424635 -399.459431) (xy 330.398069 -399.512356) (xy 330.363652 -399.560547) (xy 330.32221 -399.602848)
			(xy 330.298806 -399.620994) (xy 330.290368 -399.627915) (xy 330.279827 -399.646995) (xy 330.278486 -399.657824)
			(xy 330.274422 -399.713958) (xy 330.285598 -399.724626) (xy 330.292936 -399.731156) (xy 330.311094 -399.738603)
			(xy 330.320904 -399.739104) (xy 330.352908 -399.739104) (xy 330.362722 -399.738612) (xy 330.380886 -399.731171)
			(xy 330.388214 -399.724626) (xy 330.409704 -399.704442) (xy 330.457766 -399.670299) (xy 330.510508 -399.643955)
			(xy 330.566675 -399.626037) (xy 330.624928 -399.61697) (xy 330.654406 -399.616422) (xy 330.681777 -399.616879)
			(xy 330.735956 -399.624698) (xy 330.78846 -399.640189) (xy 330.838206 -399.663033) (xy 330.884173 -399.69276)
			(xy 330.905104 -399.710402) (xy 330.912216 -399.716498) (xy 330.929234 -399.722848) (xy 331.014578 -399.722848)
			(xy 331.031596 -399.716498) (xy 331.038708 -399.710402) (xy 331.059641 -399.692761) (xy 331.105609 -399.663037)
			(xy 331.155355 -399.640191) (xy 331.207857 -399.624695) (xy 331.262035 -399.616866) (xy 331.316777 -399.616866)
			(xy 331.370955 -399.624695) (xy 331.423457 -399.640191) (xy 331.473203 -399.663037) (xy 331.519171 -399.692761)
			(xy 331.540104 -399.710402) (xy 331.547216 -399.716498) (xy 331.564234 -399.722848) (xy 331.649578 -399.722848)
			(xy 331.666596 -399.716498) (xy 331.673708 -399.710402) (xy 331.694626 -399.692746) (xy 331.740603 -399.663037)
			(xy 331.790354 -399.640204) (xy 331.842858 -399.624717) (xy 331.897036 -399.616893) (xy 331.924406 -399.616422)
			(xy 331.95166 -399.61685) (xy 332.005614 -399.624608) (xy 332.057914 -399.639967) (xy 332.107497 -399.662612)
			(xy 332.153351 -399.692084) (xy 332.194545 -399.727781) (xy 332.230238 -399.768978) (xy 332.259705 -399.814835)
			(xy 332.282346 -399.864419) (xy 332.297699 -399.916721) (xy 332.305453 -399.970676) (xy 332.305914 -399.99793)
			(xy 332.305462 -400.025301) (xy 332.29764 -400.07948) (xy 332.282148 -400.131983) (xy 332.259303 -400.18173)
			(xy 332.229576 -400.227696) (xy 332.211934 -400.248628) (xy 332.205838 -400.25574) (xy 332.199488 -400.272758)
			(xy 332.199488 -400.358102) (xy 332.205838 -400.37512) (xy 332.211934 -400.382232) (xy 332.229606 -400.40314)
			(xy 332.259332 -400.449111) (xy 332.282178 -400.498861) (xy 332.297674 -400.551367) (xy 332.305501 -400.60555)
			(xy 332.305499 -400.633946) (xy 332.590648 -400.633946) (xy 332.591134 -400.606695) (xy 332.59889 -400.552747)
			(xy 332.614245 -400.500452) (xy 332.636887 -400.450875) (xy 332.666353 -400.405025) (xy 332.702044 -400.363834)
			(xy 332.743235 -400.328143) (xy 332.789085 -400.298677) (xy 332.838662 -400.276035) (xy 332.890957 -400.26068)
			(xy 332.944905 -400.252924) (xy 332.999407 -400.252924) (xy 333.053355 -400.26068) (xy 333.10565 -400.276035)
			(xy 333.155227 -400.298677) (xy 333.201077 -400.328143) (xy 333.242268 -400.363834) (xy 333.277959 -400.405025)
			(xy 333.307425 -400.450875) (xy 333.330067 -400.500452) (xy 333.345422 -400.552747) (xy 333.353178 -400.606695)
			(xy 333.353664 -400.633946) (xy 333.353413 -400.653974) (xy 333.34921 -400.693808) (xy 333.345282 -400.713448)
			(xy 333.344685 -400.71675) (xy 334.691736 -400.71675) (xy 334.692137 -400.693516) (xy 334.698636 -400.647506)
			(xy 334.711512 -400.602859) (xy 334.730512 -400.560454) (xy 334.755262 -400.521128) (xy 334.769968 -400.503136)
			(xy 334.776064 -400.496024) (xy 334.78216 -400.479514) (xy 334.78216 -400.395186) (xy 334.776064 -400.378676)
			(xy 334.769968 -400.371564) (xy 334.755285 -400.353555) (xy 334.730533 -400.314232) (xy 334.711527 -400.271832)
			(xy 334.698643 -400.227189) (xy 334.692133 -400.181182) (xy 334.691736 -400.15795) (xy 334.692246 -400.131963)
			(xy 334.700376 -400.080628) (xy 334.716437 -400.031198) (xy 334.740033 -399.984888) (xy 334.770583 -399.94284)
			(xy 334.807334 -399.906089) (xy 334.849382 -399.875539) (xy 334.895692 -399.851943) (xy 334.945122 -399.835882)
			(xy 334.996457 -399.827752) (xy 335.048431 -399.827752) (xy 335.099766 -399.835882) (xy 335.149196 -399.851943)
			(xy 335.195506 -399.875539) (xy 335.237554 -399.906089) (xy 335.274305 -399.94284) (xy 335.304855 -399.984888)
			(xy 335.328451 -400.031198) (xy 335.344512 -400.080628) (xy 335.352642 -400.131963) (xy 335.353152 -400.15795)
			(xy 335.352754 -400.181184) (xy 335.346255 -400.227194) (xy 335.333378 -400.271841) (xy 335.314377 -400.314246)
			(xy 335.289626 -400.353573) (xy 335.27492 -400.371564) (xy 335.268824 -400.378676) (xy 335.262728 -400.395186)
			(xy 335.262728 -400.479514) (xy 335.268824 -400.496024) (xy 335.27492 -400.503136) (xy 335.289616 -400.521135)
			(xy 335.314364 -400.560462) (xy 335.333365 -400.602865) (xy 335.346247 -400.647509) (xy 335.352755 -400.693517)
			(xy 335.353152 -400.71675) (xy 335.352642 -400.742737) (xy 335.344512 -400.794072) (xy 335.328451 -400.843502)
			(xy 335.304855 -400.889812) (xy 335.274305 -400.93186) (xy 335.237554 -400.968611) (xy 335.195506 -400.999161)
			(xy 335.149196 -401.022757) (xy 335.099766 -401.038818) (xy 335.048431 -401.046948) (xy 334.996457 -401.046948)
			(xy 334.945122 -401.038818) (xy 334.895692 -401.022757) (xy 334.849382 -400.999161) (xy 334.807334 -400.968611)
			(xy 334.770583 -400.93186) (xy 334.740033 -400.889812) (xy 334.716437 -400.843502) (xy 334.700376 -400.794072)
			(xy 334.692246 -400.742737) (xy 334.691736 -400.71675) (xy 333.344685 -400.71675) (xy 333.342648 -400.728012)
			(xy 333.345009 -400.757502) (xy 333.355727 -400.785077) (xy 333.373903 -400.808419) (xy 333.39801 -400.825569)
			(xy 333.426022 -400.835085) (xy 333.440786 -400.83613) (xy 333.46732 -400.8376) (xy 333.519615 -400.847048)
			(xy 333.570093 -400.863661) (xy 333.617779 -400.887118) (xy 333.661748 -400.916964) (xy 333.701151 -400.952622)
			(xy 333.735225 -400.993402) (xy 333.763311 -401.038516) (xy 333.784866 -401.08709) (xy 333.799472 -401.138185)
			(xy 333.806848 -401.190813) (xy 333.807308 -401.217384) (xy 333.806822 -401.244635) (xy 333.799066 -401.298583)
			(xy 333.783711 -401.350878) (xy 333.761069 -401.400455) (xy 333.731603 -401.446305) (xy 333.695912 -401.487496)
			(xy 333.654721 -401.523187) (xy 333.608871 -401.552653) (xy 333.559294 -401.575295) (xy 333.506999 -401.59065)
			(xy 333.453051 -401.598406) (xy 333.398549 -401.598406) (xy 333.344601 -401.59065) (xy 333.292306 -401.575295)
			(xy 333.242729 -401.552653) (xy 333.196879 -401.523187) (xy 333.155688 -401.487496) (xy 333.119997 -401.446305)
			(xy 333.090531 -401.400455) (xy 333.067889 -401.350878) (xy 333.052534 -401.298583) (xy 333.044778 -401.244635)
			(xy 333.044292 -401.217384) (xy 333.044547 -401.197357) (xy 333.048747 -401.157522) (xy 333.052674 -401.137882)
			(xy 333.055318 -401.123318) (xy 333.052965 -401.093823) (xy 333.042248 -401.066243) (xy 333.024069 -401.042897)
			(xy 332.999956 -401.025749) (xy 332.971936 -401.01624) (xy 332.95717 -401.0152) (xy 332.930642 -401.013651)
			(xy 332.878351 -401.004211) (xy 332.827875 -400.987606) (xy 332.780192 -400.964158) (xy 332.736223 -400.934321)
			(xy 332.69682 -400.898671) (xy 332.662745 -400.857898) (xy 332.634657 -400.812792) (xy 332.613099 -400.764225)
			(xy 332.59849 -400.713136) (xy 332.59111 -400.660514) (xy 332.590648 -400.633946) (xy 332.305499 -400.633946)
			(xy 332.305497 -400.660295) (xy 332.297664 -400.714477) (xy 332.282162 -400.766981) (xy 332.25931 -400.816728)
			(xy 332.229578 -400.862696) (xy 332.211934 -400.883628) (xy 332.205838 -400.89074) (xy 332.199488 -400.907758)
			(xy 332.199488 -400.993102) (xy 332.205838 -401.01012) (xy 332.211934 -401.017232) (xy 332.229606 -401.03814)
			(xy 332.259332 -401.084111) (xy 332.282178 -401.133861) (xy 332.297674 -401.186367) (xy 332.305501 -401.24055)
			(xy 332.305497 -401.295295) (xy 332.297664 -401.349477) (xy 332.282162 -401.401981) (xy 332.25931 -401.451728)
			(xy 332.229578 -401.497696) (xy 332.211934 -401.518628) (xy 332.205838 -401.52574) (xy 332.199488 -401.542758)
			(xy 332.199488 -401.628102) (xy 332.205838 -401.64512) (xy 332.211934 -401.652232) (xy 332.22956 -401.673175)
			(xy 332.259273 -401.719145) (xy 332.282111 -401.76889) (xy 332.297605 -401.821388) (xy 332.305437 -401.875562)
			(xy 332.305914 -401.90293) (xy 332.30545 -401.930182) (xy 332.29769 -401.98413) (xy 332.282331 -402.036425)
			(xy 332.259687 -402.086002) (xy 332.230218 -402.131852) (xy 332.194524 -402.173041) (xy 332.153332 -402.208732)
			(xy 332.107481 -402.238198) (xy 332.057902 -402.260839) (xy 332.005606 -402.276195) (xy 331.951658 -402.283952)
			(xy 331.924406 -402.284438) (xy 335.95818 -402.284438) (xy 335.958663 -402.256162) (xy 335.966948 -402.200222)
			(xy 335.983346 -402.1461) (xy 336.007501 -402.094968) (xy 336.038892 -402.047929) (xy 336.057494 -402.026628)
			(xy 336.063414 -402.019449) (xy 336.07019 -402.002136) (xy 336.070702 -401.992846) (xy 336.070956 -401.961604)
			(xy 336.070532 -401.952269) (xy 336.063899 -401.934816) (xy 336.058002 -401.927568) (xy 336.040031 -401.906561)
			(xy 336.009753 -401.860308) (xy 335.986477 -401.810165) (xy 335.97069 -401.757185) (xy 335.962725 -401.702479)
			(xy 335.962244 -401.674838) (xy 335.962244 -400.811238) (xy 335.962723 -400.784882) (xy 335.969986 -400.732674)
			(xy 335.984365 -400.681961) (xy 336.005586 -400.63371) (xy 336.033247 -400.588839) (xy 336.066819 -400.548202)
			(xy 336.085942 -400.53006) (xy 336.093054 -400.52371) (xy 336.101182 -400.506946) (xy 336.109564 -400.420332)
			(xy 336.104484 -400.402552) (xy 336.098896 -400.394678) (xy 336.084751 -400.374827) (xy 336.062291 -400.331571)
			(xy 336.046977 -400.285299) (xy 336.039197 -400.237184) (xy 336.038698 -400.212814) (xy 336.03922 -400.187559)
			(xy 336.047533 -400.137737) (xy 336.063934 -400.089963) (xy 336.087975 -400.04554) (xy 336.118999 -400.00568)
			(xy 336.156161 -399.97147) (xy 336.198447 -399.943844) (xy 336.244703 -399.923554) (xy 336.293668 -399.911154)
			(xy 336.344006 -399.906983) (xy 336.394344 -399.911154) (xy 336.443309 -399.923554) (xy 336.489565 -399.943844)
			(xy 336.531851 -399.97147) (xy 336.569013 -400.00568) (xy 336.600037 -400.04554) (xy 336.624078 -400.089963)
			(xy 336.640479 -400.137737) (xy 336.648792 -400.187559) (xy 336.649314 -400.212814) (xy 336.648843 -400.237187)
			(xy 336.641083 -400.28531) (xy 336.625763 -400.331586) (xy 336.603275 -400.374834) (xy 336.589116 -400.394678)
			(xy 336.583528 -400.402552) (xy 336.578448 -400.420332) (xy 336.58683 -400.506946) (xy 336.594958 -400.52371)
			(xy 336.60207 -400.53006) (xy 336.621208 -400.54819) (xy 336.654795 -400.588822) (xy 336.682465 -400.633693)
			(xy 336.703692 -400.681947) (xy 336.71807 -400.732665) (xy 336.725325 -400.78488) (xy 336.725768 -400.811238)
			(xy 336.725768 -401.674838) (xy 336.725284 -401.702749) (xy 336.717145 -401.757974) (xy 336.701047 -401.811425)
			(xy 336.677332 -401.861959) (xy 336.646508 -401.908499) (xy 336.628232 -401.9296) (xy 336.622327 -401.936771)
			(xy 336.615682 -401.954101) (xy 336.615278 -401.963382) (xy 336.615278 -401.994624) (xy 336.615694 -402.003899)
			(xy 336.622354 -402.021217) (xy 336.628232 -402.028406) (xy 336.646527 -402.049645) (xy 336.677369 -402.096453)
			(xy 336.701084 -402.147245) (xy 336.717167 -402.200944) (xy 336.725277 -402.25641) (xy 336.725768 -402.284438)
			(xy 337.158076 -402.284438) (xy 337.15856 -402.256162) (xy 337.166845 -402.200222) (xy 337.183243 -402.1461)
			(xy 337.207398 -402.094968) (xy 337.238788 -402.047929) (xy 337.25739 -402.026628) (xy 337.263309 -402.019449)
			(xy 337.270086 -402.002136) (xy 337.270598 -401.992846) (xy 337.270852 -401.961604) (xy 337.270428 -401.952269)
			(xy 337.263795 -401.934816) (xy 337.257898 -401.927568) (xy 337.239927 -401.906561) (xy 337.209649 -401.860308)
			(xy 337.186373 -401.810165) (xy 337.170586 -401.757185) (xy 337.162621 -401.702479) (xy 337.16214 -401.674838)
			(xy 337.16214 -400.811238) (xy 337.16262 -400.784882) (xy 337.169883 -400.732674) (xy 337.184262 -400.681962)
			(xy 337.205483 -400.633711) (xy 337.233143 -400.58884) (xy 337.266715 -400.548202) (xy 337.285838 -400.53006)
			(xy 337.29295 -400.523456) (xy 337.301332 -400.506946) (xy 337.30946 -400.420078) (xy 337.304634 -400.402298)
			(xy 337.298792 -400.394678) (xy 337.284687 -400.374809) (xy 337.262264 -400.331554) (xy 337.247007 -400.285284)
			(xy 337.239302 -400.237175) (xy 337.238848 -400.212814) (xy 337.23937 -400.187559) (xy 337.247683 -400.137737)
			(xy 337.264084 -400.089963) (xy 337.288125 -400.04554) (xy 337.319149 -400.00568) (xy 337.356311 -399.97147)
			(xy 337.398597 -399.943844) (xy 337.444853 -399.923554) (xy 337.493818 -399.911154) (xy 337.544156 -399.906983)
			(xy 337.594494 -399.911154) (xy 337.643459 -399.923554) (xy 337.689715 -399.943844) (xy 337.732001 -399.97147)
			(xy 337.769163 -400.00568) (xy 337.800187 -400.04554) (xy 337.824228 -400.089963) (xy 337.840629 -400.137737)
			(xy 337.848942 -400.187559) (xy 337.849464 -400.212814) (xy 337.848997 -400.237217) (xy 337.841238 -400.285401)
			(xy 337.825918 -400.331739) (xy 337.803427 -400.375053) (xy 337.789266 -400.394932) (xy 337.783678 -400.402552)
			(xy 337.778598 -400.420332) (xy 337.786726 -400.5072) (xy 337.795108 -400.52371) (xy 337.80222 -400.530314)
			(xy 337.821289 -400.548466) (xy 337.85478 -400.589089) (xy 337.882377 -400.633924) (xy 337.903558 -400.682122)
			(xy 337.917923 -400.732772) (xy 337.925199 -400.784915) (xy 337.925664 -400.811238) (xy 337.925664 -401.674838)
			(xy 337.925181 -401.702749) (xy 337.917042 -401.757975) (xy 337.900943 -401.811425) (xy 337.877229 -401.86196)
			(xy 337.846405 -401.9085) (xy 337.828128 -401.9296) (xy 337.822235 -401.93678) (xy 337.815581 -401.954103)
			(xy 337.815174 -401.963382) (xy 337.815174 -401.994624) (xy 337.815591 -402.003899) (xy 337.822251 -402.021217)
			(xy 337.828128 -402.028406) (xy 337.846422 -402.049646) (xy 337.877265 -402.096453) (xy 337.90098 -402.147245)
			(xy 337.917063 -402.200944) (xy 337.925173 -402.25641) (xy 337.925664 -402.284438) (xy 337.925211 -402.309838)
			(xy 338.357972 -402.309838) (xy 338.358454 -402.28214) (xy 338.366398 -402.227318) (xy 338.382141 -402.174206)
			(xy 338.405355 -402.12391) (xy 338.435558 -402.077473) (xy 338.453476 -402.056346) (xy 338.459826 -402.049488)
			(xy 338.466176 -402.03247) (xy 338.466684 -401.94738) (xy 338.460334 -401.930362) (xy 338.454238 -401.92325)
			(xy 338.437032 -401.902369) (xy 338.408008 -401.856709) (xy 338.385722 -401.807408) (xy 338.37062 -401.755455)
			(xy 338.363003 -401.70189) (xy 338.362544 -401.674838) (xy 338.362544 -400.811238) (xy 338.36301 -400.784893)
			(xy 338.370257 -400.732705) (xy 338.384606 -400.682007) (xy 338.405784 -400.633761) (xy 338.433389 -400.588882)
			(xy 338.466898 -400.548221) (xy 338.485988 -400.53006) (xy 338.4931 -400.52371) (xy 338.501228 -400.506946)
			(xy 338.50961 -400.420332) (xy 338.50453 -400.402552) (xy 338.498942 -400.394678) (xy 338.484791 -400.374832)
			(xy 338.462334 -400.331573) (xy 338.447022 -400.2853) (xy 338.439242 -400.237184) (xy 338.438744 -400.212814)
			(xy 338.439266 -400.187559) (xy 338.447579 -400.137737) (xy 338.46398 -400.089963) (xy 338.488021 -400.04554)
			(xy 338.519045 -400.00568) (xy 338.556207 -399.97147) (xy 338.598493 -399.943844) (xy 338.644749 -399.923554)
			(xy 338.693714 -399.911154) (xy 338.744052 -399.906983) (xy 338.79439 -399.911154) (xy 338.843355 -399.923554)
			(xy 338.889611 -399.943844) (xy 338.931897 -399.97147) (xy 338.969059 -400.00568) (xy 339.000083 -400.04554)
			(xy 339.024124 -400.089963) (xy 339.040525 -400.137737) (xy 339.048838 -400.187559) (xy 339.04936 -400.212814)
			(xy 339.04888 -400.237186) (xy 339.041121 -400.285309) (xy 339.025804 -400.331585) (xy 339.003319 -400.374833)
			(xy 338.989162 -400.394678) (xy 338.983574 -400.402552) (xy 338.978494 -400.420332) (xy 338.986876 -400.506946)
			(xy 338.995004 -400.52371) (xy 339.002116 -400.53006) (xy 339.021212 -400.548217) (xy 339.054735 -400.588871)
			(xy 339.08235 -400.633748) (xy 339.103533 -400.681996) (xy 339.11788 -400.732698) (xy 339.12512 -400.784891)
			(xy 339.12556 -400.811238) (xy 339.12556 -401.674838) (xy 339.125108 -401.702138) (xy 339.11733 -401.756181)
			(xy 339.101925 -401.808563) (xy 339.079207 -401.858212) (xy 339.049641 -401.904114) (xy 339.032088 -401.925028)
			(xy 339.025992 -401.93214) (xy 339.019642 -401.949158) (xy 339.019642 -402.034248) (xy 339.025992 -402.051266)
			(xy 339.032088 -402.058378) (xy 339.049711 -402.079412) (xy 339.07941 -402.125554) (xy 339.10224 -402.175452)
			(xy 339.117736 -402.228092) (xy 339.122207 -402.259038) (xy 339.557868 -402.259038) (xy 339.558296 -402.232173)
			(xy 339.565797 -402.178969) (xy 339.580645 -402.12733) (xy 339.602549 -402.078267) (xy 339.631081 -402.032738)
			(xy 339.648038 -402.011896) (xy 339.653422 -402.004931) (xy 339.65952 -401.98843) (xy 339.659976 -401.979638)
			(xy 339.66023 -401.949158) (xy 339.659941 -401.940309) (xy 339.653954 -401.923657) (xy 339.648546 -401.916646)
			(xy 339.6323 -401.896101) (xy 339.605037 -401.851377) (xy 339.584137 -401.80335) (xy 339.569989 -401.752918)
			(xy 339.562859 -401.701027) (xy 339.56244 -401.674838) (xy 339.56244 -400.811238) (xy 339.562907 -400.784893)
			(xy 339.570154 -400.732705) (xy 339.584503 -400.682007) (xy 339.60568 -400.633761) (xy 339.633285 -400.588882)
			(xy 339.666794 -400.548221) (xy 339.685884 -400.53006) (xy 339.692996 -400.52371) (xy 339.701124 -400.506946)
			(xy 339.709506 -400.420332) (xy 339.704426 -400.402552) (xy 339.698838 -400.394678) (xy 339.684686 -400.374832)
			(xy 339.66223 -400.331573) (xy 339.646918 -400.2853) (xy 339.639138 -400.237184) (xy 339.63864 -400.212814)
			(xy 339.639162 -400.187559) (xy 339.647475 -400.137737) (xy 339.663876 -400.089963) (xy 339.687917 -400.04554)
			(xy 339.718941 -400.00568) (xy 339.756103 -399.97147) (xy 339.798389 -399.943844) (xy 339.844645 -399.923554)
			(xy 339.89361 -399.911154) (xy 339.943948 -399.906983) (xy 339.994286 -399.911154) (xy 340.043251 -399.923554)
			(xy 340.089507 -399.943844) (xy 340.131793 -399.97147) (xy 340.168955 -400.00568) (xy 340.199979 -400.04554)
			(xy 340.22402 -400.089963) (xy 340.240421 -400.137737) (xy 340.248734 -400.187559) (xy 340.249256 -400.212814)
			(xy 340.248777 -400.237186) (xy 340.241018 -400.285309) (xy 340.225701 -400.331585) (xy 340.203215 -400.374833)
			(xy 340.189058 -400.394678) (xy 340.18347 -400.402552) (xy 340.17839 -400.420332) (xy 340.186772 -400.506946)
			(xy 340.1949 -400.52371) (xy 340.202012 -400.53006) (xy 340.221107 -400.548218) (xy 340.254631 -400.588871)
			(xy 340.282246 -400.633748) (xy 340.303428 -400.681996) (xy 340.317776 -400.732698) (xy 340.325016 -400.784891)
			(xy 340.325456 -400.811238) (xy 340.325456 -401.674838) (xy 340.32503 -401.701295) (xy 340.317753 -401.753707)
			(xy 340.303301 -401.80461) (xy 340.281953 -401.853027) (xy 340.254118 -401.898028) (xy 340.237572 -401.918678)
			(xy 340.232252 -401.925738) (xy 340.226271 -401.942359) (xy 340.225888 -401.95119) (xy 340.225888 -401.98167)
			(xy 340.226265 -401.990446) (xy 340.23224 -402.006948) (xy 340.237572 -402.013928) (xy 340.254219 -402.034674)
			(xy 340.282188 -402.079919) (xy 340.303645 -402.128591) (xy 340.31818 -402.179758) (xy 340.325515 -402.232442)
			(xy 340.325964 -402.259038) (xy 340.325475 -402.286471) (xy 340.322115 -402.309838) (xy 340.758272 -402.309838)
			(xy 340.758715 -402.282149) (xy 340.766613 -402.227337) (xy 340.782307 -402.174229) (xy 340.805473 -402.123929)
			(xy 340.835628 -402.077482) (xy 340.853522 -402.056346) (xy 340.859872 -402.049488) (xy 340.866222 -402.03247)
			(xy 340.86673 -401.94738) (xy 340.86038 -401.930362) (xy 340.854284 -401.92325) (xy 340.837036 -401.902391)
			(xy 340.807953 -401.856743) (xy 340.785614 -401.807443) (xy 340.770465 -401.755481) (xy 340.762811 -401.7019)
			(xy 340.762336 -401.674838) (xy 340.762336 -400.811238) (xy 340.762817 -400.784882) (xy 340.77008 -400.732674)
			(xy 340.784459 -400.681962) (xy 340.80568 -400.633711) (xy 340.83334 -400.58884) (xy 340.866912 -400.548202)
			(xy 340.886034 -400.53006) (xy 340.893146 -400.52371) (xy 340.901274 -400.506946) (xy 340.909656 -400.420332)
			(xy 340.904576 -400.402552) (xy 340.898988 -400.394678) (xy 340.884842 -400.374828) (xy 340.862383 -400.331571)
			(xy 340.847069 -400.285299) (xy 340.839289 -400.237184) (xy 340.83879 -400.212814) (xy 340.839312 -400.187559)
			(xy 340.847625 -400.137737) (xy 340.864026 -400.089963) (xy 340.888067 -400.04554) (xy 340.919091 -400.00568)
			(xy 340.956253 -399.97147) (xy 340.998539 -399.943844) (xy 341.044795 -399.923554) (xy 341.09376 -399.911154)
			(xy 341.144098 -399.906983) (xy 341.194436 -399.911154) (xy 341.243401 -399.923554) (xy 341.289657 -399.943844)
			(xy 341.331943 -399.97147) (xy 341.369105 -400.00568) (xy 341.400129 -400.04554) (xy 341.42417 -400.089963)
			(xy 341.440571 -400.137737) (xy 341.448884 -400.187559) (xy 341.449406 -400.212814) (xy 341.448936 -400.237187)
			(xy 341.441176 -400.285311) (xy 341.425856 -400.331586) (xy 341.403367 -400.374834) (xy 341.389208 -400.394678)
			(xy 341.38362 -400.402552) (xy 341.37854 -400.420332) (xy 341.386922 -400.506946) (xy 341.39505 -400.52371)
			(xy 341.402162 -400.53006) (xy 341.421298 -400.548192) (xy 341.454886 -400.588823) (xy 341.482556 -400.633693)
			(xy 341.503783 -400.681947) (xy 341.518162 -400.732665) (xy 341.525417 -400.78488) (xy 341.52586 -400.811238)
			(xy 341.52586 -401.674838) (xy 341.525349 -401.702143) (xy 341.517501 -401.756188) (xy 341.502041 -401.808566)
			(xy 341.479284 -401.858211) (xy 341.449694 -401.904112) (xy 341.432134 -401.925028) (xy 341.426038 -401.93214)
			(xy 341.419688 -401.949158) (xy 341.419688 -402.034248) (xy 341.426038 -402.051266) (xy 341.432134 -402.058378)
			(xy 341.449748 -402.07941) (xy 341.479417 -402.125555) (xy 341.502203 -402.175459) (xy 341.517641 -402.228102)
			(xy 341.525415 -402.282408) (xy 341.52586 -402.309838) (xy 341.958168 -402.309838) (xy 341.958612 -402.282149)
			(xy 341.96651 -402.227337) (xy 341.982204 -402.174229) (xy 342.005369 -402.12393) (xy 342.035524 -402.077482)
			(xy 342.053418 -402.056346) (xy 342.059768 -402.049488) (xy 342.066118 -402.03247) (xy 342.066626 -401.94738)
			(xy 342.060276 -401.930362) (xy 342.05418 -401.92325) (xy 342.036931 -401.902391) (xy 342.007849 -401.856743)
			(xy 341.985509 -401.807443) (xy 341.970361 -401.755482) (xy 341.962707 -401.7019) (xy 341.962232 -401.674838)
			(xy 341.962232 -400.811238) (xy 341.962714 -400.784883) (xy 341.969977 -400.732674) (xy 341.984356 -400.681962)
			(xy 342.005577 -400.633711) (xy 342.033236 -400.58884) (xy 342.066808 -400.548203) (xy 342.08593 -400.53006)
			(xy 342.093042 -400.52371) (xy 342.10117 -400.506946) (xy 342.109552 -400.420332) (xy 342.104472 -400.402552)
			(xy 342.098884 -400.394678) (xy 342.084738 -400.374828) (xy 342.062279 -400.331571) (xy 342.046965 -400.285299)
			(xy 342.039185 -400.237184) (xy 342.038686 -400.212814) (xy 342.039208 -400.187559) (xy 342.047521 -400.137737)
			(xy 342.063922 -400.089963) (xy 342.087963 -400.04554) (xy 342.118987 -400.00568) (xy 342.156149 -399.97147)
			(xy 342.198435 -399.943844) (xy 342.244691 -399.923554) (xy 342.293656 -399.911154) (xy 342.343994 -399.906983)
			(xy 342.394332 -399.911154) (xy 342.443297 -399.923554) (xy 342.489553 -399.943844) (xy 342.531839 -399.97147)
			(xy 342.569001 -400.00568) (xy 342.600025 -400.04554) (xy 342.624066 -400.089963) (xy 342.640467 -400.137737)
			(xy 342.64878 -400.187559) (xy 342.649302 -400.212814) (xy 342.648833 -400.237187) (xy 342.641073 -400.285311)
			(xy 342.625753 -400.331586) (xy 342.603263 -400.374834) (xy 342.589104 -400.394678) (xy 342.583516 -400.402552)
			(xy 342.578436 -400.420332) (xy 342.586818 -400.506946) (xy 342.594946 -400.52371) (xy 342.602058 -400.53006)
			(xy 342.621193 -400.548192) (xy 342.654781 -400.588824) (xy 342.682452 -400.633694) (xy 342.703679 -400.681947)
			(xy 342.718058 -400.732665) (xy 342.725313 -400.78488) (xy 342.725756 -400.811238) (xy 342.725756 -401.674838)
			(xy 342.725246 -401.702143) (xy 342.717397 -401.756189) (xy 342.701938 -401.808567) (xy 342.679181 -401.858211)
			(xy 342.64959 -401.904112) (xy 342.63203 -401.925028) (xy 342.625934 -401.93214) (xy 342.619584 -401.949158)
			(xy 342.619584 -402.034248) (xy 342.625934 -402.051266) (xy 342.63203 -402.058378) (xy 342.649644 -402.079411)
			(xy 342.679313 -402.125555) (xy 342.702099 -402.175459) (xy 342.717537 -402.228102) (xy 342.721966 -402.259038)
			(xy 343.158064 -402.259038) (xy 343.158493 -402.232173) (xy 343.165994 -402.178969) (xy 343.180842 -402.12733)
			(xy 343.202745 -402.078267) (xy 343.231277 -402.032738) (xy 343.248234 -402.011896) (xy 343.253617 -402.004931)
			(xy 343.259716 -401.98843) (xy 343.260172 -401.979638) (xy 343.260426 -401.949158) (xy 343.260138 -401.940309)
			(xy 343.25415 -401.923657) (xy 343.248742 -401.916646) (xy 343.23251 -401.89609) (xy 343.205242 -401.851371)
			(xy 343.184337 -401.803346) (xy 343.170187 -401.752916) (xy 343.163056 -401.701027) (xy 343.162636 -401.674838)
			(xy 343.162636 -400.811238) (xy 343.163105 -400.784893) (xy 343.170352 -400.732705) (xy 343.1847 -400.682007)
			(xy 343.205877 -400.633761) (xy 343.233482 -400.588882) (xy 343.26699 -400.548221) (xy 343.28608 -400.53006)
			(xy 343.293192 -400.52371) (xy 343.30132 -400.506946) (xy 343.309702 -400.420332) (xy 343.304622 -400.402552)
			(xy 343.299034 -400.394678) (xy 343.284882 -400.374833) (xy 343.262425 -400.331573) (xy 343.247114 -400.2853)
			(xy 343.239334 -400.237184) (xy 343.238836 -400.212814) (xy 343.239358 -400.187559) (xy 343.247671 -400.137737)
			(xy 343.264072 -400.089963) (xy 343.288113 -400.04554) (xy 343.319137 -400.00568) (xy 343.356299 -399.97147)
			(xy 343.398585 -399.943844) (xy 343.444841 -399.923554) (xy 343.493806 -399.911154) (xy 343.544144 -399.906983)
			(xy 343.594482 -399.911154) (xy 343.643447 -399.923554) (xy 343.689703 -399.943844) (xy 343.731989 -399.97147)
			(xy 343.769151 -400.00568) (xy 343.800175 -400.04554) (xy 343.824216 -400.089963) (xy 343.840617 -400.137737)
			(xy 343.84893 -400.187559) (xy 343.849452 -400.212814) (xy 343.848973 -400.237186) (xy 343.841215 -400.285309)
			(xy 343.825897 -400.331585) (xy 343.803411 -400.374833) (xy 343.789254 -400.394678) (xy 343.783666 -400.402552)
			(xy 343.778586 -400.420332) (xy 343.786968 -400.506946) (xy 343.795096 -400.52371) (xy 343.802208 -400.53006)
			(xy 343.821303 -400.548218) (xy 343.854826 -400.588872) (xy 343.882442 -400.633749) (xy 343.903624 -400.681996)
			(xy 343.917972 -400.732698) (xy 343.925212 -400.784892) (xy 343.925652 -400.811238) (xy 343.925652 -401.674838)
			(xy 343.925227 -401.701296) (xy 343.917949 -401.753707) (xy 343.903498 -401.80461) (xy 343.882149 -401.853027)
			(xy 343.854314 -401.898028) (xy 343.837768 -401.918678) (xy 343.832448 -401.925738) (xy 343.826467 -401.942359)
			(xy 343.826084 -401.95119) (xy 343.826084 -401.98167) (xy 343.826462 -401.990445) (xy 343.832436 -402.006948)
			(xy 343.837768 -402.013928) (xy 343.854415 -402.034674) (xy 343.882383 -402.079919) (xy 343.90384 -402.128591)
			(xy 343.918376 -402.179759) (xy 343.925711 -402.232442) (xy 343.92616 -402.259038) (xy 343.925707 -402.284438)
			(xy 344.35796 -402.284438) (xy 344.358475 -402.256152) (xy 344.36679 -402.200195) (xy 344.38323 -402.146065)
			(xy 344.40744 -402.094935) (xy 344.438893 -402.047914) (xy 344.457528 -402.026628) (xy 344.463452 -402.019452)
			(xy 344.470225 -402.002137) (xy 344.470736 -401.992846) (xy 344.47099 -401.961604) (xy 344.470558 -401.95227)
			(xy 344.46393 -401.934818) (xy 344.458036 -401.927568) (xy 344.440115 -401.906533) (xy 344.409903 -401.860265)
			(xy 344.386682 -401.810122) (xy 344.370939 -401.757154) (xy 344.363004 -401.702468) (xy 344.362532 -401.674838)
			(xy 344.362532 -400.811238) (xy 344.363002 -400.784894) (xy 344.370249 -400.732705) (xy 344.384597 -400.682007)
			(xy 344.405774 -400.633761) (xy 344.433378 -400.588882) (xy 344.466887 -400.548221) (xy 344.485976 -400.53006)
			(xy 344.493088 -400.52371) (xy 344.501216 -400.506946) (xy 344.509598 -400.420332) (xy 344.504518 -400.402552)
			(xy 344.49893 -400.394678) (xy 344.484777 -400.374833) (xy 344.462321 -400.331573) (xy 344.44701 -400.2853)
			(xy 344.43923 -400.237184) (xy 344.438732 -400.212814) (xy 344.439254 -400.187559) (xy 344.447567 -400.137737)
			(xy 344.463968 -400.089963) (xy 344.488009 -400.04554) (xy 344.519033 -400.00568) (xy 344.556195 -399.97147)
			(xy 344.598481 -399.943844) (xy 344.644737 -399.923554) (xy 344.693702 -399.911154) (xy 344.74404 -399.906983)
			(xy 344.794378 -399.911154) (xy 344.843343 -399.923554) (xy 344.889599 -399.943844) (xy 344.931885 -399.97147)
			(xy 344.969047 -400.00568) (xy 345.000071 -400.04554) (xy 345.024112 -400.089963) (xy 345.040513 -400.137737)
			(xy 345.048826 -400.187559) (xy 345.049348 -400.212814) (xy 345.04887 -400.237186) (xy 345.041111 -400.28531)
			(xy 345.025793 -400.331585) (xy 345.003307 -400.374833) (xy 344.98915 -400.394678) (xy 344.983562 -400.402552)
			(xy 344.978482 -400.420332) (xy 344.986864 -400.506946) (xy 344.994992 -400.52371) (xy 345.002104 -400.53006)
			(xy 345.021198 -400.548219) (xy 345.054722 -400.588873) (xy 345.082337 -400.633749) (xy 345.10352 -400.681997)
			(xy 345.117868 -400.732698) (xy 345.125108 -400.784892) (xy 345.125548 -400.811238) (xy 345.125548 -401.674838)
			(xy 345.125105 -401.702741) (xy 345.117013 -401.757956) (xy 345.100962 -401.811402) (xy 345.077296 -401.86194)
			(xy 345.04652 -401.908491) (xy 345.028266 -401.9296) (xy 345.022365 -401.936774) (xy 345.015717 -401.954102)
			(xy 345.015312 -401.963382) (xy 345.015312 -401.994624) (xy 345.015743 -402.003897) (xy 345.022394 -402.021215)
			(xy 345.028266 -402.028406) (xy 345.046593 -402.049631) (xy 345.077497 -402.096423) (xy 345.101268 -402.147212)
			(xy 345.117399 -402.200919) (xy 345.125549 -402.2564) (xy 345.126056 -402.284438) (xy 345.125603 -402.309838)
			(xy 345.558364 -402.309838) (xy 345.558809 -402.282149) (xy 345.566707 -402.227337) (xy 345.582401 -402.17423)
			(xy 345.605566 -402.12393) (xy 345.63572 -402.077482) (xy 345.653614 -402.056346) (xy 345.659964 -402.049488)
			(xy 345.666314 -402.03247) (xy 345.666822 -401.94738) (xy 345.660472 -401.930362) (xy 345.654376 -401.92325)
			(xy 345.637126 -401.902392) (xy 345.608045 -401.856743) (xy 345.585705 -401.807444) (xy 345.570557 -401.755482)
			(xy 345.562903 -401.7019) (xy 345.562428 -401.674838) (xy 345.562428 -400.811238) (xy 345.562861 -400.784911)
			(xy 345.570111 -400.732757) (xy 345.584465 -400.682096) (xy 345.60565 -400.633891) (xy 345.633263 -400.589057)
			(xy 345.66678 -400.548447) (xy 345.685872 -400.530314) (xy 345.692984 -400.52371) (xy 345.701366 -400.5072)
			(xy 345.709494 -400.420332) (xy 345.704414 -400.402552) (xy 345.698826 -400.394932) (xy 345.684674 -400.375048)
			(xy 345.662185 -400.331735) (xy 345.646866 -400.285398) (xy 345.639106 -400.237216) (xy 345.638628 -400.212814)
			(xy 345.63915 -400.187559) (xy 345.647463 -400.137737) (xy 345.663864 -400.089963) (xy 345.687905 -400.04554)
			(xy 345.718929 -400.00568) (xy 345.756091 -399.97147) (xy 345.798377 -399.943844) (xy 345.844633 -399.923554)
			(xy 345.893598 -399.911154) (xy 345.943936 -399.906983) (xy 345.994274 -399.911154) (xy 346.043239 -399.923554)
			(xy 346.089495 -399.943844) (xy 346.131781 -399.97147) (xy 346.168943 -400.00568) (xy 346.199967 -400.04554)
			(xy 346.224008 -400.089963) (xy 346.240409 -400.137737) (xy 346.248722 -400.187559) (xy 346.249244 -400.212814)
			(xy 346.248748 -400.237172) (xy 346.241035 -400.285275) (xy 346.225792 -400.331545) (xy 346.203403 -400.374812)
			(xy 346.1893 -400.394678) (xy 346.183458 -400.402298) (xy 346.178632 -400.420078) (xy 346.18676 -400.506946)
			(xy 346.195142 -400.523456) (xy 346.202254 -400.53006) (xy 346.221389 -400.548193) (xy 346.254976 -400.588824)
			(xy 346.282648 -400.633694) (xy 346.303875 -400.681948) (xy 346.318253 -400.732665) (xy 346.325509 -400.78488)
			(xy 346.325952 -400.811238) (xy 346.325952 -401.674838) (xy 346.325443 -401.702143) (xy 346.317594 -401.756189)
			(xy 346.302134 -401.808567) (xy 346.279377 -401.858212) (xy 346.249787 -401.904112) (xy 346.232226 -401.925028)
			(xy 346.22613 -401.93214) (xy 346.21978 -401.949158) (xy 346.21978 -402.034248) (xy 346.22613 -402.051266)
			(xy 346.232226 -402.058378) (xy 346.249839 -402.079411) (xy 346.279508 -402.125556) (xy 346.302295 -402.175459)
			(xy 346.317733 -402.228102) (xy 346.325507 -402.282408) (xy 346.325952 -402.309838) (xy 346.75826 -402.309838)
			(xy 346.758706 -402.282149) (xy 346.766604 -402.227337) (xy 346.782298 -402.17423) (xy 346.805462 -402.12393)
			(xy 346.835617 -402.077482) (xy 346.85351 -402.056346) (xy 346.85986 -402.049488) (xy 346.86621 -402.03247)
			(xy 346.866718 -401.94738) (xy 346.860368 -401.930362) (xy 346.854272 -401.92325) (xy 346.837022 -401.902392)
			(xy 346.80794 -401.856744) (xy 346.785601 -401.807444) (xy 346.770453 -401.755482) (xy 346.762799 -401.7019)
			(xy 346.762324 -401.674838) (xy 346.762324 -400.811238) (xy 346.762809 -400.784883) (xy 346.770072 -400.732674)
			(xy 346.78445 -400.681963) (xy 346.80567 -400.633712) (xy 346.833329 -400.588841) (xy 346.8669 -400.548203)
			(xy 346.886022 -400.53006) (xy 346.893134 -400.52371) (xy 346.901262 -400.506946) (xy 346.909644 -400.420332)
			(xy 346.904564 -400.402552) (xy 346.898976 -400.394678) (xy 346.884829 -400.374829) (xy 346.86237 -400.331571)
			(xy 346.847057 -400.285299) (xy 346.839276 -400.237184) (xy 346.838778 -400.212814) (xy 346.8393 -400.187559)
			(xy 346.847613 -400.137737) (xy 346.864014 -400.089963) (xy 346.888055 -400.04554) (xy 346.919079 -400.00568)
			(xy 346.956241 -399.97147) (xy 346.998527 -399.943844) (xy 347.044783 -399.923554) (xy 347.093748 -399.911154)
			(xy 347.144086 -399.906983) (xy 347.194424 -399.911154) (xy 347.243389 -399.923554) (xy 347.289645 -399.943844)
			(xy 347.331931 -399.97147) (xy 347.369093 -400.00568) (xy 347.400117 -400.04554) (xy 347.424158 -400.089963)
			(xy 347.440559 -400.137737) (xy 347.448872 -400.187559) (xy 347.449394 -400.212814) (xy 347.448927 -400.237187)
			(xy 347.441166 -400.285311) (xy 347.425846 -400.331587) (xy 347.403355 -400.374834) (xy 347.389196 -400.394678)
			(xy 347.383608 -400.402552) (xy 347.378528 -400.420332) (xy 347.38691 -400.506946) (xy 347.395038 -400.52371)
			(xy 347.40215 -400.53006) (xy 347.421284 -400.548194) (xy 347.454872 -400.588825) (xy 347.482543 -400.633694)
			(xy 347.503771 -400.681948) (xy 347.518149 -400.732665) (xy 347.525405 -400.78488) (xy 347.525848 -400.811238)
			(xy 347.525848 -401.674838) (xy 347.52534 -401.702143) (xy 347.517491 -401.756189) (xy 347.502031 -401.808567)
			(xy 347.479274 -401.858212) (xy 347.449683 -401.904112) (xy 347.432122 -401.925028) (xy 347.426026 -401.93214)
			(xy 347.419676 -401.949158) (xy 347.419676 -402.034248) (xy 347.426026 -402.051266) (xy 347.432122 -402.058378)
			(xy 347.449735 -402.079412) (xy 347.479404 -402.125556) (xy 347.502191 -402.175459) (xy 347.517629 -402.228102)
			(xy 347.525403 -402.282408) (xy 347.525848 -402.309838) (xy 347.958156 -402.309838) (xy 347.958642 -402.28214)
			(xy 347.966586 -402.227318) (xy 347.982328 -402.174207) (xy 348.005541 -402.12391) (xy 348.035743 -402.077473)
			(xy 348.05366 -402.056346) (xy 348.06001 -402.049488) (xy 348.06636 -402.03247) (xy 348.066868 -401.94738)
			(xy 348.060518 -401.930362) (xy 348.054422 -401.92325) (xy 348.037214 -401.902371) (xy 348.008191 -401.85671)
			(xy 347.985905 -401.807409) (xy 347.970803 -401.755455) (xy 347.963187 -401.70189) (xy 347.962728 -401.674838)
			(xy 347.962728 -400.811238) (xy 347.963151 -400.784921) (xy 347.970376 -400.732785) (xy 347.984694 -400.682136)
			(xy 348.005834 -400.633934) (xy 348.033395 -400.589093) (xy 348.066855 -400.548463) (xy 348.085918 -400.530314)
			(xy 348.09303 -400.52371) (xy 348.101412 -400.5072) (xy 348.10954 -400.420332) (xy 348.10446 -400.402552)
			(xy 348.098872 -400.394932) (xy 348.084713 -400.375052) (xy 348.062227 -400.331737) (xy 348.04691 -400.285399)
			(xy 348.039152 -400.237216) (xy 348.038674 -400.212814) (xy 348.039196 -400.187559) (xy 348.047509 -400.137737)
			(xy 348.06391 -400.089963) (xy 348.087951 -400.04554) (xy 348.118975 -400.00568) (xy 348.156137 -399.97147)
			(xy 348.198423 -399.943844) (xy 348.244679 -399.923554) (xy 348.293644 -399.911154) (xy 348.343982 -399.906983)
			(xy 348.39432 -399.911154) (xy 348.443285 -399.923554) (xy 348.489541 -399.943844) (xy 348.531827 -399.97147)
			(xy 348.568989 -400.00568) (xy 348.600013 -400.04554) (xy 348.624054 -400.089963) (xy 348.640455 -400.137737)
			(xy 348.648768 -400.187559) (xy 348.64929 -400.212814) (xy 348.648804 -400.237173) (xy 348.64109 -400.285276)
			(xy 348.625844 -400.331546) (xy 348.603451 -400.374813) (xy 348.589346 -400.394678) (xy 348.583504 -400.402298)
			(xy 348.578678 -400.420078) (xy 348.586806 -400.506946) (xy 348.595188 -400.523456) (xy 348.6023 -400.53006)
			(xy 348.621413 -400.5482) (xy 348.654931 -400.58886) (xy 348.682542 -400.633741) (xy 348.703721 -400.681992)
			(xy 348.718066 -400.732696) (xy 348.725304 -400.784891) (xy 348.725744 -400.811238) (xy 348.725744 -401.674838)
			(xy 348.725272 -401.702137) (xy 348.717496 -401.756178) (xy 348.702094 -401.808559) (xy 348.679381 -401.858208)
			(xy 348.649821 -401.904112) (xy 348.632272 -401.925028) (xy 348.626176 -401.93214) (xy 348.619826 -401.949158)
			(xy 348.619826 -402.034248) (xy 348.626176 -402.051266) (xy 348.632272 -402.058378) (xy 348.64989 -402.079415)
			(xy 348.679582 -402.125558) (xy 348.702407 -402.175457) (xy 348.717899 -402.228095) (xy 348.725744 -402.282403)
			(xy 348.726252 -402.309838) (xy 349.158052 -402.309838) (xy 349.158539 -402.28214) (xy 349.166483 -402.227318)
			(xy 349.182224 -402.174207) (xy 349.205437 -402.123911) (xy 349.235639 -402.077473) (xy 349.253556 -402.056346)
			(xy 349.259906 -402.049488) (xy 349.266256 -402.03247) (xy 349.266764 -401.94738) (xy 349.260414 -401.930362)
			(xy 349.254318 -401.92325) (xy 349.237109 -401.902371) (xy 349.208087 -401.85671) (xy 349.185801 -401.807409)
			(xy 349.170699 -401.755456) (xy 349.163083 -401.70189) (xy 349.162624 -401.674838) (xy 349.162624 -400.811238)
			(xy 349.163064 -400.784892) (xy 349.170313 -400.732701) (xy 349.184665 -400.682002) (xy 349.205847 -400.633755)
			(xy 349.233459 -400.588877) (xy 349.266975 -400.548219) (xy 349.286068 -400.53006) (xy 349.29318 -400.52371)
			(xy 349.301308 -400.506946) (xy 349.30969 -400.420332) (xy 349.30461 -400.402552) (xy 349.299022 -400.394678)
			(xy 349.284868 -400.374834) (xy 349.262412 -400.331574) (xy 349.247101 -400.2853) (xy 349.239322 -400.237184)
			(xy 349.238824 -400.212814) (xy 349.239346 -400.187559) (xy 349.247659 -400.137737) (xy 349.26406 -400.089963)
			(xy 349.288101 -400.04554) (xy 349.319125 -400.00568) (xy 349.356287 -399.97147) (xy 349.398573 -399.943844)
			(xy 349.444829 -399.923554) (xy 349.493794 -399.911154) (xy 349.544132 -399.906983) (xy 349.59447 -399.911154)
			(xy 349.643435 -399.923554) (xy 349.689691 -399.943844) (xy 349.731977 -399.97147) (xy 349.769139 -400.00568)
			(xy 349.800163 -400.04554) (xy 349.824204 -400.089963) (xy 349.840605 -400.137737) (xy 349.848918 -400.187559)
			(xy 349.84944 -400.212814) (xy 349.848964 -400.237186) (xy 349.841205 -400.28531) (xy 349.825886 -400.331585)
			(xy 349.803399 -400.374833) (xy 349.789242 -400.394678) (xy 349.783654 -400.402552) (xy 349.778574 -400.420332)
			(xy 349.786956 -400.506946) (xy 349.795084 -400.52371) (xy 349.802196 -400.53006) (xy 349.821308 -400.548201)
			(xy 349.854827 -400.58886) (xy 349.882438 -400.633741) (xy 349.903617 -400.681992) (xy 349.917962 -400.732696)
			(xy 349.9252 -400.784891) (xy 349.92564 -400.811238) (xy 349.92564 -401.674838) (xy 349.925169 -401.702137)
			(xy 349.917393 -401.756179) (xy 349.901991 -401.808559) (xy 349.879277 -401.858208) (xy 349.849717 -401.904112)
			(xy 349.832168 -401.925028) (xy 349.826072 -401.93214) (xy 349.819722 -401.949158) (xy 349.819722 -402.034248)
			(xy 349.826072 -402.051266) (xy 349.832168 -402.058378) (xy 349.849785 -402.079416) (xy 349.879478 -402.125558)
			(xy 349.902303 -402.175457) (xy 349.917795 -402.228095) (xy 349.922265 -402.259038) (xy 350.357948 -402.259038)
			(xy 350.35838 -402.232173) (xy 350.365881 -402.178969) (xy 350.380728 -402.127331) (xy 350.402631 -402.078268)
			(xy 350.431162 -402.032739) (xy 350.448118 -402.011896) (xy 350.4535 -402.00493) (xy 350.4596 -401.98843)
			(xy 350.460056 -401.979638) (xy 350.46031 -401.949158) (xy 350.460025 -401.940308) (xy 350.454035 -401.923656)
			(xy 350.448626 -401.916646) (xy 350.432391 -401.896092) (xy 350.405125 -401.851372) (xy 350.38422 -401.803347)
			(xy 350.37007 -401.752917) (xy 350.36294 -401.701027) (xy 350.36252 -401.674838) (xy 350.36252 -400.811238)
			(xy 350.362962 -400.784892) (xy 350.37021 -400.732702) (xy 350.384562 -400.682002) (xy 350.405744 -400.633756)
			(xy 350.433355 -400.588877) (xy 350.466871 -400.548219) (xy 350.485964 -400.53006) (xy 350.493076 -400.52371)
			(xy 350.501204 -400.506946) (xy 350.509586 -400.420332) (xy 350.504506 -400.402552) (xy 350.498918 -400.394678)
			(xy 350.484764 -400.374834) (xy 350.462308 -400.331574) (xy 350.446997 -400.2853) (xy 350.439218 -400.237184)
			(xy 350.43872 -400.212814) (xy 350.439242 -400.187559) (xy 350.447555 -400.137737) (xy 350.463956 -400.089963)
			(xy 350.487997 -400.04554) (xy 350.519021 -400.00568) (xy 350.556183 -399.97147) (xy 350.598469 -399.943844)
			(xy 350.644725 -399.923554) (xy 350.69369 -399.911154) (xy 350.744028 -399.906983) (xy 350.794366 -399.911154)
			(xy 350.843331 -399.923554) (xy 350.889587 -399.943844) (xy 350.931873 -399.97147) (xy 350.969035 -400.00568)
			(xy 351.000059 -400.04554) (xy 351.0241 -400.089963) (xy 351.040501 -400.137737) (xy 351.048814 -400.187559)
			(xy 351.049336 -400.212814) (xy 351.04886 -400.237186) (xy 351.041101 -400.28531) (xy 351.025783 -400.331585)
			(xy 351.003296 -400.374833) (xy 350.989138 -400.394678) (xy 350.98355 -400.402552) (xy 350.97847 -400.420332)
			(xy 350.986852 -400.506946) (xy 350.99498 -400.52371) (xy 351.002092 -400.53006) (xy 351.021203 -400.548201)
			(xy 351.054722 -400.588861) (xy 351.082333 -400.633742) (xy 351.103513 -400.681992) (xy 351.117858 -400.732696)
			(xy 351.125096 -400.784891) (xy 351.125536 -400.811238) (xy 351.125536 -401.674838) (xy 351.125092 -401.701295)
			(xy 351.117817 -401.753705) (xy 351.103368 -401.804607) (xy 351.082025 -401.853024) (xy 351.054195 -401.898027)
			(xy 351.037652 -401.918678) (xy 351.03233 -401.925737) (xy 351.026351 -401.942359) (xy 351.025968 -401.95119)
			(xy 351.025968 -401.98167) (xy 351.02635 -401.990445) (xy 351.032322 -402.006947) (xy 351.037652 -402.013928)
			(xy 351.054296 -402.034676) (xy 351.082266 -402.07992) (xy 351.103724 -402.128592) (xy 351.118259 -402.179759)
			(xy 351.125595 -402.232442) (xy 351.126044 -402.259038) (xy 351.125555 -402.286471) (xy 351.122195 -402.309838)
			(xy 351.557844 -402.309838) (xy 351.558333 -402.282141) (xy 351.566276 -402.227318) (xy 351.582018 -402.174207)
			(xy 351.60523 -402.123911) (xy 351.635431 -402.077474) (xy 351.653348 -402.056346) (xy 351.659698 -402.049488)
			(xy 351.666048 -402.03247) (xy 351.666556 -401.94738) (xy 351.660206 -401.930362) (xy 351.65411 -401.92325)
			(xy 351.6369 -401.902372) (xy 351.607878 -401.856711) (xy 351.585593 -401.80741) (xy 351.570491 -401.755456)
			(xy 351.562875 -401.70189) (xy 351.562416 -401.674838) (xy 351.562416 -400.811238) (xy 351.562859 -400.784892)
			(xy 351.570108 -400.732702) (xy 351.584459 -400.682002) (xy 351.605641 -400.633756) (xy 351.633252 -400.588878)
			(xy 351.666767 -400.548219) (xy 351.68586 -400.53006) (xy 351.692972 -400.52371) (xy 351.7011 -400.506946)
			(xy 351.709482 -400.420332) (xy 351.704402 -400.402552) (xy 351.698814 -400.394678) (xy 351.684659 -400.374834)
			(xy 351.662204 -400.331574) (xy 351.646893 -400.2853) (xy 351.639114 -400.237184) (xy 351.638616 -400.212814)
			(xy 351.639138 -400.187559) (xy 351.647451 -400.137737) (xy 351.663852 -400.089963) (xy 351.687893 -400.04554)
			(xy 351.718917 -400.00568) (xy 351.756079 -399.97147) (xy 351.798365 -399.943844) (xy 351.844621 -399.923554)
			(xy 351.893586 -399.911154) (xy 351.943924 -399.906983) (xy 351.994262 -399.911154) (xy 352.043227 -399.923554)
			(xy 352.089483 -399.943844) (xy 352.131769 -399.97147) (xy 352.168931 -400.00568) (xy 352.199955 -400.04554)
			(xy 352.223996 -400.089963) (xy 352.240397 -400.137737) (xy 352.24871 -400.187559) (xy 352.249232 -400.212814)
			(xy 352.248757 -400.237186) (xy 352.240998 -400.28531) (xy 352.225679 -400.331585) (xy 352.203192 -400.374833)
			(xy 352.189034 -400.394678) (xy 352.183446 -400.402552) (xy 352.178366 -400.420332) (xy 352.186748 -400.506946)
			(xy 352.194876 -400.52371) (xy 352.201988 -400.53006) (xy 352.221098 -400.548202) (xy 352.254617 -400.588861)
			(xy 352.282229 -400.633742) (xy 352.303408 -400.681992) (xy 352.317754 -400.732696) (xy 352.324992 -400.784891)
			(xy 352.325432 -400.811238) (xy 352.325432 -401.674838) (xy 352.324963 -401.702137) (xy 352.317186 -401.756179)
			(xy 352.301784 -401.808559) (xy 352.27907 -401.858209) (xy 352.24951 -401.904112) (xy 352.23196 -401.925028)
			(xy 352.225864 -401.93214) (xy 352.219514 -401.949158) (xy 352.219514 -402.034248) (xy 352.225864 -402.051266)
			(xy 352.23196 -402.058378) (xy 352.249576 -402.079417) (xy 352.279269 -402.125559) (xy 352.302094 -402.175457)
			(xy 352.317587 -402.228096) (xy 352.325432 -402.282403) (xy 352.32594 -402.309838) (xy 352.758248 -402.309838)
			(xy 352.758673 -402.282148) (xy 352.766572 -402.227334) (xy 352.78227 -402.174226) (xy 352.80544 -402.123926)
			(xy 352.835601 -402.07748) (xy 352.853498 -402.056346) (xy 352.859848 -402.049488) (xy 352.866198 -402.03247)
			(xy 352.866706 -401.94738) (xy 352.860356 -401.930362) (xy 352.85426 -401.92325) (xy 352.837008 -401.902394)
			(xy 352.807927 -401.856745) (xy 352.785588 -401.807444) (xy 352.77044 -401.755482) (xy 352.762787 -401.701901)
			(xy 352.762312 -401.674838) (xy 352.762312 -400.811238) (xy 352.762801 -400.784883) (xy 352.770063 -400.732675)
			(xy 352.784441 -400.681963) (xy 352.805661 -400.633713) (xy 352.833319 -400.588841) (xy 352.866889 -400.548203)
			(xy 352.88601 -400.53006) (xy 352.893122 -400.52371) (xy 352.90125 -400.506946) (xy 352.909632 -400.420332)
			(xy 352.904552 -400.402552) (xy 352.898964 -400.394678) (xy 352.884815 -400.37483) (xy 352.862357 -400.331572)
			(xy 352.847044 -400.285299) (xy 352.839264 -400.237184) (xy 352.838766 -400.212814) (xy 352.839288 -400.187559)
			(xy 352.847601 -400.137737) (xy 352.864002 -400.089963) (xy 352.888043 -400.04554) (xy 352.919067 -400.00568)
			(xy 352.956229 -399.97147) (xy 352.998515 -399.943844) (xy 353.044771 -399.923554) (xy 353.093736 -399.911154)
			(xy 353.144074 -399.906983) (xy 353.194412 -399.911154) (xy 353.243377 -399.923554) (xy 353.289633 -399.943844)
			(xy 353.331919 -399.97147) (xy 353.369081 -400.00568) (xy 353.400105 -400.04554) (xy 353.424146 -400.089963)
			(xy 353.440547 -400.137737) (xy 353.44886 -400.187559) (xy 353.449382 -400.212814) (xy 353.448917 -400.237187)
			(xy 353.441156 -400.285311) (xy 353.425835 -400.331587) (xy 353.403344 -400.374834) (xy 353.389184 -400.394678)
			(xy 353.383596 -400.402552) (xy 353.378516 -400.420332) (xy 353.386898 -400.506946) (xy 353.395026 -400.52371)
			(xy 353.402138 -400.53006) (xy 353.42127 -400.548196) (xy 353.454858 -400.588826) (xy 353.48253 -400.633695)
			(xy 353.503758 -400.681948) (xy 353.518137 -400.732666) (xy 353.525393 -400.78488) (xy 353.525836 -400.811238)
			(xy 353.525836 -401.674838) (xy 353.525331 -401.702144) (xy 353.517482 -401.756189) (xy 353.502021 -401.808568)
			(xy 353.479263 -401.858212) (xy 353.449671 -401.904113) (xy 353.43211 -401.925028) (xy 353.426014 -401.93214)
			(xy 353.419664 -401.949158) (xy 353.419664 -402.034248) (xy 353.426014 -402.051266) (xy 353.43211 -402.058378)
			(xy 353.449721 -402.079413) (xy 353.479391 -402.125557) (xy 353.502178 -402.17546) (xy 353.517617 -402.228102)
			(xy 353.525391 -402.282408) (xy 353.525836 -402.309838) (xy 353.525347 -402.337253) (xy 353.517544 -402.391523)
			(xy 353.502097 -402.444131) (xy 353.47932 -402.494006) (xy 353.449677 -402.540131) (xy 353.413772 -402.581568)
			(xy 353.372335 -402.617473) (xy 353.32621 -402.647116) (xy 353.276335 -402.669893) (xy 353.223727 -402.68534)
			(xy 353.169457 -402.693143) (xy 353.114627 -402.693143) (xy 353.060357 -402.68534) (xy 353.007749 -402.669893)
			(xy 352.957874 -402.647116) (xy 352.911749 -402.617473) (xy 352.870312 -402.581568) (xy 352.834407 -402.540131)
			(xy 352.804764 -402.494006) (xy 352.781987 -402.444131) (xy 352.76654 -402.391523) (xy 352.758737 -402.337253)
			(xy 352.758248 -402.309838) (xy 352.32594 -402.309838) (xy 352.325451 -402.337271) (xy 352.317643 -402.391578)
			(xy 352.302185 -402.44422) (xy 352.279393 -402.494128) (xy 352.249731 -402.540283) (xy 352.213802 -402.581748)
			(xy 352.172337 -402.617677) (xy 352.126182 -402.647339) (xy 352.076274 -402.670131) (xy 352.023632 -402.685589)
			(xy 351.969325 -402.693397) (xy 351.914459 -402.693397) (xy 351.860152 -402.685589) (xy 351.80751 -402.670131)
			(xy 351.757602 -402.647339) (xy 351.711447 -402.617677) (xy 351.669982 -402.581748) (xy 351.634053 -402.540283)
			(xy 351.604391 -402.494128) (xy 351.581599 -402.44422) (xy 351.566141 -402.391578) (xy 351.558333 -402.337271)
			(xy 351.557844 -402.309838) (xy 351.122195 -402.309838) (xy 351.117747 -402.340778) (xy 351.102289 -402.39342)
			(xy 351.079497 -402.443328) (xy 351.049835 -402.489483) (xy 351.013906 -402.530948) (xy 350.972441 -402.566877)
			(xy 350.926286 -402.596539) (xy 350.876378 -402.619331) (xy 350.823736 -402.634789) (xy 350.769429 -402.642597)
			(xy 350.714563 -402.642597) (xy 350.660256 -402.634789) (xy 350.607614 -402.619331) (xy 350.557706 -402.596539)
			(xy 350.511551 -402.566877) (xy 350.470086 -402.530948) (xy 350.434157 -402.489483) (xy 350.404495 -402.443328)
			(xy 350.381703 -402.39342) (xy 350.366245 -402.340778) (xy 350.358437 -402.286471) (xy 350.357948 -402.259038)
			(xy 349.922265 -402.259038) (xy 349.92564 -402.282403) (xy 349.926148 -402.309838) (xy 349.925659 -402.337271)
			(xy 349.917851 -402.391578) (xy 349.902393 -402.44422) (xy 349.879601 -402.494128) (xy 349.849939 -402.540283)
			(xy 349.81401 -402.581748) (xy 349.772545 -402.617677) (xy 349.72639 -402.647339) (xy 349.676482 -402.670131)
			(xy 349.62384 -402.685589) (xy 349.569533 -402.693397) (xy 349.514667 -402.693397) (xy 349.46036 -402.685589)
			(xy 349.407718 -402.670131) (xy 349.35781 -402.647339) (xy 349.311655 -402.617677) (xy 349.27019 -402.581748)
			(xy 349.234261 -402.540283) (xy 349.204599 -402.494128) (xy 349.181807 -402.44422) (xy 349.166349 -402.391578)
			(xy 349.158541 -402.337271) (xy 349.158052 -402.309838) (xy 348.726252 -402.309838) (xy 348.725763 -402.337271)
			(xy 348.717955 -402.391578) (xy 348.702497 -402.44422) (xy 348.679705 -402.494128) (xy 348.650043 -402.540283)
			(xy 348.614114 -402.581748) (xy 348.572649 -402.617677) (xy 348.526494 -402.647339) (xy 348.476586 -402.670131)
			(xy 348.423944 -402.685589) (xy 348.369637 -402.693397) (xy 348.314771 -402.693397) (xy 348.260464 -402.685589)
			(xy 348.207822 -402.670131) (xy 348.157914 -402.647339) (xy 348.111759 -402.617677) (xy 348.070294 -402.581748)
			(xy 348.034365 -402.540283) (xy 348.004703 -402.494128) (xy 347.981911 -402.44422) (xy 347.966453 -402.391578)
			(xy 347.958645 -402.337271) (xy 347.958156 -402.309838) (xy 347.525848 -402.309838) (xy 347.525359 -402.337253)
			(xy 347.517556 -402.391523) (xy 347.502109 -402.444131) (xy 347.479332 -402.494006) (xy 347.449689 -402.540131)
			(xy 347.413784 -402.581568) (xy 347.372347 -402.617473) (xy 347.326222 -402.647116) (xy 347.276347 -402.669893)
			(xy 347.223739 -402.68534) (xy 347.169469 -402.693143) (xy 347.114639 -402.693143) (xy 347.060369 -402.68534)
			(xy 347.007761 -402.669893) (xy 346.957886 -402.647116) (xy 346.911761 -402.617473) (xy 346.870324 -402.581568)
			(xy 346.834419 -402.540131) (xy 346.804776 -402.494006) (xy 346.781999 -402.444131) (xy 346.766552 -402.391523)
			(xy 346.758749 -402.337253) (xy 346.75826 -402.309838) (xy 346.325952 -402.309838) (xy 346.325463 -402.337253)
			(xy 346.31766 -402.391523) (xy 346.302213 -402.444131) (xy 346.279436 -402.494006) (xy 346.249793 -402.540131)
			(xy 346.213888 -402.581568) (xy 346.172451 -402.617473) (xy 346.126326 -402.647116) (xy 346.076451 -402.669893)
			(xy 346.023843 -402.68534) (xy 345.969573 -402.693143) (xy 345.914743 -402.693143) (xy 345.860473 -402.68534)
			(xy 345.807865 -402.669893) (xy 345.75799 -402.647116) (xy 345.711865 -402.617473) (xy 345.670428 -402.581568)
			(xy 345.634523 -402.540131) (xy 345.60488 -402.494006) (xy 345.582103 -402.444131) (xy 345.566656 -402.391523)
			(xy 345.558853 -402.337253) (xy 345.558364 -402.309838) (xy 345.125603 -402.309838) (xy 345.125567 -402.311871)
			(xy 345.117759 -402.366178) (xy 345.102301 -402.41882) (xy 345.079509 -402.468728) (xy 345.049847 -402.514883)
			(xy 345.013918 -402.556348) (xy 344.972453 -402.592277) (xy 344.926298 -402.621939) (xy 344.87639 -402.644731)
			(xy 344.823748 -402.660189) (xy 344.769441 -402.667997) (xy 344.714575 -402.667997) (xy 344.660268 -402.660189)
			(xy 344.607626 -402.644731) (xy 344.557718 -402.621939) (xy 344.511563 -402.592277) (xy 344.470098 -402.556348)
			(xy 344.434169 -402.514883) (xy 344.404507 -402.468728) (xy 344.381715 -402.41882) (xy 344.366257 -402.366178)
			(xy 344.358449 -402.311871) (xy 344.35796 -402.284438) (xy 343.925707 -402.284438) (xy 343.925671 -402.286471)
			(xy 343.917863 -402.340778) (xy 343.902405 -402.39342) (xy 343.879613 -402.443328) (xy 343.849951 -402.489483)
			(xy 343.814022 -402.530948) (xy 343.772557 -402.566877) (xy 343.726402 -402.596539) (xy 343.676494 -402.619331)
			(xy 343.623852 -402.634789) (xy 343.569545 -402.642597) (xy 343.514679 -402.642597) (xy 343.460372 -402.634789)
			(xy 343.40773 -402.619331) (xy 343.357822 -402.596539) (xy 343.311667 -402.566877) (xy 343.270202 -402.530948)
			(xy 343.234273 -402.489483) (xy 343.204611 -402.443328) (xy 343.181819 -402.39342) (xy 343.166361 -402.340778)
			(xy 343.158553 -402.286471) (xy 343.158064 -402.259038) (xy 342.721966 -402.259038) (xy 342.725311 -402.282408)
			(xy 342.725756 -402.309838) (xy 342.725267 -402.337253) (xy 342.717464 -402.391523) (xy 342.702017 -402.444131)
			(xy 342.67924 -402.494006) (xy 342.649597 -402.540131) (xy 342.613692 -402.581568) (xy 342.572255 -402.617473)
			(xy 342.52613 -402.647116) (xy 342.476255 -402.669893) (xy 342.423647 -402.68534) (xy 342.369377 -402.693143)
			(xy 342.314547 -402.693143) (xy 342.260277 -402.68534) (xy 342.207669 -402.669893) (xy 342.157794 -402.647116)
			(xy 342.111669 -402.617473) (xy 342.070232 -402.581568) (xy 342.034327 -402.540131) (xy 342.004684 -402.494006)
			(xy 341.981907 -402.444131) (xy 341.96646 -402.391523) (xy 341.958657 -402.337253) (xy 341.958168 -402.309838)
			(xy 341.52586 -402.309838) (xy 341.525371 -402.337253) (xy 341.517568 -402.391523) (xy 341.502121 -402.444131)
			(xy 341.479344 -402.494006) (xy 341.449701 -402.540131) (xy 341.413796 -402.581568) (xy 341.372359 -402.617473)
			(xy 341.326234 -402.647116) (xy 341.276359 -402.669893) (xy 341.223751 -402.68534) (xy 341.169481 -402.693143)
			(xy 341.114651 -402.693143) (xy 341.060381 -402.68534) (xy 341.007773 -402.669893) (xy 340.957898 -402.647116)
			(xy 340.911773 -402.617473) (xy 340.870336 -402.581568) (xy 340.834431 -402.540131) (xy 340.804788 -402.494006)
			(xy 340.782011 -402.444131) (xy 340.766564 -402.391523) (xy 340.758761 -402.337253) (xy 340.758272 -402.309838)
			(xy 340.322115 -402.309838) (xy 340.317667 -402.340778) (xy 340.302209 -402.39342) (xy 340.279417 -402.443328)
			(xy 340.249755 -402.489483) (xy 340.213826 -402.530948) (xy 340.172361 -402.566877) (xy 340.126206 -402.596539)
			(xy 340.076298 -402.619331) (xy 340.023656 -402.634789) (xy 339.969349 -402.642597) (xy 339.914483 -402.642597)
			(xy 339.860176 -402.634789) (xy 339.807534 -402.619331) (xy 339.757626 -402.596539) (xy 339.711471 -402.566877)
			(xy 339.670006 -402.530948) (xy 339.634077 -402.489483) (xy 339.604415 -402.443328) (xy 339.581623 -402.39342)
			(xy 339.566165 -402.340778) (xy 339.558357 -402.286471) (xy 339.557868 -402.259038) (xy 339.122207 -402.259038)
			(xy 339.125583 -402.282402) (xy 339.126068 -402.309838) (xy 339.125579 -402.337271) (xy 339.117771 -402.391578)
			(xy 339.102313 -402.44422) (xy 339.079521 -402.494128) (xy 339.049859 -402.540283) (xy 339.01393 -402.581748)
			(xy 338.972465 -402.617677) (xy 338.92631 -402.647339) (xy 338.876402 -402.670131) (xy 338.82376 -402.685589)
			(xy 338.769453 -402.693397) (xy 338.714587 -402.693397) (xy 338.66028 -402.685589) (xy 338.607638 -402.670131)
			(xy 338.55773 -402.647339) (xy 338.511575 -402.617677) (xy 338.47011 -402.581748) (xy 338.434181 -402.540283)
			(xy 338.404519 -402.494128) (xy 338.381727 -402.44422) (xy 338.366269 -402.391578) (xy 338.358461 -402.337271)
			(xy 338.357972 -402.309838) (xy 337.925211 -402.309838) (xy 337.925175 -402.311853) (xy 337.917372 -402.366123)
			(xy 337.901925 -402.418731) (xy 337.879148 -402.468606) (xy 337.849505 -402.514731) (xy 337.8136 -402.556168)
			(xy 337.772163 -402.592073) (xy 337.726038 -402.621716) (xy 337.676163 -402.644493) (xy 337.623555 -402.65994)
			(xy 337.569285 -402.667743) (xy 337.514455 -402.667743) (xy 337.460185 -402.65994) (xy 337.407577 -402.644493)
			(xy 337.357702 -402.621716) (xy 337.311577 -402.592073) (xy 337.27014 -402.556168) (xy 337.234235 -402.514731)
			(xy 337.204592 -402.468606) (xy 337.181815 -402.418731) (xy 337.166368 -402.366123) (xy 337.158565 -402.311853)
			(xy 337.158076 -402.284438) (xy 336.725768 -402.284438) (xy 336.725279 -402.311853) (xy 336.717476 -402.366123)
			(xy 336.702029 -402.418731) (xy 336.679252 -402.468606) (xy 336.649609 -402.514731) (xy 336.613704 -402.556168)
			(xy 336.572267 -402.592073) (xy 336.526142 -402.621716) (xy 336.476267 -402.644493) (xy 336.423659 -402.65994)
			(xy 336.369389 -402.667743) (xy 336.314559 -402.667743) (xy 336.260289 -402.65994) (xy 336.207681 -402.644493)
			(xy 336.157806 -402.621716) (xy 336.111681 -402.592073) (xy 336.070244 -402.556168) (xy 336.034339 -402.514731)
			(xy 336.004696 -402.468606) (xy 335.981919 -402.418731) (xy 335.966472 -402.366123) (xy 335.958669 -402.311853)
			(xy 335.95818 -402.284438) (xy 331.924406 -402.284438) (xy 331.897035 -402.283984) (xy 331.842855 -402.276165)
			(xy 331.790351 -402.260674) (xy 331.740604 -402.23783) (xy 331.694639 -402.208101) (xy 331.673708 -402.190458)
			(xy 331.666596 -402.184362) (xy 331.649578 -402.178012) (xy 331.564234 -402.178012) (xy 331.547216 -402.184362)
			(xy 331.540104 -402.190458) (xy 331.519171 -402.208099) (xy 331.473203 -402.237823) (xy 331.423457 -402.260669)
			(xy 331.370955 -402.276165) (xy 331.316777 -402.283994) (xy 331.262035 -402.283994) (xy 331.207857 -402.276165)
			(xy 331.155355 -402.260669) (xy 331.105609 -402.237823) (xy 331.059641 -402.208099) (xy 331.038708 -402.190458)
			(xy 331.031596 -402.184362) (xy 331.014578 -402.178012) (xy 330.929234 -402.178012) (xy 330.912216 -402.184362)
			(xy 330.905104 -402.190458) (xy 330.884171 -402.208099) (xy 330.838203 -402.237823) (xy 330.788457 -402.260669)
			(xy 330.735955 -402.276165) (xy 330.681777 -402.283994) (xy 330.627035 -402.283994) (xy 330.572857 -402.276165)
			(xy 330.520355 -402.260669) (xy 330.470609 -402.237823) (xy 330.424641 -402.208099) (xy 330.403708 -402.190458)
			(xy 330.396596 -402.184362) (xy 330.379578 -402.178012) (xy 330.294234 -402.178012) (xy 330.277216 -402.184362)
			(xy 330.270104 -402.190458) (xy 330.249176 -402.208102) (xy 330.203203 -402.237815) (xy 330.153454 -402.26065)
			(xy 330.100952 -402.27614) (xy 330.046776 -402.283966) (xy 330.019406 -402.284438) (xy 329.992156 -402.283917)
			(xy 329.938211 -402.276162) (xy 329.885919 -402.260809) (xy 329.836344 -402.238171) (xy 329.790495 -402.208708)
			(xy 329.749305 -402.17302) (xy 329.713614 -402.131834) (xy 329.684147 -402.085988) (xy 329.661504 -402.036415)
			(xy 329.646146 -401.984124) (xy 329.638386 -401.93018) (xy 329.637898 -401.90293) (xy 328.782934 -401.90293)
			(xy 328.782472 -401.933661) (xy 328.775061 -401.994673) (xy 328.76035 -402.054348) (xy 328.738553 -402.111815)
			(xy 328.709989 -402.166235) (xy 328.675074 -402.216816) (xy 328.634318 -402.262821) (xy 328.588313 -402.303577)
			(xy 328.537732 -402.338491) (xy 328.483311 -402.367055) (xy 328.425844 -402.388851) (xy 328.36617 -402.403561)
			(xy 328.305157 -402.410972) (xy 328.274426 -402.411438) (xy 328.243729 -402.410977) (xy 328.182784 -402.40357)
			(xy 328.123176 -402.388875) (xy 328.065772 -402.367105) (xy 328.011409 -402.338576) (xy 327.985882 -402.321522)
			(xy 327.97713 -402.316051) (xy 327.956926 -402.311923) (xy 327.936722 -402.316051) (xy 327.92797 -402.321522)
			(xy 327.902433 -402.338559) (xy 327.848066 -402.36707) (xy 327.790663 -402.388833) (xy 327.73106 -402.403534)
			(xy 327.670121 -402.410958) (xy 327.639426 -402.411438) (xy 327.608729 -402.410977) (xy 327.547784 -402.40357)
			(xy 327.488176 -402.388875) (xy 327.430772 -402.367105) (xy 327.376409 -402.338576) (xy 327.350882 -402.321522)
			(xy 327.34213 -402.316051) (xy 327.321926 -402.311923) (xy 327.301722 -402.316051) (xy 327.29297 -402.321522)
			(xy 327.267433 -402.338559) (xy 327.213066 -402.36707) (xy 327.155663 -402.388833) (xy 327.09606 -402.403534)
			(xy 327.035121 -402.410958) (xy 327.004426 -402.411438) (xy 326.973729 -402.410977) (xy 326.912784 -402.40357)
			(xy 326.853176 -402.388875) (xy 326.795772 -402.367105) (xy 326.741409 -402.338576) (xy 326.715882 -402.321522)
			(xy 326.70713 -402.316051) (xy 326.686926 -402.311923) (xy 326.666722 -402.316051) (xy 326.65797 -402.321522)
			(xy 326.632433 -402.338559) (xy 326.578066 -402.36707) (xy 326.520663 -402.388833) (xy 326.46106 -402.403534)
			(xy 326.400121 -402.410958) (xy 326.369426 -402.411438) (xy 326.338729 -402.410977) (xy 326.277784 -402.40357)
			(xy 326.218176 -402.388875) (xy 326.160772 -402.367105) (xy 326.106409 -402.338576) (xy 326.080882 -402.321522)
			(xy 326.07213 -402.316051) (xy 326.051926 -402.311923) (xy 326.031722 -402.316051) (xy 326.02297 -402.321522)
			(xy 325.997433 -402.338559) (xy 325.943066 -402.36707) (xy 325.885663 -402.388833) (xy 325.82606 -402.403534)
			(xy 325.765121 -402.410958) (xy 325.734426 -402.411438) (xy 325.703697 -402.41092) (xy 325.642686 -402.403515)
			(xy 325.583012 -402.38881) (xy 325.525547 -402.367019) (xy 325.471126 -402.338461) (xy 325.420545 -402.303551)
			(xy 325.37454 -402.262799) (xy 325.333783 -402.216799) (xy 325.298868 -402.166222) (xy 325.270304 -402.111805)
			(xy 325.248507 -402.054341) (xy 325.233795 -401.994669) (xy 325.226384 -401.933659) (xy 325.225918 -401.90293)
			(xy 324.948674 -401.90293) (xy 324.948187 -401.903968) (xy 324.917414 -401.950481) (xy 324.880197 -401.992018)
			(xy 324.837329 -402.027693) (xy 324.789723 -402.056747) (xy 324.738394 -402.078559) (xy 324.684437 -402.092665)
			(xy 324.629 -402.098765) (xy 324.573266 -402.096728) (xy 324.518423 -402.086598) (xy 324.465639 -402.068591)
			(xy 324.416039 -402.04309) (xy 324.370681 -402.010639) (xy 324.330532 -401.97193) (xy 324.296446 -401.927787)
			(xy 324.26915 -401.879152) (xy 324.249227 -401.827061) (xy 324.237101 -401.772624) (xy 324.23303 -401.717002)
			(xy 323.89826 -401.717002) (xy 323.89826 -402.581618) (xy 323.898688 -402.591685) (xy 323.906414 -402.610279)
			(xy 323.913246 -402.617686) (xy 324.029578 -402.734018) (xy 334.732628 -402.734018) (xy 334.736699 -402.678396)
			(xy 334.748825 -402.623959) (xy 334.768748 -402.571868) (xy 334.796044 -402.523233) (xy 334.83013 -402.47909)
			(xy 334.870279 -402.440381) (xy 334.915637 -402.40793) (xy 334.965237 -402.382429) (xy 335.018021 -402.364422)
			(xy 335.072864 -402.354292) (xy 335.128598 -402.352255) (xy 335.184035 -402.358355) (xy 335.237992 -402.372461)
			(xy 335.289321 -402.394273) (xy 335.336927 -402.423327) (xy 335.379795 -402.459002) (xy 335.417012 -402.500539)
			(xy 335.447785 -402.547052) (xy 335.471457 -402.597549) (xy 335.487525 -402.650956) (xy 335.495645 -402.706132)
			(xy 335.496154 -402.734018) (xy 335.495645 -402.761904) (xy 335.487525 -402.81708) (xy 335.471457 -402.870487)
			(xy 335.447785 -402.920984) (xy 335.417012 -402.967497) (xy 335.379795 -403.009034) (xy 335.336927 -403.044709)
			(xy 335.289321 -403.073763) (xy 335.237992 -403.095575) (xy 335.184035 -403.109681) (xy 335.128598 -403.115781)
			(xy 335.072864 -403.113744) (xy 335.018021 -403.103614) (xy 334.965237 -403.085607) (xy 334.915637 -403.060106)
			(xy 334.870279 -403.027655) (xy 334.83013 -402.988946) (xy 334.796044 -402.944803) (xy 334.768748 -402.896168)
			(xy 334.748825 -402.844077) (xy 334.736699 -402.78964) (xy 334.732628 -402.734018) (xy 324.029578 -402.734018)
			(xy 324.048374 -402.752814) (xy 324.054788 -402.758677) (xy 324.070505 -402.766058) (xy 324.079108 -402.767292)
			(xy 328.119994 -403.165056) (xy 328.13625 -403.161246) (xy 328.143616 -403.15642) (xy 328.171833 -403.138721)
			(xy 328.231539 -403.109191) (xy 328.294237 -403.086698) (xy 328.359099 -403.071539) (xy 328.425271 -403.063914)
			(xy 328.458576 -403.063456) (xy 328.472824 -403.063545) (xy 328.501284 -403.064942) (xy 328.515472 -403.06625)
			(xy 328.940414 -403.10816) (xy 328.974357 -403.11199) (xy 329.041082 -403.126613) (xy 329.105622 -403.148987)
			(xy 329.167081 -403.178801) (xy 329.224605 -403.215641) (xy 329.25131 -403.236938) (xy 329.259352 -403.2429)
			(xy 329.278486 -403.248715) (xy 329.298392 -403.246799) (xy 329.307444 -403.242526) (xy 329.339097 -403.226158)
			(xy 329.405547 -403.200422) (xy 329.474654 -403.183036) (xy 329.545372 -403.174265) (xy 329.581002 -403.173692)
			(xy 329.595252 -403.173843) (xy 329.623713 -403.175368) (xy 329.637898 -403.17674) (xy 330.06284 -403.21865)
			(xy 330.0951 -403.222296) (xy 330.15859 -403.235863) (xy 330.220169 -403.256434) (xy 330.279066 -403.283751)
			(xy 330.334546 -403.317472) (xy 330.385913 -403.357176) (xy 330.40955 -403.379432) (xy 330.416154 -403.385782)
			(xy 330.43114 -403.39264) (xy 330.47051 -403.396704) (xy 330.486766 -403.39264) (xy 330.494132 -403.387814)
			(xy 330.522329 -403.370142) (xy 330.581991 -403.340663) (xy 330.64464 -403.318219) (xy 330.709449 -403.303108)
			(xy 330.775564 -403.295527) (xy 330.808838 -403.295104) (xy 330.823086 -403.295192) (xy 330.851547 -403.296587)
			(xy 330.865734 -403.297898) (xy 331.290676 -403.339808) (xy 331.322988 -403.343443) (xy 331.386582 -403.357007)
			(xy 331.448261 -403.377599) (xy 331.507249 -403.40496) (xy 331.562806 -403.438748) (xy 331.614236 -403.478538)
			(xy 331.637894 -403.500844) (xy 331.64399 -403.50694) (xy 331.659738 -403.514306) (xy 334.370426 -403.781006)
			(xy 334.384543 -403.782496) (xy 334.412623 -403.786688) (xy 334.42656 -403.789388) (xy 335.6356 -404.029926)
			(xy 335.649524 -404.032821) (xy 335.677096 -404.039809) (xy 335.690718 -404.043896) (xy 336.998056 -404.44039)
			(xy 337.011652 -404.444577) (xy 337.038461 -404.454107) (xy 337.05165 -404.45944) (xy 341.17153 -406.166066)
			(xy 341.197654 -406.177293) (xy 341.247782 -406.204139) (xy 341.271606 -406.21966) (xy 342.939116 -407.333704)
			(xy 342.94552 -407.337741) (xy 342.959997 -407.34215) (xy 342.967564 -407.34234)
		)
		(stroke
			(width 0)
			(type solid)
		)
		(fill yes)
		(layer "In15.Cu")
		(net "P0V9_CPU0_RT1_2A_2D")
	)
	(gr_poly
		(pts
			(xy 361.373928 -399.02892) (xy 361.382656 -399.028566) (xy 361.39909 -399.022682) (xy 361.412563 -399.011583)
			(xy 361.417362 -399.004282) (xy 361.435142 -398.97685) (xy 361.44061 -398.968097) (xy 361.444733 -398.947895)
			(xy 361.440606 -398.927694) (xy 361.435142 -398.918938) (xy 361.418085 -398.893412) (xy 361.389551 -398.83905)
			(xy 361.367775 -398.781647) (xy 361.353076 -398.722038) (xy 361.345666 -398.661091) (xy 361.345226 -398.630394)
			(xy 361.345693 -398.599312) (xy 361.353272 -398.537613) (xy 361.368317 -398.477297) (xy 361.390602 -398.419266)
			(xy 361.419796 -398.364384) (xy 361.455463 -398.313471) (xy 361.49707 -398.267285) (xy 361.543998 -398.226517)
			(xy 361.569508 -398.208754) (xy 361.57681 -398.203395) (xy 361.587363 -398.188691) (xy 361.590082 -398.180052)
			(xy 361.59821 -398.150842) (xy 361.60024 -398.142196) (xy 361.598811 -398.124505) (xy 361.595416 -398.116298)
			(xy 361.584595 -398.091336) (xy 361.569329 -398.039116) (xy 361.561621 -397.985259) (xy 361.561126 -397.958056)
			(xy 361.561601 -397.930687) (xy 361.569431 -397.876512) (xy 361.584924 -397.824013) (xy 361.607761 -397.774267)
			(xy 361.637474 -397.728296) (xy 361.655106 -397.707358) (xy 361.661202 -397.700246) (xy 361.667552 -397.683228)
			(xy 361.667552 -397.597884) (xy 361.661202 -397.580866) (xy 361.655106 -397.573754) (xy 361.637466 -397.552822)
			(xy 361.607745 -397.506854) (xy 361.584908 -397.457107) (xy 361.569424 -397.404604) (xy 361.561612 -397.350426)
			(xy 361.561126 -397.323056) (xy 361.561615 -397.295808) (xy 361.569377 -397.241867) (xy 361.584736 -397.189579)
			(xy 361.60738 -397.14001) (xy 361.636848 -397.094167) (xy 361.67254 -397.052985) (xy 361.71373 -397.017302)
			(xy 361.759578 -396.987843) (xy 361.809152 -396.965209) (xy 361.861443 -396.94986) (xy 361.915386 -396.94211)
			(xy 361.942634 -396.941548) (xy 361.969393 -396.942) (xy 362.022385 -396.949478) (xy 362.073815 -396.964281)
			(xy 362.122674 -396.986121) (xy 362.168004 -397.014569) (xy 362.18876 -397.031464) (xy 362.197904 -397.039338)
			(xy 362.221018 -397.044926) (xy 362.323634 -397.021812) (xy 362.341922 -397.006826) (xy 362.347002 -396.995904)
			(xy 362.358681 -396.971186) (xy 362.388069 -396.925089) (xy 362.423741 -396.883663) (xy 362.464965 -396.847758)
			(xy 362.510896 -396.81811) (xy 362.560591 -396.795328) (xy 362.613031 -396.779879) (xy 362.66714 -396.77208)
			(xy 362.694474 -396.771622) (xy 362.721842 -396.772099) (xy 362.776015 -396.779933) (xy 362.828512 -396.795429)
			(xy 362.878255 -396.818269) (xy 362.924223 -396.847984) (xy 362.945172 -396.865602) (xy 362.952284 -396.871698)
			(xy 362.969302 -396.878048) (xy 363.054646 -396.878048) (xy 363.071664 -396.871698) (xy 363.078776 -396.865602)
			(xy 363.099707 -396.847959) (xy 363.145673 -396.818229) (xy 363.195419 -396.795383) (xy 363.247923 -396.779889)
			(xy 363.302103 -396.772067) (xy 363.329474 -396.771622) (xy 363.358273 -396.772146) (xy 363.415216 -396.780803)
			(xy 363.470209 -396.797925) (xy 363.522003 -396.823121) (xy 363.569419 -396.855819) (xy 363.611379 -396.895276)
			(xy 363.646928 -396.940593) (xy 363.675259 -396.990741) (xy 363.695727 -397.044579) (xy 363.702346 -397.072612)
			(xy 363.705394 -397.086582) (xy 363.72419 -397.106648) (xy 363.82325 -397.135858) (xy 363.832083 -397.138089)
			(xy 363.850245 -397.136837) (xy 363.866821 -397.129309) (xy 363.873542 -397.123158) (xy 364.19917 -396.79753)
			(xy 364.207329 -396.788294) (xy 364.214647 -396.764801) (xy 364.21314 -396.752572) (xy 364.196376 -396.658338)
			(xy 364.181136 -396.63878) (xy 364.16996 -396.633446) (xy 364.140941 -396.619522) (xy 364.086357 -396.585412)
			(xy 364.036514 -396.544688) (xy 363.992207 -396.497999) (xy 363.954145 -396.446094) (xy 363.922937 -396.389801)
			(xy 363.899081 -396.33002) (xy 363.882958 -396.267706) (xy 363.874828 -396.203857) (xy 363.874304 -396.171674)
			(xy 363.874885 -396.13672) (xy 363.884458 -396.067469) (xy 363.903419 -396.000181) (xy 363.931414 -395.936122)
			(xy 363.967913 -395.876497) (xy 363.98962 -395.849094) (xy 363.994963 -395.842117) (xy 364.00096 -395.825615)
			(xy 364.001304 -395.816836) (xy 364.001304 -395.662912) (xy 364.000884 -395.654147) (xy 363.994898 -395.637665)
			(xy 363.98962 -395.630654) (xy 363.967906 -395.603256) (xy 363.931403 -395.543633) (xy 363.903411 -395.479572)
			(xy 363.884458 -395.412282) (xy 363.874899 -395.343029) (xy 363.874304 -395.308074) (xy 363.87477 -395.277344)
			(xy 363.882181 -395.216333) (xy 363.896892 -395.15666) (xy 363.918688 -395.099196) (xy 363.947252 -395.044777)
			(xy 363.982167 -394.994199) (xy 364.022924 -394.948197) (xy 364.068929 -394.907444) (xy 364.11951 -394.872532)
			(xy 364.17393 -394.843973) (xy 364.231397 -394.82218) (xy 364.291071 -394.807474) (xy 364.352082 -394.800067)
			(xy 364.382812 -394.799566) (xy 364.408585 -394.799883) (xy 364.459865 -394.805101) (xy 364.485174 -394.80998)
			(xy 364.495588 -394.812012) (xy 364.515654 -394.807948) (xy 364.593378 -394.754354) (xy 364.6043 -394.736828)
			(xy 364.606078 -394.726414) (xy 364.610782 -394.699866) (xy 364.626682 -394.648349) (xy 364.649675 -394.599582)
			(xy 364.679303 -394.554538) (xy 364.714977 -394.514113) (xy 364.755987 -394.479111) (xy 364.801514 -394.450231)
			(xy 364.850654 -394.428047) (xy 364.902427 -394.413001) (xy 364.955803 -394.405392) (xy 364.98276 -394.40485)
			(xy 365.010014 -394.405333) (xy 365.063969 -394.413085) (xy 365.11627 -394.428436) (xy 365.165855 -394.451074)
			(xy 365.211714 -394.480539) (xy 365.252912 -394.51623) (xy 365.288612 -394.55742) (xy 365.318086 -394.603273)
			(xy 365.340735 -394.652853) (xy 365.356098 -394.705151) (xy 365.363861 -394.759104) (xy 365.364268 -394.786358)
			(xy 365.363801 -394.813288) (xy 365.356221 -394.866611) (xy 365.34122 -394.91834) (xy 365.319095 -394.967445)
			(xy 365.290287 -395.012953) (xy 365.255367 -395.053959) (xy 365.215029 -395.089648) (xy 365.170074 -395.119311)
			(xy 365.121395 -395.14236) (xy 365.06996 -395.158336) (xy 365.016789 -395.166923) (xy 364.989872 -395.167866)
			(xy 364.979204 -395.16812) (xy 364.960408 -395.176502) (xy 364.8964 -395.245844) (xy 364.889542 -395.265402)
			(xy 364.890304 -395.275816) (xy 364.89132 -395.308074) (xy 364.890736 -395.343027) (xy 364.881158 -395.412275)
			(xy 364.862191 -395.47956) (xy 364.834194 -395.543616) (xy 364.797693 -395.603236) (xy 364.776004 -395.630654)
			(xy 364.770675 -395.637635) (xy 364.764703 -395.654137) (xy 364.76432 -395.662912) (xy 364.76432 -395.816836)
			(xy 364.764729 -395.825605) (xy 364.770695 -395.842103) (xy 364.776004 -395.849094) (xy 364.796158 -395.874529)
			(xy 364.830549 -395.929562) (xy 364.844584 -395.958822) (xy 364.849918 -395.969998) (xy 364.869476 -395.985238)
			(xy 364.96371 -396.002002) (xy 364.975946 -396.00351) (xy 364.999458 -395.996225) (xy 365.008668 -395.988032)
			(xy 366.166654 -394.830046) (xy 366.174053 -394.823203) (xy 366.192652 -394.815481) (xy 366.202722 -394.81506)
			(xy 367.702592 -394.81506) (xy 367.730278 -394.792708) (xy 367.734088 -394.774928) (xy 367.740252 -394.748297)
			(xy 367.758091 -394.696624) (xy 367.781964 -394.647448) (xy 367.811532 -394.601469) (xy 367.846372 -394.559345)
			(xy 367.865914 -394.540232) (xy 367.87455 -394.53185) (xy 367.882678 -394.509498) (xy 367.87074 -394.405104)
			(xy 367.857786 -394.385292) (xy 367.847372 -394.378942) (xy 367.824004 -394.364697) (xy 367.780511 -394.331476)
			(xy 367.741283 -394.293311) (xy 367.706881 -394.250747) (xy 367.677792 -394.204387) (xy 367.665762 -394.179806)
			(xy 367.659666 -394.167106) (xy 367.636806 -394.151612) (xy 367.519966 -394.144246) (xy 367.495582 -394.156692)
			(xy 367.487962 -394.16863) (xy 367.472873 -394.191507) (xy 367.437177 -394.233089) (xy 367.395898 -394.269136)
			(xy 367.349886 -394.298906) (xy 367.300089 -394.321786) (xy 367.24753 -394.337306) (xy 367.193291 -394.345146)
			(xy 367.16589 -394.345668) (xy 367.138642 -394.345181) (xy 367.084701 -394.337424) (xy 367.032413 -394.32207)
			(xy 366.982842 -394.299431) (xy 366.936998 -394.269967) (xy 366.895813 -394.234279) (xy 366.860127 -394.193094)
			(xy 366.830665 -394.147249) (xy 366.808027 -394.097677) (xy 366.792674 -394.045389) (xy 366.784918 -393.991448)
			(xy 366.784918 -393.936952) (xy 366.792674 -393.883011) (xy 366.808027 -393.830723) (xy 366.830665 -393.781151)
			(xy 366.860127 -393.735306) (xy 366.895813 -393.694121) (xy 366.936998 -393.658433) (xy 366.982842 -393.628969)
			(xy 367.032413 -393.60633) (xy 367.084701 -393.590976) (xy 367.138642 -393.583219) (xy 367.16589 -393.582652)
			(xy 367.194525 -393.583164) (xy 367.251151 -393.591724) (xy 367.305861 -393.608653) (xy 367.357425 -393.633571)
			(xy 367.404685 -393.665917) (xy 367.446578 -393.704965) (xy 367.482163 -393.749836) (xy 367.496852 -393.774422)
			(xy 367.503964 -393.786614) (xy 367.52784 -393.80033) (xy 367.644934 -393.798044) (xy 367.668302 -393.78382)
			(xy 367.674906 -393.771374) (xy 367.689855 -393.744133) (xy 367.726004 -393.693591) (xy 367.768656 -393.648402)
			(xy 367.817028 -393.609398) (xy 367.870231 -393.577294) (xy 367.927287 -393.552681) (xy 367.987148 -393.536012)
			(xy 368.048713 -393.527592) (xy 368.079782 -393.527026) (xy 368.109751 -393.527494) (xy 368.169176 -393.535316)
			(xy 368.227072 -393.550828) (xy 368.282448 -393.573764) (xy 368.334356 -393.603733) (xy 368.381907 -393.640221)
			(xy 368.424289 -393.682605) (xy 368.460776 -393.730158) (xy 368.490743 -393.782066) (xy 368.513678 -393.837443)
			(xy 368.529187 -393.895339) (xy 368.537007 -393.954765) (xy 368.53749 -393.984734) (xy 368.536962 -394.015611)
			(xy 368.528621 -394.076799) (xy 368.512135 -394.136312) (xy 368.487804 -394.19307) (xy 368.456068 -394.246046)
			(xy 368.417502 -394.294277) (xy 368.395504 -394.31595) (xy 368.386868 -394.324332) (xy 368.37874 -394.346684)
			(xy 368.390678 -394.451078) (xy 368.403632 -394.47089) (xy 368.414046 -394.47724) (xy 368.440934 -394.493674)
			(xy 368.490344 -394.532788) (xy 368.533915 -394.578315) (xy 368.570822 -394.629393) (xy 368.600368 -394.685055)
			(xy 368.621991 -394.744246) (xy 368.629184 -394.774928) (xy 368.632994 -394.792708) (xy 368.66068 -394.81506)
			(xy 370.121688 -394.81506) (xy 370.149628 -394.791438) (xy 370.15293 -394.77315) (xy 370.156915 -394.752579)
			(xy 370.169393 -394.712578) (xy 370.177822 -394.693394) (xy 370.18214 -394.683996) (xy 370.182902 -394.66393)
			(xy 370.150644 -394.57757) (xy 370.136928 -394.562838) (xy 370.12753 -394.55852) (xy 370.103162 -394.546825)
			(xy 370.058281 -394.516714) (xy 370.018895 -394.479702) (xy 369.986055 -394.436777) (xy 369.960635 -394.389081)
			(xy 369.943312 -394.337885) (xy 369.934548 -394.284554) (xy 369.933982 -394.25753) (xy 369.934463 -394.231539)
			(xy 369.94259 -394.180196) (xy 369.95865 -394.130757) (xy 369.982246 -394.084439) (xy 370.012797 -394.042382)
			(xy 370.049552 -394.005623) (xy 370.091605 -393.975067) (xy 370.13792 -393.951465) (xy 370.187357 -393.9354)
			(xy 370.238699 -393.927266) (xy 370.26469 -393.926822) (xy 370.281123 -393.927053) (xy 370.313821 -393.930366)
			(xy 370.329968 -393.933426) (xy 370.342922 -393.935966) (xy 370.368068 -393.928092) (xy 370.445284 -393.846304)
			(xy 370.451888 -393.820904) (xy 370.448586 -393.808204) (xy 370.441612 -393.779756) (xy 370.434099 -393.721666)
			(xy 370.4336 -393.69238) (xy 370.434108 -393.661492) (xy 370.442419 -393.600277) (xy 370.458886 -393.540735)
			(xy 370.48321 -393.483949) (xy 370.498624 -393.457176) (xy 370.504466 -393.44727) (xy 370.506752 -393.424918)
			(xy 370.473478 -393.329668) (xy 370.45773 -393.313666) (xy 370.447062 -393.309602) (xy 370.423692 -393.300402)
			(xy 370.379817 -393.275963) (xy 370.340141 -393.245172) (xy 370.305574 -393.208738) (xy 370.276913 -393.167497)
			(xy 370.254815 -393.122397) (xy 370.239788 -393.074476) (xy 370.232178 -393.024833) (xy 370.23167 -392.999722)
			(xy 370.23218 -392.973735) (xy 370.24031 -392.9224) (xy 370.256371 -392.87297) (xy 370.279967 -392.82666)
			(xy 370.310517 -392.784612) (xy 370.347268 -392.747861) (xy 370.389316 -392.717311) (xy 370.435626 -392.693715)
			(xy 370.485056 -392.677654) (xy 370.536391 -392.669524) (xy 370.588365 -392.669524) (xy 370.6397 -392.677654)
			(xy 370.68913 -392.693715) (xy 370.73544 -392.717311) (xy 370.777488 -392.747861) (xy 370.814239 -392.784612)
			(xy 370.844789 -392.82666) (xy 370.868385 -392.87297) (xy 370.884446 -392.9224) (xy 370.892576 -392.973735)
			(xy 370.893086 -392.999722) (xy 370.892561 -393.026824) (xy 370.883748 -393.080307) (xy 370.87556 -393.106148)
			(xy 370.87175 -393.11707) (xy 370.87429 -393.139422) (xy 370.926868 -393.225274) (xy 370.945918 -393.23772)
			(xy 370.957094 -393.239498) (xy 370.986402 -393.244238) (xy 371.043555 -393.260307) (xy 371.098151 -393.283631)
			(xy 371.149273 -393.313817) (xy 371.196064 -393.350359) (xy 371.237738 -393.392643) (xy 371.273596 -393.439961)
			(xy 371.303035 -393.491517) (xy 371.325563 -393.546446) (xy 371.340799 -393.603827) (xy 371.34849 -393.662696)
			(xy 371.349016 -393.69238) (xy 371.348495 -393.723443) (xy 371.34008 -393.784997) (xy 371.332252 -393.815062)
			(xy 371.329458 -393.825222) (xy 371.331998 -393.845034) (xy 371.379496 -393.92733) (xy 371.395498 -393.939522)
			(xy 371.405658 -393.942062) (xy 371.434766 -393.950066) (xy 371.490734 -393.972694) (xy 371.543242 -394.002485)
			(xy 371.591376 -394.038921) (xy 371.634302 -394.081369) (xy 371.671274 -394.129093) (xy 371.70165 -394.181263)
			(xy 371.724902 -394.236975) (xy 371.740628 -394.29526) (xy 371.748554 -394.355107) (xy 371.749066 -394.385292)
			(xy 371.748942 -394.399427) (xy 371.747161 -394.427641) (xy 371.74551 -394.44168) (xy 371.744774 -394.450285)
			(xy 371.748413 -394.467158) (xy 371.752622 -394.4747) (xy 371.76837 -394.5001) (xy 371.773074 -394.507165)
			(xy 371.786185 -394.517928) (xy 371.794024 -394.521182) (xy 371.816849 -394.530173) (xy 371.859775 -394.55392)
			(xy 371.898722 -394.583747) (xy 371.932837 -394.618999) (xy 371.961372 -394.658902) (xy 371.983701 -394.702583)
			(xy 371.999333 -394.749081) (xy 372.004082 -394.77315) (xy 372.007384 -394.791438) (xy 372.035324 -394.81506)
			(xy 372.152164 -394.81506) (xy 372.162187 -394.814646) (xy 372.180709 -394.806981) (xy 372.194883 -394.792806)
			(xy 372.202547 -394.774283) (xy 372.202964 -394.76426) (xy 372.202964 -394.753338) (xy 372.194328 -394.73378)
			(xy 372.185946 -394.726414) (xy 372.162407 -394.704605) (xy 372.121054 -394.655537) (xy 372.086956 -394.601176)
			(xy 372.060781 -394.542587) (xy 372.043041 -394.480918) (xy 372.034084 -394.417377) (xy 372.033546 -394.385292)
			(xy 372.034062 -394.354228) (xy 372.042467 -394.292672) (xy 372.05031 -394.26261) (xy 372.053104 -394.25245)
			(xy 372.050564 -394.232638) (xy 372.003066 -394.150342) (xy 371.987064 -394.13815) (xy 371.976904 -394.13561)
			(xy 371.947796 -394.127604) (xy 371.891826 -394.104975) (xy 371.839318 -394.075183) (xy 371.791182 -394.038748)
			(xy 371.748254 -393.9963) (xy 371.711278 -393.948578) (xy 371.680897 -393.896408) (xy 371.657639 -393.840698)
			(xy 371.641906 -393.782413) (xy 371.633972 -393.722565) (xy 371.633496 -393.69238) (xy 371.634004 -393.661492)
			(xy 371.642315 -393.600277) (xy 371.658781 -393.540735) (xy 371.683106 -393.483949) (xy 371.69852 -393.457176)
			(xy 371.704362 -393.44727) (xy 371.706648 -393.424918) (xy 371.673374 -393.329668) (xy 371.657626 -393.313666)
			(xy 371.646958 -393.309602) (xy 371.623588 -393.300402) (xy 371.579714 -393.275962) (xy 371.540038 -393.245171)
			(xy 371.505472 -393.208737) (xy 371.476811 -393.167496) (xy 371.454713 -393.122397) (xy 371.439687 -393.074475)
			(xy 371.432077 -393.024833) (xy 371.431566 -392.999722) (xy 371.432076 -392.973735) (xy 371.440206 -392.9224)
			(xy 371.456267 -392.87297) (xy 371.479863 -392.82666) (xy 371.510413 -392.784612) (xy 371.547164 -392.747861)
			(xy 371.589212 -392.717311) (xy 371.635522 -392.693715) (xy 371.684952 -392.677654) (xy 371.736287 -392.669524)
			(xy 371.788261 -392.669524) (xy 371.839596 -392.677654) (xy 371.889026 -392.693715) (xy 371.935336 -392.717311)
			(xy 371.977384 -392.747861) (xy 372.014135 -392.784612) (xy 372.044685 -392.82666) (xy 372.068281 -392.87297)
			(xy 372.084342 -392.9224) (xy 372.092472 -392.973735) (xy 372.092982 -392.999722) (xy 372.092457 -393.026824)
			(xy 372.083644 -393.080307) (xy 372.075456 -393.106148) (xy 372.071646 -393.11707) (xy 372.074186 -393.139422)
			(xy 372.126764 -393.225274) (xy 372.145814 -393.23772) (xy 372.15699 -393.239498) (xy 372.186298 -393.244237)
			(xy 372.243451 -393.260307) (xy 372.298048 -393.28363) (xy 372.34917 -393.313816) (xy 372.395962 -393.350358)
			(xy 372.437636 -393.392642) (xy 372.473494 -393.43996) (xy 372.502934 -393.491516) (xy 372.525462 -393.546445)
			(xy 372.540699 -393.603826) (xy 372.54839 -393.662695) (xy 372.548912 -393.69238) (xy 372.548391 -393.723443)
			(xy 372.539976 -393.784997) (xy 372.532148 -393.815062) (xy 372.529354 -393.825222) (xy 372.531894 -393.845034)
			(xy 372.579392 -393.92733) (xy 372.595394 -393.939522) (xy 372.605554 -393.942062) (xy 372.634662 -393.950066)
			(xy 372.690631 -393.972694) (xy 372.743139 -394.002484) (xy 372.791273 -394.03892) (xy 372.8342 -394.081368)
			(xy 372.871172 -394.129092) (xy 372.901548 -394.181262) (xy 372.924801 -394.236974) (xy 372.940527 -394.29526)
			(xy 372.948453 -394.355107) (xy 372.948962 -394.385292) (xy 372.948838 -394.399427) (xy 372.947057 -394.427641)
			(xy 372.945406 -394.44168) (xy 372.94467 -394.450285) (xy 372.948309 -394.467158) (xy 372.952518 -394.4747)
			(xy 372.968266 -394.5001) (xy 372.972971 -394.507164) (xy 372.986079 -394.517931) (xy 372.99392 -394.521182)
			(xy 373.016763 -394.530164) (xy 373.059727 -394.553897) (xy 373.098716 -394.583714) (xy 373.132874 -394.618961)
			(xy 373.161453 -394.658865) (xy 373.183827 -394.702552) (xy 373.199505 -394.749064) (xy 373.204232 -394.77315)
			(xy 373.207534 -394.791438) (xy 373.235474 -394.81506) (xy 373.35206 -394.81506) (xy 373.362084 -394.814647)
			(xy 373.380607 -394.806982) (xy 373.394782 -394.792807) (xy 373.402447 -394.774284) (xy 373.40286 -394.76426)
			(xy 373.40286 -394.753338) (xy 373.394224 -394.73378) (xy 373.385842 -394.726414) (xy 373.362303 -394.704605)
			(xy 373.32095 -394.655536) (xy 373.286853 -394.601176) (xy 373.260678 -394.542587) (xy 373.242938 -394.480918)
			(xy 373.233982 -394.417377) (xy 373.233442 -394.385292) (xy 373.233958 -394.354228) (xy 373.242363 -394.292672)
			(xy 373.250206 -394.26261) (xy 373.253 -394.25245) (xy 373.25046 -394.232638) (xy 373.202962 -394.150342)
			(xy 373.18696 -394.13815) (xy 373.1768 -394.13561) (xy 373.147702 -394.127597) (xy 373.091757 -394.104955)
			(xy 373.039274 -394.075154) (xy 372.991165 -394.038711) (xy 372.948264 -393.99626) (xy 372.911318 -393.948536)
			(xy 372.880966 -393.89637) (xy 372.857736 -393.840665) (xy 372.842032 -393.782391) (xy 372.834126 -393.722557)
			(xy 372.833646 -393.69238) (xy 372.834154 -393.661492) (xy 372.842464 -393.600276) (xy 372.858929 -393.540734)
			(xy 372.883251 -393.483946) (xy 372.89867 -393.457176) (xy 372.904512 -393.44727) (xy 372.906798 -393.424918)
			(xy 372.873524 -393.329668) (xy 372.857776 -393.313666) (xy 372.847108 -393.309602) (xy 372.823736 -393.300404)
			(xy 372.779855 -393.275969) (xy 372.740173 -393.24518) (xy 372.705602 -393.208746) (xy 372.676936 -393.167505)
			(xy 372.654835 -393.122404) (xy 372.639806 -393.07448) (xy 372.632194 -393.024835) (xy 372.631716 -392.999722)
			(xy 372.632226 -392.973735) (xy 372.640356 -392.9224) (xy 372.656417 -392.87297) (xy 372.680013 -392.82666)
			(xy 372.710563 -392.784612) (xy 372.747314 -392.747861) (xy 372.789362 -392.717311) (xy 372.835672 -392.693715)
			(xy 372.885102 -392.677654) (xy 372.936437 -392.669524) (xy 372.988411 -392.669524) (xy 373.039746 -392.677654)
			(xy 373.089176 -392.693715) (xy 373.135486 -392.717311) (xy 373.177534 -392.747861) (xy 373.214285 -392.784612)
			(xy 373.244835 -392.82666) (xy 373.268431 -392.87297) (xy 373.284492 -392.9224) (xy 373.292622 -392.973735)
			(xy 373.293132 -392.999722) (xy 373.292608 -393.026824) (xy 373.283795 -393.080307) (xy 373.275606 -393.106148)
			(xy 373.271796 -393.11707) (xy 373.274336 -393.139422) (xy 373.326914 -393.225274) (xy 373.345964 -393.23772)
			(xy 373.35714 -393.239498) (xy 373.38645 -393.244235) (xy 373.443608 -393.260299) (xy 373.49821 -393.283619)
			(xy 373.549338 -393.313803) (xy 373.596135 -393.350344) (xy 373.637815 -393.392628) (xy 373.673677 -393.439947)
			(xy 373.703121 -393.491505) (xy 373.725651 -393.546437) (xy 373.74089 -393.603821) (xy 373.748582 -393.662694)
			(xy 373.749062 -393.69238) (xy 373.748557 -393.723507) (xy 373.740147 -393.78519) (xy 373.732298 -393.815316)
			(xy 373.729504 -393.825476) (xy 373.732044 -393.845542) (xy 373.779288 -393.92733) (xy 373.79529 -393.939522)
			(xy 373.80545 -393.942062) (xy 373.834558 -393.950066) (xy 373.890528 -393.972693) (xy 373.943036 -394.002483)
			(xy 373.991171 -394.038919) (xy 374.034097 -394.081367) (xy 374.07107 -394.129091) (xy 374.101447 -394.181262)
			(xy 374.1247 -394.236974) (xy 374.140426 -394.295259) (xy 374.148352 -394.355107) (xy 374.148858 -394.385292)
			(xy 374.148734 -394.399427) (xy 374.146953 -394.427641) (xy 374.145302 -394.44168) (xy 374.144566 -394.450285)
			(xy 374.148205 -394.467158) (xy 374.152414 -394.4747) (xy 374.168162 -394.5001) (xy 374.172867 -394.507164)
			(xy 374.185975 -394.517932) (xy 374.193816 -394.521182) (xy 374.216659 -394.530164) (xy 374.259624 -394.553896)
			(xy 374.298613 -394.583713) (xy 374.332772 -394.61896) (xy 374.361351 -394.658865) (xy 374.383725 -394.702552)
			(xy 374.399403 -394.749064) (xy 374.404128 -394.77315) (xy 374.40743 -394.791438) (xy 374.43537 -394.81506)
			(xy 374.55221 -394.81506) (xy 374.562227 -394.814638) (xy 374.580734 -394.806965) (xy 374.594893 -394.792792)
			(xy 374.602548 -394.774277) (xy 374.60301 -394.76426) (xy 374.60301 -394.753338) (xy 374.594374 -394.73378)
			(xy 374.585992 -394.726414) (xy 374.562451 -394.704606) (xy 374.521094 -394.655539) (xy 374.486993 -394.601179)
			(xy 374.460815 -394.54259) (xy 374.443073 -394.48092) (xy 374.434115 -394.417378) (xy 374.433592 -394.385292)
			(xy 374.434108 -394.354228) (xy 374.442514 -394.292672) (xy 374.450356 -394.26261) (xy 374.45315 -394.25245)
			(xy 374.45061 -394.232638) (xy 374.403112 -394.150342) (xy 374.38711 -394.13815) (xy 374.37695 -394.13561)
			(xy 374.347839 -394.127607) (xy 374.291866 -394.104981) (xy 374.239352 -394.075192) (xy 374.191211 -394.038758)
			(xy 374.148278 -393.996311) (xy 374.111299 -393.948588) (xy 374.080915 -393.896417) (xy 374.057653 -393.840704)
			(xy 374.041918 -393.782417) (xy 374.033983 -393.722567) (xy 374.033542 -393.69238) (xy 374.03405 -393.661492)
			(xy 374.04236 -393.600276) (xy 374.058825 -393.540733) (xy 374.083147 -393.483946) (xy 374.098566 -393.457176)
			(xy 374.104408 -393.44727) (xy 374.106694 -393.424918) (xy 374.07342 -393.329668) (xy 374.057672 -393.313666)
			(xy 374.047004 -393.309602) (xy 374.023632 -393.300404) (xy 373.979752 -393.275968) (xy 373.940071 -393.245179)
			(xy 373.9055 -393.208746) (xy 373.876834 -393.167504) (xy 373.854733 -393.122403) (xy 373.839704 -393.074479)
			(xy 373.832093 -393.024834) (xy 373.831612 -392.999722) (xy 373.832122 -392.973735) (xy 373.840252 -392.9224)
			(xy 373.856313 -392.87297) (xy 373.879909 -392.82666) (xy 373.910459 -392.784612) (xy 373.94721 -392.747861)
			(xy 373.989258 -392.717311) (xy 374.035568 -392.693715) (xy 374.084998 -392.677654) (xy 374.136333 -392.669524)
			(xy 374.188307 -392.669524) (xy 374.239642 -392.677654) (xy 374.289072 -392.693715) (xy 374.335382 -392.717311)
			(xy 374.37743 -392.747861) (xy 374.414181 -392.784612) (xy 374.444731 -392.82666) (xy 374.468327 -392.87297)
			(xy 374.484388 -392.9224) (xy 374.492518 -392.973735) (xy 374.493028 -392.999722) (xy 374.492504 -393.026824)
			(xy 374.483691 -393.080307) (xy 374.475502 -393.106148) (xy 374.471692 -393.11707) (xy 374.474232 -393.139422)
			(xy 374.52681 -393.225274) (xy 374.54586 -393.23772) (xy 374.557036 -393.239498) (xy 374.586346 -393.244234)
			(xy 374.643505 -393.260299) (xy 374.698107 -393.283618) (xy 374.749236 -393.313802) (xy 374.796033 -393.350342)
			(xy 374.837713 -393.392627) (xy 374.873576 -393.439946) (xy 374.90302 -393.491504) (xy 374.92555 -393.546436)
			(xy 374.94079 -393.60382) (xy 374.948482 -393.662693) (xy 374.948958 -393.69238) (xy 374.948438 -393.723443)
			(xy 374.940023 -393.784997) (xy 374.932194 -393.815062) (xy 374.9294 -393.825222) (xy 374.93194 -393.845034)
			(xy 374.979438 -393.92733) (xy 374.99544 -393.939522) (xy 375.0056 -393.942062) (xy 375.034706 -393.950069)
			(xy 375.09067 -393.9727) (xy 375.143173 -394.002493) (xy 375.191303 -394.03893) (xy 375.234224 -394.081379)
			(xy 375.271193 -394.129102) (xy 375.301565 -394.181271) (xy 375.324816 -394.236981) (xy 375.34054 -394.295264)
			(xy 375.348464 -394.355108) (xy 375.349008 -394.385292) (xy 375.348884 -394.399427) (xy 375.347103 -394.427641)
			(xy 375.345452 -394.44168) (xy 375.344716 -394.450285) (xy 375.348358 -394.467156) (xy 375.352564 -394.4747)
			(xy 375.368312 -394.5001) (xy 375.373012 -394.50717) (xy 375.386117 -394.517947) (xy 375.393966 -394.521182)
			(xy 375.416794 -394.53017) (xy 375.459726 -394.553913) (xy 375.498679 -394.583737) (xy 375.532801 -394.618987)
			(xy 375.561341 -394.658891) (xy 375.583674 -394.702573) (xy 375.59931 -394.749074) (xy 375.604024 -394.77315)
			(xy 375.607326 -394.791438) (xy 375.635266 -394.81506) (xy 375.683018 -394.81506) (xy 375.693086 -394.814632)
			(xy 375.711682 -394.806909) (xy 375.719086 -394.800074) (xy 375.767854 -394.751306) (xy 375.768616 -394.710666)
			(xy 375.754646 -394.695426) (xy 375.735706 -394.674249) (xy 375.702664 -394.628031) (xy 375.675602 -394.578076)
			(xy 375.654935 -394.525153) (xy 375.640982 -394.470078) (xy 375.633958 -394.413699) (xy 375.633488 -394.385292)
			(xy 375.634004 -394.354228) (xy 375.64241 -394.292672) (xy 375.650252 -394.26261) (xy 375.653046 -394.25245)
			(xy 375.650506 -394.232638) (xy 375.603008 -394.150342) (xy 375.587006 -394.13815) (xy 375.576846 -394.13561)
			(xy 375.547736 -394.127606) (xy 375.491762 -394.10498) (xy 375.439249 -394.075191) (xy 375.391109 -394.038757)
			(xy 375.348176 -393.99631) (xy 375.311197 -393.948587) (xy 375.280813 -393.896416) (xy 375.257552 -393.840704)
			(xy 375.241817 -393.782417) (xy 375.233882 -393.722567) (xy 375.233438 -393.69238) (xy 375.233934 -393.66146)
			(xy 375.24223 -393.600179) (xy 375.258695 -393.540571) (xy 375.28303 -393.483721) (xy 375.298462 -393.456922)
			(xy 375.304558 -393.44727) (xy 375.306844 -393.424918) (xy 375.273316 -393.329668) (xy 375.257568 -393.313666)
			(xy 375.2469 -393.309602) (xy 375.223541 -393.300396) (xy 375.179691 -393.275946) (xy 375.14004 -393.245148)
			(xy 375.105502 -393.208709) (xy 375.07687 -393.167467) (xy 375.054803 -393.122371) (xy 375.039807 -393.074456)
			(xy 375.032229 -393.024825) (xy 375.031762 -392.999722) (xy 375.032272 -392.973735) (xy 375.040402 -392.9224)
			(xy 375.056463 -392.87297) (xy 375.080059 -392.82666) (xy 375.110609 -392.784612) (xy 375.14736 -392.747861)
			(xy 375.189408 -392.717311) (xy 375.235718 -392.693715) (xy 375.285148 -392.677654) (xy 375.336483 -392.669524)
			(xy 375.388457 -392.669524) (xy 375.439792 -392.677654) (xy 375.489222 -392.693715) (xy 375.535532 -392.717311)
			(xy 375.57758 -392.747861) (xy 375.614331 -392.784612) (xy 375.644881 -392.82666) (xy 375.668477 -392.87297)
			(xy 375.684538 -392.9224) (xy 375.692668 -392.973735) (xy 375.693178 -392.999722) (xy 375.692653 -393.026824)
			(xy 375.68384 -393.080307) (xy 375.675652 -393.106148) (xy 375.671842 -393.11707) (xy 375.674382 -393.139422)
			(xy 375.72696 -393.225528) (xy 375.745756 -393.23772) (xy 375.757186 -393.239498) (xy 375.786482 -393.244249)
			(xy 375.84361 -393.260338) (xy 375.89818 -393.283676) (xy 375.949274 -393.313872) (xy 375.996037 -393.35042)
			(xy 376.037684 -393.392705) (xy 376.073515 -393.440019) (xy 376.10293 -393.491568) (xy 376.125434 -393.546486)
			(xy 376.140652 -393.603853) (xy 376.148326 -393.662705) (xy 376.148854 -393.69238) (xy 376.148334 -393.723443)
			(xy 376.139919 -393.784997) (xy 376.13209 -393.815062) (xy 376.129296 -393.825222) (xy 376.131836 -393.845034)
			(xy 376.179334 -393.92733) (xy 376.195336 -393.939522) (xy 376.205496 -393.942062) (xy 376.232657 -393.949533)
			(xy 376.285055 -393.97022) (xy 376.334522 -393.997172) (xy 376.380313 -394.029984) (xy 376.40133 -394.048742)
			(xy 376.41657 -394.062712) (xy 376.45721 -394.06195) (xy 376.518932 -394.000228) (xy 376.522488 -393.963906)
			(xy 376.512074 -393.948666) (xy 376.493543 -393.920131) (xy 376.464214 -393.858741) (xy 376.444295 -393.793686)
			(xy 376.434226 -393.726398) (xy 376.433588 -393.69238) (xy 376.434096 -393.661492) (xy 376.442406 -393.600276)
			(xy 376.458873 -393.540735) (xy 376.483197 -393.483948) (xy 376.498612 -393.457176) (xy 376.504454 -393.44727)
			(xy 376.50674 -393.424918) (xy 376.473466 -393.329668) (xy 376.457718 -393.313666) (xy 376.44705 -393.309602)
			(xy 376.423681 -393.300401) (xy 376.379807 -393.275961) (xy 376.340132 -393.24517) (xy 376.305567 -393.208735)
			(xy 376.276907 -393.167495) (xy 376.25481 -393.122395) (xy 376.239784 -393.074474) (xy 376.232174 -393.024833)
			(xy 376.231658 -392.999722) (xy 376.232168 -392.973735) (xy 376.240298 -392.9224) (xy 376.256359 -392.87297)
			(xy 376.279955 -392.82666) (xy 376.310505 -392.784612) (xy 376.347256 -392.747861) (xy 376.389304 -392.717311)
			(xy 376.435614 -392.693715) (xy 376.485044 -392.677654) (xy 376.536379 -392.669524) (xy 376.588353 -392.669524)
			(xy 376.639688 -392.677654) (xy 376.689118 -392.693715) (xy 376.735428 -392.717311) (xy 376.777476 -392.747861)
			(xy 376.814227 -392.784612) (xy 376.844777 -392.82666) (xy 376.868373 -392.87297) (xy 376.884434 -392.9224)
			(xy 376.892564 -392.973735) (xy 376.893074 -392.999722) (xy 376.89255 -393.026824) (xy 376.883739 -393.080307)
			(xy 376.875548 -393.106148) (xy 376.871738 -393.11707) (xy 376.874278 -393.139422) (xy 376.926856 -393.225274)
			(xy 376.945906 -393.23772) (xy 376.957082 -393.239498) (xy 376.990988 -393.245027) (xy 377.056738 -393.264929)
			(xy 377.118767 -393.294453) (xy 377.147582 -393.313158) (xy 377.157651 -393.319336) (xy 377.181019 -393.322586)
			(xy 377.203364 -393.315016) (xy 377.212098 -393.307062) (xy 377.430538 -393.088622) (xy 377.437904 -393.065508)
			(xy 377.435872 -393.053316) (xy 377.433832 -393.040012) (xy 377.431671 -393.013181) (xy 377.431554 -392.999722)
			(xy 377.432062 -392.973733) (xy 377.440189 -392.922393) (xy 377.456248 -392.872957) (xy 377.479842 -392.826642)
			(xy 377.510391 -392.784588) (xy 377.547142 -392.74783) (xy 377.589191 -392.717274) (xy 377.635502 -392.693671)
			(xy 377.684935 -392.677603) (xy 377.736273 -392.669467) (xy 377.762262 -392.669014) (xy 377.77572 -392.669142)
			(xy 377.80255 -392.671307) (xy 377.815856 -392.673332) (xy 377.828048 -392.675364) (xy 377.851162 -392.667998)
			(xy 378.754894 -391.764266) (xy 378.762289 -391.757411) (xy 378.780888 -391.749664) (xy 378.790962 -391.74928)
			(xy 388.748778 -391.74928) (xy 388.758841 -391.748842) (xy 388.777423 -391.741106) (xy 388.784846 -391.734294)
			(xy 388.815834 -391.703306) (xy 388.824209 -391.694041) (xy 388.831557 -391.670203) (xy 388.829804 -391.65784)
			(xy 388.81177 -391.562844) (xy 388.796276 -391.543286) (xy 388.784592 -391.538206) (xy 388.759649 -391.52677)
			(xy 388.713634 -391.496884) (xy 388.673182 -391.459814) (xy 388.639401 -391.416577) (xy 388.613219 -391.368358)
			(xy 388.595354 -391.31648) (xy 388.586294 -391.262364) (xy 388.58571 -391.23493) (xy 388.586191 -391.20894)
			(xy 388.594319 -391.157599) (xy 388.610378 -391.108161) (xy 388.633975 -391.061845) (xy 388.664527 -391.019791)
			(xy 388.701282 -390.983035) (xy 388.743335 -390.952481) (xy 388.78965 -390.928883) (xy 388.839087 -390.912821)
			(xy 388.890428 -390.904692) (xy 388.916418 -390.904222) (xy 388.943854 -390.904764) (xy 388.997974 -390.913824)
			(xy 389.049855 -390.931695) (xy 389.098075 -390.957884) (xy 389.14131 -390.991673) (xy 389.178374 -391.032136)
			(xy 389.208251 -391.078162) (xy 389.219694 -391.103104) (xy 389.224774 -391.114788) (xy 389.244332 -391.130282)
			(xy 389.339328 -391.148316) (xy 389.351696 -391.150071) (xy 389.375548 -391.142745) (xy 389.384794 -391.134346)
			(xy 389.585454 -390.933686) (xy 389.592851 -390.926839) (xy 389.611451 -390.919111) (xy 389.621522 -390.9187)
			(xy 393.376658 -390.9187) (xy 393.386723 -390.919134) (xy 393.405313 -390.926863) (xy 393.412726 -390.933686)
			(xy 393.42949 -390.95045) (xy 393.436832 -390.957267) (xy 393.455295 -390.965011) (xy 393.465304 -390.965436)
			(xy 393.474448 -390.965436) (xy 393.49299 -390.973056) (xy 393.858242 -391.338308) (xy 393.865058 -391.345651)
			(xy 393.872796 -391.364114) (xy 393.873228 -391.374122) (xy 393.873228 -391.383012) (xy 393.880848 -391.401808)
			(xy 393.88542 -391.40638) (xy 393.89304 -391.424922) (xy 393.89304 -394.176758) (xy 393.892605 -394.186822)
			(xy 393.884869 -394.205406) (xy 393.878054 -394.212826) (xy 392.624818 -395.466062) (xy 392.983718 -395.466062)
			(xy 392.987789 -395.41044) (xy 392.999915 -395.356003) (xy 393.019838 -395.303912) (xy 393.047134 -395.255277)
			(xy 393.08122 -395.211134) (xy 393.121369 -395.172425) (xy 393.166727 -395.139974) (xy 393.216327 -395.114473)
			(xy 393.269111 -395.096466) (xy 393.323954 -395.086336) (xy 393.379688 -395.084299) (xy 393.435125 -395.090399)
			(xy 393.489082 -395.104505) (xy 393.540411 -395.126317) (xy 393.588017 -395.155371) (xy 393.630885 -395.191046)
			(xy 393.668102 -395.232583) (xy 393.698875 -395.279096) (xy 393.722547 -395.329593) (xy 393.738615 -395.383)
			(xy 393.746735 -395.438176) (xy 393.747244 -395.466062) (xy 393.746735 -395.493948) (xy 393.738615 -395.549124)
			(xy 393.722547 -395.602531) (xy 393.698875 -395.653028) (xy 393.668102 -395.699541) (xy 393.630885 -395.741078)
			(xy 393.588017 -395.776753) (xy 393.540411 -395.805807) (xy 393.489082 -395.827619) (xy 393.435125 -395.841725)
			(xy 393.379688 -395.847825) (xy 393.323954 -395.845788) (xy 393.269111 -395.835658) (xy 393.216327 -395.817651)
			(xy 393.166727 -395.79215) (xy 393.121369 -395.759699) (xy 393.08122 -395.72099) (xy 393.047134 -395.676847)
			(xy 393.019838 -395.628212) (xy 392.999915 -395.576121) (xy 392.987789 -395.521684) (xy 392.983718 -395.466062)
			(xy 392.624818 -395.466062) (xy 392.536426 -395.554454) (xy 392.529585 -395.561854) (xy 392.521867 -395.580453)
			(xy 392.52144 -395.590522) (xy 392.52144 -396.1765) (xy 395.05712 -396.1765) (xy 395.061191 -396.120878)
			(xy 395.073317 -396.066441) (xy 395.09324 -396.01435) (xy 395.120536 -395.965715) (xy 395.154622 -395.921572)
			(xy 395.194771 -395.882863) (xy 395.240129 -395.850412) (xy 395.289729 -395.824911) (xy 395.342513 -395.806904)
			(xy 395.397356 -395.796774) (xy 395.45309 -395.794737) (xy 395.508527 -395.800837) (xy 395.562484 -395.814943)
			(xy 395.613813 -395.836755) (xy 395.661419 -395.865809) (xy 395.704287 -395.901484) (xy 395.741504 -395.943021)
			(xy 395.772277 -395.989534) (xy 395.795949 -396.040031) (xy 395.812017 -396.093438) (xy 395.820137 -396.148614)
			(xy 395.820646 -396.1765) (xy 395.820137 -396.204386) (xy 395.812017 -396.259562) (xy 395.795949 -396.312969)
			(xy 395.772277 -396.363466) (xy 395.741504 -396.409979) (xy 395.704287 -396.451516) (xy 395.661419 -396.487191)
			(xy 395.613813 -396.516245) (xy 395.562484 -396.538057) (xy 395.508527 -396.552163) (xy 395.45309 -396.558263)
			(xy 395.397356 -396.556226) (xy 395.342513 -396.546096) (xy 395.289729 -396.528089) (xy 395.240129 -396.502588)
			(xy 395.194771 -396.470137) (xy 395.154622 -396.431428) (xy 395.120536 -396.387285) (xy 395.09324 -396.33865)
			(xy 395.073317 -396.286559) (xy 395.061191 -396.232122) (xy 395.05712 -396.1765) (xy 392.52144 -396.1765)
			(xy 392.52144 -396.356078) (xy 392.521879 -396.366141) (xy 392.529617 -396.384721) (xy 392.536426 -396.392146)
			(xy 392.933174 -396.788894) (xy 392.940576 -396.795729) (xy 392.959175 -396.803438) (xy 392.969242 -396.80388)
			(xy 395.068298 -396.80388) (xy 395.077696 -396.80007) (xy 395.105359 -396.789348) (xy 395.163076 -396.775634)
			(xy 395.222222 -396.771025) (xy 395.281368 -396.775634) (xy 395.339085 -396.789348) (xy 395.366748 -396.80007)
			(xy 395.376146 -396.80388) (xy 395.703298 -396.80388) (xy 395.712696 -396.80007) (xy 395.740359 -396.789348)
			(xy 395.798076 -396.775634) (xy 395.857222 -396.771025) (xy 395.916368 -396.775634) (xy 395.974085 -396.789348)
			(xy 396.001748 -396.80007) (xy 396.011146 -396.80388) (xy 396.792958 -396.80388) (xy 396.803023 -396.803446)
			(xy 396.82161 -396.795714) (xy 396.829026 -396.788894) (xy 396.857982 -396.759938) (xy 396.864701 -396.752506)
			(xy 396.872342 -396.734006) (xy 396.872341 -396.71399) (xy 396.864699 -396.695491) (xy 396.857982 -396.688056)
			(xy 396.852394 -396.682214) (xy 396.83817 -396.675102) (xy 396.830296 -396.673832) (xy 396.798125 -396.668184)
			(xy 396.735474 -396.649706) (xy 396.675705 -396.623359) (xy 396.619802 -396.589574) (xy 396.568685 -396.548909)
			(xy 396.523196 -396.502033) (xy 396.484085 -396.449718) (xy 396.451994 -396.392826) (xy 396.427453 -396.332293)
			(xy 396.410866 -396.269115) (xy 396.402505 -396.204333) (xy 396.402052 -396.171674) (xy 396.402633 -396.136719)
			(xy 396.412205 -396.067468) (xy 396.431165 -396.000179) (xy 396.459157 -395.936118) (xy 396.495653 -395.876492)
			(xy 396.517368 -395.849094) (xy 396.522706 -395.842116) (xy 396.528697 -395.825614) (xy 396.529052 -395.816836)
			(xy 396.529052 -395.662912) (xy 396.528633 -395.654147) (xy 396.522652 -395.637661) (xy 396.517368 -395.630654)
			(xy 396.495656 -395.603255) (xy 396.459157 -395.543631) (xy 396.431168 -395.47957) (xy 396.412216 -395.41228)
			(xy 396.402659 -395.343028) (xy 396.402052 -395.308074) (xy 396.402517 -395.277343) (xy 396.409928 -395.21633)
			(xy 396.424639 -395.156654) (xy 396.446435 -395.099187) (xy 396.474998 -395.044766) (xy 396.509912 -394.994184)
			(xy 396.550669 -394.948178) (xy 396.596673 -394.907421) (xy 396.647254 -394.872505) (xy 396.701674 -394.84394)
			(xy 396.759141 -394.822143) (xy 396.818816 -394.807431) (xy 396.879829 -394.800018) (xy 396.91056 -394.799566)
			(xy 396.931485 -394.799779) (xy 396.973194 -394.80321) (xy 396.993872 -394.806424) (xy 397.003016 -394.807948)
			(xy 397.020796 -394.804646) (xy 397.092932 -394.760958) (xy 397.104108 -394.746988) (xy 397.107156 -394.738352)
			(xy 397.115923 -394.713332) (xy 397.139406 -394.665801) (xy 397.169248 -394.621983) (xy 397.204875 -394.582723)
			(xy 397.245598 -394.548779) (xy 397.290633 -394.520806) (xy 397.33911 -394.499343) (xy 397.390093 -394.484806)
			(xy 397.442598 -394.477474) (xy 397.469106 -394.476986) (xy 397.496357 -394.477472) (xy 397.550305 -394.485229)
			(xy 397.602599 -394.500585) (xy 397.652176 -394.523226) (xy 397.698026 -394.552693) (xy 397.739216 -394.588384)
			(xy 397.774907 -394.629574) (xy 397.804374 -394.675424) (xy 397.827015 -394.725001) (xy 397.842371 -394.777295)
			(xy 397.850128 -394.831243) (xy 397.850614 -394.858494) (xy 397.850118 -394.886462) (xy 397.84194 -394.941798)
			(xy 397.825774 -394.995349) (xy 397.801966 -395.045966) (xy 397.771026 -395.092567) (xy 397.733616 -395.134153)
			(xy 397.690537 -395.169834) (xy 397.642712 -395.198847) (xy 397.591164 -395.220568) (xy 397.536999 -395.234534)
			(xy 397.509238 -395.23797) (xy 397.500094 -395.238732) (xy 397.483838 -395.24686) (xy 397.425926 -395.308074)
			(xy 397.418814 -395.324584) (xy 397.418306 -395.333728) (xy 397.416175 -395.366041) (xy 397.404744 -395.429783)
			(xy 397.385317 -395.491558) (xy 397.358207 -395.550369) (xy 397.323853 -395.605264) (xy 397.303752 -395.630654)
			(xy 397.298419 -395.637634) (xy 397.292441 -395.654136) (xy 397.292068 -395.662912) (xy 397.292068 -395.816836)
			(xy 397.292478 -395.825604) (xy 397.298449 -395.842099) (xy 397.303752 -395.849094) (xy 397.323434 -395.873875)
			(xy 397.357159 -395.927424) (xy 397.38398 -395.984744) (xy 397.394176 -396.014702) (xy 397.398494 -396.027656)
			(xy 397.417544 -396.045182) (xy 397.514826 -396.068804) (xy 397.523394 -396.070519) (xy 397.540759 -396.068683)
			(xy 397.556483 -396.061089) (xy 397.562832 -396.055088) (xy 398.775174 -394.842746) (xy 398.782015 -394.835346)
			(xy 398.789733 -394.816747) (xy 398.79016 -394.806678) (xy 398.79016 -388.288022) (xy 398.789721 -388.277959)
			(xy 398.781983 -388.259379) (xy 398.775174 -388.251954) (xy 397.410686 -386.887466) (xy 397.40329 -386.880615)
			(xy 397.384691 -386.872875) (xy 397.374618 -386.87248) (xy 394.794486 -386.87248) (xy 394.785529 -386.872826)
			(xy 394.768703 -386.878971) (xy 394.755002 -386.890511) (xy 394.75029 -386.898134) (xy 394.699744 -386.986272)
			(xy 394.699744 -387.013704) (xy 394.706856 -387.025388) (xy 394.719285 -387.047434) (xy 394.738859 -387.094106)
			(xy 394.752096 -387.142954) (xy 394.758764 -387.193123) (xy 394.75918 -387.218428) (xy 394.758164 -387.24713)
			(xy 394.757148 -387.260338) (xy 394.76807 -387.28396) (xy 394.858748 -387.350762) (xy 394.884656 -387.354064)
			(xy 394.897102 -387.348984) (xy 394.919612 -387.340448) (xy 394.966238 -387.328458) (xy 395.014001 -387.322421)
			(xy 395.038072 -387.32206) (xy 395.065328 -387.322521) (xy 395.119287 -387.330275) (xy 395.171593 -387.34563)
			(xy 395.221181 -387.368273) (xy 395.267041 -387.397743) (xy 395.308241 -387.43344) (xy 395.34394 -387.474636)
			(xy 395.373413 -387.520495) (xy 395.39606 -387.570081) (xy 395.411419 -387.622386) (xy 395.419177 -387.676344)
			(xy 395.419177 -387.730856) (xy 395.411419 -387.784814) (xy 395.39606 -387.837119) (xy 395.373413 -387.886705)
			(xy 395.34394 -387.932564) (xy 395.308241 -387.97376) (xy 395.267041 -388.009457) (xy 395.221181 -388.038927)
			(xy 395.171593 -388.06157) (xy 395.119287 -388.076925) (xy 395.065328 -388.084679) (xy 395.038072 -388.085076)
			(xy 395.008634 -388.08453) (xy 394.950459 -388.07547) (xy 394.922248 -388.067042) (xy 394.913633 -388.064751)
			(xy 394.895838 -388.065545) (xy 394.88745 -388.068566) (xy 394.859256 -388.080504) (xy 394.851027 -388.084333)
			(xy 394.837765 -388.096704) (xy 394.833348 -388.104634) (xy 394.820166 -388.13032) (xy 394.788849 -388.178823)
			(xy 394.770864 -388.201408) (xy 394.765523 -388.208385) (xy 394.759529 -388.224888) (xy 394.75918 -388.233666)
			(xy 394.75918 -388.38759) (xy 394.759599 -388.396355) (xy 394.765584 -388.412838) (xy 394.770864 -388.419848)
			(xy 394.788861 -388.442424) (xy 394.820174 -388.490932) (xy 394.833348 -388.516622) (xy 394.837751 -388.524561)
			(xy 394.851024 -388.536927) (xy 394.859256 -388.540752) (xy 394.88745 -388.55269) (xy 394.895816 -388.555804)
			(xy 394.913639 -388.556577) (xy 394.922248 -388.554214) (xy 394.950462 -388.545801) (xy 395.008636 -388.536748)
			(xy 395.038072 -388.53618) (xy 395.065327 -388.536641) (xy 395.119283 -388.544395) (xy 395.171586 -388.559749)
			(xy 395.221171 -388.582391) (xy 395.267029 -388.611859) (xy 395.308226 -388.647554) (xy 395.343924 -388.688748)
			(xy 395.373396 -388.734604) (xy 395.396041 -388.784188) (xy 395.411399 -388.83649) (xy 395.419157 -388.890445)
			(xy 395.419157 -388.944955) (xy 395.411399 -388.99891) (xy 395.396041 -389.051212) (xy 395.373396 -389.100796)
			(xy 395.343924 -389.146652) (xy 395.308226 -389.187846) (xy 395.267029 -389.223541) (xy 395.221171 -389.253009)
			(xy 395.171586 -389.275651) (xy 395.119283 -389.291005) (xy 395.065327 -389.298759) (xy 395.038072 -389.299196)
			(xy 395.014 -389.298845) (xy 394.966236 -389.292812) (xy 394.919613 -389.280808) (xy 394.897102 -389.272272)
			(xy 394.884656 -389.267192) (xy 394.858748 -389.270494) (xy 394.76807 -389.337296) (xy 394.757148 -389.360918)
			(xy 394.758164 -389.374126) (xy 394.75918 -389.402828) (xy 394.758694 -389.430079) (xy 394.750938 -389.484027)
			(xy 394.735583 -389.536322) (xy 394.712941 -389.585899) (xy 394.683475 -389.631749) (xy 394.647784 -389.67294)
			(xy 394.606593 -389.708631) (xy 394.560743 -389.738097) (xy 394.557778 -389.739451) (xy 396.016978 -389.739451)
			(xy 396.016978 -389.684949) (xy 396.024734 -389.631003) (xy 396.040088 -389.578709) (xy 396.062729 -389.529132)
			(xy 396.092194 -389.483283) (xy 396.127884 -389.442093) (xy 396.169073 -389.406401) (xy 396.214922 -389.376935)
			(xy 396.264498 -389.354293) (xy 396.316791 -389.338937) (xy 396.370737 -389.331179) (xy 396.397988 -389.330692)
			(xy 396.421925 -389.331042) (xy 396.469426 -389.337016) (xy 396.515803 -389.348897) (xy 396.538196 -389.357362)
			(xy 396.550134 -389.362188) (xy 396.575026 -389.35914) (xy 396.665958 -389.295894) (xy 396.677134 -389.273796)
			(xy 396.67688 -389.260588) (xy 396.67688 -389.25246) (xy 396.677366 -389.225209) (xy 396.685122 -389.171261)
			(xy 396.700477 -389.118966) (xy 396.723119 -389.069389) (xy 396.752585 -389.023539) (xy 396.788276 -388.982348)
			(xy 396.829467 -388.946657) (xy 396.875317 -388.917191) (xy 396.924894 -388.894549) (xy 396.977189 -388.879194)
			(xy 397.031137 -388.871438) (xy 397.085639 -388.871438) (xy 397.139587 -388.879194) (xy 397.191882 -388.894549)
			(xy 397.241459 -388.917191) (xy 397.287309 -388.946657) (xy 397.3285 -388.982348) (xy 397.364191 -389.023539)
			(xy 397.393657 -389.069389) (xy 397.416299 -389.118966) (xy 397.431654 -389.171261) (xy 397.43941 -389.225209)
			(xy 397.439896 -389.25246) (xy 397.439896 -389.260588) (xy 397.439642 -389.273796) (xy 397.450818 -389.295894)
			(xy 397.54175 -389.35914) (xy 397.566642 -389.362188) (xy 397.57858 -389.357362) (xy 397.600987 -389.348938)
			(xy 397.64736 -389.337062) (xy 397.694853 -389.33107) (xy 397.718788 -389.330692) (xy 397.746041 -389.331155)
			(xy 397.799994 -389.33891) (xy 397.852293 -389.354265) (xy 397.901875 -389.376907) (xy 397.947729 -389.406375)
			(xy 397.988923 -389.442068) (xy 398.024618 -389.483261) (xy 398.054087 -389.529115) (xy 398.076731 -389.578696)
			(xy 398.092087 -389.630995) (xy 398.099845 -389.684947) (xy 398.099845 -389.739453) (xy 398.092087 -389.793405)
			(xy 398.076731 -389.845704) (xy 398.054087 -389.895285) (xy 398.024618 -389.941139) (xy 397.988923 -389.982332)
			(xy 397.947729 -390.018025) (xy 397.901875 -390.047493) (xy 397.852293 -390.070135) (xy 397.799994 -390.08549)
			(xy 397.746041 -390.093245) (xy 397.718788 -390.093708) (xy 397.689352 -390.093137) (xy 397.631178 -390.084086)
			(xy 397.602964 -390.075674) (xy 397.594353 -390.07332) (xy 397.576532 -390.074088) (xy 397.568166 -390.077198)
			(xy 397.539972 -390.089136) (xy 397.531745 -390.09297) (xy 397.518469 -390.10533) (xy 397.514064 -390.113266)
			(xy 397.500896 -390.13896) (xy 397.469579 -390.187466) (xy 397.45158 -390.21004) (xy 397.446267 -390.217028)
			(xy 397.440302 -390.233528) (xy 397.439896 -390.242298) (xy 397.439896 -390.396222) (xy 397.440247 -390.405)
			(xy 397.44624 -390.421503) (xy 397.45158 -390.42848) (xy 397.469564 -390.451065) (xy 397.500882 -390.499568)
			(xy 397.514064 -390.525254) (xy 397.518451 -390.533203) (xy 397.531735 -390.545562) (xy 397.539972 -390.549384)
			(xy 397.568166 -390.561322) (xy 397.576552 -390.564349) (xy 397.594348 -390.565137) (xy 397.602964 -390.562846)
			(xy 397.631174 -390.554414) (xy 397.68935 -390.545356) (xy 397.718788 -390.544812) (xy 397.746043 -390.545234)
			(xy 397.799998 -390.55299) (xy 397.8523 -390.568346) (xy 397.901884 -390.590989) (xy 397.947741 -390.620458)
			(xy 397.988938 -390.656154) (xy 398.024635 -390.697349) (xy 398.054105 -390.743205) (xy 398.07675 -390.792789)
			(xy 398.092107 -390.84509) (xy 398.099865 -390.899045) (xy 398.099865 -390.953555) (xy 398.092107 -391.00751)
			(xy 398.07675 -391.059811) (xy 398.054105 -391.109395) (xy 398.024635 -391.155251) (xy 397.988938 -391.196446)
			(xy 397.947741 -391.232142) (xy 397.901884 -391.261611) (xy 397.8523 -391.284254) (xy 397.799998 -391.29961)
			(xy 397.746043 -391.307366) (xy 397.718788 -391.307828) (xy 397.694717 -391.307463) (xy 397.646954 -391.301427)
			(xy 397.600328 -391.28944) (xy 397.577818 -391.280904) (xy 397.565372 -391.275824) (xy 397.539464 -391.279126)
			(xy 397.448786 -391.345928) (xy 397.437864 -391.36955) (xy 397.43888 -391.382758) (xy 397.439896 -391.41146)
			(xy 397.43941 -391.438711) (xy 397.431654 -391.492659) (xy 397.416299 -391.544954) (xy 397.393657 -391.594531)
			(xy 397.364191 -391.640381) (xy 397.3285 -391.681572) (xy 397.287309 -391.717263) (xy 397.241459 -391.746729)
			(xy 397.191882 -391.769371) (xy 397.139587 -391.784726) (xy 397.085639 -391.792482) (xy 397.031137 -391.792482)
			(xy 396.977189 -391.784726) (xy 396.924894 -391.769371) (xy 396.875317 -391.746729) (xy 396.829467 -391.717263)
			(xy 396.788276 -391.681572) (xy 396.752585 -391.640381) (xy 396.723119 -391.594531) (xy 396.700477 -391.544954)
			(xy 396.685122 -391.492659) (xy 396.677366 -391.438711) (xy 396.67688 -391.41146) (xy 396.677896 -391.382758)
			(xy 396.678912 -391.36955) (xy 396.66799 -391.345928) (xy 396.577312 -391.279126) (xy 396.551404 -391.275824)
			(xy 396.538958 -391.280904) (xy 396.51645 -391.289449) (xy 396.469826 -391.30145) (xy 396.42206 -391.307479)
			(xy 396.397988 -391.307828) (xy 396.370739 -391.307301) (xy 396.316795 -391.299543) (xy 396.264505 -391.284188)
			(xy 396.214932 -391.261548) (xy 396.169085 -391.232082) (xy 396.127899 -391.196393) (xy 396.09221 -391.155205)
			(xy 396.062747 -391.109358) (xy 396.040108 -391.059784) (xy 396.024754 -391.007493) (xy 396.016998 -390.953549)
			(xy 396.016998 -390.899051) (xy 396.024754 -390.845107) (xy 396.040108 -390.792816) (xy 396.062747 -390.743242)
			(xy 396.09221 -390.697395) (xy 396.127899 -390.656207) (xy 396.169085 -390.620518) (xy 396.214932 -390.591052)
			(xy 396.264505 -390.568412) (xy 396.316795 -390.553057) (xy 396.370739 -390.545299) (xy 396.397988 -390.544812)
			(xy 396.427425 -390.545365) (xy 396.485599 -390.554428) (xy 396.513812 -390.562846) (xy 396.522415 -390.565237)
			(xy 396.540244 -390.564444) (xy 396.54861 -390.561322) (xy 396.576804 -390.549384) (xy 396.585042 -390.545569)
			(xy 396.598313 -390.533197) (xy 396.602712 -390.525254) (xy 396.615873 -390.499556) (xy 396.647195 -390.451053)
			(xy 396.665196 -390.42848) (xy 396.67051 -390.421493) (xy 396.676473 -390.404992) (xy 396.67688 -390.396222)
			(xy 396.67688 -390.242298) (xy 396.676503 -390.233523) (xy 396.670527 -390.217021) (xy 396.665196 -390.21004)
			(xy 396.647212 -390.187455) (xy 396.615894 -390.138952) (xy 396.602712 -390.113266) (xy 396.598328 -390.105315)
			(xy 396.585042 -390.092956) (xy 396.576804 -390.089136) (xy 396.54861 -390.077198) (xy 396.540228 -390.074158)
			(xy 396.522428 -390.073378) (xy 396.513812 -390.075674) (xy 396.485603 -390.084111) (xy 396.427427 -390.093166)
			(xy 396.397988 -390.093708) (xy 396.370737 -390.093221) (xy 396.316791 -390.085463) (xy 396.264498 -390.070107)
			(xy 396.214922 -390.047465) (xy 396.169073 -390.017999) (xy 396.127884 -389.982307) (xy 396.092194 -389.941117)
			(xy 396.062729 -389.895268) (xy 396.040088 -389.845691) (xy 396.024734 -389.793397) (xy 396.016978 -389.739451)
			(xy 394.557778 -389.739451) (xy 394.511166 -389.760739) (xy 394.458871 -389.776094) (xy 394.404923 -389.78385)
			(xy 394.350421 -389.78385) (xy 394.296473 -389.776094) (xy 394.244178 -389.760739) (xy 394.194601 -389.738097)
			(xy 394.148751 -389.708631) (xy 394.10756 -389.67294) (xy 394.071869 -389.631749) (xy 394.042403 -389.585899)
			(xy 394.019761 -389.536322) (xy 394.004406 -389.484027) (xy 393.99665 -389.430079) (xy 393.996164 -389.402828)
			(xy 393.99718 -389.374126) (xy 393.998196 -389.360918) (xy 393.987274 -389.337296) (xy 393.896596 -389.270494)
			(xy 393.870688 -389.267192) (xy 393.858242 -389.272272) (xy 393.835732 -389.28081) (xy 393.789107 -389.292803)
			(xy 393.741344 -389.298845) (xy 393.717272 -389.299196) (xy 393.690023 -389.298708) (xy 393.63608 -389.290948)
			(xy 393.58379 -389.275591) (xy 393.534218 -389.252949) (xy 393.488373 -389.223483) (xy 393.447187 -389.187793)
			(xy 393.4115 -389.146605) (xy 393.382037 -389.100757) (xy 393.359399 -389.051183) (xy 393.344046 -388.998893)
			(xy 393.33629 -388.944949) (xy 393.33629 -388.890451) (xy 393.344046 -388.836507) (xy 393.359399 -388.784217)
			(xy 393.382037 -388.734643) (xy 393.4115 -388.688795) (xy 393.447187 -388.647607) (xy 393.488373 -388.611917)
			(xy 393.534218 -388.582451) (xy 393.58379 -388.559809) (xy 393.63608 -388.544452) (xy 393.690023 -388.536692)
			(xy 393.717272 -388.53618) (xy 393.746711 -388.536721) (xy 393.804888 -388.545773) (xy 393.833096 -388.554214)
			(xy 393.841712 -388.556513) (xy 393.859514 -388.555738) (xy 393.867894 -388.55269) (xy 393.896088 -388.540752)
			(xy 393.904327 -388.536933) (xy 393.917614 -388.524575) (xy 393.921996 -388.516622) (xy 393.935178 -388.490936)
			(xy 393.966496 -388.442433) (xy 393.98448 -388.419848) (xy 393.98981 -388.412867) (xy 393.995785 -388.396365)
			(xy 393.996164 -388.38759) (xy 393.996164 -388.233666) (xy 393.995754 -388.224897) (xy 393.989787 -388.2084)
			(xy 393.98448 -388.201408) (xy 393.96648 -388.178835) (xy 393.935159 -388.13033) (xy 393.921996 -388.104634)
			(xy 393.917595 -388.096694) (xy 393.904321 -388.084328) (xy 393.896088 -388.080504) (xy 393.867894 -388.068566)
			(xy 393.859528 -388.065447) (xy 393.841701 -388.06466) (xy 393.833096 -388.067042) (xy 393.804883 -388.075459)
			(xy 393.746709 -388.08452) (xy 393.717272 -388.085076) (xy 393.690024 -388.084588) (xy 393.636084 -388.076829)
			(xy 393.583797 -388.061473) (xy 393.534228 -388.038832) (xy 393.488385 -388.009367) (xy 393.447201 -387.973679)
			(xy 393.411516 -387.932493) (xy 393.382055 -387.886648) (xy 393.359418 -387.837076) (xy 393.344065 -387.784788)
			(xy 393.33631 -387.730848) (xy 393.33631 -387.676352) (xy 393.344065 -387.622412) (xy 393.359418 -387.570124)
			(xy 393.382055 -387.520552) (xy 393.411516 -387.474707) (xy 393.447201 -387.433521) (xy 393.488385 -387.397833)
			(xy 393.534228 -387.368368) (xy 393.583797 -387.345727) (xy 393.636084 -387.330371) (xy 393.690024 -387.322612)
			(xy 393.717272 -387.32206) (xy 393.741345 -387.322408) (xy 393.789111 -387.328435) (xy 393.835736 -387.340434)
			(xy 393.858242 -387.348984) (xy 393.870688 -387.354064) (xy 393.896596 -387.350762) (xy 393.987274 -387.28396)
			(xy 393.998196 -387.260338) (xy 393.99718 -387.24713) (xy 393.996164 -387.218428) (xy 393.996556 -387.193121)
			(xy 394.003212 -387.142946) (xy 394.01645 -387.094094) (xy 394.036038 -387.047424) (xy 394.048488 -387.025388)
			(xy 394.0556 -387.013704) (xy 394.0556 -386.986272) (xy 394.005054 -386.898134) (xy 394.000329 -386.890513)
			(xy 393.986653 -386.878934) (xy 393.969819 -386.872792) (xy 393.960858 -386.87248) (xy 393.018518 -386.87248)
			(xy 393.005843 -386.873217) (xy 392.983565 -386.885327) (xy 392.9761 -386.895594) (xy 392.959454 -386.92031)
			(xy 392.921267 -386.966057) (xy 392.877996 -387.007028) (xy 392.830234 -387.042663) (xy 392.778635 -387.072473)
			(xy 392.723906 -387.096049) (xy 392.666797 -387.113068) (xy 392.637518 -387.118606) (xy 392.628266 -387.120595)
			(xy 392.612094 -387.130395) (xy 392.606022 -387.137656) (xy 392.586972 -387.16204) (xy 392.581575 -387.169796)
			(xy 392.576235 -387.187903) (xy 392.576558 -387.197346) (xy 392.578336 -387.238748) (xy 392.577834 -387.270709)
			(xy 392.569823 -387.334127) (xy 392.553926 -387.396041) (xy 392.530394 -387.455474) (xy 392.4996 -387.511489)
			(xy 392.462027 -387.563204) (xy 392.41827 -387.609801) (xy 392.369017 -387.650546) (xy 392.315046 -387.684797)
			(xy 392.257207 -387.712014) (xy 392.196414 -387.731767) (xy 392.133624 -387.743745) (xy 392.069828 -387.747759)
			(xy 392.006032 -387.743745) (xy 391.943242 -387.731767) (xy 391.882449 -387.712014) (xy 391.82461 -387.684797)
			(xy 391.770639 -387.650546) (xy 391.721386 -387.609801) (xy 391.677629 -387.563204) (xy 391.640056 -387.511489)
			(xy 391.609262 -387.455474) (xy 391.58573 -387.396041) (xy 391.569833 -387.334127) (xy 391.561822 -387.270709)
			(xy 391.56132 -387.238748) (xy 391.561693 -387.210203) (xy 391.568062 -387.153469) (xy 391.580748 -387.097806)
			(xy 391.599592 -387.043916) (xy 391.611612 -387.018022) (xy 391.617454 -387.006084) (xy 391.61593 -386.98043)
			(xy 391.563098 -386.896356) (xy 391.558288 -386.889252) (xy 391.544919 -386.878519) (xy 391.528745 -386.872834)
			(xy 391.520172 -386.87248) (xy 380.313692 -386.87248) (xy 380.303684 -386.872969) (xy 380.285191 -386.880629)
			(xy 380.271036 -386.894781) (xy 380.263371 -386.913272) (xy 380.262892 -386.92328) (xy 380.262892 -386.975858)
			(xy 380.262443 -387.00838) (xy 380.255141 -387.073012) (xy 380.240647 -387.136421) (xy 380.219142 -387.197807)
			(xy 380.190897 -387.256398) (xy 380.156269 -387.311458) (xy 380.115692 -387.362293) (xy 380.092966 -387.38556)
			(xy 379.785626 -387.6929) (xy 379.762327 -387.715584) (xy 379.711489 -387.756135) (xy 379.65643 -387.790737)
			(xy 379.597841 -387.818954) (xy 379.53646 -387.840432) (xy 379.47306 -387.854899) (xy 379.408439 -387.862174)
			(xy 379.375924 -387.862572) (xy 370.877084 -387.862572) (xy 370.844572 -387.862116) (xy 370.779956 -387.854836)
			(xy 370.716562 -387.840369) (xy 370.655185 -387.818898) (xy 370.596597 -387.790692) (xy 370.541534 -387.756105)
			(xy 370.490688 -387.715573) (xy 370.467382 -387.6929) (xy 370.160042 -387.38556) (xy 370.137363 -387.36225)
			(xy 370.096796 -387.311414) (xy 370.062172 -387.256359) (xy 370.033925 -387.197775) (xy 370.01241 -387.136399)
			(xy 369.997898 -387.073001) (xy 369.99057 -387.008377) (xy 369.990116 -386.975858) (xy 369.990116 -386.92328)
			(xy 369.989625 -386.913274) (xy 369.981962 -386.894786) (xy 369.967811 -386.880635) (xy 369.949322 -386.872974)
			(xy 369.939316 -386.87248) (xy 361.545124 -386.87248) (xy 361.536701 -386.872829) (xy 361.520758 -386.878271)
			(xy 361.513882 -386.883148) (xy 361.45868 -386.925551) (xy 361.343628 -387.003929) (xy 361.223728 -387.07467)
			(xy 361.099488 -387.137474) (xy 360.971431 -387.192077) (xy 360.840098 -387.238248) (xy 360.773218 -387.257544)
			(xy 360.76001 -387.261354) (xy 360.74096 -387.280912) (xy 360.712766 -387.392926) (xy 360.720132 -387.419088)
			(xy 360.730038 -387.42874) (xy 360.748202 -387.446769) (xy 360.780028 -387.48685) (xy 360.806204 -387.530829)
			(xy 360.826261 -387.577914) (xy 360.839837 -387.62726) (xy 360.846689 -387.677978) (xy 360.847132 -387.703568)
			(xy 360.846671 -387.730823) (xy 360.838918 -387.784779) (xy 360.823565 -387.837082) (xy 360.800925 -387.886668)
			(xy 360.771458 -387.932527) (xy 360.735765 -387.973725) (xy 360.694571 -388.009424) (xy 360.648717 -388.038898)
			(xy 360.599134 -388.061546) (xy 360.546834 -388.076906) (xy 360.492879 -388.084667) (xy 360.465624 -388.085076)
			(xy 360.436185 -388.084534) (xy 360.378008 -388.075481) (xy 360.3498 -388.067042) (xy 360.341184 -388.064742)
			(xy 360.323383 -388.065519) (xy 360.315002 -388.068566) (xy 360.286808 -388.080504) (xy 360.278574 -388.084327)
			(xy 360.265299 -388.096692) (xy 360.2609 -388.104634) (xy 360.24772 -388.130321) (xy 360.216405 -388.178826)
			(xy 360.198416 -388.201408) (xy 360.19308 -388.208387) (xy 360.187091 -388.224889) (xy 360.186732 -388.233666)
			(xy 360.186732 -388.38759) (xy 360.187151 -388.396356) (xy 360.193131 -388.412841) (xy 360.198416 -388.419848)
			(xy 360.216414 -388.442423) (xy 360.24773 -388.490929) (xy 360.2609 -388.516622) (xy 360.265306 -388.524556)
			(xy 360.278585 -388.53691) (xy 360.286808 -388.540752) (xy 360.315002 -388.55269) (xy 360.323368 -388.555812)
			(xy 360.341196 -388.556601) (xy 360.3498 -388.554214) (xy 360.378014 -388.545797) (xy 360.436187 -388.536737)
			(xy 360.465624 -388.53618) (xy 360.492875 -388.536667) (xy 360.546822 -388.544427) (xy 360.599115 -388.559785)
			(xy 360.648691 -388.582428) (xy 360.69454 -388.611896) (xy 360.735729 -388.647588) (xy 360.771419 -388.688779)
			(xy 360.800884 -388.73463) (xy 360.823524 -388.784207) (xy 360.838878 -388.836502) (xy 360.846634 -388.890449)
			(xy 360.846634 -388.944951) (xy 360.838878 -388.998898) (xy 360.823524 -389.051193) (xy 360.800884 -389.10077)
			(xy 360.771419 -389.146621) (xy 360.735729 -389.187812) (xy 360.69454 -389.223504) (xy 360.648691 -389.252972)
			(xy 360.599115 -389.275615) (xy 360.546822 -389.290973) (xy 360.492875 -389.298733) (xy 360.465624 -389.299196)
			(xy 360.441551 -389.298848) (xy 360.393785 -389.292821) (xy 360.347159 -389.280824) (xy 360.324654 -389.272272)
			(xy 360.312208 -389.267192) (xy 360.2863 -389.270494) (xy 360.195622 -389.337296) (xy 360.1847 -389.360918)
			(xy 360.185716 -389.374126) (xy 360.186732 -389.402828) (xy 360.186246 -389.430079) (xy 360.17849 -389.484027)
			(xy 360.163135 -389.536322) (xy 360.140493 -389.585899) (xy 360.111027 -389.631749) (xy 360.075336 -389.67294)
			(xy 360.034145 -389.708631) (xy 359.988295 -389.738097) (xy 359.985322 -389.739455) (xy 363.489155 -389.739455)
			(xy 363.489155 -389.684945) (xy 363.496913 -389.630991) (xy 363.512272 -389.57869) (xy 363.534917 -389.529107)
			(xy 363.564389 -389.483252) (xy 363.600087 -389.442058) (xy 363.641284 -389.406365) (xy 363.687142 -389.376898)
			(xy 363.736727 -389.354258) (xy 363.78903 -389.338905) (xy 363.842985 -389.331153) (xy 363.87024 -389.330692)
			(xy 363.894178 -389.331026) (xy 363.941679 -389.337007) (xy 363.988055 -389.348894) (xy 364.010448 -389.357362)
			(xy 364.022386 -389.362188) (xy 364.047278 -389.35914) (xy 364.13821 -389.295894) (xy 364.149386 -389.273796)
			(xy 364.149132 -389.260588) (xy 364.149132 -389.25246) (xy 364.149618 -389.225209) (xy 364.157374 -389.171261)
			(xy 364.172729 -389.118966) (xy 364.195371 -389.069389) (xy 364.224837 -389.023539) (xy 364.260528 -388.982348)
			(xy 364.301719 -388.946657) (xy 364.347569 -388.917191) (xy 364.397146 -388.894549) (xy 364.449441 -388.879194)
			(xy 364.503389 -388.871438) (xy 364.557891 -388.871438) (xy 364.611839 -388.879194) (xy 364.664134 -388.894549)
			(xy 364.713711 -388.917191) (xy 364.759561 -388.946657) (xy 364.800752 -388.982348) (xy 364.836443 -389.023539)
			(xy 364.865909 -389.069389) (xy 364.888551 -389.118966) (xy 364.903906 -389.171261) (xy 364.911662 -389.225209)
			(xy 364.912148 -389.25246) (xy 364.912148 -389.260588) (xy 364.911894 -389.273796) (xy 364.92307 -389.295894)
			(xy 365.014002 -389.35914) (xy 365.038894 -389.362188) (xy 365.050832 -389.357362) (xy 365.073233 -389.348923)
			(xy 365.119609 -389.337053) (xy 365.167105 -389.331067) (xy 365.19104 -389.330692) (xy 365.218289 -389.331181)
			(xy 365.272233 -389.338942) (xy 365.324523 -389.3543) (xy 365.374095 -389.376944) (xy 365.41994 -389.406411)
			(xy 365.461126 -389.442103) (xy 365.461869 -389.44296) (xy 366.444782 -389.44296) (xy 366.448853 -389.387338)
			(xy 366.460979 -389.332901) (xy 366.480902 -389.28081) (xy 366.508198 -389.232175) (xy 366.542284 -389.188032)
			(xy 366.582433 -389.149323) (xy 366.627791 -389.116872) (xy 366.677391 -389.091371) (xy 366.730175 -389.073364)
			(xy 366.785018 -389.063234) (xy 366.840752 -389.061197) (xy 366.896189 -389.067297) (xy 366.950146 -389.081403)
			(xy 367.001475 -389.103215) (xy 367.049081 -389.132269) (xy 367.091949 -389.167944) (xy 367.129166 -389.209481)
			(xy 367.159939 -389.255994) (xy 367.183611 -389.306491) (xy 367.199679 -389.359898) (xy 367.207799 -389.415074)
			(xy 367.208308 -389.44296) (xy 367.207799 -389.470846) (xy 367.199679 -389.526022) (xy 367.183611 -389.579429)
			(xy 367.159939 -389.629926) (xy 367.129166 -389.676439) (xy 367.091949 -389.717976) (xy 367.049081 -389.753651)
			(xy 367.001475 -389.782705) (xy 366.950146 -389.804517) (xy 366.896189 -389.818623) (xy 366.840752 -389.824723)
			(xy 366.785018 -389.822686) (xy 366.730175 -389.812556) (xy 366.677391 -389.794549) (xy 366.627791 -389.769048)
			(xy 366.582433 -389.736597) (xy 366.542284 -389.697888) (xy 366.508198 -389.653745) (xy 366.480902 -389.60511)
			(xy 366.460979 -389.553019) (xy 366.448853 -389.498582) (xy 366.444782 -389.44296) (xy 365.461869 -389.44296)
			(xy 365.496813 -389.483292) (xy 365.526276 -389.52914) (xy 365.548914 -389.578715) (xy 365.564267 -389.631006)
			(xy 365.572022 -389.684951) (xy 365.572022 -389.739449) (xy 365.564267 -389.793394) (xy 365.548914 -389.845685)
			(xy 365.526276 -389.89526) (xy 365.496813 -389.941108) (xy 365.461126 -389.982297) (xy 365.41994 -390.017989)
			(xy 365.374095 -390.047456) (xy 365.324523 -390.0701) (xy 365.272233 -390.085458) (xy 365.218289 -390.093219)
			(xy 365.19104 -390.093708) (xy 365.161603 -390.093148) (xy 365.10343 -390.08409) (xy 365.075216 -390.075674)
			(xy 365.06661 -390.073296) (xy 365.048784 -390.07408) (xy 365.040418 -390.077198) (xy 365.012224 -390.089136)
			(xy 365.004006 -390.092987) (xy 364.990724 -390.105334) (xy 364.986316 -390.113266) (xy 364.973143 -390.138957)
			(xy 364.941829 -390.187465) (xy 364.923832 -390.21004) (xy 364.918513 -390.217024) (xy 364.912553 -390.233527)
			(xy 364.912148 -390.242298) (xy 364.912148 -390.396222) (xy 364.912509 -390.404999) (xy 364.918496 -390.421501)
			(xy 364.923832 -390.42848) (xy 364.94182 -390.451062) (xy 364.973136 -390.499567) (xy 364.986316 -390.525254)
			(xy 364.990685 -390.533215) (xy 365.003982 -390.545568) (xy 365.012224 -390.549384) (xy 365.040418 -390.561322)
			(xy 365.048796 -390.564375) (xy 365.0666 -390.565146) (xy 365.075216 -390.562846) (xy 365.103429 -390.554425)
			(xy 365.161602 -390.54536) (xy 365.19104 -390.544812) (xy 365.218247 -390.545236) (xy 365.272109 -390.552972)
			(xy 365.324325 -390.568282) (xy 365.373836 -390.590855) (xy 365.419638 -390.620234) (xy 365.460802 -390.655821)
			(xy 365.496493 -390.696895) (xy 365.525985 -390.742624) (xy 365.548682 -390.792079) (xy 365.564123 -390.844256)
			(xy 365.571994 -390.898098) (xy 365.572548 -390.925304) (xy 365.572548 -390.936226) (xy 365.58093 -390.955276)
			(xy 365.651542 -391.0203) (xy 365.671354 -391.027158) (xy 365.682022 -391.026396) (xy 365.7219 -391.024872)
			(xy 365.753441 -391.025368) (xy 365.816039 -391.033171) (xy 365.877192 -391.048657) (xy 365.935959 -391.071588)
			(xy 365.991438 -391.101612) (xy 366.042778 -391.138268) (xy 366.089189 -391.180993) (xy 366.129959 -391.229131)
			(xy 366.164461 -391.281942) (xy 366.180761 -391.315286) (xy 368.129087 -391.315286) (xy 368.129087 -391.263314)
			(xy 368.137217 -391.211981) (xy 368.153276 -391.162552) (xy 368.176869 -391.116244) (xy 368.207416 -391.074195)
			(xy 368.244163 -391.037443) (xy 368.286208 -391.006891) (xy 368.332513 -390.983292) (xy 368.38194 -390.967227)
			(xy 368.433272 -390.959091) (xy 368.459258 -390.958578) (xy 368.482492 -390.958965) (xy 368.528503 -390.965465)
			(xy 368.573151 -390.978344) (xy 368.615556 -390.997348) (xy 368.654881 -391.022102) (xy 368.672872 -391.03681)
			(xy 368.679984 -391.042906) (xy 368.696494 -391.049002) (xy 368.780822 -391.049002) (xy 368.797332 -391.042906)
			(xy 368.804444 -391.03681) (xy 368.822443 -391.022115) (xy 368.86177 -390.997366) (xy 368.904173 -390.978364)
			(xy 368.948817 -390.965482) (xy 368.994825 -390.958974) (xy 369.018058 -390.958578) (xy 369.046653 -390.959172)
			(xy 369.102987 -390.969026) (xy 369.156791 -390.988414) (xy 369.206462 -391.016759) (xy 369.228878 -391.034524)
			(xy 369.235736 -391.040112) (xy 369.2525 -391.046208) (xy 369.334796 -391.046208) (xy 369.35156 -391.040366)
			(xy 369.358418 -391.034778) (xy 369.380783 -391.017142) (xy 369.430299 -390.989007) (xy 369.483899 -390.969757)
			(xy 369.540001 -390.95996) (xy 369.568476 -390.95934) (xy 369.59447 -390.959725) (xy 369.645819 -390.967855)
			(xy 369.695264 -390.983917) (xy 369.741587 -391.007517) (xy 369.783648 -391.038073) (xy 369.820411 -391.074834)
			(xy 369.85097 -391.116892) (xy 369.874573 -391.163214) (xy 369.890639 -391.212657) (xy 369.898284 -391.260917)
			(xy 370.586256 -391.260917) (xy 370.586256 -391.208943) (xy 370.594386 -391.157608) (xy 370.610447 -391.108178)
			(xy 370.634043 -391.061868) (xy 370.664593 -391.01982) (xy 370.701344 -390.983069) (xy 370.743392 -390.952519)
			(xy 370.789702 -390.928923) (xy 370.839132 -390.912862) (xy 370.890467 -390.904732) (xy 370.942441 -390.904732)
			(xy 370.993776 -390.912862) (xy 371.043206 -390.928923) (xy 371.089516 -390.952519) (xy 371.131564 -390.983069)
			(xy 371.168315 -391.01982) (xy 371.198865 -391.061868) (xy 371.222461 -391.108178) (xy 371.238522 -391.157608)
			(xy 371.246652 -391.208943) (xy 371.247162 -391.23493) (xy 371.246652 -391.260917) (xy 371.786406 -391.260917)
			(xy 371.786406 -391.208943) (xy 371.794536 -391.157608) (xy 371.810597 -391.108178) (xy 371.834193 -391.061868)
			(xy 371.864743 -391.01982) (xy 371.901494 -390.983069) (xy 371.943542 -390.952519) (xy 371.989852 -390.928923)
			(xy 372.039282 -390.912862) (xy 372.090617 -390.904732) (xy 372.142591 -390.904732) (xy 372.193926 -390.912862)
			(xy 372.243356 -390.928923) (xy 372.289666 -390.952519) (xy 372.331714 -390.983069) (xy 372.368465 -391.01982)
			(xy 372.399015 -391.061868) (xy 372.422611 -391.108178) (xy 372.438672 -391.157608) (xy 372.446802 -391.208943)
			(xy 372.447312 -391.23493) (xy 372.446802 -391.260917) (xy 372.986302 -391.260917) (xy 372.986302 -391.208943)
			(xy 372.994432 -391.157608) (xy 373.010493 -391.108178) (xy 373.034089 -391.061868) (xy 373.064639 -391.01982)
			(xy 373.10139 -390.983069) (xy 373.143438 -390.952519) (xy 373.189748 -390.928923) (xy 373.239178 -390.912862)
			(xy 373.290513 -390.904732) (xy 373.342487 -390.904732) (xy 373.393822 -390.912862) (xy 373.443252 -390.928923)
			(xy 373.489562 -390.952519) (xy 373.53161 -390.983069) (xy 373.568361 -391.01982) (xy 373.598911 -391.061868)
			(xy 373.622507 -391.108178) (xy 373.638568 -391.157608) (xy 373.646698 -391.208943) (xy 373.647208 -391.23493)
			(xy 373.646698 -391.260917) (xy 374.186198 -391.260917) (xy 374.186198 -391.208943) (xy 374.194328 -391.157608)
			(xy 374.210389 -391.108178) (xy 374.233985 -391.061868) (xy 374.264535 -391.01982) (xy 374.301286 -390.983069)
			(xy 374.343334 -390.952519) (xy 374.389644 -390.928923) (xy 374.439074 -390.912862) (xy 374.490409 -390.904732)
			(xy 374.542383 -390.904732) (xy 374.593718 -390.912862) (xy 374.643148 -390.928923) (xy 374.689458 -390.952519)
			(xy 374.731506 -390.983069) (xy 374.768257 -391.01982) (xy 374.798807 -391.061868) (xy 374.822403 -391.108178)
			(xy 374.838464 -391.157608) (xy 374.846594 -391.208943) (xy 374.847104 -391.23493) (xy 374.846594 -391.260917)
			(xy 375.386348 -391.260917) (xy 375.386348 -391.208943) (xy 375.394478 -391.157608) (xy 375.410539 -391.108178)
			(xy 375.434135 -391.061868) (xy 375.464685 -391.01982) (xy 375.501436 -390.983069) (xy 375.543484 -390.952519)
			(xy 375.589794 -390.928923) (xy 375.639224 -390.912862) (xy 375.690559 -390.904732) (xy 375.742533 -390.904732)
			(xy 375.793868 -390.912862) (xy 375.843298 -390.928923) (xy 375.889608 -390.952519) (xy 375.931656 -390.983069)
			(xy 375.968407 -391.01982) (xy 375.998957 -391.061868) (xy 376.022553 -391.108178) (xy 376.038614 -391.157608)
			(xy 376.046744 -391.208943) (xy 376.047254 -391.23493) (xy 376.046744 -391.260917) (xy 376.586244 -391.260917)
			(xy 376.586244 -391.208943) (xy 376.594374 -391.157608) (xy 376.610435 -391.108178) (xy 376.634031 -391.061868)
			(xy 376.664581 -391.01982) (xy 376.701332 -390.983069) (xy 376.74338 -390.952519) (xy 376.78969 -390.928923)
			(xy 376.83912 -390.912862) (xy 376.890455 -390.904732) (xy 376.942429 -390.904732) (xy 376.993764 -390.912862)
			(xy 377.043194 -390.928923) (xy 377.089504 -390.952519) (xy 377.131552 -390.983069) (xy 377.168303 -391.01982)
			(xy 377.198853 -391.061868) (xy 377.222449 -391.108178) (xy 377.23851 -391.157608) (xy 377.24664 -391.208943)
			(xy 377.24715 -391.23493) (xy 377.24664 -391.260917) (xy 377.786394 -391.260917) (xy 377.786394 -391.208943)
			(xy 377.794524 -391.157608) (xy 377.810585 -391.108178) (xy 377.834181 -391.061868) (xy 377.864731 -391.01982)
			(xy 377.901482 -390.983069) (xy 377.94353 -390.952519) (xy 377.98984 -390.928923) (xy 378.03927 -390.912862)
			(xy 378.090605 -390.904732) (xy 378.142579 -390.904732) (xy 378.193914 -390.912862) (xy 378.243344 -390.928923)
			(xy 378.289654 -390.952519) (xy 378.331702 -390.983069) (xy 378.368453 -391.01982) (xy 378.399003 -391.061868)
			(xy 378.422599 -391.108178) (xy 378.43866 -391.157608) (xy 378.44679 -391.208943) (xy 378.4473 -391.23493)
			(xy 378.44679 -391.260917) (xy 378.98629 -391.260917) (xy 378.98629 -391.208943) (xy 378.99442 -391.157608)
			(xy 379.010481 -391.108178) (xy 379.034077 -391.061868) (xy 379.064627 -391.01982) (xy 379.101378 -390.983069)
			(xy 379.143426 -390.952519) (xy 379.189736 -390.928923) (xy 379.239166 -390.912862) (xy 379.290501 -390.904732)
			(xy 379.342475 -390.904732) (xy 379.39381 -390.912862) (xy 379.44324 -390.928923) (xy 379.48955 -390.952519)
			(xy 379.531598 -390.983069) (xy 379.568349 -391.01982) (xy 379.598899 -391.061868) (xy 379.622495 -391.108178)
			(xy 379.638556 -391.157608) (xy 379.646686 -391.208943) (xy 379.647196 -391.23493) (xy 379.646686 -391.260917)
			(xy 380.186186 -391.260917) (xy 380.186186 -391.208943) (xy 380.194316 -391.157608) (xy 380.210377 -391.108178)
			(xy 380.233973 -391.061868) (xy 380.264523 -391.01982) (xy 380.301274 -390.983069) (xy 380.343322 -390.952519)
			(xy 380.389632 -390.928923) (xy 380.439062 -390.912862) (xy 380.490397 -390.904732) (xy 380.542371 -390.904732)
			(xy 380.593706 -390.912862) (xy 380.643136 -390.928923) (xy 380.689446 -390.952519) (xy 380.731494 -390.983069)
			(xy 380.768245 -391.01982) (xy 380.798795 -391.061868) (xy 380.822391 -391.108178) (xy 380.838452 -391.157608)
			(xy 380.846582 -391.208943) (xy 380.847092 -391.23493) (xy 380.846582 -391.260917) (xy 381.386336 -391.260917)
			(xy 381.386336 -391.208943) (xy 381.394466 -391.157608) (xy 381.410527 -391.108178) (xy 381.434123 -391.061868)
			(xy 381.464673 -391.01982) (xy 381.501424 -390.983069) (xy 381.543472 -390.952519) (xy 381.589782 -390.928923)
			(xy 381.639212 -390.912862) (xy 381.690547 -390.904732) (xy 381.742521 -390.904732) (xy 381.793856 -390.912862)
			(xy 381.843286 -390.928923) (xy 381.889596 -390.952519) (xy 381.931644 -390.983069) (xy 381.968395 -391.01982)
			(xy 381.998945 -391.061868) (xy 382.022541 -391.108178) (xy 382.038602 -391.157608) (xy 382.046732 -391.208943)
			(xy 382.047242 -391.23493) (xy 382.046732 -391.260917) (xy 382.586232 -391.260917) (xy 382.586232 -391.208943)
			(xy 382.594362 -391.157608) (xy 382.610423 -391.108178) (xy 382.634019 -391.061868) (xy 382.664569 -391.01982)
			(xy 382.70132 -390.983069) (xy 382.743368 -390.952519) (xy 382.789678 -390.928923) (xy 382.839108 -390.912862)
			(xy 382.890443 -390.904732) (xy 382.942417 -390.904732) (xy 382.993752 -390.912862) (xy 383.043182 -390.928923)
			(xy 383.089492 -390.952519) (xy 383.13154 -390.983069) (xy 383.168291 -391.01982) (xy 383.198841 -391.061868)
			(xy 383.222437 -391.108178) (xy 383.238498 -391.157608) (xy 383.246628 -391.208943) (xy 383.247138 -391.23493)
			(xy 383.246628 -391.260917) (xy 383.786382 -391.260917) (xy 383.786382 -391.208943) (xy 383.794512 -391.157608)
			(xy 383.810573 -391.108178) (xy 383.834169 -391.061868) (xy 383.864719 -391.01982) (xy 383.90147 -390.983069)
			(xy 383.943518 -390.952519) (xy 383.989828 -390.928923) (xy 384.039258 -390.912862) (xy 384.090593 -390.904732)
			(xy 384.142567 -390.904732) (xy 384.193902 -390.912862) (xy 384.243332 -390.928923) (xy 384.289642 -390.952519)
			(xy 384.33169 -390.983069) (xy 384.368441 -391.01982) (xy 384.398991 -391.061868) (xy 384.422587 -391.108178)
			(xy 384.438648 -391.157608) (xy 384.446778 -391.208943) (xy 384.447288 -391.23493) (xy 384.446778 -391.260917)
			(xy 384.986278 -391.260917) (xy 384.986278 -391.208943) (xy 384.994408 -391.157608) (xy 385.010469 -391.108178)
			(xy 385.034065 -391.061868) (xy 385.064615 -391.01982) (xy 385.101366 -390.983069) (xy 385.143414 -390.952519)
			(xy 385.189724 -390.928923) (xy 385.239154 -390.912862) (xy 385.290489 -390.904732) (xy 385.342463 -390.904732)
			(xy 385.393798 -390.912862) (xy 385.443228 -390.928923) (xy 385.489538 -390.952519) (xy 385.531586 -390.983069)
			(xy 385.568337 -391.01982) (xy 385.598887 -391.061868) (xy 385.622483 -391.108178) (xy 385.638544 -391.157608)
			(xy 385.646674 -391.208943) (xy 385.647184 -391.23493) (xy 385.646674 -391.260917) (xy 386.186174 -391.260917)
			(xy 386.186174 -391.208943) (xy 386.194304 -391.157608) (xy 386.210365 -391.108178) (xy 386.233961 -391.061868)
			(xy 386.264511 -391.01982) (xy 386.301262 -390.983069) (xy 386.34331 -390.952519) (xy 386.38962 -390.928923)
			(xy 386.43905 -390.912862) (xy 386.490385 -390.904732) (xy 386.542359 -390.904732) (xy 386.593694 -390.912862)
			(xy 386.643124 -390.928923) (xy 386.689434 -390.952519) (xy 386.731482 -390.983069) (xy 386.768233 -391.01982)
			(xy 386.798783 -391.061868) (xy 386.822379 -391.108178) (xy 386.83844 -391.157608) (xy 386.84657 -391.208943)
			(xy 386.84708 -391.23493) (xy 386.84657 -391.260917) (xy 387.386324 -391.260917) (xy 387.386324 -391.208943)
			(xy 387.394454 -391.157608) (xy 387.410515 -391.108178) (xy 387.434111 -391.061868) (xy 387.464661 -391.01982)
			(xy 387.501412 -390.983069) (xy 387.54346 -390.952519) (xy 387.58977 -390.928923) (xy 387.6392 -390.912862)
			(xy 387.690535 -390.904732) (xy 387.742509 -390.904732) (xy 387.793844 -390.912862) (xy 387.843274 -390.928923)
			(xy 387.889584 -390.952519) (xy 387.931632 -390.983069) (xy 387.968383 -391.01982) (xy 387.998933 -391.061868)
			(xy 388.022529 -391.108178) (xy 388.03859 -391.157608) (xy 388.04672 -391.208943) (xy 388.04723 -391.23493)
			(xy 388.04672 -391.260917) (xy 388.03859 -391.312252) (xy 388.022529 -391.361682) (xy 387.998933 -391.407992)
			(xy 387.968383 -391.45004) (xy 387.931632 -391.486791) (xy 387.889584 -391.517341) (xy 387.843274 -391.540937)
			(xy 387.793844 -391.556998) (xy 387.742509 -391.565128) (xy 387.690535 -391.565128) (xy 387.6392 -391.556998)
			(xy 387.58977 -391.540937) (xy 387.54346 -391.517341) (xy 387.501412 -391.486791) (xy 387.464661 -391.45004)
			(xy 387.434111 -391.407992) (xy 387.410515 -391.361682) (xy 387.394454 -391.312252) (xy 387.386324 -391.260917)
			(xy 386.84657 -391.260917) (xy 386.83844 -391.312252) (xy 386.822379 -391.361682) (xy 386.798783 -391.407992)
			(xy 386.768233 -391.45004) (xy 386.731482 -391.486791) (xy 386.689434 -391.517341) (xy 386.643124 -391.540937)
			(xy 386.593694 -391.556998) (xy 386.542359 -391.565128) (xy 386.490385 -391.565128) (xy 386.43905 -391.556998)
			(xy 386.38962 -391.540937) (xy 386.34331 -391.517341) (xy 386.301262 -391.486791) (xy 386.264511 -391.45004)
			(xy 386.233961 -391.407992) (xy 386.210365 -391.361682) (xy 386.194304 -391.312252) (xy 386.186174 -391.260917)
			(xy 385.646674 -391.260917) (xy 385.638544 -391.312252) (xy 385.622483 -391.361682) (xy 385.598887 -391.407992)
			(xy 385.568337 -391.45004) (xy 385.531586 -391.486791) (xy 385.489538 -391.517341) (xy 385.443228 -391.540937)
			(xy 385.393798 -391.556998) (xy 385.342463 -391.565128) (xy 385.290489 -391.565128) (xy 385.239154 -391.556998)
			(xy 385.189724 -391.540937) (xy 385.143414 -391.517341) (xy 385.101366 -391.486791) (xy 385.064615 -391.45004)
			(xy 385.034065 -391.407992) (xy 385.010469 -391.361682) (xy 384.994408 -391.312252) (xy 384.986278 -391.260917)
			(xy 384.446778 -391.260917) (xy 384.438648 -391.312252) (xy 384.422587 -391.361682) (xy 384.398991 -391.407992)
			(xy 384.368441 -391.45004) (xy 384.33169 -391.486791) (xy 384.289642 -391.517341) (xy 384.243332 -391.540937)
			(xy 384.193902 -391.556998) (xy 384.142567 -391.565128) (xy 384.090593 -391.565128) (xy 384.039258 -391.556998)
			(xy 383.989828 -391.540937) (xy 383.943518 -391.517341) (xy 383.90147 -391.486791) (xy 383.864719 -391.45004)
			(xy 383.834169 -391.407992) (xy 383.810573 -391.361682) (xy 383.794512 -391.312252) (xy 383.786382 -391.260917)
			(xy 383.246628 -391.260917) (xy 383.238498 -391.312252) (xy 383.222437 -391.361682) (xy 383.198841 -391.407992)
			(xy 383.168291 -391.45004) (xy 383.13154 -391.486791) (xy 383.089492 -391.517341) (xy 383.043182 -391.540937)
			(xy 382.993752 -391.556998) (xy 382.942417 -391.565128) (xy 382.890443 -391.565128) (xy 382.839108 -391.556998)
			(xy 382.789678 -391.540937) (xy 382.743368 -391.517341) (xy 382.70132 -391.486791) (xy 382.664569 -391.45004)
			(xy 382.634019 -391.407992) (xy 382.610423 -391.361682) (xy 382.594362 -391.312252) (xy 382.586232 -391.260917)
			(xy 382.046732 -391.260917) (xy 382.038602 -391.312252) (xy 382.022541 -391.361682) (xy 381.998945 -391.407992)
			(xy 381.968395 -391.45004) (xy 381.931644 -391.486791) (xy 381.889596 -391.517341) (xy 381.843286 -391.540937)
			(xy 381.793856 -391.556998) (xy 381.742521 -391.565128) (xy 381.690547 -391.565128) (xy 381.639212 -391.556998)
			(xy 381.589782 -391.540937) (xy 381.543472 -391.517341) (xy 381.501424 -391.486791) (xy 381.464673 -391.45004)
			(xy 381.434123 -391.407992) (xy 381.410527 -391.361682) (xy 381.394466 -391.312252) (xy 381.386336 -391.260917)
			(xy 380.846582 -391.260917) (xy 380.838452 -391.312252) (xy 380.822391 -391.361682) (xy 380.798795 -391.407992)
			(xy 380.768245 -391.45004) (xy 380.731494 -391.486791) (xy 380.689446 -391.517341) (xy 380.643136 -391.540937)
			(xy 380.593706 -391.556998) (xy 380.542371 -391.565128) (xy 380.490397 -391.565128) (xy 380.439062 -391.556998)
			(xy 380.389632 -391.540937) (xy 380.343322 -391.517341) (xy 380.301274 -391.486791) (xy 380.264523 -391.45004)
			(xy 380.233973 -391.407992) (xy 380.210377 -391.361682) (xy 380.194316 -391.312252) (xy 380.186186 -391.260917)
			(xy 379.646686 -391.260917) (xy 379.638556 -391.312252) (xy 379.622495 -391.361682) (xy 379.598899 -391.407992)
			(xy 379.568349 -391.45004) (xy 379.531598 -391.486791) (xy 379.48955 -391.517341) (xy 379.44324 -391.540937)
			(xy 379.39381 -391.556998) (xy 379.342475 -391.565128) (xy 379.290501 -391.565128) (xy 379.239166 -391.556998)
			(xy 379.189736 -391.540937) (xy 379.143426 -391.517341) (xy 379.101378 -391.486791) (xy 379.064627 -391.45004)
			(xy 379.034077 -391.407992) (xy 379.010481 -391.361682) (xy 378.99442 -391.312252) (xy 378.98629 -391.260917)
			(xy 378.44679 -391.260917) (xy 378.43866 -391.312252) (xy 378.422599 -391.361682) (xy 378.399003 -391.407992)
			(xy 378.368453 -391.45004) (xy 378.331702 -391.486791) (xy 378.289654 -391.517341) (xy 378.243344 -391.540937)
			(xy 378.193914 -391.556998) (xy 378.142579 -391.565128) (xy 378.090605 -391.565128) (xy 378.03927 -391.556998)
			(xy 377.98984 -391.540937) (xy 377.94353 -391.517341) (xy 377.901482 -391.486791) (xy 377.864731 -391.45004)
			(xy 377.834181 -391.407992) (xy 377.810585 -391.361682) (xy 377.794524 -391.312252) (xy 377.786394 -391.260917)
			(xy 377.24664 -391.260917) (xy 377.23851 -391.312252) (xy 377.222449 -391.361682) (xy 377.198853 -391.407992)
			(xy 377.168303 -391.45004) (xy 377.131552 -391.486791) (xy 377.089504 -391.517341) (xy 377.043194 -391.540937)
			(xy 376.993764 -391.556998) (xy 376.942429 -391.565128) (xy 376.890455 -391.565128) (xy 376.83912 -391.556998)
			(xy 376.78969 -391.540937) (xy 376.74338 -391.517341) (xy 376.701332 -391.486791) (xy 376.664581 -391.45004)
			(xy 376.634031 -391.407992) (xy 376.610435 -391.361682) (xy 376.594374 -391.312252) (xy 376.586244 -391.260917)
			(xy 376.046744 -391.260917) (xy 376.038614 -391.312252) (xy 376.022553 -391.361682) (xy 375.998957 -391.407992)
			(xy 375.968407 -391.45004) (xy 375.931656 -391.486791) (xy 375.889608 -391.517341) (xy 375.843298 -391.540937)
			(xy 375.793868 -391.556998) (xy 375.742533 -391.565128) (xy 375.690559 -391.565128) (xy 375.639224 -391.556998)
			(xy 375.589794 -391.540937) (xy 375.543484 -391.517341) (xy 375.501436 -391.486791) (xy 375.464685 -391.45004)
			(xy 375.434135 -391.407992) (xy 375.410539 -391.361682) (xy 375.394478 -391.312252) (xy 375.386348 -391.260917)
			(xy 374.846594 -391.260917) (xy 374.838464 -391.312252) (xy 374.822403 -391.361682) (xy 374.798807 -391.407992)
			(xy 374.768257 -391.45004) (xy 374.731506 -391.486791) (xy 374.689458 -391.517341) (xy 374.643148 -391.540937)
			(xy 374.593718 -391.556998) (xy 374.542383 -391.565128) (xy 374.490409 -391.565128) (xy 374.439074 -391.556998)
			(xy 374.389644 -391.540937) (xy 374.343334 -391.517341) (xy 374.301286 -391.486791) (xy 374.264535 -391.45004)
			(xy 374.233985 -391.407992) (xy 374.210389 -391.361682) (xy 374.194328 -391.312252) (xy 374.186198 -391.260917)
			(xy 373.646698 -391.260917) (xy 373.638568 -391.312252) (xy 373.622507 -391.361682) (xy 373.598911 -391.407992)
			(xy 373.568361 -391.45004) (xy 373.53161 -391.486791) (xy 373.489562 -391.517341) (xy 373.443252 -391.540937)
			(xy 373.393822 -391.556998) (xy 373.342487 -391.565128) (xy 373.290513 -391.565128) (xy 373.239178 -391.556998)
			(xy 373.189748 -391.540937) (xy 373.143438 -391.517341) (xy 373.10139 -391.486791) (xy 373.064639 -391.45004)
			(xy 373.034089 -391.407992) (xy 373.010493 -391.361682) (xy 372.994432 -391.312252) (xy 372.986302 -391.260917)
			(xy 372.446802 -391.260917) (xy 372.438672 -391.312252) (xy 372.422611 -391.361682) (xy 372.399015 -391.407992)
			(xy 372.368465 -391.45004) (xy 372.331714 -391.486791) (xy 372.289666 -391.517341) (xy 372.243356 -391.540937)
			(xy 372.193926 -391.556998) (xy 372.142591 -391.565128) (xy 372.090617 -391.565128) (xy 372.039282 -391.556998)
			(xy 371.989852 -391.540937) (xy 371.943542 -391.517341) (xy 371.901494 -391.486791) (xy 371.864743 -391.45004)
			(xy 371.834193 -391.407992) (xy 371.810597 -391.361682) (xy 371.794536 -391.312252) (xy 371.786406 -391.260917)
			(xy 371.246652 -391.260917) (xy 371.238522 -391.312252) (xy 371.222461 -391.361682) (xy 371.198865 -391.407992)
			(xy 371.168315 -391.45004) (xy 371.131564 -391.486791) (xy 371.089516 -391.517341) (xy 371.043206 -391.540937)
			(xy 370.993776 -391.556998) (xy 370.942441 -391.565128) (xy 370.890467 -391.565128) (xy 370.839132 -391.556998)
			(xy 370.789702 -391.540937) (xy 370.743392 -391.517341) (xy 370.701344 -391.486791) (xy 370.664593 -391.45004)
			(xy 370.634043 -391.407992) (xy 370.610447 -391.361682) (xy 370.594386 -391.312252) (xy 370.586256 -391.260917)
			(xy 369.898284 -391.260917) (xy 369.898773 -391.264006) (xy 369.898773 -391.315994) (xy 369.890639 -391.367343)
			(xy 369.874573 -391.416786) (xy 369.85097 -391.463108) (xy 369.820411 -391.505166) (xy 369.783648 -391.541927)
			(xy 369.741587 -391.572483) (xy 369.695264 -391.596083) (xy 369.645819 -391.612145) (xy 369.59447 -391.620275)
			(xy 369.568476 -391.620756) (xy 369.539883 -391.620135) (xy 369.483549 -391.610288) (xy 369.429746 -391.590908)
			(xy 369.380073 -391.562571) (xy 369.357656 -391.54481) (xy 369.350798 -391.539222) (xy 369.334034 -391.533126)
			(xy 369.251738 -391.533126) (xy 369.234974 -391.538968) (xy 369.228116 -391.544556) (xy 369.205732 -391.562167)
			(xy 369.156223 -391.590309) (xy 369.10263 -391.609567) (xy 369.046532 -391.619371) (xy 369.018058 -391.619994)
			(xy 368.994824 -391.619604) (xy 368.948813 -391.613105) (xy 368.904165 -391.600227) (xy 368.86176 -391.581224)
			(xy 368.822435 -391.55647) (xy 368.804444 -391.541762) (xy 368.797332 -391.535666) (xy 368.780822 -391.52957)
			(xy 368.696494 -391.52957) (xy 368.679984 -391.535666) (xy 368.672872 -391.541762) (xy 368.654863 -391.556446)
			(xy 368.61554 -391.581197) (xy 368.573139 -391.600202) (xy 368.528497 -391.613086) (xy 368.48249 -391.619597)
			(xy 368.459258 -391.619994) (xy 368.433272 -391.619509) (xy 368.38194 -391.611373) (xy 368.332513 -391.595308)
			(xy 368.286208 -391.571709) (xy 368.244163 -391.541157) (xy 368.207416 -391.504405) (xy 368.176869 -391.462356)
			(xy 368.153276 -391.416048) (xy 368.137217 -391.366619) (xy 368.129087 -391.315286) (xy 366.180761 -391.315286)
			(xy 366.192166 -391.338615) (xy 366.212649 -391.39828) (xy 366.225593 -391.46002) (xy 366.230802 -391.522887)
			(xy 366.228194 -391.585916) (xy 366.21781 -391.648138) (xy 366.19981 -391.708597) (xy 366.174469 -391.766366)
			(xy 366.142177 -391.820557) (xy 366.10343 -391.870338) (xy 366.058823 -391.914943) (xy 366.009041 -391.953688)
			(xy 365.954849 -391.985978) (xy 365.897079 -392.011316) (xy 365.836618 -392.029315) (xy 365.774396 -392.039696)
			(xy 365.711367 -392.042302) (xy 365.6485 -392.03709) (xy 365.58676 -392.024143) (xy 365.527096 -392.003659)
			(xy 365.470424 -391.975951) (xy 365.417615 -391.941447) (xy 365.369479 -391.900675) (xy 365.326756 -391.854262)
			(xy 365.290101 -391.802921) (xy 365.260079 -391.747441) (xy 365.23715 -391.688673) (xy 365.221667 -391.62752)
			(xy 365.213866 -391.564921) (xy 365.213392 -391.53338) (xy 365.213759 -391.506438) (xy 365.219487 -391.452858)
			(xy 365.224822 -391.426446) (xy 365.227108 -391.415778) (xy 365.22279 -391.395204) (xy 365.167672 -391.316718)
			(xy 365.149892 -391.305796) (xy 365.139224 -391.304272) (xy 365.116373 -391.300832) (xy 365.071671 -391.289115)
			(xy 365.05007 -391.280904) (xy 365.037624 -391.275824) (xy 365.011716 -391.279126) (xy 364.921038 -391.345928)
			(xy 364.910116 -391.36955) (xy 364.911132 -391.382758) (xy 364.912148 -391.41146) (xy 364.911662 -391.438711)
			(xy 364.903906 -391.492659) (xy 364.888551 -391.544954) (xy 364.865909 -391.594531) (xy 364.836443 -391.640381)
			(xy 364.800752 -391.681572) (xy 364.759561 -391.717263) (xy 364.713711 -391.746729) (xy 364.664134 -391.769371)
			(xy 364.611839 -391.784726) (xy 364.557891 -391.792482) (xy 364.503389 -391.792482) (xy 364.449441 -391.784726)
			(xy 364.397146 -391.769371) (xy 364.347569 -391.746729) (xy 364.301719 -391.717263) (xy 364.260528 -391.681572)
			(xy 364.224837 -391.640381) (xy 364.195371 -391.594531) (xy 364.172729 -391.544954) (xy 364.157374 -391.492659)
			(xy 364.149618 -391.438711) (xy 364.149132 -391.41146) (xy 364.150148 -391.382758) (xy 364.151164 -391.36955)
			(xy 364.140242 -391.345928) (xy 364.049564 -391.279126) (xy 364.023656 -391.275824) (xy 364.01121 -391.280904)
			(xy 363.988707 -391.289463) (xy 363.94208 -391.301459) (xy 363.894313 -391.307482) (xy 363.87024 -391.307828)
			(xy 363.842987 -391.307327) (xy 363.789034 -391.299576) (xy 363.736734 -391.284224) (xy 363.687152 -391.261585)
			(xy 363.641296 -391.232119) (xy 363.600101 -391.196428) (xy 363.564405 -391.155236) (xy 363.534934 -391.109383)
			(xy 363.51229 -391.059803) (xy 363.496933 -391.007505) (xy 363.489175 -390.953553) (xy 363.489175 -390.899047)
			(xy 363.496933 -390.845095) (xy 363.51229 -390.792797) (xy 363.534934 -390.743217) (xy 363.564405 -390.697364)
			(xy 363.600101 -390.656172) (xy 363.641296 -390.620481) (xy 363.687152 -390.591015) (xy 363.736734 -390.568376)
			(xy 363.789034 -390.553024) (xy 363.842987 -390.545273) (xy 363.87024 -390.544812) (xy 363.899677 -390.545376)
			(xy 363.95785 -390.554431) (xy 363.986064 -390.562846) (xy 363.994672 -390.565212) (xy 364.012496 -390.564436)
			(xy 364.020862 -390.561322) (xy 364.049056 -390.549384) (xy 364.057303 -390.545586) (xy 364.070569 -390.533201)
			(xy 364.074964 -390.525254) (xy 364.088129 -390.499558) (xy 364.119448 -390.451054) (xy 364.137448 -390.42848)
			(xy 364.142757 -390.421489) (xy 364.148724 -390.404991) (xy 364.149132 -390.396222) (xy 364.149132 -390.242298)
			(xy 364.148766 -390.233521) (xy 364.142783 -390.217019) (xy 364.137448 -390.21004) (xy 364.119468 -390.187452)
			(xy 364.088147 -390.138951) (xy 364.074964 -390.113266) (xy 364.070562 -390.105327) (xy 364.057288 -390.092962)
			(xy 364.049056 -390.089136) (xy 364.020862 -390.077198) (xy 364.012487 -390.074135) (xy 363.994681 -390.07337)
			(xy 363.986064 -390.075674) (xy 363.957852 -390.0841) (xy 363.899678 -390.093162) (xy 363.87024 -390.093708)
			(xy 363.842985 -390.093247) (xy 363.78903 -390.085495) (xy 363.736727 -390.070142) (xy 363.687142 -390.047502)
			(xy 363.641284 -390.018035) (xy 363.600087 -389.982342) (xy 363.564389 -389.941148) (xy 363.534917 -389.895293)
			(xy 363.512272 -389.84571) (xy 363.496913 -389.793409) (xy 363.489155 -389.739455) (xy 359.985322 -389.739455)
			(xy 359.938718 -389.760739) (xy 359.886423 -389.776094) (xy 359.832475 -389.78385) (xy 359.777973 -389.78385)
			(xy 359.724025 -389.776094) (xy 359.67173 -389.760739) (xy 359.622153 -389.738097) (xy 359.576303 -389.708631)
			(xy 359.535112 -389.67294) (xy 359.499421 -389.631749) (xy 359.469955 -389.585899) (xy 359.447313 -389.536322)
			(xy 359.431958 -389.484027) (xy 359.424202 -389.430079) (xy 359.423716 -389.402828) (xy 359.424732 -389.374126)
			(xy 359.425748 -389.360918) (xy 359.414826 -389.337296) (xy 359.324148 -389.270494) (xy 359.29824 -389.267192)
			(xy 359.285794 -389.272272) (xy 359.263284 -389.280807) (xy 359.216658 -389.292794) (xy 359.168895 -389.29883)
			(xy 359.144824 -389.299196) (xy 359.117571 -389.298734) (xy 359.063619 -389.29098) (xy 359.01132 -389.275627)
			(xy 358.961738 -389.252986) (xy 358.915884 -389.22352) (xy 358.874689 -389.187828) (xy 358.838994 -389.146636)
			(xy 358.809525 -389.100783) (xy 358.786881 -389.051203) (xy 358.771525 -388.998904) (xy 358.763767 -388.944953)
			(xy 358.763767 -388.890447) (xy 358.771525 -388.836496) (xy 358.786881 -388.784197) (xy 358.809525 -388.734617)
			(xy 358.838994 -388.688764) (xy 358.874689 -388.647572) (xy 358.915884 -388.61188) (xy 358.961738 -388.582414)
			(xy 359.01132 -388.559773) (xy 359.063619 -388.54442) (xy 359.117571 -388.536666) (xy 359.144824 -388.53618)
			(xy 359.174262 -388.536725) (xy 359.232437 -388.545784) (xy 359.260648 -388.554214) (xy 359.269263 -388.556503)
			(xy 359.287058 -388.555712) (xy 359.295446 -388.55269) (xy 359.32364 -388.540752) (xy 359.331873 -388.536927)
			(xy 359.345148 -388.524563) (xy 359.349548 -388.516622) (xy 359.362731 -388.490938) (xy 359.394052 -388.442436)
			(xy 359.412032 -388.419848) (xy 359.417367 -388.412869) (xy 359.423347 -388.396366) (xy 359.423716 -388.38759)
			(xy 359.423716 -388.233666) (xy 359.423306 -388.224898) (xy 359.417334 -388.208404) (xy 359.412032 -388.201408)
			(xy 359.394033 -388.178834) (xy 359.362716 -388.130328) (xy 359.349548 -388.104634) (xy 359.345151 -388.096689)
			(xy 359.331882 -388.084311) (xy 359.32364 -388.080504) (xy 359.295446 -388.068566) (xy 359.28708 -388.065455)
			(xy 359.269258 -388.064684) (xy 359.260648 -388.067042) (xy 359.232434 -388.075456) (xy 359.174261 -388.084509)
			(xy 359.144824 -388.085076) (xy 359.117571 -388.084614) (xy 359.063619 -388.07686) (xy 359.01132 -388.061506)
			(xy 358.961739 -388.038864) (xy 358.915885 -388.009396) (xy 358.874692 -387.973702) (xy 358.838999 -387.932508)
			(xy 358.809532 -387.886654) (xy 358.786892 -387.837072) (xy 358.771538 -387.784773) (xy 358.763785 -387.730821)
			(xy 358.763316 -387.703568) (xy 358.763813 -387.675866) (xy 358.771826 -387.621045) (xy 358.787678 -387.567957)
			(xy 358.811038 -387.517719) (xy 358.8258 -387.494272) (xy 358.833674 -387.482588) (xy 358.83469 -387.454648)
			(xy 358.785668 -387.363462) (xy 358.780989 -387.355606) (xy 358.767213 -387.343605) (xy 358.7501 -387.337203)
			(xy 358.740964 -387.336792) (xy 333.069438 -387.336792) (xy 333.058923 -387.337312) (xy 333.039637 -387.345699)
			(xy 333.0321 -387.353048) (xy 332.974188 -387.415024) (xy 332.96733 -387.434836) (xy 332.967838 -387.44525)
			(xy 332.969108 -387.47954) (xy 332.968606 -387.511501) (xy 332.960595 -387.574919) (xy 332.944698 -387.636833)
			(xy 332.921166 -387.696266) (xy 332.890372 -387.752281) (xy 332.852799 -387.803996) (xy 332.809042 -387.850593)
			(xy 332.759789 -387.891338) (xy 332.705818 -387.925589) (xy 332.647979 -387.952806) (xy 332.587186 -387.972559)
			(xy 332.524396 -387.984537) (xy 332.4606 -387.988551) (xy 332.396804 -387.984537) (xy 332.334014 -387.972559)
			(xy 332.273221 -387.952806) (xy 332.215382 -387.925589) (xy 332.161411 -387.891338) (xy 332.112158 -387.850593)
			(xy 332.068401 -387.803996) (xy 332.030828 -387.752281) (xy 332.000034 -387.696266) (xy 331.976502 -387.636833)
			(xy 331.960605 -387.574919) (xy 331.952594 -387.511501) (xy 331.952092 -387.47954) (xy 331.953362 -387.44525)
			(xy 331.95387 -387.434836) (xy 331.947012 -387.415024) (xy 331.8891 -387.353048) (xy 331.881574 -387.34568)
			(xy 331.862283 -387.337289) (xy 331.851762 -387.336792) (xy 330.02601 -387.336792) (xy 330.016296 -387.337221)
			(xy 329.99826 -387.344441) (xy 329.984201 -387.357849) (xy 329.979782 -387.36651) (xy 329.935078 -387.463792)
			(xy 329.939142 -387.493256) (xy 329.948794 -387.504432) (xy 329.967969 -387.527522) (xy 330.001346 -387.577405)
			(xy 330.028623 -387.630869) (xy 330.049422 -387.68717) (xy 330.063452 -387.745527) (xy 330.07052 -387.80513)
			(xy 330.070968 -387.83514) (xy 330.070529 -387.865126) (xy 330.063469 -387.924681) (xy 330.049453 -387.982992)
			(xy 330.028674 -388.03925) (xy 330.001421 -388.092672) (xy 329.985116 -388.117842) (xy 329.9795 -388.127201)
			(xy 329.975987 -388.148723) (xy 329.981663 -388.169777) (xy 329.988164 -388.178548) (xy 330.009964 -388.205967)
			(xy 330.046622 -388.265658) (xy 330.074739 -388.329816) (xy 330.093783 -388.397226) (xy 330.103393 -388.466612)
			(xy 330.103988 -388.501636) (xy 330.103455 -388.534127) (xy 330.095148 -388.598576) (xy 330.078712 -388.661446)
			(xy 330.054413 -388.721714) (xy 330.038964 -388.750302) (xy 330.03363 -388.760208) (xy 330.033551 -388.761181)
			(xy 330.299054 -388.761181) (xy 330.299054 -388.697259) (xy 330.307065 -388.633841) (xy 330.322962 -388.571927)
			(xy 330.346494 -388.512494) (xy 330.377288 -388.456479) (xy 330.414861 -388.404764) (xy 330.458618 -388.358167)
			(xy 330.507871 -388.317422) (xy 330.561842 -388.283171) (xy 330.619681 -388.255954) (xy 330.680474 -388.236201)
			(xy 330.743264 -388.224223) (xy 330.80706 -388.22021) (xy 330.870856 -388.224223) (xy 330.933646 -388.236201)
			(xy 330.994439 -388.255954) (xy 331.052278 -388.283171) (xy 331.106249 -388.317422) (xy 331.155502 -388.358167)
			(xy 331.199259 -388.404764) (xy 331.236832 -388.456479) (xy 331.267626 -388.512494) (xy 331.291158 -388.571927)
			(xy 331.307055 -388.633841) (xy 331.315066 -388.697259) (xy 331.315568 -388.72922) (xy 331.315066 -388.761181)
			(xy 331.307055 -388.824599) (xy 331.291158 -388.886513) (xy 331.267626 -388.945946) (xy 331.236832 -389.001961)
			(xy 331.199259 -389.053676) (xy 331.155502 -389.100273) (xy 331.106249 -389.141018) (xy 331.052278 -389.175269)
			(xy 330.994439 -389.202486) (xy 330.933646 -389.222239) (xy 330.870856 -389.234217) (xy 330.80706 -389.238231)
			(xy 330.743264 -389.234217) (xy 330.680474 -389.222239) (xy 330.619681 -389.202486) (xy 330.561842 -389.175269)
			(xy 330.507871 -389.141018) (xy 330.458618 -389.100273) (xy 330.414861 -389.053676) (xy 330.377288 -389.001961)
			(xy 330.346494 -388.945946) (xy 330.322962 -388.886513) (xy 330.307065 -388.824599) (xy 330.299054 -388.761181)
			(xy 330.033551 -388.761181) (xy 330.031852 -388.782052) (xy 330.065888 -388.875524) (xy 330.081636 -388.891272)
			(xy 330.09205 -388.895082) (xy 330.118941 -388.905749) (xy 330.169411 -388.934021) (xy 330.21504 -388.969582)
			(xy 330.254783 -389.011617) (xy 330.287732 -389.059166) (xy 330.313132 -389.111141) (xy 330.330403 -389.166351)
			(xy 330.339149 -389.223536) (xy 330.3397 -389.25246) (xy 330.3397 -389.260588) (xy 330.339446 -389.273796)
			(xy 330.350622 -389.295894) (xy 330.441554 -389.35914) (xy 330.466446 -389.362188) (xy 330.478384 -389.357362)
			(xy 330.500777 -389.348896) (xy 330.547154 -389.337012) (xy 330.594654 -389.331036) (xy 330.618592 -389.330692)
			(xy 330.645845 -389.331155) (xy 330.699797 -389.338911) (xy 330.752096 -389.354266) (xy 330.801677 -389.376908)
			(xy 330.847531 -389.406376) (xy 330.888725 -389.44207) (xy 330.920309 -389.47852) (xy 331.923642 -389.47852)
			(xy 331.927713 -389.422898) (xy 331.939839 -389.368461) (xy 331.959762 -389.31637) (xy 331.987058 -389.267735)
			(xy 332.021144 -389.223592) (xy 332.061293 -389.184883) (xy 332.106651 -389.152432) (xy 332.156251 -389.126931)
			(xy 332.209035 -389.108924) (xy 332.263878 -389.098794) (xy 332.319612 -389.096757) (xy 332.375049 -389.102857)
			(xy 332.429006 -389.116963) (xy 332.480335 -389.138775) (xy 332.527941 -389.167829) (xy 332.570809 -389.203504)
			(xy 332.608026 -389.245041) (xy 332.638799 -389.291554) (xy 332.662471 -389.342051) (xy 332.678539 -389.395458)
			(xy 332.686659 -389.450634) (xy 332.687168 -389.47852) (xy 332.686659 -389.506406) (xy 332.678539 -389.561582)
			(xy 332.662471 -389.614989) (xy 332.638799 -389.665486) (xy 332.608026 -389.711999) (xy 332.570809 -389.753536)
			(xy 332.527941 -389.789211) (xy 332.480335 -389.818265) (xy 332.429006 -389.840077) (xy 332.375049 -389.854183)
			(xy 332.319612 -389.860283) (xy 332.263878 -389.858246) (xy 332.209035 -389.848116) (xy 332.156251 -389.830109)
			(xy 332.106651 -389.804608) (xy 332.061293 -389.772157) (xy 332.021144 -389.733448) (xy 331.987058 -389.689305)
			(xy 331.959762 -389.64067) (xy 331.939839 -389.588579) (xy 331.927713 -389.534142) (xy 331.923642 -389.47852)
			(xy 330.920309 -389.47852) (xy 330.924419 -389.483263) (xy 330.953888 -389.529116) (xy 330.976531 -389.578697)
			(xy 330.991887 -389.630995) (xy 330.999645 -389.684947) (xy 330.999645 -389.739453) (xy 330.991887 -389.793405)
			(xy 330.976531 -389.845703) (xy 330.953888 -389.895284) (xy 330.924419 -389.941137) (xy 330.888725 -389.98233)
			(xy 330.847531 -390.018024) (xy 330.801677 -390.047492) (xy 330.752096 -390.070134) (xy 330.699797 -390.085489)
			(xy 330.645845 -390.093245) (xy 330.618592 -390.093708) (xy 330.589154 -390.093164) (xy 330.530978 -390.084107)
			(xy 330.502768 -390.075674) (xy 330.494152 -390.073382) (xy 330.476355 -390.074168) (xy 330.46797 -390.077198)
			(xy 330.439776 -390.089136) (xy 330.43154 -390.092958) (xy 330.418259 -390.10532) (xy 330.413868 -390.113266)
			(xy 330.400686 -390.138951) (xy 330.369367 -390.187454) (xy 330.351384 -390.21004) (xy 330.346046 -390.217018)
			(xy 330.34006 -390.233521) (xy 330.3397 -390.242298) (xy 330.3397 -390.396222) (xy 330.340109 -390.404991)
			(xy 330.346079 -390.421486) (xy 330.351384 -390.42848) (xy 330.369386 -390.451052) (xy 330.400709 -390.499555)
			(xy 330.413868 -390.525254) (xy 330.418265 -390.533198) (xy 330.431534 -390.545575) (xy 330.439776 -390.549384)
			(xy 330.46797 -390.561322) (xy 330.476336 -390.56443) (xy 330.494157 -390.565196) (xy 330.502768 -390.562846)
			(xy 330.530982 -390.554434) (xy 330.589156 -390.545383) (xy 330.618592 -390.544812) (xy 330.645844 -390.545275)
			(xy 330.699793 -390.55303) (xy 330.752089 -390.568385) (xy 330.801667 -390.591026) (xy 330.847519 -390.620492)
			(xy 330.888711 -390.656184) (xy 330.924403 -390.697375) (xy 330.95387 -390.743226) (xy 330.976512 -390.792804)
			(xy 330.991868 -390.845099) (xy 330.999625 -390.899048) (xy 330.999625 -390.953552) (xy 330.991868 -391.007501)
			(xy 330.976512 -391.059796) (xy 330.95387 -391.109374) (xy 330.924403 -391.155225) (xy 330.888711 -391.196416)
			(xy 330.847519 -391.232108) (xy 330.801667 -391.261574) (xy 330.752089 -391.284215) (xy 330.699793 -391.29957)
			(xy 330.645844 -391.307325) (xy 330.618592 -391.307828) (xy 330.59452 -391.307478) (xy 330.546755 -391.301446)
			(xy 330.500132 -391.289443) (xy 330.477622 -391.280904) (xy 330.465176 -391.275824) (xy 330.439268 -391.279126)
			(xy 330.390177 -391.315291) (xy 333.556561 -391.315291) (xy 333.556561 -391.263309) (xy 333.564693 -391.211967)
			(xy 333.580757 -391.16253) (xy 333.604356 -391.116214) (xy 333.634911 -391.07416) (xy 333.671668 -391.037404)
			(xy 333.713723 -391.006851) (xy 333.760039 -390.983253) (xy 333.809477 -390.967191) (xy 333.860819 -390.95906)
			(xy 333.88681 -390.958578) (xy 333.910008 -390.958961) (xy 333.955948 -390.965453) (xy 334.000533 -390.978294)
			(xy 334.042888 -390.997233) (xy 334.082184 -391.021899) (xy 334.10017 -391.036556) (xy 334.107282 -391.042652)
			(xy 334.124808 -391.048748) (xy 334.210406 -391.04697) (xy 334.227678 -391.039858) (xy 334.234536 -391.033508)
			(xy 334.252953 -391.01716) (xy 334.293734 -390.989556) (xy 334.338157 -390.968303) (xy 334.38524 -390.953872)
			(xy 334.433942 -390.94658) (xy 334.458564 -390.946132) (xy 334.483401 -390.946579) (xy 334.532518 -390.953998)
			(xy 334.57997 -390.968689) (xy 334.624686 -390.990322) (xy 334.665658 -391.018407) (xy 334.684116 -391.035032)
			(xy 334.691192 -391.041057) (xy 334.708374 -391.0481) (xy 334.717644 -391.048748) (xy 334.748886 -391.04951)
			(xy 334.758141 -391.049354) (xy 334.775594 -391.043229) (xy 334.782922 -391.037572) (xy 334.805455 -391.019365)
			(xy 334.855596 -390.990358) (xy 334.910019 -390.970516) (xy 334.967064 -390.960443) (xy 334.996028 -390.959848)
			(xy 335.02201 -390.960448) (xy 335.073334 -390.968581) (xy 335.122755 -390.984642) (xy 335.169054 -391.008236)
			(xy 335.211093 -391.038783) (xy 335.247836 -391.075529) (xy 335.278378 -391.11757) (xy 335.301968 -391.163871)
			(xy 335.318026 -391.213293) (xy 335.325568 -391.260917) (xy 336.013808 -391.260917) (xy 336.013808 -391.208943)
			(xy 336.021938 -391.157608) (xy 336.037999 -391.108178) (xy 336.061595 -391.061868) (xy 336.092145 -391.01982)
			(xy 336.128896 -390.983069) (xy 336.170944 -390.952519) (xy 336.217254 -390.928923) (xy 336.266684 -390.912862)
			(xy 336.318019 -390.904732) (xy 336.369993 -390.904732) (xy 336.421328 -390.912862) (xy 336.470758 -390.928923)
			(xy 336.517068 -390.952519) (xy 336.559116 -390.983069) (xy 336.595867 -391.01982) (xy 336.626417 -391.061868)
			(xy 336.650013 -391.108178) (xy 336.666074 -391.157608) (xy 336.674204 -391.208943) (xy 336.674714 -391.23493)
			(xy 336.674204 -391.260917) (xy 337.213958 -391.260917) (xy 337.213958 -391.208943) (xy 337.222088 -391.157608)
			(xy 337.238149 -391.108178) (xy 337.261745 -391.061868) (xy 337.292295 -391.01982) (xy 337.329046 -390.983069)
			(xy 337.371094 -390.952519) (xy 337.417404 -390.928923) (xy 337.466834 -390.912862) (xy 337.518169 -390.904732)
			(xy 337.570143 -390.904732) (xy 337.621478 -390.912862) (xy 337.670908 -390.928923) (xy 337.717218 -390.952519)
			(xy 337.759266 -390.983069) (xy 337.796017 -391.01982) (xy 337.826567 -391.061868) (xy 337.850163 -391.108178)
			(xy 337.866224 -391.157608) (xy 337.874354 -391.208943) (xy 337.874864 -391.23493) (xy 337.874354 -391.260917)
			(xy 338.413854 -391.260917) (xy 338.413854 -391.208943) (xy 338.421984 -391.157608) (xy 338.438045 -391.108178)
			(xy 338.461641 -391.061868) (xy 338.492191 -391.01982) (xy 338.528942 -390.983069) (xy 338.57099 -390.952519)
			(xy 338.6173 -390.928923) (xy 338.66673 -390.912862) (xy 338.718065 -390.904732) (xy 338.770039 -390.904732)
			(xy 338.821374 -390.912862) (xy 338.870804 -390.928923) (xy 338.917114 -390.952519) (xy 338.959162 -390.983069)
			(xy 338.995913 -391.01982) (xy 339.026463 -391.061868) (xy 339.050059 -391.108178) (xy 339.06612 -391.157608)
			(xy 339.07425 -391.208943) (xy 339.07476 -391.23493) (xy 339.07425 -391.260917) (xy 339.61375 -391.260917)
			(xy 339.61375 -391.208943) (xy 339.62188 -391.157608) (xy 339.637941 -391.108178) (xy 339.661537 -391.061868)
			(xy 339.692087 -391.01982) (xy 339.728838 -390.983069) (xy 339.770886 -390.952519) (xy 339.817196 -390.928923)
			(xy 339.866626 -390.912862) (xy 339.917961 -390.904732) (xy 339.969935 -390.904732) (xy 340.02127 -390.912862)
			(xy 340.0707 -390.928923) (xy 340.11701 -390.952519) (xy 340.159058 -390.983069) (xy 340.195809 -391.01982)
			(xy 340.226359 -391.061868) (xy 340.249955 -391.108178) (xy 340.266016 -391.157608) (xy 340.274146 -391.208943)
			(xy 340.274656 -391.23493) (xy 340.274146 -391.260917) (xy 340.8139 -391.260917) (xy 340.8139 -391.208943)
			(xy 340.82203 -391.157608) (xy 340.838091 -391.108178) (xy 340.861687 -391.061868) (xy 340.892237 -391.01982)
			(xy 340.928988 -390.983069) (xy 340.971036 -390.952519) (xy 341.017346 -390.928923) (xy 341.066776 -390.912862)
			(xy 341.118111 -390.904732) (xy 341.170085 -390.904732) (xy 341.22142 -390.912862) (xy 341.27085 -390.928923)
			(xy 341.31716 -390.952519) (xy 341.359208 -390.983069) (xy 341.395959 -391.01982) (xy 341.426509 -391.061868)
			(xy 341.450105 -391.108178) (xy 341.466166 -391.157608) (xy 341.474296 -391.208943) (xy 341.474806 -391.23493)
			(xy 341.474296 -391.260917) (xy 342.013796 -391.260917) (xy 342.013796 -391.208943) (xy 342.021926 -391.157608)
			(xy 342.037987 -391.108178) (xy 342.061583 -391.061868) (xy 342.092133 -391.01982) (xy 342.128884 -390.983069)
			(xy 342.170932 -390.952519) (xy 342.217242 -390.928923) (xy 342.266672 -390.912862) (xy 342.318007 -390.904732)
			(xy 342.369981 -390.904732) (xy 342.421316 -390.912862) (xy 342.470746 -390.928923) (xy 342.517056 -390.952519)
			(xy 342.559104 -390.983069) (xy 342.595855 -391.01982) (xy 342.626405 -391.061868) (xy 342.650001 -391.108178)
			(xy 342.666062 -391.157608) (xy 342.674192 -391.208943) (xy 342.674702 -391.23493) (xy 342.674192 -391.260917)
			(xy 343.213946 -391.260917) (xy 343.213946 -391.208943) (xy 343.222076 -391.157608) (xy 343.238137 -391.108178)
			(xy 343.261733 -391.061868) (xy 343.292283 -391.01982) (xy 343.329034 -390.983069) (xy 343.371082 -390.952519)
			(xy 343.417392 -390.928923) (xy 343.466822 -390.912862) (xy 343.518157 -390.904732) (xy 343.570131 -390.904732)
			(xy 343.621466 -390.912862) (xy 343.670896 -390.928923) (xy 343.717206 -390.952519) (xy 343.759254 -390.983069)
			(xy 343.796005 -391.01982) (xy 343.826555 -391.061868) (xy 343.850151 -391.108178) (xy 343.866212 -391.157608)
			(xy 343.874342 -391.208943) (xy 343.874852 -391.23493) (xy 343.874342 -391.260917) (xy 344.413842 -391.260917)
			(xy 344.413842 -391.208943) (xy 344.421972 -391.157608) (xy 344.438033 -391.108178) (xy 344.461629 -391.061868)
			(xy 344.492179 -391.01982) (xy 344.52893 -390.983069) (xy 344.570978 -390.952519) (xy 344.617288 -390.928923)
			(xy 344.666718 -390.912862) (xy 344.718053 -390.904732) (xy 344.770027 -390.904732) (xy 344.821362 -390.912862)
			(xy 344.870792 -390.928923) (xy 344.917102 -390.952519) (xy 344.95915 -390.983069) (xy 344.995901 -391.01982)
			(xy 345.026451 -391.061868) (xy 345.050047 -391.108178) (xy 345.066108 -391.157608) (xy 345.074238 -391.208943)
			(xy 345.074748 -391.23493) (xy 345.074238 -391.260917) (xy 345.613738 -391.260917) (xy 345.613738 -391.208943)
			(xy 345.621868 -391.157608) (xy 345.637929 -391.108178) (xy 345.661525 -391.061868) (xy 345.692075 -391.01982)
			(xy 345.728826 -390.983069) (xy 345.770874 -390.952519) (xy 345.817184 -390.928923) (xy 345.866614 -390.912862)
			(xy 345.917949 -390.904732) (xy 345.969923 -390.904732) (xy 346.021258 -390.912862) (xy 346.070688 -390.928923)
			(xy 346.116998 -390.952519) (xy 346.159046 -390.983069) (xy 346.195797 -391.01982) (xy 346.226347 -391.061868)
			(xy 346.249943 -391.108178) (xy 346.266004 -391.157608) (xy 346.274134 -391.208943) (xy 346.274644 -391.23493)
			(xy 346.274134 -391.260917) (xy 346.813888 -391.260917) (xy 346.813888 -391.208943) (xy 346.822018 -391.157608)
			(xy 346.838079 -391.108178) (xy 346.861675 -391.061868) (xy 346.892225 -391.01982) (xy 346.928976 -390.983069)
			(xy 346.971024 -390.952519) (xy 347.017334 -390.928923) (xy 347.066764 -390.912862) (xy 347.118099 -390.904732)
			(xy 347.170073 -390.904732) (xy 347.221408 -390.912862) (xy 347.270838 -390.928923) (xy 347.317148 -390.952519)
			(xy 347.359196 -390.983069) (xy 347.395947 -391.01982) (xy 347.426497 -391.061868) (xy 347.450093 -391.108178)
			(xy 347.466154 -391.157608) (xy 347.474284 -391.208943) (xy 347.474794 -391.23493) (xy 347.474284 -391.260917)
			(xy 348.013784 -391.260917) (xy 348.013784 -391.208943) (xy 348.021914 -391.157608) (xy 348.037975 -391.108178)
			(xy 348.061571 -391.061868) (xy 348.092121 -391.01982) (xy 348.128872 -390.983069) (xy 348.17092 -390.952519)
			(xy 348.21723 -390.928923) (xy 348.26666 -390.912862) (xy 348.317995 -390.904732) (xy 348.369969 -390.904732)
			(xy 348.421304 -390.912862) (xy 348.470734 -390.928923) (xy 348.517044 -390.952519) (xy 348.559092 -390.983069)
			(xy 348.595843 -391.01982) (xy 348.626393 -391.061868) (xy 348.649989 -391.108178) (xy 348.66605 -391.157608)
			(xy 348.67418 -391.208943) (xy 348.67469 -391.23493) (xy 348.67418 -391.260917) (xy 349.213934 -391.260917)
			(xy 349.213934 -391.208943) (xy 349.222064 -391.157608) (xy 349.238125 -391.108178) (xy 349.261721 -391.061868)
			(xy 349.292271 -391.01982) (xy 349.329022 -390.983069) (xy 349.37107 -390.952519) (xy 349.41738 -390.928923)
			(xy 349.46681 -390.912862) (xy 349.518145 -390.904732) (xy 349.570119 -390.904732) (xy 349.621454 -390.912862)
			(xy 349.670884 -390.928923) (xy 349.717194 -390.952519) (xy 349.759242 -390.983069) (xy 349.795993 -391.01982)
			(xy 349.826543 -391.061868) (xy 349.850139 -391.108178) (xy 349.8662 -391.157608) (xy 349.87433 -391.208943)
			(xy 349.87484 -391.23493) (xy 349.87433 -391.260917) (xy 350.41383 -391.260917) (xy 350.41383 -391.208943)
			(xy 350.42196 -391.157608) (xy 350.438021 -391.108178) (xy 350.461617 -391.061868) (xy 350.492167 -391.01982)
			(xy 350.528918 -390.983069) (xy 350.570966 -390.952519) (xy 350.617276 -390.928923) (xy 350.666706 -390.912862)
			(xy 350.718041 -390.904732) (xy 350.770015 -390.904732) (xy 350.82135 -390.912862) (xy 350.87078 -390.928923)
			(xy 350.91709 -390.952519) (xy 350.959138 -390.983069) (xy 350.995889 -391.01982) (xy 351.026439 -391.061868)
			(xy 351.050035 -391.108178) (xy 351.066096 -391.157608) (xy 351.074226 -391.208943) (xy 351.074736 -391.23493)
			(xy 351.074226 -391.260917) (xy 351.613726 -391.260917) (xy 351.613726 -391.208943) (xy 351.621856 -391.157608)
			(xy 351.637917 -391.108178) (xy 351.661513 -391.061868) (xy 351.692063 -391.01982) (xy 351.728814 -390.983069)
			(xy 351.770862 -390.952519) (xy 351.817172 -390.928923) (xy 351.866602 -390.912862) (xy 351.917937 -390.904732)
			(xy 351.969911 -390.904732) (xy 352.021246 -390.912862) (xy 352.070676 -390.928923) (xy 352.116986 -390.952519)
			(xy 352.159034 -390.983069) (xy 352.195785 -391.01982) (xy 352.226335 -391.061868) (xy 352.249931 -391.108178)
			(xy 352.265992 -391.157608) (xy 352.274122 -391.208943) (xy 352.274632 -391.23493) (xy 352.274122 -391.260917)
			(xy 352.813876 -391.260917) (xy 352.813876 -391.208943) (xy 352.822006 -391.157608) (xy 352.838067 -391.108178)
			(xy 352.861663 -391.061868) (xy 352.892213 -391.01982) (xy 352.928964 -390.983069) (xy 352.971012 -390.952519)
			(xy 353.017322 -390.928923) (xy 353.066752 -390.912862) (xy 353.118087 -390.904732) (xy 353.170061 -390.904732)
			(xy 353.221396 -390.912862) (xy 353.270826 -390.928923) (xy 353.317136 -390.952519) (xy 353.359184 -390.983069)
			(xy 353.395935 -391.01982) (xy 353.426485 -391.061868) (xy 353.450081 -391.108178) (xy 353.466142 -391.157608)
			(xy 353.474272 -391.208943) (xy 353.474782 -391.23493) (xy 353.474272 -391.260917) (xy 353.466142 -391.312252)
			(xy 353.450081 -391.361682) (xy 353.426485 -391.407992) (xy 353.395935 -391.45004) (xy 353.359184 -391.486791)
			(xy 353.317136 -391.517341) (xy 353.270826 -391.540937) (xy 353.221396 -391.556998) (xy 353.170061 -391.565128)
			(xy 353.118087 -391.565128) (xy 353.066752 -391.556998) (xy 353.017322 -391.540937) (xy 352.971012 -391.517341)
			(xy 352.928964 -391.486791) (xy 352.892213 -391.45004) (xy 352.861663 -391.407992) (xy 352.838067 -391.361682)
			(xy 352.822006 -391.312252) (xy 352.813876 -391.260917) (xy 352.274122 -391.260917) (xy 352.265992 -391.312252)
			(xy 352.249931 -391.361682) (xy 352.226335 -391.407992) (xy 352.195785 -391.45004) (xy 352.159034 -391.486791)
			(xy 352.116986 -391.517341) (xy 352.070676 -391.540937) (xy 352.021246 -391.556998) (xy 351.969911 -391.565128)
			(xy 351.917937 -391.565128) (xy 351.866602 -391.556998) (xy 351.817172 -391.540937) (xy 351.770862 -391.517341)
			(xy 351.728814 -391.486791) (xy 351.692063 -391.45004) (xy 351.661513 -391.407992) (xy 351.637917 -391.361682)
			(xy 351.621856 -391.312252) (xy 351.613726 -391.260917) (xy 351.074226 -391.260917) (xy 351.066096 -391.312252)
			(xy 351.050035 -391.361682) (xy 351.026439 -391.407992) (xy 350.995889 -391.45004) (xy 350.959138 -391.486791)
			(xy 350.91709 -391.517341) (xy 350.87078 -391.540937) (xy 350.82135 -391.556998) (xy 350.770015 -391.565128)
			(xy 350.718041 -391.565128) (xy 350.666706 -391.556998) (xy 350.617276 -391.540937) (xy 350.570966 -391.517341)
			(xy 350.528918 -391.486791) (xy 350.492167 -391.45004) (xy 350.461617 -391.407992) (xy 350.438021 -391.361682)
			(xy 350.42196 -391.312252) (xy 350.41383 -391.260917) (xy 349.87433 -391.260917) (xy 349.8662 -391.312252)
			(xy 349.850139 -391.361682) (xy 349.826543 -391.407992) (xy 349.795993 -391.45004) (xy 349.759242 -391.486791)
			(xy 349.717194 -391.517341) (xy 349.670884 -391.540937) (xy 349.621454 -391.556998) (xy 349.570119 -391.565128)
			(xy 349.518145 -391.565128) (xy 349.46681 -391.556998) (xy 349.41738 -391.540937) (xy 349.37107 -391.517341)
			(xy 349.329022 -391.486791) (xy 349.292271 -391.45004) (xy 349.261721 -391.407992) (xy 349.238125 -391.361682)
			(xy 349.222064 -391.312252) (xy 349.213934 -391.260917) (xy 348.67418 -391.260917) (xy 348.66605 -391.312252)
			(xy 348.649989 -391.361682) (xy 348.626393 -391.407992) (xy 348.595843 -391.45004) (xy 348.559092 -391.486791)
			(xy 348.517044 -391.517341) (xy 348.470734 -391.540937) (xy 348.421304 -391.556998) (xy 348.369969 -391.565128)
			(xy 348.317995 -391.565128) (xy 348.26666 -391.556998) (xy 348.21723 -391.540937) (xy 348.17092 -391.517341)
			(xy 348.128872 -391.486791) (xy 348.092121 -391.45004) (xy 348.061571 -391.407992) (xy 348.037975 -391.361682)
			(xy 348.021914 -391.312252) (xy 348.013784 -391.260917) (xy 347.474284 -391.260917) (xy 347.466154 -391.312252)
			(xy 347.450093 -391.361682) (xy 347.426497 -391.407992) (xy 347.395947 -391.45004) (xy 347.359196 -391.486791)
			(xy 347.317148 -391.517341) (xy 347.270838 -391.540937) (xy 347.221408 -391.556998) (xy 347.170073 -391.565128)
			(xy 347.118099 -391.565128) (xy 347.066764 -391.556998) (xy 347.017334 -391.540937) (xy 346.971024 -391.517341)
			(xy 346.928976 -391.486791) (xy 346.892225 -391.45004) (xy 346.861675 -391.407992) (xy 346.838079 -391.361682)
			(xy 346.822018 -391.312252) (xy 346.813888 -391.260917) (xy 346.274134 -391.260917) (xy 346.266004 -391.312252)
			(xy 346.249943 -391.361682) (xy 346.226347 -391.407992) (xy 346.195797 -391.45004) (xy 346.159046 -391.486791)
			(xy 346.116998 -391.517341) (xy 346.070688 -391.540937) (xy 346.021258 -391.556998) (xy 345.969923 -391.565128)
			(xy 345.917949 -391.565128) (xy 345.866614 -391.556998) (xy 345.817184 -391.540937) (xy 345.770874 -391.517341)
			(xy 345.728826 -391.486791) (xy 345.692075 -391.45004) (xy 345.661525 -391.407992) (xy 345.637929 -391.361682)
			(xy 345.621868 -391.312252) (xy 345.613738 -391.260917) (xy 345.074238 -391.260917) (xy 345.066108 -391.312252)
			(xy 345.050047 -391.361682) (xy 345.026451 -391.407992) (xy 344.995901 -391.45004) (xy 344.95915 -391.486791)
			(xy 344.917102 -391.517341) (xy 344.870792 -391.540937) (xy 344.821362 -391.556998) (xy 344.770027 -391.565128)
			(xy 344.718053 -391.565128) (xy 344.666718 -391.556998) (xy 344.617288 -391.540937) (xy 344.570978 -391.517341)
			(xy 344.52893 -391.486791) (xy 344.492179 -391.45004) (xy 344.461629 -391.407992) (xy 344.438033 -391.361682)
			(xy 344.421972 -391.312252) (xy 344.413842 -391.260917) (xy 343.874342 -391.260917) (xy 343.866212 -391.312252)
			(xy 343.850151 -391.361682) (xy 343.826555 -391.407992) (xy 343.796005 -391.45004) (xy 343.759254 -391.486791)
			(xy 343.717206 -391.517341) (xy 343.670896 -391.540937) (xy 343.621466 -391.556998) (xy 343.570131 -391.565128)
			(xy 343.518157 -391.565128) (xy 343.466822 -391.556998) (xy 343.417392 -391.540937) (xy 343.371082 -391.517341)
			(xy 343.329034 -391.486791) (xy 343.292283 -391.45004) (xy 343.261733 -391.407992) (xy 343.238137 -391.361682)
			(xy 343.222076 -391.312252) (xy 343.213946 -391.260917) (xy 342.674192 -391.260917) (xy 342.666062 -391.312252)
			(xy 342.650001 -391.361682) (xy 342.626405 -391.407992) (xy 342.595855 -391.45004) (xy 342.559104 -391.486791)
			(xy 342.517056 -391.517341) (xy 342.470746 -391.540937) (xy 342.421316 -391.556998) (xy 342.369981 -391.565128)
			(xy 342.318007 -391.565128) (xy 342.266672 -391.556998) (xy 342.217242 -391.540937) (xy 342.170932 -391.517341)
			(xy 342.128884 -391.486791) (xy 342.092133 -391.45004) (xy 342.061583 -391.407992) (xy 342.037987 -391.361682)
			(xy 342.021926 -391.312252) (xy 342.013796 -391.260917) (xy 341.474296 -391.260917) (xy 341.466166 -391.312252)
			(xy 341.450105 -391.361682) (xy 341.426509 -391.407992) (xy 341.395959 -391.45004) (xy 341.359208 -391.486791)
			(xy 341.31716 -391.517341) (xy 341.27085 -391.540937) (xy 341.22142 -391.556998) (xy 341.170085 -391.565128)
			(xy 341.118111 -391.565128) (xy 341.066776 -391.556998) (xy 341.017346 -391.540937) (xy 340.971036 -391.517341)
			(xy 340.928988 -391.486791) (xy 340.892237 -391.45004) (xy 340.861687 -391.407992) (xy 340.838091 -391.361682)
			(xy 340.82203 -391.312252) (xy 340.8139 -391.260917) (xy 340.274146 -391.260917) (xy 340.266016 -391.312252)
			(xy 340.249955 -391.361682) (xy 340.226359 -391.407992) (xy 340.195809 -391.45004) (xy 340.159058 -391.486791)
			(xy 340.11701 -391.517341) (xy 340.0707 -391.540937) (xy 340.02127 -391.556998) (xy 339.969935 -391.565128)
			(xy 339.917961 -391.565128) (xy 339.866626 -391.556998) (xy 339.817196 -391.540937) (xy 339.770886 -391.517341)
			(xy 339.728838 -391.486791) (xy 339.692087 -391.45004) (xy 339.661537 -391.407992) (xy 339.637941 -391.361682)
			(xy 339.62188 -391.312252) (xy 339.61375 -391.260917) (xy 339.07425 -391.260917) (xy 339.06612 -391.312252)
			(xy 339.050059 -391.361682) (xy 339.026463 -391.407992) (xy 338.995913 -391.45004) (xy 338.959162 -391.486791)
			(xy 338.917114 -391.517341) (xy 338.870804 -391.540937) (xy 338.821374 -391.556998) (xy 338.770039 -391.565128)
			(xy 338.718065 -391.565128) (xy 338.66673 -391.556998) (xy 338.6173 -391.540937) (xy 338.57099 -391.517341)
			(xy 338.528942 -391.486791) (xy 338.492191 -391.45004) (xy 338.461641 -391.407992) (xy 338.438045 -391.361682)
			(xy 338.421984 -391.312252) (xy 338.413854 -391.260917) (xy 337.874354 -391.260917) (xy 337.866224 -391.312252)
			(xy 337.850163 -391.361682) (xy 337.826567 -391.407992) (xy 337.796017 -391.45004) (xy 337.759266 -391.486791)
			(xy 337.717218 -391.517341) (xy 337.670908 -391.540937) (xy 337.621478 -391.556998) (xy 337.570143 -391.565128)
			(xy 337.518169 -391.565128) (xy 337.466834 -391.556998) (xy 337.417404 -391.540937) (xy 337.371094 -391.517341)
			(xy 337.329046 -391.486791) (xy 337.292295 -391.45004) (xy 337.261745 -391.407992) (xy 337.238149 -391.361682)
			(xy 337.222088 -391.312252) (xy 337.213958 -391.260917) (xy 336.674204 -391.260917) (xy 336.666074 -391.312252)
			(xy 336.650013 -391.361682) (xy 336.626417 -391.407992) (xy 336.595867 -391.45004) (xy 336.559116 -391.486791)
			(xy 336.517068 -391.517341) (xy 336.470758 -391.540937) (xy 336.421328 -391.556998) (xy 336.369993 -391.565128)
			(xy 336.318019 -391.565128) (xy 336.266684 -391.556998) (xy 336.217254 -391.540937) (xy 336.170944 -391.517341)
			(xy 336.128896 -391.486791) (xy 336.092145 -391.45004) (xy 336.061595 -391.407992) (xy 336.037999 -391.361682)
			(xy 336.021938 -391.312252) (xy 336.013808 -391.260917) (xy 335.325568 -391.260917) (xy 335.326154 -391.264618)
			(xy 335.326154 -391.316582) (xy 335.318026 -391.367907) (xy 335.301968 -391.417329) (xy 335.278378 -391.46363)
			(xy 335.247836 -391.505671) (xy 335.211093 -391.542417) (xy 335.169054 -391.572964) (xy 335.122755 -391.596558)
			(xy 335.073334 -391.612619) (xy 335.02201 -391.620752) (xy 334.996028 -391.621264) (xy 334.971191 -391.620823)
			(xy 334.922073 -391.613403) (xy 334.874622 -391.59871) (xy 334.829905 -391.577076) (xy 334.788933 -391.54899)
			(xy 334.770476 -391.532364) (xy 334.763402 -391.526335) (xy 334.746219 -391.519294) (xy 334.736948 -391.518648)
			(xy 334.705706 -391.517886) (xy 334.69645 -391.518039) (xy 334.678997 -391.524166) (xy 334.67167 -391.529824)
			(xy 334.649105 -391.547988) (xy 334.598975 -391.577005) (xy 334.544562 -391.596858) (xy 334.487525 -391.606945)
			(xy 334.458564 -391.607548) (xy 334.435368 -391.607117) (xy 334.38943 -391.600636) (xy 334.344846 -391.587805)
			(xy 334.30249 -391.568877) (xy 334.263191 -391.544222) (xy 334.245204 -391.52957) (xy 334.238092 -391.523474)
			(xy 334.220566 -391.517378) (xy 334.134968 -391.519156) (xy 334.117696 -391.526268) (xy 334.110838 -391.532618)
			(xy 334.092395 -391.548936) (xy 334.051621 -391.576543) (xy 334.007204 -391.597801) (xy 333.960128 -391.61224)
			(xy 333.911431 -391.619541) (xy 333.88681 -391.619994) (xy 333.860819 -391.61954) (xy 333.809477 -391.611409)
			(xy 333.760039 -391.595347) (xy 333.713723 -391.571749) (xy 333.671668 -391.541196) (xy 333.634911 -391.50444)
			(xy 333.604356 -391.462386) (xy 333.580757 -391.41607) (xy 333.564693 -391.366633) (xy 333.556561 -391.315291)
			(xy 330.390177 -391.315291) (xy 330.34859 -391.345928) (xy 330.337668 -391.36955) (xy 330.338684 -391.382758)
			(xy 330.3397 -391.41146) (xy 330.339214 -391.438711) (xy 330.331458 -391.492659) (xy 330.316103 -391.544954)
			(xy 330.293461 -391.594531) (xy 330.263995 -391.640381) (xy 330.228304 -391.681572) (xy 330.187113 -391.717263)
			(xy 330.141263 -391.746729) (xy 330.091686 -391.769371) (xy 330.039391 -391.784726) (xy 329.985443 -391.792482)
			(xy 329.930941 -391.792482) (xy 329.876993 -391.784726) (xy 329.824698 -391.769371) (xy 329.775121 -391.746729)
			(xy 329.729271 -391.717263) (xy 329.68808 -391.681572) (xy 329.652389 -391.640381) (xy 329.622923 -391.594531)
			(xy 329.600281 -391.544954) (xy 329.584926 -391.492659) (xy 329.57717 -391.438711) (xy 329.576684 -391.41146)
			(xy 329.5777 -391.382758) (xy 329.578716 -391.36955) (xy 329.567794 -391.345928) (xy 329.477116 -391.279126)
			(xy 329.451208 -391.275824) (xy 329.438762 -391.280904) (xy 329.416252 -391.289439) (xy 329.369626 -391.301424)
			(xy 329.321863 -391.307457) (xy 329.297792 -391.307828) (xy 329.27054 -391.307342) (xy 329.21659 -391.299584)
			(xy 329.164293 -391.284227) (xy 329.114715 -391.261584) (xy 329.068863 -391.232116) (xy 329.027671 -391.196423)
			(xy 328.991979 -391.155231) (xy 328.962512 -391.109378) (xy 328.93987 -391.059799) (xy 328.924515 -391.007502)
			(xy 328.916758 -390.953552) (xy 328.916758 -390.899048) (xy 328.924515 -390.845098) (xy 328.93987 -390.792801)
			(xy 328.962512 -390.743222) (xy 328.991979 -390.697369) (xy 329.027671 -390.656177) (xy 329.068863 -390.620484)
			(xy 329.114715 -390.591016) (xy 329.164293 -390.568373) (xy 329.21659 -390.553016) (xy 329.27054 -390.545258)
			(xy 329.297792 -390.544812) (xy 329.327231 -390.545355) (xy 329.385407 -390.55441) (xy 329.413616 -390.562846)
			(xy 329.422232 -390.56514) (xy 329.440031 -390.564359) (xy 329.448414 -390.561322) (xy 329.476608 -390.549384)
			(xy 329.484847 -390.545565) (xy 329.498136 -390.533208) (xy 329.502516 -390.525254) (xy 329.515697 -390.499568)
			(xy 329.547014 -390.451064) (xy 329.565 -390.42848) (xy 329.570333 -390.4215) (xy 329.576316 -390.404998)
			(xy 329.576684 -390.396222) (xy 329.576684 -390.242298) (xy 329.57628 -390.233527) (xy 329.570323 -390.217022)
			(xy 329.565 -390.21004) (xy 329.547002 -390.187465) (xy 329.515686 -390.138959) (xy 329.502516 -390.113266)
			(xy 329.49811 -390.105332) (xy 329.484832 -390.092977) (xy 329.476608 -390.089136) (xy 329.448414 -390.077198)
			(xy 329.440048 -390.074074) (xy 329.422218 -390.07328) (xy 329.413616 -390.075674) (xy 329.385403 -390.084092)
			(xy 329.327229 -390.093155) (xy 329.297792 -390.093708) (xy 329.273492 -390.093343) (xy 329.225283 -390.087197)
			(xy 329.178248 -390.074967) (xy 329.155552 -390.066276) (xy 329.145127 -390.06264) (xy 329.123096 -390.063689)
			(xy 329.103534 -390.073878) (xy 329.09637 -390.082278) (xy 329.069848 -390.115919) (xy 329.011853 -390.178977)
			(xy 328.948619 -390.23678) (xy 328.88062 -390.288895) (xy 328.808367 -390.33493) (xy 328.732401 -390.37454)
			(xy 328.693018 -390.391396) (xy 328.692256 -390.391904) (xy 328.08672 -390.642856) (xy 328.043599 -390.660198)
			(xy 327.955184 -390.688881) (xy 327.864792 -390.710543) (xy 327.77298 -390.725052) (xy 327.680314 -390.732319)
			(xy 327.633838 -390.732772) (xy 325.980552 -390.732772) (xy 325.980552 -390.733026) (xy 325.96068 -390.733366)
			(xy 325.921366 -390.739183) (xy 325.883337 -390.750729) (xy 325.865236 -390.758934) (xy 325.856739 -390.763413)
			(xy 325.843642 -390.777441) (xy 325.836639 -390.79531) (xy 325.83628 -390.804908) (xy 325.83628 -391.388854)
			(xy 325.836875 -391.401476) (xy 325.848731 -391.423754) (xy 325.858886 -391.431272) (xy 325.940166 -391.48512)
			(xy 325.965566 -391.487406) (xy 325.97725 -391.48258) (xy 326.000774 -391.473099) (xy 326.049703 -391.459747)
			(xy 326.099973 -391.453013) (xy 326.125332 -391.452608) (xy 326.152581 -391.453096) (xy 326.206525 -391.460857)
			(xy 326.258815 -391.476215) (xy 326.308387 -391.498858) (xy 326.354232 -391.528325) (xy 326.395417 -391.564017)
			(xy 326.431103 -391.605207) (xy 326.460565 -391.651055) (xy 326.483202 -391.70063) (xy 326.498553 -391.752922)
			(xy 326.506307 -391.806867) (xy 326.50684 -391.834116) (xy 326.506216 -391.865767) (xy 326.495741 -391.928197)
			(xy 326.486012 -391.958322) (xy 326.483564 -391.966614) (xy 326.483824 -391.983889) (xy 326.48652 -391.992104)
			(xy 326.49668 -392.020298) (xy 326.500053 -392.028494) (xy 326.51135 -392.042134) (xy 326.518778 -392.046968)
			(xy 326.547113 -392.06413) (xy 326.599496 -392.10468) (xy 326.619867 -392.1252) (xy 332.211424 -392.1252)
			(xy 332.215495 -392.069578) (xy 332.227621 -392.015141) (xy 332.247544 -391.96305) (xy 332.27484 -391.914415)
			(xy 332.308926 -391.870272) (xy 332.349075 -391.831563) (xy 332.394433 -391.799112) (xy 332.444033 -391.773611)
			(xy 332.496817 -391.755604) (xy 332.55166 -391.745474) (xy 332.607394 -391.743437) (xy 332.662831 -391.749537)
			(xy 332.716788 -391.763643) (xy 332.768117 -391.785455) (xy 332.815723 -391.814509) (xy 332.858591 -391.850184)
			(xy 332.895808 -391.891721) (xy 332.926581 -391.938234) (xy 332.950253 -391.988731) (xy 332.966321 -392.042138)
			(xy 332.974441 -392.097314) (xy 332.97495 -392.1252) (xy 332.974441 -392.153086) (xy 332.966321 -392.208262)
			(xy 332.950253 -392.261669) (xy 332.926581 -392.312166) (xy 332.895808 -392.358679) (xy 332.858591 -392.400216)
			(xy 332.815723 -392.435891) (xy 332.768117 -392.464945) (xy 332.716788 -392.486757) (xy 332.662831 -392.500863)
			(xy 332.607394 -392.506963) (xy 332.55166 -392.504926) (xy 332.496817 -392.494796) (xy 332.444033 -392.476789)
			(xy 332.394433 -392.451288) (xy 332.349075 -392.418837) (xy 332.308926 -392.380128) (xy 332.27484 -392.335985)
			(xy 332.247544 -392.28735) (xy 332.227621 -392.235259) (xy 332.215495 -392.180822) (xy 332.211424 -392.1252)
			(xy 326.619867 -392.1252) (xy 326.646167 -392.151693) (xy 326.686334 -392.20437) (xy 326.719318 -392.26182)
			(xy 326.744558 -392.323067) (xy 326.761627 -392.387075) (xy 326.770236 -392.452758) (xy 326.770746 -392.48588)
			(xy 326.770302 -392.51599) (xy 326.763188 -392.575789) (xy 326.749057 -392.634328) (xy 326.728107 -392.690786)
			(xy 326.700632 -392.744374) (xy 326.667017 -392.794339) (xy 326.627733 -392.839981) (xy 326.58333 -392.880662)
			(xy 326.559164 -392.89863) (xy 326.549734 -392.906288) (xy 326.538724 -392.927902) (xy 326.538082 -392.940032)
			(xy 326.538082 -393.022328) (xy 326.538712 -393.034461) (xy 326.54392 -393.04468) (xy 332.211424 -393.04468)
			(xy 332.215495 -392.989058) (xy 332.227621 -392.934621) (xy 332.247544 -392.88253) (xy 332.27484 -392.833895)
			(xy 332.308926 -392.789752) (xy 332.349075 -392.751043) (xy 332.394433 -392.718592) (xy 332.444033 -392.693091)
			(xy 332.496817 -392.675084) (xy 332.55166 -392.664954) (xy 332.607394 -392.662917) (xy 332.662831 -392.669017)
			(xy 332.716788 -392.683123) (xy 332.768117 -392.704935) (xy 332.815723 -392.733989) (xy 332.858202 -392.76934)
			(xy 333.471502 -392.76934) (xy 333.471502 -392.709404) (xy 333.479325 -392.649982) (xy 333.494838 -392.592089)
			(xy 333.517774 -392.536716) (xy 333.547741 -392.48481) (xy 333.584228 -392.43726) (xy 333.626608 -392.39488)
			(xy 333.674158 -392.358393) (xy 333.726064 -392.328426) (xy 333.781437 -392.30549) (xy 333.83933 -392.289977)
			(xy 333.898752 -392.282154) (xy 333.958688 -392.282154) (xy 334.01811 -392.289977) (xy 334.076003 -392.30549)
			(xy 334.131376 -392.328426) (xy 334.183282 -392.358393) (xy 334.230832 -392.39488) (xy 334.273212 -392.43726)
			(xy 334.309699 -392.48481) (xy 334.339666 -392.536716) (xy 334.362602 -392.592089) (xy 334.378115 -392.649982)
			(xy 334.385938 -392.709404) (xy 334.386428 -392.739372) (xy 334.385938 -392.76934) (xy 334.378115 -392.828762)
			(xy 334.362602 -392.886655) (xy 334.339666 -392.942028) (xy 334.309699 -392.993934) (xy 334.273212 -393.041484)
			(xy 334.230832 -393.083864) (xy 334.183282 -393.120351) (xy 334.131376 -393.150318) (xy 334.076003 -393.173254)
			(xy 334.01811 -393.188767) (xy 333.958688 -393.19659) (xy 333.898752 -393.19659) (xy 333.83933 -393.188767)
			(xy 333.781437 -393.173254) (xy 333.726064 -393.150318) (xy 333.674158 -393.120351) (xy 333.626608 -393.083864)
			(xy 333.584228 -393.041484) (xy 333.547741 -392.993934) (xy 333.517774 -392.942028) (xy 333.494838 -392.886655)
			(xy 333.479325 -392.828762) (xy 333.471502 -392.76934) (xy 332.858202 -392.76934) (xy 332.858591 -392.769664)
			(xy 332.895808 -392.811201) (xy 332.926581 -392.857714) (xy 332.950253 -392.908211) (xy 332.966321 -392.961618)
			(xy 332.974441 -393.016794) (xy 332.97495 -393.04468) (xy 332.974441 -393.072566) (xy 332.966321 -393.127742)
			(xy 332.950253 -393.181149) (xy 332.926581 -393.231646) (xy 332.895808 -393.278159) (xy 332.858591 -393.319696)
			(xy 332.815723 -393.355371) (xy 332.768117 -393.384425) (xy 332.716788 -393.406237) (xy 332.662831 -393.420343)
			(xy 332.607394 -393.426443) (xy 332.55166 -393.424406) (xy 332.496817 -393.414276) (xy 332.444033 -393.396269)
			(xy 332.394433 -393.370768) (xy 332.349075 -393.338317) (xy 332.308926 -393.299608) (xy 332.27484 -393.255465)
			(xy 332.247544 -393.20683) (xy 332.227621 -393.154739) (xy 332.215495 -393.100302) (xy 332.211424 -393.04468)
			(xy 326.54392 -393.04468) (xy 326.549727 -393.056076) (xy 326.559164 -393.06373) (xy 326.583345 -393.081675)
			(xy 326.627731 -393.122371) (xy 326.667001 -393.168024) (xy 326.700605 -393.217994) (xy 326.728074 -393.271582)
			(xy 326.749023 -393.328039) (xy 326.763159 -393.386575) (xy 326.770283 -393.446371) (xy 326.770746 -393.47648)
			(xy 326.770284 -393.507213) (xy 326.762877 -393.56823) (xy 326.74817 -393.62791) (xy 326.726377 -393.685382)
			(xy 326.697816 -393.739808) (xy 326.662902 -393.790395) (xy 326.622146 -393.836405) (xy 326.576141 -393.877166)
			(xy 326.525558 -393.912086) (xy 326.471135 -393.940653) (xy 326.413665 -393.962453) (xy 326.353987 -393.977167)
			(xy 326.292971 -393.98458) (xy 326.262238 -393.984988) (xy 326.226606 -393.984392) (xy 326.156039 -393.974451)
			(xy 326.08755 -393.954758) (xy 326.02248 -393.925699) (xy 325.991982 -393.907264) (xy 325.980044 -393.899644)
			(xy 325.952612 -393.898882) (xy 325.862442 -393.948666) (xy 325.854697 -393.953366) (xy 325.842889 -393.967089)
			(xy 325.836595 -393.984064) (xy 325.83628 -393.993116) (xy 325.83628 -394.035534) (xy 325.844154 -394.05433)
			(xy 325.851266 -394.061442) (xy 325.872907 -394.083517) (xy 325.911233 -394.132025) (xy 325.943392 -394.184822)
			(xy 325.968911 -394.241131) (xy 325.987411 -394.300118) (xy 325.998621 -394.360914) (xy 326.002374 -394.422621)
			(xy 325.998616 -394.484328) (xy 325.987401 -394.545123) (xy 325.968896 -394.604109) (xy 325.943372 -394.660415)
			(xy 325.911209 -394.71321) (xy 325.872879 -394.761714) (xy 325.851266 -394.783818) (xy 325.844415 -394.791214)
			(xy 325.836677 -394.809813) (xy 325.83628 -394.819886) (xy 325.83628 -395.11097) (xy 325.836685 -395.12086)
			(xy 325.84407 -395.139202) (xy 325.857864 -395.15337) (xy 325.86676 -395.157706) (xy 325.96582 -395.20114)
			(xy 325.995538 -395.19606) (xy 326.006714 -395.185646) (xy 326.027975 -395.166722) (xy 326.075061 -395.134747)
			(xy 326.12638 -395.110135) (xy 326.180791 -395.093433) (xy 326.237081 -395.085014) (xy 326.26554 -395.084554)
			(xy 326.292792 -395.085043) (xy 326.346741 -395.092805) (xy 326.399036 -395.108165) (xy 326.448613 -395.13081)
			(xy 326.494463 -395.160281) (xy 326.535653 -395.195976) (xy 326.571343 -395.237169) (xy 326.600809 -395.283022)
			(xy 326.623449 -395.332602) (xy 326.638804 -395.384898) (xy 326.64656 -395.438848) (xy 326.64656 -395.493352)
			(xy 326.638804 -395.547302) (xy 326.623449 -395.599598) (xy 326.600809 -395.649178) (xy 326.571343 -395.695031)
			(xy 326.535653 -395.736224) (xy 326.494463 -395.771919) (xy 326.448613 -395.80139) (xy 326.399036 -395.824035)
			(xy 326.346741 -395.839395) (xy 326.292792 -395.847157) (xy 326.26554 -395.84757) (xy 326.237089 -395.847035)
			(xy 326.180818 -395.838577) (xy 326.126423 -395.82187) (xy 326.075105 -395.797285) (xy 326.027999 -395.765365)
			(xy 326.006714 -395.746478) (xy 325.995538 -395.736064) (xy 325.96582 -395.730984) (xy 325.86676 -395.774418)
			(xy 325.857894 -395.778801) (xy 325.844114 -395.792963) (xy 325.836687 -395.811274) (xy 325.83628 -395.821154)
			(xy 325.83628 -395.883638) (xy 325.836709 -395.893706) (xy 325.844431 -395.912302) (xy 325.851266 -395.919706)
			(xy 326.06361 -396.13205) (xy 326.070953 -396.138865) (xy 326.089416 -396.146601) (xy 326.099424 -396.147036)
			(xy 327.932542 -396.147036) (xy 327.960736 -396.123668) (xy 327.964038 -396.105634) (xy 327.969696 -396.078407)
			(xy 327.987847 -396.025843) (xy 328.013437 -395.976472) (xy 328.045922 -395.931338) (xy 328.084616 -395.891398)
			(xy 328.128697 -395.857499) (xy 328.177232 -395.830357) (xy 328.229194 -395.810549) (xy 328.28348 -395.798494)
			(xy 328.338942 -395.794447) (xy 328.394404 -395.798494) (xy 328.44869 -395.810549) (xy 328.500652 -395.830357)
			(xy 328.549187 -395.857499) (xy 328.593268 -395.891398) (xy 328.631962 -395.931338) (xy 328.664447 -395.976472)
			(xy 328.690037 -396.025843) (xy 328.708188 -396.078407) (xy 328.713846 -396.105634) (xy 328.717148 -396.123668)
			(xy 328.745342 -396.147036) (xy 329.27544 -396.147036) (xy 329.303888 -396.12189) (xy 329.306428 -396.103094)
			(xy 329.311746 -396.0684) (xy 329.330687 -396.000814) (xy 329.358741 -395.936476) (xy 329.395375 -395.876605)
			(xy 329.417172 -395.849094) (xy 329.42251 -395.842115) (xy 329.4285 -395.825614) (xy 329.428856 -395.816836)
			(xy 329.428856 -395.662912) (xy 329.428438 -395.654146) (xy 329.422456 -395.637661) (xy 329.417172 -395.630654)
			(xy 329.39546 -395.603255) (xy 329.358961 -395.543631) (xy 329.330971 -395.479571) (xy 329.312019 -395.41228)
			(xy 329.302462 -395.343028) (xy 329.301856 -395.308074) (xy 329.302321 -395.277343) (xy 329.309732 -395.21633)
			(xy 329.324443 -395.156655) (xy 329.346239 -395.099188) (xy 329.374802 -395.044767) (xy 329.409716 -394.994185)
			(xy 329.450473 -394.94818) (xy 329.496477 -394.907423) (xy 329.547058 -394.872507) (xy 329.601479 -394.843943)
			(xy 329.658945 -394.822146) (xy 329.71862 -394.807434) (xy 329.779633 -394.800022) (xy 329.810364 -394.799566)
			(xy 329.822 -394.79961) (xy 329.84525 -394.800629) (xy 329.856846 -394.801598) (xy 329.866498 -394.802614)
			(xy 329.884786 -394.79728) (xy 329.95489 -394.743432) (xy 329.964542 -394.727176) (xy 329.96632 -394.717778)
			(xy 329.971288 -394.691512) (xy 329.987605 -394.640608) (xy 330.010866 -394.592479) (xy 330.040617 -394.548068)
			(xy 330.076275 -394.508243) (xy 330.117142 -394.473785) (xy 330.162418 -394.445368) (xy 330.211217 -394.423547)
			(xy 330.262583 -394.408751) (xy 330.315513 -394.401268) (xy 330.34224 -394.400786) (xy 330.36949 -394.401275)
			(xy 330.423433 -394.409036) (xy 330.475724 -394.424394) (xy 330.525296 -394.447037) (xy 330.571142 -394.476505)
			(xy 330.612328 -394.512196) (xy 330.648016 -394.553385) (xy 330.677479 -394.599234) (xy 330.700118 -394.648808)
			(xy 330.715472 -394.7011) (xy 330.723228 -394.755044) (xy 330.723748 -394.782294) (xy 330.723283 -394.809246)
			(xy 330.715696 -394.862612) (xy 330.700671 -394.914379) (xy 330.678507 -394.963515) (xy 330.649648 -395.009042)
			(xy 330.614666 -395.050052) (xy 330.574259 -395.085729) (xy 330.529232 -395.115363) (xy 330.480482 -395.138362)
			(xy 330.428979 -395.154269) (xy 330.402438 -395.158976) (xy 330.392786 -395.1605) (xy 330.37653 -395.170152)
			(xy 330.32192 -395.239748) (xy 330.316586 -395.257782) (xy 330.317348 -395.267434) (xy 330.318872 -395.308074)
			(xy 330.318288 -395.343027) (xy 330.308709 -395.412274) (xy 330.289741 -395.479558) (xy 330.261742 -395.543612)
			(xy 330.225238 -395.603231) (xy 330.203556 -395.630654) (xy 330.198223 -395.637634) (xy 330.192244 -395.654136)
			(xy 330.191872 -395.662912) (xy 330.191872 -395.816836) (xy 330.192282 -395.825604) (xy 330.198254 -395.842099)
			(xy 330.203556 -395.849094) (xy 330.225362 -395.876599) (xy 330.262002 -395.936469) (xy 330.290061 -396.000809)
			(xy 330.309005 -396.068395) (xy 330.3143 -396.103094) (xy 330.31684 -396.12189) (xy 330.345288 -396.147036)
			(xy 330.397612 -396.147036) (xy 330.40768 -396.146609) (xy 330.426275 -396.138884) (xy 330.43368 -396.13205)
			(xy 331.558646 -395.007084) (xy 331.566054 -395.000393) (xy 331.584489 -394.992794) (xy 331.59446 -394.992352)
			(xy 331.607668 -394.992352) (xy 331.757274 -394.842746) (xy 331.764674 -394.835906) (xy 331.783273 -394.828191)
			(xy 331.793342 -394.82776) (xy 333.128112 -394.82776) (xy 333.156052 -394.804646) (xy 333.159354 -394.786358)
			(xy 333.165092 -394.75844) (xy 333.182587 -394.704196) (xy 333.206685 -394.652544) (xy 333.237013 -394.604287)
			(xy 333.273101 -394.560171) (xy 333.293466 -394.540232) (xy 333.302102 -394.53185) (xy 333.31023 -394.509498)
			(xy 333.298292 -394.405104) (xy 333.285338 -394.385292) (xy 333.274924 -394.378942) (xy 333.251554 -394.364699)
			(xy 333.208057 -394.331481) (xy 333.168826 -394.293318) (xy 333.134419 -394.250755) (xy 333.105327 -394.204396)
			(xy 333.093314 -394.179806) (xy 333.087218 -394.167106) (xy 333.064358 -394.151612) (xy 332.947518 -394.144246)
			(xy 332.923134 -394.156692) (xy 332.915514 -394.16863) (xy 332.900426 -394.191509) (xy 332.864731 -394.233097)
			(xy 332.823454 -394.269149) (xy 332.777443 -394.298925) (xy 332.727645 -394.321812) (xy 332.675085 -394.337339)
			(xy 332.620845 -394.345186) (xy 332.593442 -394.345668) (xy 332.56619 -394.345208) (xy 332.51224 -394.337456)
			(xy 332.459943 -394.322106) (xy 332.410363 -394.299468) (xy 332.364509 -394.270004) (xy 332.323316 -394.234314)
			(xy 332.287621 -394.193125) (xy 332.258152 -394.147274) (xy 332.235509 -394.097697) (xy 332.220153 -394.045401)
			(xy 332.212395 -393.991452) (xy 332.212395 -393.936948) (xy 332.220153 -393.882999) (xy 332.235509 -393.830703)
			(xy 332.258152 -393.781126) (xy 332.287621 -393.735275) (xy 332.323316 -393.694086) (xy 332.364509 -393.658396)
			(xy 332.410363 -393.628932) (xy 332.459943 -393.606294) (xy 332.51224 -393.590944) (xy 332.56619 -393.583192)
			(xy 332.593442 -393.582652) (xy 332.622078 -393.583161) (xy 332.678709 -393.591715) (xy 332.733424 -393.608639)
			(xy 332.784994 -393.633553) (xy 332.832259 -393.665897) (xy 332.874158 -393.704943) (xy 332.909749 -393.749815)
			(xy 332.924404 -393.774422) (xy 332.931516 -393.786614) (xy 332.955392 -393.80033) (xy 333.072486 -393.798044)
			(xy 333.095854 -393.78382) (xy 333.102458 -393.771374) (xy 333.117407 -393.744131) (xy 333.153554 -393.693585)
			(xy 333.196205 -393.648392) (xy 333.244576 -393.609382) (xy 333.297778 -393.577273) (xy 333.354835 -393.552655)
			(xy 333.414697 -393.535979) (xy 333.476264 -393.527552) (xy 333.507334 -393.527026) (xy 333.537299 -393.527518)
			(xy 333.596717 -393.535345) (xy 333.654605 -393.550861) (xy 333.709972 -393.573799) (xy 333.761871 -393.603769)
			(xy 333.809415 -393.640256) (xy 333.851789 -393.682636) (xy 333.888269 -393.730185) (xy 333.918231 -393.782089)
			(xy 333.941161 -393.83746) (xy 333.956668 -393.89535) (xy 333.964486 -393.954769) (xy 333.965042 -393.984734)
			(xy 333.964514 -394.01561) (xy 333.956172 -394.076798) (xy 333.939685 -394.136309) (xy 333.915352 -394.193067)
			(xy 333.883613 -394.24604) (xy 333.845045 -394.294268) (xy 333.823056 -394.31595) (xy 333.81442 -394.324332)
			(xy 333.806292 -394.346684) (xy 333.81823 -394.451078) (xy 333.831184 -394.47089) (xy 333.841598 -394.47724)
			(xy 333.869306 -394.4942) (xy 333.920073 -394.534732) (xy 333.964592 -394.582042) (xy 334.001966 -394.635177)
			(xy 334.031441 -394.693068) (xy 334.052425 -394.754548) (xy 334.059022 -394.786358) (xy 334.062324 -394.804646)
			(xy 334.090264 -394.82776) (xy 335.547716 -394.82776) (xy 335.57591 -394.803122) (xy 335.578704 -394.784072)
			(xy 335.582476 -394.760647) (xy 335.59586 -394.715129) (xy 335.605374 -394.693394) (xy 335.609692 -394.683996)
			(xy 335.610454 -394.66393) (xy 335.578196 -394.57757) (xy 335.56448 -394.562838) (xy 335.555082 -394.55852)
			(xy 335.530711 -394.546828) (xy 335.485823 -394.51672) (xy 335.446432 -394.47971) (xy 335.413586 -394.436785)
			(xy 335.388161 -394.389088) (xy 335.370835 -394.33789) (xy 335.362069 -394.284555) (xy 335.361534 -394.25753)
			(xy 335.362015 -394.23154) (xy 335.370143 -394.180201) (xy 335.386203 -394.130765) (xy 335.4098 -394.08445)
			(xy 335.440352 -394.042398) (xy 335.477108 -394.005644) (xy 335.519161 -393.975093) (xy 335.565476 -393.951498)
			(xy 335.614912 -393.93544) (xy 335.666252 -393.927314) (xy 335.692242 -393.926822) (xy 335.708675 -393.92705)
			(xy 335.741374 -393.930359) (xy 335.75752 -393.933426) (xy 335.770474 -393.935966) (xy 335.79562 -393.928092)
			(xy 335.872836 -393.846304) (xy 335.87944 -393.820904) (xy 335.876138 -393.808204) (xy 335.869163 -393.779756)
			(xy 335.86165 -393.721666) (xy 335.861152 -393.69238) (xy 335.86166 -393.661492) (xy 335.86997 -393.600276)
			(xy 335.886435 -393.540734) (xy 335.910757 -393.483946) (xy 335.926176 -393.457176) (xy 335.932018 -393.44727)
			(xy 335.934304 -393.424918) (xy 335.90103 -393.329668) (xy 335.885282 -393.313666) (xy 335.874614 -393.309602)
			(xy 335.851247 -393.3004) (xy 335.807377 -393.275957) (xy 335.767706 -393.245164) (xy 335.733145 -393.208729)
			(xy 335.704488 -393.167488) (xy 335.682394 -393.12239) (xy 335.667369 -393.074471) (xy 335.659761 -393.024832)
			(xy 335.659222 -392.999722) (xy 335.659732 -392.973735) (xy 335.667862 -392.9224) (xy 335.683923 -392.87297)
			(xy 335.707519 -392.82666) (xy 335.738069 -392.784612) (xy 335.77482 -392.747861) (xy 335.816868 -392.717311)
			(xy 335.863178 -392.693715) (xy 335.912608 -392.677654) (xy 335.963943 -392.669524) (xy 336.015917 -392.669524)
			(xy 336.067252 -392.677654) (xy 336.116682 -392.693715) (xy 336.162992 -392.717311) (xy 336.20504 -392.747861)
			(xy 336.241791 -392.784612) (xy 336.272341 -392.82666) (xy 336.295937 -392.87297) (xy 336.311998 -392.9224)
			(xy 336.320128 -392.973735) (xy 336.320638 -392.999722) (xy 336.320114 -393.026824) (xy 336.311302 -393.080307)
			(xy 336.303112 -393.106148) (xy 336.299302 -393.11707) (xy 336.301842 -393.139422) (xy 336.35442 -393.225274)
			(xy 336.37347 -393.23772) (xy 336.384646 -393.239498) (xy 336.413956 -393.244235) (xy 336.471114 -393.2603)
			(xy 336.525715 -393.28362) (xy 336.576842 -393.313804) (xy 336.623638 -393.350345) (xy 336.665317 -393.39263)
			(xy 336.701179 -393.439948) (xy 336.730622 -393.491506) (xy 336.753153 -393.546438) (xy 336.768391 -393.603822)
			(xy 336.776083 -393.662694) (xy 336.776568 -393.69238) (xy 336.776047 -393.723443) (xy 336.767631 -393.784997)
			(xy 336.759804 -393.815062) (xy 336.75701 -393.825222) (xy 336.75955 -393.845034) (xy 336.807048 -393.92733)
			(xy 336.82305 -393.939522) (xy 336.83321 -393.942062) (xy 336.862316 -393.950069) (xy 336.918279 -393.972701)
			(xy 336.97078 -394.002495) (xy 337.018909 -394.038932) (xy 337.06183 -394.081381) (xy 337.098797 -394.129104)
			(xy 337.129169 -394.181273) (xy 337.152419 -394.236983) (xy 337.168142 -394.295265) (xy 337.176067 -394.355109)
			(xy 337.176618 -394.385292) (xy 337.176494 -394.399427) (xy 337.174713 -394.427641) (xy 337.173062 -394.44168)
			(xy 337.172326 -394.450285) (xy 337.175969 -394.467156) (xy 337.180174 -394.4747) (xy 337.195922 -394.5001)
			(xy 337.200622 -394.507169) (xy 337.213729 -394.517944) (xy 337.221576 -394.521182) (xy 337.24513 -394.530485)
			(xy 337.289324 -394.555211) (xy 337.329235 -394.586381) (xy 337.36393 -394.623269) (xy 337.392599 -394.665013)
			(xy 337.414573 -394.710637) (xy 337.429339 -394.759077) (xy 337.433412 -394.784072) (xy 337.436206 -394.803122)
			(xy 337.4644 -394.82776) (xy 337.594448 -394.82776) (xy 337.604446 -394.827263) (xy 337.622915 -394.819593)
			(xy 337.637043 -394.805441) (xy 337.64468 -394.786959) (xy 337.645248 -394.77696) (xy 337.645248 -394.76553)
			(xy 337.635596 -394.74521) (xy 337.62696 -394.737844) (xy 337.605097 -394.719159) (xy 337.565738 -394.677224)
			(xy 337.531942 -394.630688) (xy 337.50424 -394.580286) (xy 337.48307 -394.526812) (xy 337.468765 -394.471107)
			(xy 337.46155 -394.414048) (xy 337.461098 -394.385292) (xy 337.461614 -394.354228) (xy 337.47002 -394.292672)
			(xy 337.477862 -394.26261) (xy 337.480656 -394.25245) (xy 337.478116 -394.232638) (xy 337.430618 -394.150342)
			(xy 337.414616 -394.13815) (xy 337.404456 -394.13561) (xy 337.375345 -394.127607) (xy 337.319371 -394.104982)
			(xy 337.266857 -394.075193) (xy 337.218715 -394.038759) (xy 337.175782 -393.996312) (xy 337.138802 -393.948589)
			(xy 337.108417 -393.896418) (xy 337.085155 -393.840705) (xy 337.06942 -393.782418) (xy 337.061485 -393.722567)
			(xy 337.061048 -393.69238) (xy 337.061556 -393.661492) (xy 337.069866 -393.600276) (xy 337.086331 -393.540734)
			(xy 337.110653 -393.483946) (xy 337.126072 -393.457176) (xy 337.131914 -393.44727) (xy 337.1342 -393.424918)
			(xy 337.100926 -393.329668) (xy 337.085178 -393.313666) (xy 337.07451 -393.309602) (xy 337.051138 -393.300404)
			(xy 337.007257 -393.275969) (xy 336.967575 -393.24518) (xy 336.933003 -393.208747) (xy 336.904337 -393.167505)
			(xy 336.882236 -393.122404) (xy 336.867206 -393.07448) (xy 336.859595 -393.024835) (xy 336.859118 -392.999722)
			(xy 336.859628 -392.973735) (xy 336.867758 -392.9224) (xy 336.883819 -392.87297) (xy 336.907415 -392.82666)
			(xy 336.937965 -392.784612) (xy 336.974716 -392.747861) (xy 337.016764 -392.717311) (xy 337.063074 -392.693715)
			(xy 337.112504 -392.677654) (xy 337.163839 -392.669524) (xy 337.215813 -392.669524) (xy 337.267148 -392.677654)
			(xy 337.316578 -392.693715) (xy 337.362888 -392.717311) (xy 337.404936 -392.747861) (xy 337.441687 -392.784612)
			(xy 337.472237 -392.82666) (xy 337.495833 -392.87297) (xy 337.511894 -392.9224) (xy 337.520024 -392.973735)
			(xy 337.520534 -392.999722) (xy 337.52001 -393.026824) (xy 337.511197 -393.080307) (xy 337.503008 -393.106148)
			(xy 337.499198 -393.11707) (xy 337.501738 -393.139422) (xy 337.554316 -393.225274) (xy 337.573366 -393.23772)
			(xy 337.584542 -393.239498) (xy 337.613852 -393.244235) (xy 337.67101 -393.260299) (xy 337.725612 -393.283619)
			(xy 337.77674 -393.313803) (xy 337.823536 -393.350344) (xy 337.865215 -393.392629) (xy 337.901078 -393.439947)
			(xy 337.930521 -393.491505) (xy 337.953052 -393.546437) (xy 337.968291 -393.603821) (xy 337.975983 -393.662694)
			(xy 337.976464 -393.69238) (xy 337.975943 -393.723443) (xy 337.967527 -393.784997) (xy 337.9597 -393.815062)
			(xy 337.956906 -393.825222) (xy 337.959446 -393.845034) (xy 338.006944 -393.92733) (xy 338.022946 -393.939522)
			(xy 338.033106 -393.942062) (xy 338.062212 -393.950069) (xy 338.118175 -393.972701) (xy 338.170677 -394.002494)
			(xy 338.218807 -394.038931) (xy 338.261728 -394.08138) (xy 338.298695 -394.129103) (xy 338.329068 -394.181272)
			(xy 338.352318 -394.236982) (xy 338.368041 -394.295265) (xy 338.375966 -394.355109) (xy 338.376514 -394.385292)
			(xy 338.37639 -394.399427) (xy 338.374609 -394.427641) (xy 338.372958 -394.44168) (xy 338.372222 -394.450285)
			(xy 338.375864 -394.467156) (xy 338.38007 -394.4747) (xy 338.395818 -394.5001) (xy 338.40052 -394.507168)
			(xy 338.413624 -394.517947) (xy 338.421472 -394.521182) (xy 338.445041 -394.530477) (xy 338.489267 -394.555191)
			(xy 338.52921 -394.586354) (xy 338.563939 -394.62324) (xy 338.592643 -394.664987) (xy 338.61465 -394.710619)
			(xy 338.629448 -394.759072) (xy 338.633562 -394.784072) (xy 338.636356 -394.803122) (xy 338.66455 -394.82776)
			(xy 338.794344 -394.82776) (xy 338.804343 -394.827264) (xy 338.822813 -394.819595) (xy 338.836942 -394.805442)
			(xy 338.84458 -394.78696) (xy 338.845144 -394.77696) (xy 338.845144 -394.76553) (xy 338.835492 -394.74521)
			(xy 338.826856 -394.737844) (xy 338.804993 -394.719159) (xy 338.765634 -394.677223) (xy 338.731838 -394.630688)
			(xy 338.704137 -394.580286) (xy 338.682968 -394.526811) (xy 338.668663 -394.471106) (xy 338.661447 -394.414048)
			(xy 338.660994 -394.385292) (xy 338.661501 -394.354165) (xy 338.669916 -394.292483) (xy 338.677758 -394.262356)
			(xy 338.680552 -394.252196) (xy 338.678012 -394.232384) (xy 338.630768 -394.150342) (xy 338.614766 -394.13815)
			(xy 338.604606 -394.13561) (xy 338.575497 -394.127604) (xy 338.519528 -394.104975) (xy 338.46702 -394.075184)
			(xy 338.418883 -394.038748) (xy 338.375955 -393.996301) (xy 338.338979 -393.948578) (xy 338.308598 -393.896409)
			(xy 338.285339 -393.840698) (xy 338.269606 -393.782413) (xy 338.261672 -393.722566) (xy 338.261198 -393.69238)
			(xy 338.261706 -393.661492) (xy 338.270017 -393.600277) (xy 338.286484 -393.540735) (xy 338.310808 -393.483949)
			(xy 338.326222 -393.457176) (xy 338.332064 -393.44727) (xy 338.33435 -393.424918) (xy 338.301076 -393.329668)
			(xy 338.285328 -393.313666) (xy 338.27466 -393.309602) (xy 338.25129 -393.300402) (xy 338.207416 -393.275962)
			(xy 338.167739 -393.245172) (xy 338.133173 -393.208737) (xy 338.104512 -393.167496) (xy 338.082414 -393.122397)
			(xy 338.067387 -393.074475) (xy 338.059777 -393.024833) (xy 338.059268 -392.999722) (xy 338.059778 -392.973735)
			(xy 338.067908 -392.9224) (xy 338.083969 -392.87297) (xy 338.107565 -392.82666) (xy 338.138115 -392.784612)
			(xy 338.174866 -392.747861) (xy 338.216914 -392.717311) (xy 338.263224 -392.693715) (xy 338.312654 -392.677654)
			(xy 338.363989 -392.669524) (xy 338.415963 -392.669524) (xy 338.467298 -392.677654) (xy 338.516728 -392.693715)
			(xy 338.563038 -392.717311) (xy 338.605086 -392.747861) (xy 338.641837 -392.784612) (xy 338.672387 -392.82666)
			(xy 338.695983 -392.87297) (xy 338.712044 -392.9224) (xy 338.720174 -392.973735) (xy 338.720684 -392.999722)
			(xy 338.720159 -393.026824) (xy 338.711346 -393.080307) (xy 338.703158 -393.106148) (xy 338.699348 -393.11707)
			(xy 338.701888 -393.139422) (xy 338.754466 -393.225274) (xy 338.773516 -393.23772) (xy 338.784692 -393.239498)
			(xy 338.814 -393.244237) (xy 338.871153 -393.260307) (xy 338.925749 -393.28363) (xy 338.976872 -393.313816)
			(xy 339.023663 -393.350358) (xy 339.065337 -393.392643) (xy 339.101195 -393.43996) (xy 339.130635 -393.491516)
			(xy 339.153162 -393.546446) (xy 339.168399 -393.603826) (xy 339.17609 -393.662695) (xy 339.176614 -393.69238)
			(xy 339.176093 -393.723443) (xy 339.167678 -393.784997) (xy 339.15985 -393.815062) (xy 339.157056 -393.825222)
			(xy 339.159596 -393.845034) (xy 339.207094 -393.92733) (xy 339.223096 -393.939522) (xy 339.233256 -393.942062)
			(xy 339.262352 -393.950078) (xy 339.318293 -393.972724) (xy 339.370772 -394.002528) (xy 339.418878 -394.038972)
			(xy 339.461775 -394.081423) (xy 339.49872 -394.129146) (xy 339.52907 -394.181311) (xy 339.552299 -394.237013)
			(xy 339.568005 -394.295285) (xy 339.575913 -394.355116) (xy 339.57641 -394.385292) (xy 339.576286 -394.399427)
			(xy 339.574505 -394.427641) (xy 339.572854 -394.44168) (xy 339.572118 -394.450285) (xy 339.57576 -394.467156)
			(xy 339.579966 -394.4747) (xy 339.595714 -394.5001) (xy 339.600422 -394.50716) (xy 339.613535 -394.517916)
			(xy 339.621368 -394.521182) (xy 339.644937 -394.530477) (xy 339.689163 -394.55519) (xy 339.729107 -394.586354)
			(xy 339.763837 -394.623239) (xy 339.792541 -394.664986) (xy 339.814549 -394.710619) (xy 339.829347 -394.759072)
			(xy 339.833458 -394.784072) (xy 339.836252 -394.803122) (xy 339.864446 -394.82776) (xy 339.994494 -394.82776)
			(xy 340.004513 -394.827341) (xy 340.023025 -394.819671) (xy 340.03719 -394.805497) (xy 340.044848 -394.786979)
			(xy 340.045294 -394.77696) (xy 340.045294 -394.76553) (xy 340.035642 -394.74521) (xy 340.027006 -394.737844)
			(xy 340.005145 -394.719158) (xy 339.96579 -394.67722) (xy 339.931998 -394.630684) (xy 339.9043 -394.580282)
			(xy 339.883133 -394.526808) (xy 339.86883 -394.471104) (xy 339.861615 -394.414047) (xy 339.861144 -394.385292)
			(xy 339.86166 -394.354228) (xy 339.870065 -394.292672) (xy 339.877908 -394.26261) (xy 339.880702 -394.25245)
			(xy 339.878162 -394.232638) (xy 339.830664 -394.150342) (xy 339.814662 -394.13815) (xy 339.804502 -394.13561)
			(xy 339.775394 -394.127604) (xy 339.719425 -394.104974) (xy 339.666917 -394.075183) (xy 339.618781 -394.038747)
			(xy 339.575852 -393.9963) (xy 339.538877 -393.948577) (xy 339.508497 -393.896408) (xy 339.485238 -393.840697)
			(xy 339.469505 -393.782413) (xy 339.461571 -393.722565) (xy 339.461094 -393.69238) (xy 339.461602 -393.661492)
			(xy 339.469913 -393.600276) (xy 339.486379 -393.540735) (xy 339.510703 -393.483948) (xy 339.526118 -393.457176)
			(xy 339.53196 -393.44727) (xy 339.534246 -393.424918) (xy 339.500972 -393.329668) (xy 339.485224 -393.313666)
			(xy 339.474556 -393.309602) (xy 339.451187 -393.300401) (xy 339.407312 -393.275962) (xy 339.367636 -393.245171)
			(xy 339.333071 -393.208736) (xy 339.30441 -393.167496) (xy 339.282312 -393.122396) (xy 339.267286 -393.074475)
			(xy 339.259676 -393.024833) (xy 339.259164 -392.999722) (xy 339.259674 -392.973735) (xy 339.267804 -392.9224)
			(xy 339.283865 -392.87297) (xy 339.307461 -392.82666) (xy 339.338011 -392.784612) (xy 339.374762 -392.747861)
			(xy 339.41681 -392.717311) (xy 339.46312 -392.693715) (xy 339.51255 -392.677654) (xy 339.563885 -392.669524)
			(xy 339.615859 -392.669524) (xy 339.667194 -392.677654) (xy 339.716624 -392.693715) (xy 339.762934 -392.717311)
			(xy 339.804982 -392.747861) (xy 339.841733 -392.784612) (xy 339.872283 -392.82666) (xy 339.895879 -392.87297)
			(xy 339.91194 -392.9224) (xy 339.92007 -392.973735) (xy 339.92058 -392.999722) (xy 339.920055 -393.026824)
			(xy 339.911242 -393.080307) (xy 339.903054 -393.106148) (xy 339.899244 -393.11707) (xy 339.901784 -393.139422)
			(xy 339.954362 -393.225274) (xy 339.973412 -393.23772) (xy 339.984588 -393.239498) (xy 340.013896 -393.244237)
			(xy 340.07105 -393.260306) (xy 340.125646 -393.283629) (xy 340.176769 -393.313815) (xy 340.223561 -393.350357)
			(xy 340.265235 -393.392642) (xy 340.301094 -393.439959) (xy 340.330534 -393.491515) (xy 340.353061 -393.546445)
			(xy 340.368298 -393.603826) (xy 340.375989 -393.662695) (xy 340.37651 -393.69238) (xy 340.375989 -393.723443)
			(xy 340.367574 -393.784997) (xy 340.359746 -393.815062) (xy 340.356952 -393.825222) (xy 340.359492 -393.845034)
			(xy 340.40699 -393.92733) (xy 340.422992 -393.939522) (xy 340.433152 -393.942062) (xy 340.46226 -393.950066)
			(xy 340.518229 -393.972694) (xy 340.570737 -394.002484) (xy 340.618872 -394.038919) (xy 340.661799 -394.081367)
			(xy 340.698771 -394.129091) (xy 340.729147 -394.181262) (xy 340.752401 -394.236974) (xy 340.768126 -394.29526)
			(xy 340.776052 -394.355107) (xy 340.77656 -394.385292) (xy 340.776436 -394.399427) (xy 340.774655 -394.427641)
			(xy 340.773004 -394.44168) (xy 340.772268 -394.450285) (xy 340.775907 -394.467158) (xy 340.780116 -394.4747)
			(xy 340.795864 -394.5001) (xy 340.800567 -394.507165) (xy 340.813678 -394.51793) (xy 340.821518 -394.521182)
			(xy 340.845799 -394.530769) (xy 340.891231 -394.556475) (xy 340.932065 -394.588996) (xy 340.967285 -394.627524)
			(xy 340.99602 -394.671104) (xy 341.017557 -394.718655) (xy 341.024972 -394.743686) (xy 341.02675 -394.75029)
			(xy 341.0331 -394.761466) (xy 341.037926 -394.766292) (xy 341.045292 -394.773132) (xy 341.063825 -394.780874)
			(xy 341.083909 -394.780874) (xy 341.102442 -394.773132) (xy 341.109808 -394.766292) (xy 341.162132 -394.713968)
			(xy 341.164672 -394.676122) (xy 341.153242 -394.660882) (xy 341.135811 -394.636976) (xy 341.106589 -394.585531)
			(xy 341.084237 -394.53075) (xy 341.069125 -394.473547) (xy 341.061507 -394.414875) (xy 341.06104 -394.385292)
			(xy 341.061556 -394.354228) (xy 341.069961 -394.292672) (xy 341.077804 -394.26261) (xy 341.080598 -394.25245)
			(xy 341.078058 -394.232638) (xy 341.03056 -394.150342) (xy 341.014558 -394.13815) (xy 341.004398 -394.13561)
			(xy 340.97529 -394.127604) (xy 340.919321 -394.104974) (xy 340.866814 -394.075182) (xy 340.818678 -394.038746)
			(xy 340.77575 -393.996299) (xy 340.738775 -393.948576) (xy 340.708395 -393.896407) (xy 340.685137 -393.840697)
			(xy 340.669404 -393.782412) (xy 340.66147 -393.722565) (xy 340.66099 -393.69238) (xy 340.661486 -393.66146)
			(xy 340.669781 -393.600178) (xy 340.686245 -393.54057) (xy 340.710578 -393.483718) (xy 340.726014 -393.456922)
			(xy 340.73211 -393.44727) (xy 340.734396 -393.424918) (xy 340.700868 -393.329668) (xy 340.68512 -393.313666)
			(xy 340.674452 -393.309602) (xy 340.651096 -393.300393) (xy 340.607251 -393.27594) (xy 340.567606 -393.24514)
			(xy 340.533073 -393.2087) (xy 340.504446 -393.167459) (xy 340.482382 -393.122364) (xy 340.467389 -393.074452)
			(xy 340.459812 -393.024824) (xy 340.459314 -392.999722) (xy 340.459824 -392.973735) (xy 340.467954 -392.9224)
			(xy 340.484015 -392.87297) (xy 340.507611 -392.82666) (xy 340.538161 -392.784612) (xy 340.574912 -392.747861)
			(xy 340.61696 -392.717311) (xy 340.66327 -392.693715) (xy 340.7127 -392.677654) (xy 340.764035 -392.669524)
			(xy 340.816009 -392.669524) (xy 340.867344 -392.677654) (xy 340.916774 -392.693715) (xy 340.963084 -392.717311)
			(xy 341.005132 -392.747861) (xy 341.041883 -392.784612) (xy 341.072433 -392.82666) (xy 341.096029 -392.87297)
			(xy 341.11209 -392.9224) (xy 341.12022 -392.973735) (xy 341.12073 -392.999722) (xy 341.120206 -393.026824)
			(xy 341.111393 -393.080307) (xy 341.103204 -393.106148) (xy 341.099394 -393.11707) (xy 341.101934 -393.139422)
			(xy 341.154512 -393.225528) (xy 341.173308 -393.23772) (xy 341.184738 -393.239498) (xy 341.214036 -393.244246)
			(xy 341.271169 -393.260331) (xy 341.325744 -393.283666) (xy 341.376844 -393.31386) (xy 341.423612 -393.350406)
			(xy 341.465263 -393.392692) (xy 341.501098 -393.440007) (xy 341.530517 -393.491557) (xy 341.553024 -393.546478)
			(xy 341.568244 -393.603847) (xy 341.575919 -393.662703) (xy 341.576406 -393.69238) (xy 341.575885 -393.723443)
			(xy 341.56747 -393.784997) (xy 341.559642 -393.815062) (xy 341.556848 -393.825222) (xy 341.559388 -393.845034)
			(xy 341.606886 -393.92733) (xy 341.622888 -393.939522) (xy 341.633048 -393.942062) (xy 341.662023 -393.950025)
			(xy 341.717747 -393.972511) (xy 341.770057 -394.002084) (xy 341.794338 -394.019786) (xy 341.809578 -394.031216)
			(xy 341.847424 -394.028676) (xy 341.918798 -393.957302) (xy 341.923878 -393.924028) (xy 341.91575 -393.909296)
			(xy 341.902728 -393.884215) (xy 341.882281 -393.83153) (xy 341.868487 -393.776725) (xy 341.861557 -393.720637)
			(xy 341.86114 -393.69238) (xy 341.861648 -393.661491) (xy 341.869958 -393.600276) (xy 341.886423 -393.540733)
			(xy 341.910744 -393.483946) (xy 341.926164 -393.457176) (xy 341.932006 -393.44727) (xy 341.934292 -393.424918)
			(xy 341.901018 -393.329668) (xy 341.88527 -393.313666) (xy 341.874602 -393.309602) (xy 341.85123 -393.300404)
			(xy 341.80735 -393.275968) (xy 341.767669 -393.245179) (xy 341.733099 -393.208745) (xy 341.704433 -393.167504)
			(xy 341.682332 -393.122403) (xy 341.667303 -393.074479) (xy 341.659692 -393.024834) (xy 341.65921 -392.999722)
			(xy 341.65972 -392.973735) (xy 341.66785 -392.9224) (xy 341.683911 -392.87297) (xy 341.707507 -392.82666)
			(xy 341.738057 -392.784612) (xy 341.774808 -392.747861) (xy 341.816856 -392.717311) (xy 341.863166 -392.693715)
			(xy 341.912596 -392.677654) (xy 341.963931 -392.669524) (xy 342.015905 -392.669524) (xy 342.06724 -392.677654)
			(xy 342.11667 -392.693715) (xy 342.16298 -392.717311) (xy 342.205028 -392.747861) (xy 342.241779 -392.784612)
			(xy 342.272329 -392.82666) (xy 342.295925 -392.87297) (xy 342.311986 -392.9224) (xy 342.320116 -392.973735)
			(xy 342.320626 -392.999722) (xy 342.320102 -393.026824) (xy 342.311289 -393.080307) (xy 342.3031 -393.106148)
			(xy 342.29929 -393.11707) (xy 342.30183 -393.139422) (xy 342.354408 -393.225274) (xy 342.373458 -393.23772)
			(xy 342.384634 -393.239498) (xy 342.410965 -393.243705) (xy 342.462494 -393.257421) (xy 342.512087 -393.277018)
			(xy 342.535764 -393.289282) (xy 342.550496 -393.29741) (xy 342.58377 -393.29233) (xy 342.851486 -393.024614)
			(xy 342.859106 -393.00658) (xy 342.859106 -392.99642) (xy 342.859844 -392.970767) (xy 342.868274 -392.920145)
			(xy 342.884423 -392.871433) (xy 342.907902 -392.8258) (xy 342.938148 -392.784342) (xy 342.974436 -392.748053)
			(xy 343.015893 -392.717806) (xy 343.061525 -392.694326) (xy 343.110237 -392.678176) (xy 343.160859 -392.669745)
			(xy 343.186512 -392.669014) (xy 343.196672 -392.669014) (xy 343.214706 -392.661394) (xy 344.088974 -391.787126)
			(xy 344.096375 -391.780288) (xy 344.114974 -391.772577) (xy 344.125042 -391.77214) (xy 344.189304 -391.77214)
			(xy 344.190574 -391.770616) (xy 354.241862 -391.770616) (xy 354.251825 -391.770131) (xy 354.270252 -391.762546)
			(xy 354.277676 -391.755884) (xy 354.308156 -391.725404) (xy 354.314201 -391.718829) (xy 354.321672 -391.702618)
			(xy 354.32313 -391.684828) (xy 354.32111 -391.676128) (xy 354.294186 -391.57783) (xy 354.274882 -391.558526)
			(xy 354.261674 -391.555224) (xy 354.235388 -391.547891) (xy 354.185485 -391.525818) (xy 354.139882 -391.495852)
			(xy 354.099816 -391.458807) (xy 354.066375 -391.415688) (xy 354.040465 -391.367665) (xy 354.022789 -391.31604)
			(xy 354.013827 -391.262214) (xy 354.013262 -391.23493) (xy 354.013769 -391.20894) (xy 354.021896 -391.157601)
			(xy 354.037954 -391.108164) (xy 354.061548 -391.061848) (xy 354.092096 -391.019794) (xy 354.128848 -390.983035)
			(xy 354.170897 -390.952479) (xy 354.217209 -390.928877) (xy 354.266642 -390.91281) (xy 354.317981 -390.904674)
			(xy 354.34397 -390.904222) (xy 354.371255 -390.904779) (xy 354.425087 -390.913734) (xy 354.476717 -390.931405)
			(xy 354.524745 -390.957314) (xy 354.567868 -390.990756) (xy 354.604915 -391.030825) (xy 354.63488 -391.076433)
			(xy 354.65695 -391.126341) (xy 354.664264 -391.152634) (xy 354.667566 -391.165842) (xy 354.68687 -391.185146)
			(xy 354.785168 -391.21207) (xy 354.793865 -391.214099) (xy 354.811651 -391.212628) (xy 354.827853 -391.205143)
			(xy 354.834444 -391.199116) (xy 355.04882 -390.98474) (xy 355.058218 -390.98474) (xy 355.06279 -390.980168)
			(xy 355.070201 -390.973486) (xy 355.088636 -390.965905) (xy 355.098604 -390.965436) (xy 355.236272 -390.965436)
			(xy 355.24821 -390.962388) (xy 355.253798 -390.959086) (xy 355.278109 -390.946617) (xy 355.329807 -390.928948)
			(xy 355.383707 -390.920019) (xy 355.411024 -390.919462) (xy 355.438343 -390.92) (xy 355.492243 -390.928935)
			(xy 355.543943 -390.946607) (xy 355.56825 -390.959086) (xy 355.573838 -390.962388) (xy 355.585776 -390.965436)
			(xy 355.769672 -390.965436) (xy 355.78161 -390.962388) (xy 355.787198 -390.959086) (xy 355.811509 -390.946617)
			(xy 355.863207 -390.928948) (xy 355.917107 -390.920019) (xy 355.944424 -390.919462) (xy 355.971743 -390.92)
			(xy 356.025643 -390.928935) (xy 356.077343 -390.946607) (xy 356.10165 -390.959086) (xy 356.107238 -390.962388)
			(xy 356.119176 -390.965436) (xy 357.58501 -390.965436) (xy 357.593908 -390.964997) (xy 357.610601 -390.958816)
			(xy 357.624179 -390.947305) (xy 357.628952 -390.939782) (xy 357.679752 -390.85139) (xy 357.679498 -390.824212)
			(xy 357.67264 -390.812274) (xy 357.660213 -390.790261) (xy 357.640638 -390.743655) (xy 357.627394 -390.69487)
			(xy 357.620714 -390.644763) (xy 357.620316 -390.619488) (xy 357.620802 -390.592237) (xy 357.628558 -390.538289)
			(xy 357.643913 -390.485994) (xy 357.666555 -390.436417) (xy 357.696021 -390.390567) (xy 357.731712 -390.349376)
			(xy 357.772903 -390.313685) (xy 357.818753 -390.284219) (xy 357.86833 -390.261577) (xy 357.920625 -390.246222)
			(xy 357.974573 -390.238466) (xy 358.029075 -390.238466) (xy 358.083023 -390.246222) (xy 358.135318 -390.261577)
			(xy 358.184895 -390.284219) (xy 358.230745 -390.313685) (xy 358.244508 -390.32561) (xy 361.246672 -390.32561)
			(xy 361.250743 -390.269988) (xy 361.262869 -390.215551) (xy 361.282792 -390.16346) (xy 361.310088 -390.114825)
			(xy 361.344174 -390.070682) (xy 361.384323 -390.031973) (xy 361.429681 -389.999522) (xy 361.479281 -389.974021)
			(xy 361.532065 -389.956014) (xy 361.586908 -389.945884) (xy 361.642642 -389.943847) (xy 361.698079 -389.949947)
			(xy 361.752036 -389.964053) (xy 361.803365 -389.985865) (xy 361.850971 -390.014919) (xy 361.893839 -390.050594)
			(xy 361.931056 -390.092131) (xy 361.961829 -390.138644) (xy 361.985501 -390.189141) (xy 362.001569 -390.242548)
			(xy 362.009689 -390.297724) (xy 362.010198 -390.32561) (xy 362.009689 -390.353496) (xy 362.001569 -390.408672)
			(xy 361.985501 -390.462079) (xy 361.961829 -390.512576) (xy 361.931056 -390.559089) (xy 361.893839 -390.600626)
			(xy 361.850971 -390.636301) (xy 361.803365 -390.665355) (xy 361.752036 -390.687167) (xy 361.698079 -390.701273)
			(xy 361.642642 -390.707373) (xy 361.586908 -390.705336) (xy 361.532065 -390.695206) (xy 361.479281 -390.677199)
			(xy 361.429681 -390.651698) (xy 361.384323 -390.619247) (xy 361.344174 -390.580538) (xy 361.310088 -390.536395)
			(xy 361.282792 -390.48776) (xy 361.262869 -390.435669) (xy 361.250743 -390.381232) (xy 361.246672 -390.32561)
			(xy 358.244508 -390.32561) (xy 358.271936 -390.349376) (xy 358.307627 -390.390567) (xy 358.337093 -390.436417)
			(xy 358.359735 -390.485994) (xy 358.37509 -390.538289) (xy 358.382846 -390.592237) (xy 358.383332 -390.619488)
			(xy 358.382922 -390.644763) (xy 358.376245 -390.694869) (xy 358.363006 -390.743655) (xy 358.343437 -390.790263)
			(xy 358.331008 -390.812274) (xy 358.32415 -390.824212) (xy 358.323896 -390.85139) (xy 358.374696 -390.939782)
			(xy 358.379393 -390.947373) (xy 358.392984 -390.95893) (xy 358.409719 -390.965114) (xy 358.418638 -390.965436)
			(xy 358.89184 -390.965436) (xy 358.901803 -390.965919) (xy 358.920231 -390.973504) (xy 358.927654 -390.980168)
			(xy 359.285794 -391.338308) (xy 359.292604 -391.345654) (xy 359.300334 -391.364116) (xy 359.30078 -391.374122)
			(xy 359.30078 -392.1252) (xy 366.783872 -392.1252) (xy 366.787943 -392.069578) (xy 366.800069 -392.015141)
			(xy 366.819992 -391.96305) (xy 366.847288 -391.914415) (xy 366.881374 -391.870272) (xy 366.921523 -391.831563)
			(xy 366.966881 -391.799112) (xy 367.016481 -391.773611) (xy 367.069265 -391.755604) (xy 367.124108 -391.745474)
			(xy 367.179842 -391.743437) (xy 367.235279 -391.749537) (xy 367.289236 -391.763643) (xy 367.340565 -391.785455)
			(xy 367.388171 -391.814509) (xy 367.431039 -391.850184) (xy 367.468256 -391.891721) (xy 367.499029 -391.938234)
			(xy 367.522701 -391.988731) (xy 367.538769 -392.042138) (xy 367.546889 -392.097314) (xy 367.547398 -392.1252)
			(xy 367.546889 -392.153086) (xy 367.538769 -392.208262) (xy 367.522701 -392.261669) (xy 367.499029 -392.312166)
			(xy 367.468256 -392.358679) (xy 367.431039 -392.400216) (xy 367.388171 -392.435891) (xy 367.340565 -392.464945)
			(xy 367.289236 -392.486757) (xy 367.235279 -392.500863) (xy 367.179842 -392.506963) (xy 367.124108 -392.504926)
			(xy 367.069265 -392.494796) (xy 367.016481 -392.476789) (xy 366.966881 -392.451288) (xy 366.921523 -392.418837)
			(xy 366.881374 -392.380128) (xy 366.847288 -392.335985) (xy 366.819992 -392.28735) (xy 366.800069 -392.235259)
			(xy 366.787943 -392.180822) (xy 366.783872 -392.1252) (xy 359.30078 -392.1252) (xy 359.30078 -393.04468)
			(xy 366.783872 -393.04468) (xy 366.787943 -392.989058) (xy 366.800069 -392.934621) (xy 366.819992 -392.88253)
			(xy 366.847288 -392.833895) (xy 366.881374 -392.789752) (xy 366.921523 -392.751043) (xy 366.966881 -392.718592)
			(xy 367.016481 -392.693091) (xy 367.069265 -392.675084) (xy 367.124108 -392.664954) (xy 367.179842 -392.662917)
			(xy 367.235279 -392.669017) (xy 367.289236 -392.683123) (xy 367.340565 -392.704935) (xy 367.388171 -392.733989)
			(xy 367.43065 -392.76934) (xy 368.04395 -392.76934) (xy 368.04395 -392.709404) (xy 368.051773 -392.649982)
			(xy 368.067286 -392.592089) (xy 368.090222 -392.536716) (xy 368.120189 -392.48481) (xy 368.156676 -392.43726)
			(xy 368.199056 -392.39488) (xy 368.246606 -392.358393) (xy 368.298512 -392.328426) (xy 368.353885 -392.30549)
			(xy 368.411778 -392.289977) (xy 368.4712 -392.282154) (xy 368.531136 -392.282154) (xy 368.590558 -392.289977)
			(xy 368.648451 -392.30549) (xy 368.703824 -392.328426) (xy 368.75573 -392.358393) (xy 368.80328 -392.39488)
			(xy 368.84566 -392.43726) (xy 368.882147 -392.48481) (xy 368.912114 -392.536716) (xy 368.93505 -392.592089)
			(xy 368.950563 -392.649982) (xy 368.958386 -392.709404) (xy 368.958876 -392.739372) (xy 368.958386 -392.76934)
			(xy 368.950563 -392.828762) (xy 368.93505 -392.886655) (xy 368.912114 -392.942028) (xy 368.882147 -392.993934)
			(xy 368.84566 -393.041484) (xy 368.80328 -393.083864) (xy 368.75573 -393.120351) (xy 368.703824 -393.150318)
			(xy 368.648451 -393.173254) (xy 368.590558 -393.188767) (xy 368.531136 -393.19659) (xy 368.4712 -393.19659)
			(xy 368.411778 -393.188767) (xy 368.353885 -393.173254) (xy 368.298512 -393.150318) (xy 368.246606 -393.120351)
			(xy 368.199056 -393.083864) (xy 368.156676 -393.041484) (xy 368.120189 -392.993934) (xy 368.090222 -392.942028)
			(xy 368.067286 -392.886655) (xy 368.051773 -392.828762) (xy 368.04395 -392.76934) (xy 367.43065 -392.76934)
			(xy 367.431039 -392.769664) (xy 367.468256 -392.811201) (xy 367.499029 -392.857714) (xy 367.522701 -392.908211)
			(xy 367.538769 -392.961618) (xy 367.546889 -393.016794) (xy 367.547398 -393.04468) (xy 367.546889 -393.072566)
			(xy 367.538769 -393.127742) (xy 367.522701 -393.181149) (xy 367.499029 -393.231646) (xy 367.468256 -393.278159)
			(xy 367.431039 -393.319696) (xy 367.388171 -393.355371) (xy 367.340565 -393.384425) (xy 367.289236 -393.406237)
			(xy 367.235279 -393.420343) (xy 367.179842 -393.426443) (xy 367.124108 -393.424406) (xy 367.069265 -393.414276)
			(xy 367.016481 -393.396269) (xy 366.966881 -393.370768) (xy 366.921523 -393.338317) (xy 366.881374 -393.299608)
			(xy 366.847288 -393.255465) (xy 366.819992 -393.20683) (xy 366.800069 -393.154739) (xy 366.787943 -393.100302)
			(xy 366.783872 -393.04468) (xy 359.30078 -393.04468) (xy 359.30078 -394.137642) (xy 359.300235 -394.147626)
			(xy 359.292508 -394.166045) (xy 359.285794 -394.173456) (xy 358.83172 -394.6276) (xy 362.130076 -394.6276)
			(xy 362.13409 -394.563802) (xy 362.146068 -394.501011) (xy 362.165822 -394.440216) (xy 362.19304 -394.382375)
			(xy 362.227292 -394.328403) (xy 362.268038 -394.279149) (xy 362.314637 -394.23539) (xy 362.366353 -394.197817)
			(xy 362.42237 -394.167021) (xy 362.481805 -394.143489) (xy 362.54372 -394.127592) (xy 362.60714 -394.119581)
			(xy 362.639102 -394.1191) (xy 362.669798 -394.119591) (xy 362.730742 -394.126989) (xy 362.79035 -394.141677)
			(xy 362.847755 -394.163441) (xy 362.902118 -394.191964) (xy 362.927646 -394.209016) (xy 362.936398 -394.214487)
			(xy 362.956602 -394.218615) (xy 362.976806 -394.214487) (xy 362.985558 -394.209016) (xy 363.011082 -394.19196)
			(xy 363.065454 -394.163454) (xy 363.12286 -394.141695) (xy 363.182466 -394.126998) (xy 363.243407 -394.119579)
			(xy 363.274102 -394.1191) (xy 363.306063 -394.119586) (xy 363.369482 -394.127598) (xy 363.431397 -394.143495)
			(xy 363.490831 -394.167027) (xy 363.546847 -394.197822) (xy 363.598561 -394.235395) (xy 363.645159 -394.279154)
			(xy 363.685905 -394.328407) (xy 363.720157 -394.382379) (xy 363.747374 -394.440218) (xy 363.767127 -394.501013)
			(xy 363.779105 -394.563803) (xy 363.783119 -394.6276) (xy 363.779105 -394.691397) (xy 363.767127 -394.754187)
			(xy 363.747374 -394.814982) (xy 363.720157 -394.872821) (xy 363.685905 -394.926793) (xy 363.645159 -394.976046)
			(xy 363.598561 -395.019805) (xy 363.546847 -395.057378) (xy 363.490831 -395.088173) (xy 363.431397 -395.111705)
			(xy 363.369482 -395.127602) (xy 363.306063 -395.135614) (xy 363.274102 -395.136116) (xy 363.243405 -395.135671)
			(xy 363.182459 -395.128261) (xy 363.12285 -395.113562) (xy 363.065447 -395.091788) (xy 363.011085 -395.063256)
			(xy 362.985558 -395.0462) (xy 362.976806 -395.040729) (xy 362.956602 -395.036601) (xy 362.936398 -395.040729)
			(xy 362.927646 -395.0462) (xy 362.902122 -395.063257) (xy 362.84775 -395.091762) (xy 362.790344 -395.113521)
			(xy 362.730738 -395.128217) (xy 362.669797 -395.135637) (xy 362.639102 -395.136116) (xy 362.60714 -395.135619)
			(xy 362.54372 -395.127608) (xy 362.481805 -395.111711) (xy 362.42237 -395.088179) (xy 362.366353 -395.057383)
			(xy 362.314637 -395.01981) (xy 362.268038 -394.976051) (xy 362.227292 -394.926797) (xy 362.19304 -394.872825)
			(xy 362.165822 -394.814984) (xy 362.146068 -394.754189) (xy 362.13409 -394.691398) (xy 362.130076 -394.6276)
			(xy 358.83172 -394.6276) (xy 357.993388 -395.466062) (xy 358.41127 -395.466062) (xy 358.415341 -395.41044)
			(xy 358.427467 -395.356003) (xy 358.44739 -395.303912) (xy 358.474686 -395.255277) (xy 358.508772 -395.211134)
			(xy 358.548921 -395.172425) (xy 358.594279 -395.139974) (xy 358.643879 -395.114473) (xy 358.696663 -395.096466)
			(xy 358.751506 -395.086336) (xy 358.80724 -395.084299) (xy 358.862677 -395.090399) (xy 358.916634 -395.104505)
			(xy 358.967963 -395.126317) (xy 359.015569 -395.155371) (xy 359.058437 -395.191046) (xy 359.095654 -395.232583)
			(xy 359.126427 -395.279096) (xy 359.150099 -395.329593) (xy 359.166167 -395.383) (xy 359.174287 -395.438176)
			(xy 359.174796 -395.466062) (xy 359.174287 -395.493948) (xy 359.166167 -395.549124) (xy 359.150099 -395.602531)
			(xy 359.126427 -395.653028) (xy 359.095654 -395.699541) (xy 359.058437 -395.741078) (xy 359.015569 -395.776753)
			(xy 358.967963 -395.805807) (xy 358.916634 -395.827619) (xy 358.862677 -395.841725) (xy 358.80724 -395.847825)
			(xy 358.751506 -395.845788) (xy 358.696663 -395.835658) (xy 358.643879 -395.817651) (xy 358.594279 -395.79215)
			(xy 358.548921 -395.759699) (xy 358.508772 -395.72099) (xy 358.474686 -395.676847) (xy 358.44739 -395.628212)
			(xy 358.427467 -395.576121) (xy 358.415341 -395.521684) (xy 358.41127 -395.466062) (xy 357.993388 -395.466062)
			(xy 357.644446 -395.815058) (xy 357.63764 -395.822404) (xy 357.629921 -395.840867) (xy 357.62946 -395.850872)
			(xy 357.62946 -396.1765) (xy 360.484672 -396.1765) (xy 360.488743 -396.120878) (xy 360.500869 -396.066441)
			(xy 360.520792 -396.01435) (xy 360.548088 -395.965715) (xy 360.582174 -395.921572) (xy 360.622323 -395.882863)
			(xy 360.667681 -395.850412) (xy 360.717281 -395.824911) (xy 360.770065 -395.806904) (xy 360.824908 -395.796774)
			(xy 360.880642 -395.794737) (xy 360.936079 -395.800837) (xy 360.990036 -395.814943) (xy 361.041365 -395.836755)
			(xy 361.088971 -395.865809) (xy 361.131839 -395.901484) (xy 361.169056 -395.943021) (xy 361.199829 -395.989534)
			(xy 361.223501 -396.040031) (xy 361.239569 -396.093438) (xy 361.247689 -396.148614) (xy 361.248198 -396.1765)
			(xy 361.247689 -396.204386) (xy 361.239569 -396.259562) (xy 361.223501 -396.312969) (xy 361.199829 -396.363466)
			(xy 361.169056 -396.409979) (xy 361.131839 -396.451516) (xy 361.088971 -396.487191) (xy 361.041365 -396.516245)
			(xy 360.990036 -396.538057) (xy 360.936079 -396.552163) (xy 360.880642 -396.558263) (xy 360.824908 -396.556226)
			(xy 360.770065 -396.546096) (xy 360.717281 -396.528089) (xy 360.667681 -396.502588) (xy 360.622323 -396.470137)
			(xy 360.582174 -396.431428) (xy 360.548088 -396.387285) (xy 360.520792 -396.33865) (xy 360.500869 -396.286559)
			(xy 360.488743 -396.232122) (xy 360.484672 -396.1765) (xy 357.62946 -396.1765) (xy 357.62946 -396.832328)
			(xy 357.63021 -396.844994) (xy 357.642343 -396.867241) (xy 357.652574 -396.874746) (xy 357.734616 -396.92834)
			(xy 357.760016 -396.930372) (xy 357.771954 -396.925292) (xy 357.796237 -396.915114) (xy 357.846896 -396.900765)
			(xy 357.899044 -396.8935) (xy 357.92537 -396.893034) (xy 357.952738 -396.893511) (xy 358.006911 -396.901344)
			(xy 358.059408 -396.91684) (xy 358.109151 -396.93968) (xy 358.155119 -396.969396) (xy 358.176068 -396.987014)
			(xy 358.18318 -396.99311) (xy 358.200198 -396.99946) (xy 358.285542 -396.99946) (xy 358.30256 -396.99311)
			(xy 358.309672 -396.987014) (xy 358.330603 -396.96937) (xy 358.376568 -396.939639) (xy 358.426314 -396.916792)
			(xy 358.478818 -396.901297) (xy 358.532999 -396.893474) (xy 358.56037 -396.893034) (xy 358.587621 -396.893495)
			(xy 358.641569 -396.901248) (xy 358.693865 -396.9166) (xy 358.743444 -396.939238) (xy 358.789295 -396.968702)
			(xy 358.830487 -397.004392) (xy 358.86618 -397.04558) (xy 358.895648 -397.09143) (xy 358.91829 -397.141007)
			(xy 358.933646 -397.193301) (xy 358.941403 -397.247249) (xy 358.941403 -397.301751) (xy 358.933646 -397.355699)
			(xy 358.91829 -397.407993) (xy 358.895648 -397.45757) (xy 358.86618 -397.50342) (xy 358.830487 -397.544608)
			(xy 358.789295 -397.580298) (xy 358.743444 -397.609762) (xy 358.693865 -397.6324) (xy 358.641569 -397.647752)
			(xy 358.587621 -397.655505) (xy 358.56037 -397.65605) (xy 358.533001 -397.655576) (xy 358.478826 -397.647748)
			(xy 358.426326 -397.632256) (xy 358.376579 -397.609418) (xy 358.330608 -397.579705) (xy 358.309672 -397.56207)
			(xy 358.30256 -397.555974) (xy 358.285542 -397.549624) (xy 358.200198 -397.549624) (xy 358.18318 -397.555974)
			(xy 358.176068 -397.56207) (xy 358.155137 -397.579711) (xy 358.10917 -397.609436) (xy 358.059423 -397.632277)
			(xy 358.00692 -397.647764) (xy 357.95274 -397.655579) (xy 357.92537 -397.65605) (xy 357.899043 -397.655608)
			(xy 357.84689 -397.648355) (xy 357.796236 -397.633977) (xy 357.771954 -397.623792) (xy 357.760016 -397.618712)
			(xy 357.734616 -397.620744) (xy 357.652574 -397.674338) (xy 357.645669 -397.679168) (xy 357.635275 -397.692419)
			(xy 357.629769 -397.708335) (xy 357.62946 -397.716756) (xy 357.62946 -398.289018) (xy 357.629888 -398.299085)
			(xy 357.637614 -398.317679) (xy 357.644446 -398.325086) (xy 358.333294 -399.013934) (xy 358.340689 -399.020789)
			(xy 358.359288 -399.028536) (xy 358.369362 -399.02892)
		)
		(stroke
			(width 0)
			(type solid)
		)
		(fill yes)
		(layer "In15.Cu")
		(net "P1V8_CPU0_RT_1D")
	)
	(gr_poly
		(pts
			(xy 45.969682 -401.115784) (xy 45.979745 -401.115345) (xy 45.998327 -401.107608) (xy 46.00575 -401.100798)
			(xy 46.253654 -400.852894) (xy 46.260505 -400.845497) (xy 46.268244 -400.826899) (xy 46.26864 -400.816826)
			(xy 46.26864 -392.596878) (xy 46.268173 -392.587245) (xy 46.260995 -392.56936) (xy 46.25467 -392.56208)
			(xy 46.23778 -392.54354) (xy 46.209221 -392.502315) (xy 46.187207 -392.457254) (xy 46.172244 -392.409388)
			(xy 46.164673 -392.359812) (xy 46.164667 -392.309661) (xy 46.172227 -392.260083) (xy 46.187181 -392.212213)
			(xy 46.209184 -392.167147) (xy 46.237735 -392.125917) (xy 46.25467 -392.10742) (xy 46.261528 -392.100308)
			(xy 46.26864 -392.082274) (xy 46.26864 -392.028426) (xy 46.261528 -392.010392) (xy 46.25467 -392.00328)
			(xy 46.237787 -391.984739) (xy 46.209241 -391.943514) (xy 46.187242 -391.898455) (xy 46.172292 -391.850592)
			(xy 46.164735 -391.801022) (xy 46.164246 -391.77595) (xy 46.164725 -391.749957) (xy 46.17285 -391.69861)
			(xy 46.188907 -391.649165) (xy 46.212502 -391.602842) (xy 46.243052 -391.56078) (xy 46.279807 -391.524015)
			(xy 46.32186 -391.493452) (xy 46.368177 -391.469844) (xy 46.417616 -391.453773) (xy 46.468961 -391.445633)
			(xy 46.494954 -391.445242) (xy 46.521865 -391.445775) (xy 46.574976 -391.454504) (xy 46.625971 -391.471721)
			(xy 46.673503 -391.496973) (xy 46.716316 -391.529592) (xy 46.753279 -391.568716) (xy 46.783415 -391.613311)
			(xy 46.795182 -391.63752) (xy 46.801532 -391.650982) (xy 46.826424 -391.666984) (xy 47.53229 -391.666984)
			(xy 47.544113 -391.666435) (xy 47.56531 -391.655973) (xy 47.57293 -391.646918) (xy 47.5888 -391.626744)
			(xy 47.626121 -391.591509) (xy 47.668812 -391.563018) (xy 47.71567 -391.542072) (xy 47.765372 -391.529264)
			(xy 47.816516 -391.524954) (xy 47.86766 -391.529264) (xy 47.917362 -391.542072) (xy 47.96422 -391.563018)
			(xy 48.006911 -391.591509) (xy 48.044232 -391.626744) (xy 48.060102 -391.646918) (xy 48.067748 -391.655938)
			(xy 48.088931 -391.66638) (xy 48.100742 -391.666984) (xy 48.73244 -391.666984) (xy 48.744257 -391.666424)
			(xy 48.765437 -391.65595) (xy 48.77308 -391.646918) (xy 48.78895 -391.626744) (xy 48.826271 -391.591509)
			(xy 48.868962 -391.563018) (xy 48.91582 -391.542072) (xy 48.965522 -391.529264) (xy 49.016666 -391.524954)
			(xy 49.06781 -391.529264) (xy 49.117512 -391.542072) (xy 49.16437 -391.563018) (xy 49.207061 -391.591509)
			(xy 49.244382 -391.626744) (xy 49.260252 -391.646918) (xy 49.267895 -391.655946) (xy 49.289078 -391.666409)
			(xy 49.300892 -391.666984) (xy 49.932336 -391.666984) (xy 49.944154 -391.666425) (xy 49.965335 -391.655952)
			(xy 49.972976 -391.646918) (xy 49.988846 -391.626744) (xy 50.026167 -391.591509) (xy 50.068858 -391.563018)
			(xy 50.115716 -391.542072) (xy 50.165418 -391.529264) (xy 50.216562 -391.524954) (xy 50.267706 -391.529264)
			(xy 50.317408 -391.542072) (xy 50.364266 -391.563018) (xy 50.406957 -391.591509) (xy 50.444278 -391.626744)
			(xy 50.460148 -391.646918) (xy 50.46779 -391.655947) (xy 50.488974 -391.666411) (xy 50.500788 -391.666984)
			(xy 51.132232 -391.666984) (xy 51.14405 -391.666426) (xy 51.165233 -391.655954) (xy 51.172872 -391.646918)
			(xy 51.188742 -391.626744) (xy 51.226063 -391.591509) (xy 51.268754 -391.563018) (xy 51.315612 -391.542072)
			(xy 51.365314 -391.529264) (xy 51.416458 -391.524954) (xy 51.467602 -391.529264) (xy 51.517304 -391.542072)
			(xy 51.564162 -391.563018) (xy 51.606853 -391.591509) (xy 51.644174 -391.626744) (xy 51.660044 -391.646918)
			(xy 51.667686 -391.655947) (xy 51.688869 -391.666413) (xy 51.700684 -391.666984) (xy 52.332382 -391.666984)
			(xy 52.344206 -391.666436) (xy 52.365406 -391.655977) (xy 52.373022 -391.646918) (xy 52.388892 -391.626744)
			(xy 52.426213 -391.591509) (xy 52.468904 -391.563018) (xy 52.515762 -391.542072) (xy 52.565464 -391.529264)
			(xy 52.616608 -391.524954) (xy 52.667752 -391.529264) (xy 52.717454 -391.542072) (xy 52.764312 -391.563018)
			(xy 52.807003 -391.591509) (xy 52.844324 -391.626744) (xy 52.860194 -391.646918) (xy 52.867839 -391.655939)
			(xy 52.889023 -391.666384) (xy 52.900834 -391.666984) (xy 53.532278 -391.666984) (xy 53.544102 -391.666437)
			(xy 53.565303 -391.655979) (xy 53.572918 -391.646918) (xy 53.588788 -391.626744) (xy 53.626109 -391.591509)
			(xy 53.6688 -391.563018) (xy 53.715658 -391.542072) (xy 53.76536 -391.529264) (xy 53.816504 -391.524954)
			(xy 53.867648 -391.529264) (xy 53.91735 -391.542072) (xy 53.964208 -391.563018) (xy 54.006899 -391.591509)
			(xy 54.04422 -391.626744) (xy 54.06009 -391.646918) (xy 54.067735 -391.65594) (xy 54.088919 -391.666387)
			(xy 54.10073 -391.666984) (xy 54.732428 -391.666984) (xy 54.744246 -391.666427) (xy 54.765431 -391.655956)
			(xy 54.773068 -391.646918) (xy 54.788938 -391.626744) (xy 54.826259 -391.591509) (xy 54.86895 -391.563018)
			(xy 54.915808 -391.542072) (xy 54.96551 -391.529264) (xy 55.016654 -391.524954) (xy 55.067798 -391.529264)
			(xy 55.1175 -391.542072) (xy 55.164358 -391.563018) (xy 55.207049 -391.591509) (xy 55.24437 -391.626744)
			(xy 55.26024 -391.646918) (xy 55.267882 -391.655948) (xy 55.289065 -391.666416) (xy 55.30088 -391.666984)
			(xy 55.932324 -391.666984) (xy 55.944143 -391.666427) (xy 55.965329 -391.655958) (xy 55.972964 -391.646918)
			(xy 55.988834 -391.626744) (xy 56.026155 -391.591509) (xy 56.068846 -391.563018) (xy 56.115704 -391.542072)
			(xy 56.165406 -391.529264) (xy 56.21655 -391.524954) (xy 56.267694 -391.529264) (xy 56.317396 -391.542072)
			(xy 56.364254 -391.563018) (xy 56.406945 -391.591509) (xy 56.444266 -391.626744) (xy 56.460136 -391.646918)
			(xy 56.467778 -391.655949) (xy 56.488961 -391.666418) (xy 56.500776 -391.666984) (xy 57.13222 -391.666984)
			(xy 57.144039 -391.666428) (xy 57.165226 -391.65596) (xy 57.17286 -391.646918) (xy 57.18873 -391.626744)
			(xy 57.226051 -391.591509) (xy 57.268742 -391.563018) (xy 57.3156 -391.542072) (xy 57.365302 -391.529264)
			(xy 57.416446 -391.524954) (xy 57.46759 -391.529264) (xy 57.517292 -391.542072) (xy 57.56415 -391.563018)
			(xy 57.606841 -391.591509) (xy 57.644162 -391.626744) (xy 57.660032 -391.646918) (xy 57.667673 -391.655949)
			(xy 57.688856 -391.66642) (xy 57.700672 -391.666984) (xy 58.33237 -391.666984) (xy 58.344195 -391.666439)
			(xy 58.365399 -391.655983) (xy 58.37301 -391.646918) (xy 58.38888 -391.626744) (xy 58.426201 -391.591509)
			(xy 58.468892 -391.563018) (xy 58.51575 -391.542072) (xy 58.565452 -391.529264) (xy 58.616596 -391.524954)
			(xy 58.66774 -391.529264) (xy 58.717442 -391.542072) (xy 58.7643 -391.563018) (xy 58.806991 -391.591509)
			(xy 58.844312 -391.626744) (xy 58.860182 -391.646918) (xy 58.867827 -391.655941) (xy 58.88901 -391.666391)
			(xy 58.900822 -391.666984) (xy 59.532266 -391.666984) (xy 59.544091 -391.66644) (xy 59.565297 -391.655984)
			(xy 59.572906 -391.646918) (xy 59.588776 -391.626744) (xy 59.626097 -391.591509) (xy 59.668788 -391.563018)
			(xy 59.715646 -391.542072) (xy 59.765348 -391.529264) (xy 59.816492 -391.524954) (xy 59.867636 -391.529264)
			(xy 59.917338 -391.542072) (xy 59.964196 -391.563018) (xy 60.006887 -391.591509) (xy 60.044208 -391.626744)
			(xy 60.060078 -391.646918) (xy 60.067722 -391.655942) (xy 60.088906 -391.666394) (xy 60.100718 -391.666984)
			(xy 60.732416 -391.666984) (xy 60.744236 -391.666429) (xy 60.765424 -391.655961) (xy 60.773056 -391.646918)
			(xy 60.788926 -391.626744) (xy 60.826247 -391.591509) (xy 60.868938 -391.563018) (xy 60.915796 -391.542072)
			(xy 60.965498 -391.529264) (xy 61.016642 -391.524954) (xy 61.067786 -391.529264) (xy 61.117488 -391.542072)
			(xy 61.164346 -391.563018) (xy 61.207037 -391.591509) (xy 61.244358 -391.626744) (xy 61.260228 -391.646918)
			(xy 61.267869 -391.65595) (xy 61.289052 -391.666423) (xy 61.300868 -391.666984) (xy 61.932312 -391.666984)
			(xy 61.944132 -391.66643) (xy 61.965322 -391.655963) (xy 61.972952 -391.646918) (xy 61.988822 -391.626744)
			(xy 62.026143 -391.591509) (xy 62.068834 -391.563018) (xy 62.115692 -391.542072) (xy 62.165394 -391.529264)
			(xy 62.216538 -391.524954) (xy 62.267682 -391.529264) (xy 62.317384 -391.542072) (xy 62.364242 -391.563018)
			(xy 62.406933 -391.591509) (xy 62.444254 -391.626744) (xy 62.460124 -391.646918) (xy 62.467765 -391.655951)
			(xy 62.488948 -391.666425) (xy 62.500764 -391.666984) (xy 63.132208 -391.666984) (xy 63.144029 -391.666431)
			(xy 63.16522 -391.655965) (xy 63.172848 -391.646918) (xy 63.188718 -391.626744) (xy 63.226039 -391.591509)
			(xy 63.26873 -391.563018) (xy 63.315588 -391.542072) (xy 63.36529 -391.529264) (xy 63.416434 -391.524954)
			(xy 63.467578 -391.529264) (xy 63.51728 -391.542072) (xy 63.564138 -391.563018) (xy 63.606829 -391.591509)
			(xy 63.64415 -391.626744) (xy 63.66002 -391.646918) (xy 63.66766 -391.655952) (xy 63.688843 -391.666427)
			(xy 63.70066 -391.666984) (xy 64.332358 -391.666984) (xy 64.344184 -391.666441) (xy 64.365392 -391.655988)
			(xy 64.372998 -391.646918) (xy 64.388868 -391.626744) (xy 64.426189 -391.591509) (xy 64.46888 -391.563018)
			(xy 64.515738 -391.542072) (xy 64.56544 -391.529264) (xy 64.616584 -391.524954) (xy 64.667728 -391.529264)
			(xy 64.71743 -391.542072) (xy 64.764288 -391.563018) (xy 64.806979 -391.591509) (xy 64.8443 -391.626744)
			(xy 64.86017 -391.646918) (xy 64.867814 -391.655943) (xy 64.888997 -391.666399) (xy 64.90081 -391.666984)
			(xy 65.532254 -391.666984) (xy 65.544081 -391.666442) (xy 65.56529 -391.65599) (xy 65.572894 -391.646918)
			(xy 65.588764 -391.626744) (xy 65.626085 -391.591509) (xy 65.668776 -391.563018) (xy 65.715634 -391.542072)
			(xy 65.765336 -391.529264) (xy 65.81648 -391.524954) (xy 65.867624 -391.529264) (xy 65.917326 -391.542072)
			(xy 65.964184 -391.563018) (xy 66.006875 -391.591509) (xy 66.044196 -391.626744) (xy 66.060066 -391.646918)
			(xy 66.067709 -391.655944) (xy 66.088893 -391.666401) (xy 66.100706 -391.666984) (xy 66.507614 -391.666984)
			(xy 66.517683 -391.666558) (xy 66.536282 -391.658838) (xy 66.543682 -391.651998) (xy 66.781934 -391.413746)
			(xy 66.788779 -391.406348) (xy 66.796504 -391.387749) (xy 66.79692 -391.377678) (xy 66.79692 -390.562592)
			(xy 66.796496 -390.552522) (xy 66.788782 -390.533918) (xy 66.781934 -390.526524) (xy 66.760344 -390.504934)
			(xy 66.753482 -390.498689) (xy 66.736555 -390.491129) (xy 66.727324 -390.490202) (xy 66.700989 -390.488244)
			(xy 66.649391 -390.477015) (xy 66.600233 -390.457729) (xy 66.554764 -390.430877) (xy 66.514141 -390.39714)
			(xy 66.479395 -390.357376) (xy 66.451409 -390.312596) (xy 66.430895 -390.263938) (xy 66.418375 -390.212638)
			(xy 66.414166 -390.16) (xy 66.418375 -390.107362) (xy 66.430895 -390.056062) (xy 66.451409 -390.007404)
			(xy 66.479394 -389.962624) (xy 66.51414 -389.92286) (xy 66.554764 -389.889123) (xy 66.600233 -389.862271)
			(xy 66.649391 -389.842985) (xy 66.700989 -389.831756) (xy 66.727324 -389.829802) (xy 66.736559 -389.828888)
			(xy 66.753487 -389.821324) (xy 66.760344 -389.81507) (xy 66.781934 -389.79348) (xy 66.788784 -389.786084)
			(xy 66.796522 -389.767485) (xy 66.79692 -389.757412) (xy 66.79692 -387.330442) (xy 66.796487 -387.320376)
			(xy 66.78876 -387.301785) (xy 66.781934 -387.294374) (xy 66.095626 -386.608066) (xy 66.088227 -386.601224)
			(xy 66.069628 -386.593506) (xy 66.059558 -386.59308) (xy 65.706498 -386.59308) (xy 65.697709 -386.593451)
			(xy 65.681172 -386.599406) (xy 65.66763 -386.610612) (xy 65.66281 -386.617972) (xy 65.650289 -386.63827)
			(xy 65.620324 -386.67537) (xy 65.60312 -386.691886) (xy 65.595673 -386.699378) (xy 65.587136 -386.718674)
			(xy 65.58661 -386.729224) (xy 65.58661 -386.8039) (xy 65.587201 -386.814433) (xy 65.595736 -386.833702)
			(xy 65.60312 -386.841238) (xy 65.622775 -386.86017) (xy 65.656219 -386.903291) (xy 65.682127 -386.951317)
			(xy 65.699797 -387.002947) (xy 65.708748 -387.056777) (xy 65.709292 -387.084062) (xy 65.708859 -387.10818)
			(xy 65.701863 -387.155904) (xy 65.688014 -387.202109) (xy 65.667605 -387.245813) (xy 65.654682 -387.26618)
			(xy 65.64884 -387.27507) (xy 65.645284 -387.295136) (xy 65.666366 -387.387338) (xy 65.678558 -387.404102)
			(xy 65.687448 -387.409436) (xy 65.708249 -387.422292) (xy 65.746164 -387.453171) (xy 65.779112 -387.489302)
			(xy 65.806373 -387.529896) (xy 65.827351 -387.574066) (xy 65.841589 -387.620845) (xy 65.848774 -387.669213)
			(xy 65.849246 -387.693662) (xy 65.848808 -387.718033) (xy 65.841652 -387.766246) (xy 65.827504 -387.812889)
			(xy 65.80667 -387.856953) (xy 65.779599 -387.897485) (xy 65.746878 -387.933611) (xy 65.728342 -387.94944)
			(xy 65.719452 -387.956552) (xy 65.710054 -387.97611) (xy 65.70726 -388.075424) (xy 65.715896 -388.09549)
			(xy 65.724278 -388.10311) (xy 65.742701 -388.120597) (xy 65.774045 -388.160564) (xy 65.798344 -388.205167)
			(xy 65.814927 -388.253175) (xy 65.823338 -388.303266) (xy 65.823846 -388.328662) (xy 65.823774 -388.33802)
			(xy 65.822628 -388.356702) (xy 65.82156 -388.366) (xy 65.820544 -388.37489) (xy 65.824354 -388.391654)
			(xy 65.868296 -388.461504) (xy 65.882012 -388.471918) (xy 65.890394 -388.474712) (xy 65.914431 -388.483165)
			(xy 65.959614 -388.506709) (xy 66.000429 -388.537205) (xy 66.035815 -388.573861) (xy 66.064854 -388.615725)
			(xy 66.08679 -388.66171) (xy 66.094356 -388.68604) (xy 66.09588 -388.691882) (xy 66.416174 -389.245602)
			(xy 66.420238 -389.24992) (xy 66.436427 -389.26763) (xy 66.463802 -389.307033) (xy 66.484892 -389.350128)
			(xy 66.49921 -389.395921) (xy 66.506426 -389.443354) (xy 66.506852 -389.467344) (xy 66.506362 -389.492131)
			(xy 66.498601 -389.541093) (xy 66.483276 -389.588239) (xy 66.460765 -389.632407) (xy 66.431622 -389.67251)
			(xy 66.396565 -389.707561) (xy 66.356456 -389.736696) (xy 66.312284 -389.759199) (xy 66.265135 -389.774515)
			(xy 66.216171 -389.782267) (xy 66.191384 -389.782812) (xy 66.165991 -389.782303) (xy 66.11586 -389.774171)
			(xy 66.067678 -389.758118) (xy 66.022687 -389.734559) (xy 65.982047 -389.704102) (xy 65.946807 -389.667532)
			(xy 65.917876 -389.625792) (xy 65.896 -389.579959) (xy 65.888362 -389.555736) (xy 65.886838 -389.549894)
			(xy 65.566544 -388.996174) (xy 65.56248 -388.991856) (xy 65.546265 -388.974157) (xy 65.518837 -388.934767)
			(xy 65.497695 -388.891675) (xy 65.483326 -388.845878) (xy 65.476063 -388.798431) (xy 65.475612 -388.774432)
			(xy 65.47577 -388.76238) (xy 65.477679 -388.738352) (xy 65.479422 -388.726426) (xy 65.480692 -388.717536)
			(xy 65.477644 -388.700518) (xy 65.43548 -388.629652) (xy 65.422272 -388.618476) (xy 65.41389 -388.615428)
			(xy 65.392149 -388.607023) (xy 65.351304 -388.584571) (xy 65.314345 -388.556172) (xy 65.282131 -388.522486)
			(xy 65.255411 -388.484295) (xy 65.234806 -388.442487) (xy 65.220794 -388.398034) (xy 65.213701 -388.351967)
			(xy 65.21323 -388.328662) (xy 65.21373 -388.303264) (xy 65.22213 -388.253168) (xy 65.238709 -388.205155)
			(xy 65.263009 -388.160549) (xy 65.294359 -388.120582) (xy 65.312798 -388.10311) (xy 65.32118 -388.09549)
			(xy 65.329816 -388.075424) (xy 65.327022 -387.97611) (xy 65.317624 -387.956552) (xy 65.308734 -387.94944)
			(xy 65.290171 -387.933639) (xy 65.257441 -387.897513) (xy 65.230366 -387.856977) (xy 65.209531 -387.812906)
			(xy 65.195387 -387.766256) (xy 65.18824 -387.718036) (xy 65.18783 -387.693662) (xy 65.188269 -387.669546)
			(xy 65.195275 -387.621826) (xy 65.209133 -387.575628) (xy 65.229551 -387.531931) (xy 65.24244 -387.511544)
			(xy 65.248282 -387.502654) (xy 65.251838 -387.482588) (xy 65.230756 -387.390386) (xy 65.218564 -387.373622)
			(xy 65.209674 -387.368288) (xy 65.188871 -387.355433) (xy 65.150951 -387.324556) (xy 65.117999 -387.288426)
			(xy 65.090733 -387.247833) (xy 65.069749 -387.203663) (xy 65.055508 -387.156882) (xy 65.048318 -387.108513)
			(xy 65.047876 -387.084062) (xy 65.048437 -387.056779) (xy 65.057397 -387.002954) (xy 65.075069 -386.951329)
			(xy 65.100972 -386.903304) (xy 65.134405 -386.860181) (xy 65.154048 -386.841238) (xy 65.161503 -386.833749)
			(xy 65.170055 -386.814453) (xy 65.170558 -386.8039) (xy 65.170558 -386.729224) (xy 65.169971 -386.71869)
			(xy 65.161438 -386.699418) (xy 65.154048 -386.691886) (xy 65.136839 -386.675374) (xy 65.106871 -386.638275)
			(xy 65.094358 -386.617972) (xy 65.089559 -386.610594) (xy 65.076007 -386.599385) (xy 65.059463 -386.593417)
			(xy 65.05067 -386.59308) (xy 64.506602 -386.59308) (xy 64.497813 -386.59345) (xy 64.481275 -386.599405)
			(xy 64.467731 -386.61061) (xy 64.462914 -386.617972) (xy 64.450393 -386.63827) (xy 64.420428 -386.67537)
			(xy 64.403224 -386.691886) (xy 64.395776 -386.699378) (xy 64.387238 -386.718674) (xy 64.386714 -386.729224)
			(xy 64.386714 -386.8039) (xy 64.387305 -386.814433) (xy 64.395841 -386.833701) (xy 64.403224 -386.841238)
			(xy 64.422879 -386.86017) (xy 64.456322 -386.903291) (xy 64.48223 -386.951318) (xy 64.499899 -387.002947)
			(xy 64.508851 -387.056777) (xy 64.509396 -387.084062) (xy 64.508963 -387.10818) (xy 64.501967 -387.155905)
			(xy 64.488118 -387.202109) (xy 64.46771 -387.245813) (xy 64.454786 -387.26618) (xy 64.448944 -387.27507)
			(xy 64.445388 -387.295136) (xy 64.46647 -387.387338) (xy 64.478662 -387.404102) (xy 64.487552 -387.409436)
			(xy 64.508353 -387.422292) (xy 64.546267 -387.453171) (xy 64.579215 -387.489303) (xy 64.606475 -387.529897)
			(xy 64.627454 -387.574066) (xy 64.641691 -387.620845) (xy 64.648876 -387.669213) (xy 64.64935 -387.693662)
			(xy 64.648912 -387.718033) (xy 64.641757 -387.766246) (xy 64.627608 -387.812889) (xy 64.606774 -387.856953)
			(xy 64.579704 -387.897486) (xy 64.546983 -387.933612) (xy 64.528446 -387.94944) (xy 64.519556 -387.956552)
			(xy 64.510158 -387.97611) (xy 64.507364 -388.075424) (xy 64.516 -388.09549) (xy 64.524382 -388.10311)
			(xy 64.542805 -388.120597) (xy 64.574148 -388.160565) (xy 64.598447 -388.205167) (xy 64.61503 -388.253176)
			(xy 64.62344 -388.303266) (xy 64.62395 -388.328662) (xy 64.623878 -388.33802) (xy 64.622732 -388.356702)
			(xy 64.621664 -388.366) (xy 64.620648 -388.37489) (xy 64.624458 -388.391654) (xy 64.6684 -388.461504)
			(xy 64.682116 -388.471918) (xy 64.690498 -388.474712) (xy 64.714594 -388.483195) (xy 64.759881 -388.506826)
			(xy 64.800773 -388.537438) (xy 64.836204 -388.574234) (xy 64.865249 -388.616254) (xy 64.887152 -388.662402)
			(xy 64.894714 -388.686802) (xy 64.896238 -388.692644) (xy 65.216024 -389.245602) (xy 65.220088 -389.24992)
			(xy 65.236305 -389.267618) (xy 65.263739 -389.307007) (xy 65.284887 -389.350098) (xy 65.299261 -389.395896)
			(xy 65.306528 -389.443344) (xy 65.306956 -389.467344) (xy 65.306491 -389.492146) (xy 65.298721 -389.541137)
			(xy 65.283379 -389.588308) (xy 65.260844 -389.632497) (xy 65.231671 -389.672615) (xy 65.196579 -389.707673)
			(xy 65.156433 -389.736806) (xy 65.112221 -389.759298) (xy 65.065035 -389.774593) (xy 65.016036 -389.782315)
			(xy 64.991234 -389.782812) (xy 64.965839 -389.782307) (xy 64.915702 -389.774181) (xy 64.867514 -389.758133)
			(xy 64.822516 -389.734577) (xy 64.781869 -389.704122) (xy 64.746623 -389.667551) (xy 64.717686 -389.62581)
			(xy 64.695805 -389.579974) (xy 64.688212 -389.555736) (xy 64.686688 -389.549894) (xy 64.36614 -388.995412)
			(xy 64.362076 -388.991094) (xy 64.34597 -388.973426) (xy 64.318727 -388.934142) (xy 64.297714 -388.891201)
			(xy 64.283411 -388.845585) (xy 64.276143 -388.798335) (xy 64.275716 -388.774432) (xy 64.275874 -388.76238)
			(xy 64.277783 -388.738352) (xy 64.279526 -388.726426) (xy 64.280796 -388.717536) (xy 64.277748 -388.700518)
			(xy 64.235584 -388.629652) (xy 64.222376 -388.618476) (xy 64.213994 -388.615428) (xy 64.192253 -388.607023)
			(xy 64.151407 -388.584571) (xy 64.114447 -388.556173) (xy 64.082234 -388.522486) (xy 64.055513 -388.484296)
			(xy 64.034908 -388.442488) (xy 64.020896 -388.398034) (xy 64.013803 -388.351967) (xy 64.013334 -388.328662)
			(xy 64.013834 -388.303264) (xy 64.022234 -388.253169) (xy 64.038813 -388.205155) (xy 64.063114 -388.16055)
			(xy 64.094464 -388.120583) (xy 64.112902 -388.10311) (xy 64.121284 -388.09549) (xy 64.12992 -388.075424)
			(xy 64.127126 -387.97611) (xy 64.117728 -387.956552) (xy 64.108838 -387.94944) (xy 64.090275 -387.933639)
			(xy 64.057545 -387.897513) (xy 64.030469 -387.856977) (xy 64.009633 -387.812907) (xy 63.995489 -387.766256)
			(xy 63.988343 -387.718036) (xy 63.987934 -387.693662) (xy 63.988373 -387.669546) (xy 63.995379 -387.621826)
			(xy 64.009238 -387.575629) (xy 64.029655 -387.531932) (xy 64.042544 -387.511544) (xy 64.048386 -387.502654)
			(xy 64.051942 -387.482588) (xy 64.03086 -387.390386) (xy 64.018668 -387.373622) (xy 64.009778 -387.368288)
			(xy 63.988975 -387.355434) (xy 63.951055 -387.324557) (xy 63.918102 -387.288427) (xy 63.890835 -387.247833)
			(xy 63.869852 -387.203663) (xy 63.85561 -387.156882) (xy 63.84842 -387.108513) (xy 63.84798 -387.084062)
			(xy 63.848541 -387.056779) (xy 63.857501 -387.002954) (xy 63.875173 -386.95133) (xy 63.901076 -386.903305)
			(xy 63.93451 -386.860181) (xy 63.954152 -386.841238) (xy 63.961606 -386.833749) (xy 63.970158 -386.814453)
			(xy 63.970662 -386.8039) (xy 63.970662 -386.729224) (xy 63.970075 -386.71869) (xy 63.961542 -386.699417)
			(xy 63.954152 -386.691886) (xy 63.936943 -386.675374) (xy 63.906974 -386.638275) (xy 63.894462 -386.617972)
			(xy 63.889658 -386.610605) (xy 63.876102 -386.599421) (xy 63.859561 -386.593484) (xy 63.850774 -386.59308)
			(xy 63.306452 -386.59308) (xy 63.297659 -386.593442) (xy 63.281108 -386.599386) (xy 63.267551 -386.610587)
			(xy 63.262764 -386.617972) (xy 63.250242 -386.638268) (xy 63.220274 -386.675365) (xy 63.203074 -386.691886)
			(xy 63.195632 -386.699381) (xy 63.187103 -386.718676) (xy 63.186564 -386.729224) (xy 63.186564 -386.8039)
			(xy 63.187156 -386.814432) (xy 63.195698 -386.833694) (xy 63.203074 -386.841238) (xy 63.222727 -386.860172)
			(xy 63.256165 -386.903294) (xy 63.282069 -386.951321) (xy 63.299735 -387.00295) (xy 63.308685 -387.056778)
			(xy 63.309246 -387.084062) (xy 63.308813 -387.108179) (xy 63.301816 -387.155904) (xy 63.287965 -387.202107)
			(xy 63.267555 -387.24581) (xy 63.254636 -387.26618) (xy 63.248794 -387.27507) (xy 63.245238 -387.295136)
			(xy 63.26632 -387.387338) (xy 63.278512 -387.404102) (xy 63.287402 -387.409436) (xy 63.308205 -387.42229)
			(xy 63.346125 -387.453167) (xy 63.379077 -387.489297) (xy 63.406343 -387.529891) (xy 63.427324 -387.574061)
			(xy 63.441564 -387.620842) (xy 63.448751 -387.669212) (xy 63.4492 -387.693662) (xy 63.448763 -387.718033)
			(xy 63.441607 -387.766247) (xy 63.427461 -387.812892) (xy 63.406629 -387.856958) (xy 63.379561 -387.897494)
			(xy 63.346843 -387.933624) (xy 63.328296 -387.94944) (xy 63.319406 -387.956552) (xy 63.310008 -387.97611)
			(xy 63.307214 -388.075424) (xy 63.31585 -388.09549) (xy 63.324232 -388.10311) (xy 63.342652 -388.120599)
			(xy 63.373991 -388.160568) (xy 63.398285 -388.205171) (xy 63.414865 -388.253178) (xy 63.423274 -388.303267)
			(xy 63.4238 -388.328662) (xy 63.423728 -388.33802) (xy 63.422582 -388.356702) (xy 63.421514 -388.366)
			(xy 63.420498 -388.37489) (xy 63.424308 -388.391654) (xy 63.46825 -388.461504) (xy 63.481966 -388.471918)
			(xy 63.490348 -388.474712) (xy 63.514382 -388.483168) (xy 63.559559 -388.506717) (xy 63.600367 -388.537216)
			(xy 63.635747 -388.573874) (xy 63.66478 -388.615738) (xy 63.686713 -388.661721) (xy 63.69431 -388.68604)
			(xy 63.695834 -388.691882) (xy 64.016128 -389.245602) (xy 64.020192 -389.24992) (xy 64.036409 -389.267618)
			(xy 64.063843 -389.307007) (xy 64.08499 -389.350098) (xy 64.099364 -389.395896) (xy 64.106631 -389.443344)
			(xy 64.10706 -389.467344) (xy 64.106595 -389.492146) (xy 64.098825 -389.541137) (xy 64.083483 -389.588309)
			(xy 64.060948 -389.632498) (xy 64.031775 -389.672616) (xy 63.996683 -389.707674) (xy 63.956537 -389.736808)
			(xy 63.912326 -389.7593) (xy 63.865139 -389.774596) (xy 63.81614 -389.782319) (xy 63.791338 -389.782812)
			(xy 63.765942 -389.782307) (xy 63.715806 -389.774182) (xy 63.667616 -389.758134) (xy 63.622618 -389.734579)
			(xy 63.581971 -389.704123) (xy 63.546724 -389.667553) (xy 63.517787 -389.625811) (xy 63.495906 -389.579975)
			(xy 63.488316 -389.555736) (xy 63.486792 -389.549894) (xy 63.166498 -388.996174) (xy 63.162434 -388.991856)
			(xy 63.146243 -388.974148) (xy 63.118866 -388.934746) (xy 63.097774 -388.89165) (xy 63.083455 -388.845857)
			(xy 63.076241 -388.798422) (xy 63.07582 -388.774432) (xy 63.075906 -388.762384) (xy 63.077689 -388.738355)
			(xy 63.079376 -388.726426) (xy 63.080646 -388.717536) (xy 63.077598 -388.700518) (xy 63.035434 -388.629652)
			(xy 63.022226 -388.618476) (xy 63.013844 -388.615428) (xy 62.992106 -388.607021) (xy 62.951265 -388.584565)
			(xy 62.914312 -388.556164) (xy 62.882103 -388.522477) (xy 62.855388 -388.484287) (xy 62.834787 -388.442481)
			(xy 62.820777 -388.398029) (xy 62.813685 -388.351965) (xy 62.813184 -388.328662) (xy 62.813683 -388.303264)
			(xy 62.822083 -388.253167) (xy 62.83866 -388.205152) (xy 62.862957 -388.160543) (xy 62.894304 -388.120573)
			(xy 62.912752 -388.10311) (xy 62.921134 -388.09549) (xy 62.92977 -388.075424) (xy 62.926976 -387.97611)
			(xy 62.917578 -387.956552) (xy 62.908688 -387.94944) (xy 62.890127 -387.933637) (xy 62.857402 -387.89751)
			(xy 62.83033 -387.856973) (xy 62.809498 -387.812903) (xy 62.795356 -387.766254) (xy 62.788211 -387.718035)
			(xy 62.787784 -387.693662) (xy 62.788223 -387.669546) (xy 62.795228 -387.621825) (xy 62.809085 -387.575627)
			(xy 62.8295 -387.531928) (xy 62.842394 -387.511544) (xy 62.848236 -387.502654) (xy 62.851792 -387.482588)
			(xy 62.83071 -387.390386) (xy 62.818518 -387.373622) (xy 62.809628 -387.368288) (xy 62.788827 -387.355432)
			(xy 62.750913 -387.324552) (xy 62.717964 -387.288421) (xy 62.690702 -387.247827) (xy 62.669722 -387.203658)
			(xy 62.655483 -387.156879) (xy 62.648295 -387.108511) (xy 62.64783 -387.084062) (xy 62.648391 -387.05678)
			(xy 62.657353 -387.002956) (xy 62.675026 -386.951333) (xy 62.700932 -386.90331) (xy 62.734369 -386.860191)
			(xy 62.754002 -386.841238) (xy 62.76145 -386.833746) (xy 62.769993 -386.814451) (xy 62.770512 -386.8039)
			(xy 62.770512 -386.729224) (xy 62.769926 -386.718688) (xy 62.7614 -386.699411) (xy 62.754002 -386.691886)
			(xy 62.736795 -386.675372) (xy 62.70683 -386.638271) (xy 62.694312 -386.617972) (xy 62.689511 -386.610599)
			(xy 62.675957 -386.599402) (xy 62.659414 -386.593449) (xy 62.650624 -386.59308) (xy 62.106556 -386.59308)
			(xy 62.097762 -386.593441) (xy 62.08121 -386.599384) (xy 62.067652 -386.610586) (xy 62.062868 -386.617972)
			(xy 62.050346 -386.638268) (xy 62.020378 -386.675366) (xy 62.003178 -386.691886) (xy 61.995736 -386.699381)
			(xy 61.987206 -386.718676) (xy 61.986668 -386.729224) (xy 61.986668 -386.8039) (xy 61.987258 -386.814434)
			(xy 61.995788 -386.833707) (xy 62.003178 -386.841238) (xy 62.02283 -386.860172) (xy 62.056268 -386.903294)
			(xy 62.082172 -386.951321) (xy 62.099838 -387.00295) (xy 62.108787 -387.056778) (xy 62.10935 -387.084062)
			(xy 62.108917 -387.108179) (xy 62.10192 -387.155904) (xy 62.08807 -387.202107) (xy 62.067659 -387.24581)
			(xy 62.05474 -387.26618) (xy 62.048898 -387.27507) (xy 62.045342 -387.295136) (xy 62.066424 -387.387338)
			(xy 62.078616 -387.404102) (xy 62.087506 -387.409436) (xy 62.108309 -387.42229) (xy 62.146228 -387.453167)
			(xy 62.17918 -387.489297) (xy 62.206445 -387.529891) (xy 62.227427 -387.574061) (xy 62.241666 -387.620842)
			(xy 62.248853 -387.669212) (xy 62.249304 -387.693662) (xy 62.248866 -387.718032) (xy 62.24171 -387.766245)
			(xy 62.22756 -387.812886) (xy 62.206724 -387.856948) (xy 62.179651 -387.897479) (xy 62.146928 -387.933601)
			(xy 62.1284 -387.94944) (xy 62.11951 -387.956552) (xy 62.110112 -387.97611) (xy 62.107318 -388.075424)
			(xy 62.115954 -388.09549) (xy 62.124336 -388.10311) (xy 62.142756 -388.120599) (xy 62.174094 -388.160568)
			(xy 62.198388 -388.205171) (xy 62.214968 -388.253178) (xy 62.223377 -388.303267) (xy 62.223904 -388.328662)
			(xy 62.223832 -388.33802) (xy 62.222686 -388.356702) (xy 62.221618 -388.366) (xy 62.220602 -388.37489)
			(xy 62.224412 -388.391654) (xy 62.268354 -388.461504) (xy 62.28207 -388.471918) (xy 62.290452 -388.474712)
			(xy 62.314545 -388.483198) (xy 62.359825 -388.506834) (xy 62.400711 -388.53745) (xy 62.436136 -388.574247)
			(xy 62.465176 -388.616267) (xy 62.487074 -388.662413) (xy 62.494668 -388.686802) (xy 62.496192 -388.692644)
			(xy 62.815978 -389.245602) (xy 62.820042 -389.24992) (xy 62.83623 -389.26763) (xy 62.863605 -389.307033)
			(xy 62.884695 -389.350128) (xy 62.899013 -389.395921) (xy 62.906229 -389.443354) (xy 62.906656 -389.467344)
			(xy 62.906166 -389.492131) (xy 62.898405 -389.541094) (xy 62.88308 -389.58824) (xy 62.860569 -389.632408)
			(xy 62.831426 -389.672511) (xy 62.796369 -389.707562) (xy 62.75626 -389.736698) (xy 62.712088 -389.759201)
			(xy 62.664939 -389.774518) (xy 62.615975 -389.782271) (xy 62.591188 -389.782812) (xy 62.565795 -389.782303)
			(xy 62.515664 -389.774171) (xy 62.467481 -389.758119) (xy 62.422489 -389.734561) (xy 62.381849 -389.704103)
			(xy 62.346608 -389.667533) (xy 62.317677 -389.625793) (xy 62.2958 -389.57996) (xy 62.288166 -389.555736)
			(xy 62.286642 -389.549894) (xy 61.966094 -388.995412) (xy 61.96203 -388.991094) (xy 61.945952 -388.973415)
			(xy 61.918768 -388.934116) (xy 61.897812 -388.891172) (xy 61.883563 -388.845561) (xy 61.876347 -388.798324)
			(xy 61.875924 -388.774432) (xy 61.87601 -388.762384) (xy 61.877793 -388.738355) (xy 61.87948 -388.726426)
			(xy 61.88075 -388.717536) (xy 61.877702 -388.700518) (xy 61.835538 -388.629652) (xy 61.82233 -388.618476)
			(xy 61.813948 -388.615428) (xy 61.792209 -388.607021) (xy 61.751369 -388.584565) (xy 61.714415 -388.556164)
			(xy 61.682206 -388.522478) (xy 61.65549 -388.484288) (xy 61.634888 -388.442481) (xy 61.620879 -388.39803)
			(xy 61.613787 -388.351965) (xy 61.613288 -388.328662) (xy 61.613788 -388.303264) (xy 61.622187 -388.253167)
			(xy 61.638764 -388.205152) (xy 61.663062 -388.160544) (xy 61.694409 -388.120574) (xy 61.712856 -388.10311)
			(xy 61.721238 -388.09549) (xy 61.729874 -388.075424) (xy 61.72708 -387.97611) (xy 61.717682 -387.956552)
			(xy 61.708792 -387.94944) (xy 61.690231 -387.933637) (xy 61.657505 -387.89751) (xy 61.630433 -387.856973)
			(xy 61.609601 -387.812903) (xy 61.595459 -387.766254) (xy 61.588313 -387.718035) (xy 61.587888 -387.693662)
			(xy 61.588327 -387.669546) (xy 61.595332 -387.621826) (xy 61.609189 -387.575627) (xy 61.629604 -387.531929)
			(xy 61.642498 -387.511544) (xy 61.64834 -387.502654) (xy 61.651896 -387.482588) (xy 61.630814 -387.390386)
			(xy 61.618622 -387.373622) (xy 61.609732 -387.368288) (xy 61.588931 -387.355432) (xy 61.551016 -387.324552)
			(xy 61.518067 -387.288421) (xy 61.490805 -387.247827) (xy 61.469825 -387.203658) (xy 61.455585 -387.156879)
			(xy 61.448397 -387.108512) (xy 61.447934 -387.084062) (xy 61.448495 -387.056779) (xy 61.457454 -387.002953)
			(xy 61.475124 -386.951327) (xy 61.501025 -386.903299) (xy 61.534455 -386.860173) (xy 61.554106 -386.841238)
			(xy 61.561554 -386.833746) (xy 61.570096 -386.814451) (xy 61.570616 -386.8039) (xy 61.570616 -386.729224)
			(xy 61.57003 -386.718688) (xy 61.561504 -386.69941) (xy 61.554106 -386.691886) (xy 61.536899 -386.675372)
			(xy 61.506934 -386.638272) (xy 61.494416 -386.617972) (xy 61.489615 -386.610599) (xy 61.476061 -386.599401)
			(xy 61.459519 -386.593446) (xy 61.450728 -386.59308) (xy 60.906406 -386.59308) (xy 60.897617 -386.593449)
			(xy 60.881077 -386.599403) (xy 60.867533 -386.610608) (xy 60.862718 -386.617972) (xy 60.84884 -386.640358)
			(xy 60.815119 -386.680817) (xy 60.775409 -386.715415) (xy 60.730714 -386.743278) (xy 60.682166 -386.763699)
			(xy 60.630993 -386.776163) (xy 60.578492 -386.780353) (xy 60.525991 -386.776163) (xy 60.474818 -386.763699)
			(xy 60.42627 -386.743278) (xy 60.381575 -386.715415) (xy 60.341865 -386.680817) (xy 60.308144 -386.640358)
			(xy 60.294266 -386.617972) (xy 60.289463 -386.610604) (xy 60.275906 -386.59942) (xy 60.259366 -386.593481)
			(xy 60.250578 -386.59308) (xy 59.70651 -386.59308) (xy 59.69772 -386.593449) (xy 59.68118 -386.599402)
			(xy 59.667635 -386.610606) (xy 59.662822 -386.617972) (xy 59.654186 -386.631688) (xy 59.649435 -386.639658)
			(xy 59.645414 -386.657757) (xy 59.646312 -386.666994) (xy 59.65063 -386.697982) (xy 59.652435 -386.707234)
			(xy 59.661696 -386.723634) (xy 59.668664 -386.729986) (xy 59.690762 -386.748659) (xy 59.730541 -386.790667)
			(xy 59.764708 -386.837354) (xy 59.792718 -386.887975) (xy 59.814124 -386.941724) (xy 59.828584 -386.997741)
			(xy 59.835869 -387.055135) (xy 59.836304 -387.084062) (xy 59.8357 -387.117382) (xy 59.826031 -387.183317)
			(xy 59.806907 -387.247154) (xy 59.793378 -387.27761) (xy 59.789115 -387.288079) (xy 59.78919 -387.310653)
			(xy 59.798946 -387.33101) (xy 59.807348 -387.33857) (xy 59.829594 -387.357245) (xy 59.869657 -387.399301)
			(xy 59.904077 -387.446087) (xy 59.932303 -387.496852) (xy 59.95388 -387.55078) (xy 59.968462 -387.607003)
			(xy 59.975814 -387.66462) (xy 59.976258 -387.693662) (xy 59.975807 -387.722666) (xy 59.968476 -387.780208)
			(xy 59.953938 -387.836364) (xy 59.932427 -387.890235) (xy 59.904286 -387.940959) (xy 59.869967 -387.987725)
			(xy 59.830017 -388.029783) (xy 59.807856 -388.0485) (xy 59.800744 -388.054088) (xy 59.7916 -388.069328)
			(xy 59.77636 -388.152132) (xy 59.779154 -388.169404) (xy 59.783726 -388.177532) (xy 59.796322 -388.20071)
			(xy 59.814213 -388.25033) (xy 59.823298 -388.302289) (xy 59.823858 -388.328662) (xy 60.413138 -388.328662)
			(xy 60.41366 -388.303407) (xy 60.421973 -388.253585) (xy 60.438374 -388.205811) (xy 60.462415 -388.161388)
			(xy 60.493439 -388.121528) (xy 60.530601 -388.087318) (xy 60.572887 -388.059692) (xy 60.619143 -388.039402)
			(xy 60.668108 -388.027002) (xy 60.718446 -388.022831) (xy 60.768784 -388.027002) (xy 60.817749 -388.039402)
			(xy 60.864005 -388.059692) (xy 60.906291 -388.087318) (xy 60.943453 -388.121528) (xy 60.974477 -388.161388)
			(xy 60.998518 -388.205811) (xy 61.014919 -388.253585) (xy 61.023232 -388.303407) (xy 61.023754 -388.328662)
			(xy 61.023685 -388.338021) (xy 61.022542 -388.356703) (xy 61.021468 -388.366) (xy 61.020452 -388.37489)
			(xy 61.024262 -388.391654) (xy 61.068204 -388.461504) (xy 61.08192 -388.471918) (xy 61.090302 -388.474712)
			(xy 61.114323 -388.4832) (xy 61.159496 -388.506748) (xy 61.200302 -388.537243) (xy 61.235683 -388.573894)
			(xy 61.26472 -388.61575) (xy 61.28666 -388.661725) (xy 61.294264 -388.68604) (xy 61.295788 -388.691882)
			(xy 61.616082 -389.245602) (xy 61.620146 -389.24992) (xy 61.636342 -389.267622) (xy 61.663705 -389.307033)
			(xy 61.684789 -389.350131) (xy 61.699107 -389.395923) (xy 61.706332 -389.443354) (xy 61.70676 -389.467344)
			(xy 61.706323 -389.492135) (xy 61.69856 -389.541106) (xy 61.683233 -389.58826) (xy 61.660718 -389.632436)
			(xy 61.63157 -389.672547) (xy 61.596507 -389.707604) (xy 61.556392 -389.736745) (xy 61.512212 -389.759252)
			(xy 61.465056 -389.774572) (xy 61.416083 -389.782327) (xy 61.391292 -389.782812) (xy 61.365897 -389.782319)
			(xy 61.315763 -389.774187) (xy 61.267578 -389.758134) (xy 61.222583 -389.734575) (xy 61.181941 -389.704116)
			(xy 61.146698 -389.667544) (xy 61.117765 -389.625802) (xy 61.095887 -389.579967) (xy 61.08827 -389.555736)
			(xy 61.086746 -389.549894) (xy 60.766452 -388.996174) (xy 60.762388 -388.991856) (xy 60.746183 -388.974149)
			(xy 60.718759 -388.934758) (xy 60.697617 -388.891668) (xy 60.683243 -388.845874) (xy 60.67597 -388.798431)
			(xy 60.67552 -388.774432) (xy 60.675662 -388.76238) (xy 60.677568 -388.73835) (xy 60.67933 -388.726426)
			(xy 60.6806 -388.717536) (xy 60.677552 -388.700518) (xy 60.635388 -388.629652) (xy 60.62218 -388.618476)
			(xy 60.613798 -388.615428) (xy 60.592056 -388.607017) (xy 60.551197 -388.58458) (xy 60.514225 -388.55619)
			(xy 60.482001 -388.522507) (xy 60.455275 -388.484315) (xy 60.434668 -388.442503) (xy 60.42066 -388.398043)
			(xy 60.413576 -388.351969) (xy 60.413138 -388.328662) (xy 59.823858 -388.328662) (xy 59.823786 -388.33802)
			(xy 59.82264 -388.356702) (xy 59.821572 -388.366) (xy 59.820556 -388.37489) (xy 59.824366 -388.391654)
			(xy 59.868308 -388.461504) (xy 59.882024 -388.471918) (xy 59.890406 -388.474712) (xy 59.914442 -388.483165)
			(xy 59.959624 -388.506711) (xy 60.000437 -388.537207) (xy 60.035822 -388.573864) (xy 60.064859 -388.615728)
			(xy 60.086795 -388.661713) (xy 60.094368 -388.68604) (xy 60.095892 -388.691882) (xy 60.416186 -389.245602)
			(xy 60.42025 -389.24992) (xy 60.436443 -389.267627) (xy 60.463825 -389.307028) (xy 60.484921 -389.350123)
			(xy 60.499244 -389.395917) (xy 60.506462 -389.443353) (xy 60.506864 -389.467344) (xy 60.506374 -389.492131)
			(xy 60.498613 -389.541094) (xy 60.483288 -389.588241) (xy 60.460777 -389.63241) (xy 60.431634 -389.672514)
			(xy 60.396577 -389.707566) (xy 60.356469 -389.736702) (xy 60.312296 -389.759206) (xy 60.265148 -389.774524)
			(xy 60.216183 -389.782278) (xy 60.191396 -389.782812) (xy 60.166002 -389.782304) (xy 60.11587 -389.774173)
			(xy 60.067686 -389.758122) (xy 60.022694 -389.734564) (xy 59.982052 -389.704107) (xy 59.946811 -389.667536)
			(xy 59.917878 -389.625796) (xy 59.896001 -389.579963) (xy 59.888374 -389.555736) (xy 59.88685 -389.549894)
			(xy 59.566556 -388.996174) (xy 59.562492 -388.991856) (xy 59.546277 -388.974157) (xy 59.518848 -388.934767)
			(xy 59.497705 -388.891676) (xy 59.483335 -388.845878) (xy 59.476072 -388.798432) (xy 59.475624 -388.774432)
			(xy 59.475782 -388.76238) (xy 59.477691 -388.738352) (xy 59.479434 -388.726426) (xy 59.480704 -388.717536)
			(xy 59.477656 -388.700518) (xy 59.435492 -388.629652) (xy 59.422284 -388.618476) (xy 59.413902 -388.615428)
			(xy 59.39216 -388.607024) (xy 59.351313 -388.584572) (xy 59.314353 -388.556174) (xy 59.282138 -388.522488)
			(xy 59.255417 -388.484297) (xy 59.234811 -388.442489) (xy 59.220799 -388.398035) (xy 59.213706 -388.351967)
			(xy 59.213242 -388.328662) (xy 59.213824 -388.302291) (xy 59.222925 -388.25034) (xy 59.2408 -388.200719)
			(xy 59.253374 -388.177532) (xy 59.257946 -388.169404) (xy 59.26074 -388.152132) (xy 59.2455 -388.069328)
			(xy 59.236356 -388.054088) (xy 59.229244 -388.0485) (xy 59.207055 -388.029815) (xy 59.167105 -387.987755)
			(xy 59.132787 -387.940985) (xy 59.104654 -387.890254) (xy 59.083153 -387.836376) (xy 59.068632 -387.780214)
			(xy 59.061321 -387.722667) (xy 59.060842 -387.693662) (xy 59.061445 -387.660342) (xy 59.071111 -387.594406)
			(xy 59.090234 -387.530568) (xy 59.103768 -387.500114) (xy 59.108034 -387.489643) (xy 59.107967 -387.467062)
			(xy 59.098222 -387.446692) (xy 59.089798 -387.439154) (xy 59.067553 -387.420479) (xy 59.027494 -387.378423)
			(xy 58.993078 -387.331636) (xy 58.964858 -387.28087) (xy 58.943287 -387.226942) (xy 58.928713 -387.170719)
			(xy 58.921369 -387.113103) (xy 58.920888 -387.084062) (xy 58.921333 -387.055136) (xy 58.928626 -386.997746)
			(xy 58.943091 -386.941732) (xy 58.964498 -386.887987) (xy 58.992505 -386.837367) (xy 59.026667 -386.790678)
			(xy 59.066438 -386.748666) (xy 59.088528 -386.729986) (xy 59.095603 -386.723722) (xy 59.104891 -386.707281)
			(xy 59.106562 -386.697982) (xy 59.11088 -386.666994) (xy 59.111828 -386.657756) (xy 59.107792 -386.639646)
			(xy 59.103006 -386.631688) (xy 59.09437 -386.617972) (xy 59.089567 -386.610604) (xy 59.076011 -386.599418)
			(xy 59.05947 -386.593478) (xy 59.050682 -386.59308) (xy 58.50636 -386.59308) (xy 58.497575 -386.593457)
			(xy 58.481047 -386.59942) (xy 58.467515 -386.610629) (xy 58.462672 -386.617972) (xy 58.45015 -386.638269)
			(xy 58.420182 -386.675366) (xy 58.402982 -386.691886) (xy 58.395539 -386.69938) (xy 58.387009 -386.718675)
			(xy 58.386472 -386.729224) (xy 58.386472 -386.8039) (xy 58.387062 -386.814434) (xy 58.395592 -386.833707)
			(xy 58.402982 -386.841238) (xy 58.422634 -386.860172) (xy 58.456072 -386.903294) (xy 58.481975 -386.951321)
			(xy 58.499641 -387.00295) (xy 58.50859 -387.056778) (xy 58.509154 -387.084062) (xy 58.508721 -387.108179)
			(xy 58.501724 -387.155904) (xy 58.487874 -387.202107) (xy 58.467463 -387.245811) (xy 58.454544 -387.26618)
			(xy 58.448702 -387.27507) (xy 58.445146 -387.295136) (xy 58.466228 -387.387338) (xy 58.47842 -387.404102)
			(xy 58.48731 -387.409436) (xy 58.508113 -387.42229) (xy 58.546032 -387.453167) (xy 58.578983 -387.489298)
			(xy 58.606248 -387.529892) (xy 58.627229 -387.574062) (xy 58.641468 -387.620843) (xy 58.648655 -387.669212)
			(xy 58.649108 -387.693662) (xy 58.64867 -387.718032) (xy 58.641514 -387.766245) (xy 58.627364 -387.812886)
			(xy 58.606528 -387.856949) (xy 58.579456 -387.89748) (xy 58.546732 -387.933602) (xy 58.528204 -387.94944)
			(xy 58.519314 -387.956552) (xy 58.509916 -387.97611) (xy 58.507122 -388.075424) (xy 58.515758 -388.09549)
			(xy 58.52414 -388.10311) (xy 58.54256 -388.120599) (xy 58.573898 -388.160568) (xy 58.598191 -388.205171)
			(xy 58.614771 -388.253178) (xy 58.62318 -388.303267) (xy 58.623708 -388.328662) (xy 58.623636 -388.33802)
			(xy 58.62249 -388.356702) (xy 58.621422 -388.366) (xy 58.620406 -388.37489) (xy 58.624216 -388.391654)
			(xy 58.668158 -388.461504) (xy 58.681874 -388.471918) (xy 58.690256 -388.474712) (xy 58.714289 -388.483168)
			(xy 58.759465 -388.506718) (xy 58.800273 -388.537218) (xy 58.835652 -388.573876) (xy 58.864684 -388.61574)
			(xy 58.886616 -388.661723) (xy 58.894218 -388.68604) (xy 58.895742 -388.691882) (xy 59.216036 -389.245602)
			(xy 59.2201 -389.24992) (xy 59.236317 -389.267618) (xy 59.26375 -389.307007) (xy 59.284897 -389.350098)
			(xy 59.29927 -389.395896) (xy 59.306537 -389.443344) (xy 59.306968 -389.467344) (xy 59.306503 -389.492146)
			(xy 59.298733 -389.541138) (xy 59.283391 -389.58831) (xy 59.260857 -389.6325) (xy 59.231684 -389.672619)
			(xy 59.196592 -389.707678) (xy 59.156445 -389.736813) (xy 59.112234 -389.759306) (xy 59.065048 -389.774602)
			(xy 59.016048 -389.782326) (xy 58.991246 -389.782812) (xy 58.96585 -389.782308) (xy 58.915712 -389.774183)
			(xy 58.867522 -389.758137) (xy 58.822523 -389.734582) (xy 58.781875 -389.704126) (xy 58.746627 -389.667556)
			(xy 58.717689 -389.625814) (xy 58.695807 -389.579978) (xy 58.688224 -389.555736) (xy 58.6867 -389.549894)
			(xy 58.366406 -388.996174) (xy 58.362342 -388.991856) (xy 58.346151 -388.974148) (xy 58.318772 -388.934746)
			(xy 58.29768 -388.891651) (xy 58.283361 -388.845857) (xy 58.276147 -388.798423) (xy 58.275728 -388.774432)
			(xy 58.275814 -388.762384) (xy 58.277597 -388.738355) (xy 58.279284 -388.726426) (xy 58.280554 -388.717536)
			(xy 58.277506 -388.700518) (xy 58.235342 -388.629652) (xy 58.222134 -388.618476) (xy 58.213752 -388.615428)
			(xy 58.192013 -388.607021) (xy 58.151172 -388.584566) (xy 58.114218 -388.556165) (xy 58.082008 -388.522478)
			(xy 58.055292 -388.484288) (xy 58.03469 -388.442482) (xy 58.02068 -388.39803) (xy 58.013588 -388.351966)
			(xy 58.013092 -388.328662) (xy 58.013592 -388.303264) (xy 58.021991 -388.253167) (xy 58.038569 -388.205152)
			(xy 58.062867 -388.160545) (xy 58.094214 -388.120575) (xy 58.11266 -388.10311) (xy 58.121042 -388.09549)
			(xy 58.129678 -388.075424) (xy 58.126884 -387.97611) (xy 58.117486 -387.956552) (xy 58.108596 -387.94944)
			(xy 58.090035 -387.933637) (xy 58.057309 -387.897511) (xy 58.030236 -387.856974) (xy 58.009404 -387.812904)
			(xy 57.995261 -387.766254) (xy 57.988116 -387.718035) (xy 57.987692 -387.693662) (xy 57.988131 -387.669546)
			(xy 57.995136 -387.621826) (xy 58.008993 -387.575627) (xy 58.029409 -387.531929) (xy 58.042302 -387.511544)
			(xy 58.048144 -387.502654) (xy 58.0517 -387.482588) (xy 58.030618 -387.390386) (xy 58.018426 -387.373622)
			(xy 58.009536 -387.368288) (xy 57.988735 -387.355432) (xy 57.950819 -387.324553) (xy 57.91787 -387.288422)
			(xy 57.890608 -387.247828) (xy 57.869627 -387.203659) (xy 57.855387 -387.156879) (xy 57.848199 -387.108512)
			(xy 57.847738 -387.084062) (xy 57.848299 -387.056779) (xy 57.857258 -387.002953) (xy 57.874928 -386.951327)
			(xy 57.900829 -386.9033) (xy 57.93426 -386.860173) (xy 57.95391 -386.841238) (xy 57.961357 -386.833745)
			(xy 57.969899 -386.81445) (xy 57.97042 -386.8039) (xy 57.97042 -386.729224) (xy 57.969835 -386.718688)
			(xy 57.961309 -386.699409) (xy 57.95391 -386.691886) (xy 57.936703 -386.675373) (xy 57.906737 -386.638272)
			(xy 57.89422 -386.617972) (xy 57.889419 -386.610598) (xy 57.875865 -386.599399) (xy 57.859323 -386.593443)
			(xy 57.850532 -386.59308) (xy 57.526682 -386.59308) (xy 57.516614 -386.592653) (xy 57.498016 -386.584932)
			(xy 57.490614 -386.578094) (xy 57.451244 -386.538724) (xy 57.44185 -386.530326) (xy 57.417732 -386.52314)
			(xy 57.40527 -386.525008) (xy 57.309766 -386.544566) (xy 57.289954 -386.560822) (xy 57.285382 -386.57276)
			(xy 57.275856 -386.595162) (xy 57.251199 -386.637135) (xy 57.220674 -386.675056) (xy 57.203086 -386.691886)
			(xy 57.195643 -386.69938) (xy 57.187112 -386.718675) (xy 57.186576 -386.729224) (xy 57.186576 -386.8039)
			(xy 57.187166 -386.814434) (xy 57.195697 -386.833706) (xy 57.203086 -386.841238) (xy 57.222738 -386.860172)
			(xy 57.256175 -386.903295) (xy 57.282078 -386.951322) (xy 57.299744 -387.00295) (xy 57.308693 -387.056778)
			(xy 57.309258 -387.084062) (xy 57.308825 -387.108179) (xy 57.301828 -387.155904) (xy 57.287978 -387.202107)
			(xy 57.267568 -387.245811) (xy 57.254648 -387.26618) (xy 57.248806 -387.27507) (xy 57.24525 -387.295136)
			(xy 57.266332 -387.387338) (xy 57.278524 -387.404102) (xy 57.287414 -387.409436) (xy 57.308217 -387.422291)
			(xy 57.346135 -387.453168) (xy 57.379086 -387.489298) (xy 57.406351 -387.529892) (xy 57.427331 -387.574062)
			(xy 57.441571 -387.620843) (xy 57.448757 -387.669212) (xy 57.449212 -387.693662) (xy 57.448774 -387.718032)
			(xy 57.441618 -387.766245) (xy 57.427469 -387.812887) (xy 57.406633 -387.856949) (xy 57.37956 -387.89748)
			(xy 57.346837 -387.933603) (xy 57.328308 -387.94944) (xy 57.319418 -387.956552) (xy 57.31002 -387.97611)
			(xy 57.307226 -388.075424) (xy 57.315862 -388.09549) (xy 57.324244 -388.10311) (xy 57.342663 -388.120599)
			(xy 57.374001 -388.160568) (xy 57.398294 -388.205171) (xy 57.414874 -388.253179) (xy 57.423282 -388.303267)
			(xy 57.423812 -388.328662) (xy 57.42374 -388.33802) (xy 57.422594 -388.356702) (xy 57.421526 -388.366)
			(xy 57.42051 -388.37489) (xy 57.42432 -388.391654) (xy 57.468262 -388.461504) (xy 57.481978 -388.471918)
			(xy 57.49036 -388.474712) (xy 57.514393 -388.483169) (xy 57.559569 -388.506719) (xy 57.600376 -388.537219)
			(xy 57.635754 -388.573876) (xy 57.664786 -388.61574) (xy 57.686718 -388.661724) (xy 57.694322 -388.68604)
			(xy 57.695846 -388.691882) (xy 58.01614 -389.245602) (xy 58.020204 -389.24992) (xy 58.036421 -389.267618)
			(xy 58.063853 -389.307007) (xy 58.085 -389.350099) (xy 58.099373 -389.395897) (xy 58.10664 -389.443344)
			(xy 58.107072 -389.467344) (xy 58.106607 -389.492146) (xy 58.098837 -389.541138) (xy 58.083495 -389.588311)
			(xy 58.060961 -389.632501) (xy 58.031788 -389.67262) (xy 57.996696 -389.707679) (xy 57.95655 -389.736815)
			(xy 57.912339 -389.759308) (xy 57.865152 -389.774605) (xy 57.816153 -389.78233) (xy 57.79135 -389.782812)
			(xy 57.765954 -389.782308) (xy 57.715816 -389.774184) (xy 57.667625 -389.758138) (xy 57.622625 -389.734583)
			(xy 57.581977 -389.704128) (xy 57.546728 -389.667558) (xy 57.51779 -389.625816) (xy 57.495907 -389.579979)
			(xy 57.488328 -389.555736) (xy 57.486804 -389.549894) (xy 57.16651 -388.996174) (xy 57.162446 -388.991856)
			(xy 57.146255 -388.974148) (xy 57.118876 -388.934746) (xy 57.097783 -388.891651) (xy 57.083464 -388.845857)
			(xy 57.07625 -388.798423) (xy 57.075832 -388.774432) (xy 57.075918 -388.762384) (xy 57.077701 -388.738355)
			(xy 57.079388 -388.726426) (xy 57.080658 -388.717536) (xy 57.07761 -388.700518) (xy 57.035446 -388.629652)
			(xy 57.022238 -388.618476) (xy 57.013856 -388.615428) (xy 56.992117 -388.607021) (xy 56.951275 -388.584566)
			(xy 56.91432 -388.556166) (xy 56.882111 -388.522479) (xy 56.855394 -388.484289) (xy 56.834792 -388.442482)
			(xy 56.820782 -388.39803) (xy 56.81369 -388.351966) (xy 56.813196 -388.328662) (xy 56.813696 -388.303264)
			(xy 56.822096 -388.253167) (xy 56.838673 -388.205153) (xy 56.862971 -388.160545) (xy 56.894319 -388.120576)
			(xy 56.912764 -388.10311) (xy 56.921146 -388.09549) (xy 56.929782 -388.075424) (xy 56.926988 -387.97611)
			(xy 56.91759 -387.956552) (xy 56.9087 -387.94944) (xy 56.890139 -387.933638) (xy 56.857412 -387.897511)
			(xy 56.830339 -387.856974) (xy 56.809506 -387.812904) (xy 56.795364 -387.766255) (xy 56.788218 -387.718035)
			(xy 56.787796 -387.693662) (xy 56.788235 -387.669546) (xy 56.79524 -387.621826) (xy 56.809098 -387.575627)
			(xy 56.829513 -387.531929) (xy 56.842406 -387.511544) (xy 56.848248 -387.502654) (xy 56.851804 -387.482588)
			(xy 56.830722 -387.390386) (xy 56.81853 -387.373622) (xy 56.80964 -387.368288) (xy 56.788839 -387.355432)
			(xy 56.750923 -387.324553) (xy 56.717973 -387.288422) (xy 56.69071 -387.247828) (xy 56.669729 -387.203659)
			(xy 56.655489 -387.15688) (xy 56.648301 -387.108512) (xy 56.647842 -387.084062) (xy 56.648403 -387.056779)
			(xy 56.657363 -387.002953) (xy 56.675033 -386.951327) (xy 56.700934 -386.9033) (xy 56.734365 -386.860174)
			(xy 56.754014 -386.841238) (xy 56.761461 -386.833745) (xy 56.770001 -386.81445) (xy 56.770524 -386.8039)
			(xy 56.770524 -386.729224) (xy 56.769939 -386.718688) (xy 56.761414 -386.699409) (xy 56.754014 -386.691886)
			(xy 56.734361 -386.672952) (xy 56.70092 -386.629831) (xy 56.675014 -386.581804) (xy 56.657345 -386.530175)
			(xy 56.648392 -386.476346) (xy 56.647842 -386.449062) (xy 56.648096 -386.43687) (xy 56.64835 -386.427218)
			(xy 56.642254 -386.409184) (xy 56.58358 -386.341874) (xy 56.566816 -386.333238) (xy 56.55691 -386.332222)
			(xy 56.529994 -386.328875) (xy 56.477688 -386.314536) (xy 56.428424 -386.291852) (xy 56.383523 -386.26143)
			(xy 56.34419 -386.224088) (xy 56.31148 -386.180827) (xy 56.286269 -386.132807) (xy 56.269235 -386.081316)
			(xy 56.264556 -386.0546) (xy 56.263032 -386.045202) (xy 55.989982 -385.572762) (xy 55.98287 -385.56692)
			(xy 55.964137 -385.55114) (xy 55.931083 -385.514997) (xy 55.903724 -385.474371) (xy 55.88266 -385.430153)
			(xy 55.868351 -385.38331) (xy 55.861112 -385.334869) (xy 55.860696 -385.31038) (xy 55.861104 -385.286876)
			(xy 55.867753 -385.240342) (xy 55.880929 -385.195219) (xy 55.900365 -385.152418) (xy 55.925669 -385.112802)
			(xy 55.940706 -385.094734) (xy 55.95366 -385.079494) (xy 55.952136 -385.039616) (xy 55.86857 -384.95605)
			(xy 55.851552 -384.94843) (xy 55.842408 -384.947922) (xy 55.815838 -384.945769) (xy 55.763841 -384.934043)
			(xy 55.714396 -384.914132) (xy 55.668784 -384.886551) (xy 55.628184 -384.852013) (xy 55.593647 -384.811412)
			(xy 55.566066 -384.7658) (xy 55.546156 -384.716355) (xy 55.534431 -384.664358) (xy 55.532274 -384.637788)
			(xy 55.531766 -384.628644) (xy 55.524146 -384.611626) (xy 54.04104 -383.12852) (xy 54.006242 -383.124456)
			(xy 53.991002 -383.133854) (xy 53.971267 -383.145647) (xy 53.92923 -383.164261) (xy 53.885021 -383.176873)
			(xy 53.839491 -383.183241) (xy 53.816504 -383.183638) (xy 53.790963 -383.18317) (xy 53.740487 -383.175328)
			(xy 53.691818 -383.159813) (xy 53.646115 -383.136995) (xy 53.604467 -383.107419) (xy 53.567865 -383.071787)
			(xy 53.53718 -383.030948) (xy 53.513144 -382.985875) (xy 53.504338 -382.961896) (xy 53.499004 -382.946656)
			(xy 53.472588 -382.92786) (xy 52.960524 -382.92786) (xy 52.934108 -382.946656) (xy 52.928774 -382.961896)
			(xy 52.919911 -382.985847) (xy 52.895867 -383.030902) (xy 52.865182 -383.071724) (xy 52.828585 -383.107342)
			(xy 52.786947 -383.13691) (xy 52.741257 -383.159724) (xy 52.692604 -383.175241) (xy 52.642142 -383.183093)
			(xy 52.591074 -383.183093) (xy 52.540612 -383.175241) (xy 52.491959 -383.159724) (xy 52.446269 -383.13691)
			(xy 52.404631 -383.107342) (xy 52.368034 -383.071724) (xy 52.337349 -383.030902) (xy 52.313305 -382.985847)
			(xy 52.304442 -382.961896) (xy 52.299108 -382.946656) (xy 52.272692 -382.92786) (xy 51.760374 -382.92786)
			(xy 51.733958 -382.946656) (xy 51.728624 -382.961896) (xy 51.719761 -382.985847) (xy 51.695717 -383.030902)
			(xy 51.665032 -383.071724) (xy 51.628435 -383.107342) (xy 51.586797 -383.13691) (xy 51.541107 -383.159724)
			(xy 51.492454 -383.175241) (xy 51.441992 -383.183093) (xy 51.390924 -383.183093) (xy 51.340462 -383.175241)
			(xy 51.291809 -383.159724) (xy 51.246119 -383.13691) (xy 51.204481 -383.107342) (xy 51.167884 -383.071724)
			(xy 51.137199 -383.030902) (xy 51.113155 -382.985847) (xy 51.104292 -382.961896) (xy 51.098958 -382.946656)
			(xy 51.072542 -382.92786) (xy 50.560478 -382.92786) (xy 50.534062 -382.946656) (xy 50.528728 -382.961896)
			(xy 50.519865 -382.985847) (xy 50.495821 -383.030902) (xy 50.465136 -383.071724) (xy 50.428539 -383.107342)
			(xy 50.386901 -383.13691) (xy 50.341211 -383.159724) (xy 50.292558 -383.175241) (xy 50.242096 -383.183093)
			(xy 50.191028 -383.183093) (xy 50.140566 -383.175241) (xy 50.091913 -383.159724) (xy 50.046223 -383.13691)
			(xy 50.004585 -383.107342) (xy 49.967988 -383.071724) (xy 49.937303 -383.030902) (xy 49.913259 -382.985847)
			(xy 49.904396 -382.961896) (xy 49.899062 -382.946656) (xy 49.872646 -382.92786) (xy 49.360582 -382.92786)
			(xy 49.334166 -382.946656) (xy 49.328832 -382.961896) (xy 49.319969 -382.985847) (xy 49.295925 -383.030902)
			(xy 49.26524 -383.071724) (xy 49.228643 -383.107342) (xy 49.187005 -383.13691) (xy 49.141315 -383.159724)
			(xy 49.092662 -383.175241) (xy 49.0422 -383.183093) (xy 48.991132 -383.183093) (xy 48.94067 -383.175241)
			(xy 48.892017 -383.159724) (xy 48.846327 -383.13691) (xy 48.804689 -383.107342) (xy 48.768092 -383.071724)
			(xy 48.737407 -383.030902) (xy 48.713363 -382.985847) (xy 48.7045 -382.961896) (xy 48.699166 -382.946656)
			(xy 48.67275 -382.92786) (xy 48.160432 -382.92786) (xy 48.134016 -382.946656) (xy 48.128682 -382.961896)
			(xy 48.119819 -382.985847) (xy 48.095775 -383.030902) (xy 48.06509 -383.071724) (xy 48.028493 -383.107342)
			(xy 47.986855 -383.13691) (xy 47.941165 -383.159724) (xy 47.892512 -383.175241) (xy 47.84205 -383.183093)
			(xy 47.790982 -383.183093) (xy 47.74052 -383.175241) (xy 47.691867 -383.159724) (xy 47.646177 -383.13691)
			(xy 47.604539 -383.107342) (xy 47.567942 -383.071724) (xy 47.537257 -383.030902) (xy 47.513213 -382.985847)
			(xy 47.50435 -382.961896) (xy 47.499016 -382.946656) (xy 47.4726 -382.92786) (xy 46.8249 -382.92786)
			(xy 46.79696 -382.950974) (xy 46.793658 -382.969262) (xy 46.788466 -382.994186) (xy 46.771452 -383.042168)
			(xy 46.747292 -383.086979) (xy 46.716557 -383.127563) (xy 46.679971 -383.162964) (xy 46.638397 -383.192345)
			(xy 46.592814 -383.215016) (xy 46.544298 -383.23044) (xy 46.493992 -383.238255) (xy 46.468538 -383.238756)
			(xy 46.439942 -383.238153) (xy 46.383604 -383.228318) (xy 46.329798 -383.208933) (xy 46.280131 -383.180579)
			(xy 46.257718 -383.16281) (xy 46.25086 -383.157222) (xy 46.234096 -383.151126) (xy 46.1518 -383.151126)
			(xy 46.135036 -383.156968) (xy 46.128178 -383.162556) (xy 46.105824 -383.180211) (xy 46.056314 -383.208372)
			(xy 46.00271 -383.22763) (xy 45.946599 -383.237413) (xy 45.91812 -383.237994) (xy 45.894886 -383.237602)
			(xy 45.848874 -383.231101) (xy 45.804225 -383.218226) (xy 45.761818 -383.199228) (xy 45.722486 -383.174482)
			(xy 45.704506 -383.159762) (xy 45.697394 -383.153666) (xy 45.680884 -383.14757) (xy 45.596556 -383.14757)
			(xy 45.580046 -383.153666) (xy 45.572934 -383.159762) (xy 45.554943 -383.174468) (xy 45.515617 -383.19922)
			(xy 45.473212 -383.21822) (xy 45.428564 -383.231096) (xy 45.382554 -383.237592) (xy 45.35932 -383.237994)
			(xy 45.333907 -383.237531) (xy 45.283677 -383.229759) (xy 45.235228 -383.214396) (xy 45.189699 -383.191803)
			(xy 45.148161 -383.162511) (xy 45.111593 -383.127211) (xy 45.080855 -383.086732) (xy 45.05667 -383.042028)
			(xy 45.039608 -382.99415) (xy 45.034454 -382.969262) (xy 45.030898 -382.950974) (xy 45.002958 -382.92786)
			(xy 41.91381 -382.92786) (xy 41.903841 -382.928331) (xy 41.885393 -382.935895) (xy 41.877996 -382.942592)
			(xy 41.81983 -383.000504) (xy 41.81221 -383.018792) (xy 41.81221 -383.028952) (xy 41.811631 -383.055967)
			(xy 41.803789 -383.10943) (xy 41.788482 -383.161252) (xy 41.766017 -383.210395) (xy 41.736842 -383.255877)
			(xy 41.701542 -383.296787) (xy 41.660822 -383.332307) (xy 41.615498 -383.361726) (xy 41.566476 -383.384456)
			(xy 41.514738 -383.400042) (xy 41.488106 -383.404618) (xy 41.476422 -383.406396) (xy 41.457372 -383.419604)
			(xy 41.406572 -383.510536) (xy 41.405302 -383.53365) (xy 41.409874 -383.544572) (xy 41.422635 -383.576116)
			(xy 41.44062 -383.641741) (xy 41.4497 -383.709178) (xy 41.45026 -383.7432) (xy 43.683934 -383.7432)
			(xy 43.688005 -383.687578) (xy 43.700131 -383.633141) (xy 43.720054 -383.58105) (xy 43.74735 -383.532415)
			(xy 43.781436 -383.488272) (xy 43.821585 -383.449563) (xy 43.866943 -383.417112) (xy 43.916543 -383.391611)
			(xy 43.969327 -383.373604) (xy 44.02417 -383.363474) (xy 44.079904 -383.361437) (xy 44.135341 -383.367537)
			(xy 44.189298 -383.381643) (xy 44.240627 -383.403455) (xy 44.288233 -383.432509) (xy 44.331101 -383.468184)
			(xy 44.368318 -383.509721) (xy 44.399091 -383.556234) (xy 44.422763 -383.606731) (xy 44.438831 -383.660138)
			(xy 44.446951 -383.715314) (xy 44.44746 -383.7432) (xy 44.446951 -383.771086) (xy 44.438831 -383.826262)
			(xy 44.422763 -383.879669) (xy 44.399091 -383.930166) (xy 44.368318 -383.976679) (xy 44.331101 -384.018216)
			(xy 44.288233 -384.053891) (xy 44.240627 -384.082945) (xy 44.189298 -384.104757) (xy 44.135341 -384.118863)
			(xy 44.079904 -384.124963) (xy 44.02417 -384.122926) (xy 43.969327 -384.112796) (xy 43.916543 -384.094789)
			(xy 43.866943 -384.069288) (xy 43.821585 -384.036837) (xy 43.781436 -383.998128) (xy 43.74735 -383.953985)
			(xy 43.720054 -383.90535) (xy 43.700131 -383.853259) (xy 43.688005 -383.798822) (xy 43.683934 -383.7432)
			(xy 41.45026 -383.7432) (xy 41.449814 -383.773931) (xy 41.442405 -383.834945) (xy 41.427696 -383.894621)
			(xy 41.4059 -383.952089) (xy 41.377335 -384.00651) (xy 41.342419 -384.057091) (xy 41.30166 -384.103094)
			(xy 41.255653 -384.143849) (xy 41.205069 -384.17876) (xy 41.150645 -384.207319) (xy 41.093175 -384.22911)
			(xy 41.033498 -384.243814) (xy 40.972483 -384.251217) (xy 40.941752 -384.251708) (xy 40.909606 -384.251231)
			(xy 40.845824 -384.243156) (xy 40.783569 -384.227102) (xy 40.723835 -384.203326) (xy 40.667577 -384.172207)
			(xy 40.615691 -384.134243) (xy 40.591994 -384.112516) (xy 40.577008 -384.098292) (xy 40.53586 -384.0988)
			(xy 39.97198 -384.66268) (xy 43.683934 -384.66268) (xy 43.688005 -384.607058) (xy 43.700131 -384.552621)
			(xy 43.720054 -384.50053) (xy 43.74735 -384.451895) (xy 43.781436 -384.407752) (xy 43.821585 -384.369043)
			(xy 43.866943 -384.336592) (xy 43.916543 -384.311091) (xy 43.969327 -384.293084) (xy 44.02417 -384.282954)
			(xy 44.079904 -384.280917) (xy 44.135341 -384.287017) (xy 44.189298 -384.301123) (xy 44.240627 -384.322935)
			(xy 44.288233 -384.351989) (xy 44.325928 -384.383359) (xy 45.071032 -384.383359) (xy 45.071032 -384.331385)
			(xy 45.079162 -384.28005) (xy 45.095223 -384.23062) (xy 45.118819 -384.18431) (xy 45.149369 -384.142262)
			(xy 45.18612 -384.105511) (xy 45.228168 -384.074961) (xy 45.274478 -384.051365) (xy 45.323908 -384.035304)
			(xy 45.375243 -384.027174) (xy 45.427217 -384.027174) (xy 45.478552 -384.035304) (xy 45.527982 -384.051365)
			(xy 45.574292 -384.074961) (xy 45.61634 -384.105511) (xy 45.653091 -384.142262) (xy 45.683641 -384.18431)
			(xy 45.707237 -384.23062) (xy 45.723298 -384.28005) (xy 45.731428 -384.331385) (xy 45.731938 -384.357372)
			(xy 45.731428 -384.383359) (xy 45.723298 -384.434694) (xy 45.707237 -384.484124) (xy 45.683641 -384.530434)
			(xy 45.653091 -384.572482) (xy 45.61634 -384.609233) (xy 45.574292 -384.639783) (xy 45.566587 -384.643709)
			(xy 47.132242 -384.643709) (xy 47.132242 -384.591735) (xy 47.140372 -384.5404) (xy 47.156433 -384.49097)
			(xy 47.180029 -384.44466) (xy 47.210579 -384.402612) (xy 47.24733 -384.365861) (xy 47.289378 -384.335311)
			(xy 47.335688 -384.311715) (xy 47.385118 -384.295654) (xy 47.436453 -384.287524) (xy 47.488427 -384.287524)
			(xy 47.539762 -384.295654) (xy 47.589192 -384.311715) (xy 47.635502 -384.335311) (xy 47.67755 -384.365861)
			(xy 47.714301 -384.402612) (xy 47.744851 -384.44466) (xy 47.768447 -384.49097) (xy 47.784508 -384.5404)
			(xy 47.792638 -384.591735) (xy 47.793148 -384.617722) (xy 47.792638 -384.643709) (xy 48.332138 -384.643709)
			(xy 48.332138 -384.591735) (xy 48.340268 -384.5404) (xy 48.356329 -384.49097) (xy 48.379925 -384.44466)
			(xy 48.410475 -384.402612) (xy 48.447226 -384.365861) (xy 48.489274 -384.335311) (xy 48.535584 -384.311715)
			(xy 48.585014 -384.295654) (xy 48.636349 -384.287524) (xy 48.688323 -384.287524) (xy 48.739658 -384.295654)
			(xy 48.789088 -384.311715) (xy 48.835398 -384.335311) (xy 48.877446 -384.365861) (xy 48.914197 -384.402612)
			(xy 48.944747 -384.44466) (xy 48.968343 -384.49097) (xy 48.984404 -384.5404) (xy 48.992534 -384.591735)
			(xy 48.993044 -384.617722) (xy 48.992534 -384.643709) (xy 49.532288 -384.643709) (xy 49.532288 -384.591735)
			(xy 49.540418 -384.5404) (xy 49.556479 -384.49097) (xy 49.580075 -384.44466) (xy 49.610625 -384.402612)
			(xy 49.647376 -384.365861) (xy 49.689424 -384.335311) (xy 49.735734 -384.311715) (xy 49.785164 -384.295654)
			(xy 49.836499 -384.287524) (xy 49.888473 -384.287524) (xy 49.939808 -384.295654) (xy 49.989238 -384.311715)
			(xy 50.035548 -384.335311) (xy 50.077596 -384.365861) (xy 50.114347 -384.402612) (xy 50.144897 -384.44466)
			(xy 50.168493 -384.49097) (xy 50.184554 -384.5404) (xy 50.192684 -384.591735) (xy 50.193194 -384.617722)
			(xy 50.192684 -384.643709) (xy 50.732184 -384.643709) (xy 50.732184 -384.591735) (xy 50.740314 -384.5404)
			(xy 50.756375 -384.49097) (xy 50.779971 -384.44466) (xy 50.810521 -384.402612) (xy 50.847272 -384.365861)
			(xy 50.88932 -384.335311) (xy 50.93563 -384.311715) (xy 50.98506 -384.295654) (xy 51.036395 -384.287524)
			(xy 51.088369 -384.287524) (xy 51.139704 -384.295654) (xy 51.189134 -384.311715) (xy 51.235444 -384.335311)
			(xy 51.277492 -384.365861) (xy 51.314243 -384.402612) (xy 51.344793 -384.44466) (xy 51.368389 -384.49097)
			(xy 51.38445 -384.5404) (xy 51.39258 -384.591735) (xy 51.39309 -384.617722) (xy 51.39258 -384.643709)
			(xy 51.932334 -384.643709) (xy 51.932334 -384.591735) (xy 51.940464 -384.5404) (xy 51.956525 -384.49097)
			(xy 51.980121 -384.44466) (xy 52.010671 -384.402612) (xy 52.047422 -384.365861) (xy 52.08947 -384.335311)
			(xy 52.13578 -384.311715) (xy 52.18521 -384.295654) (xy 52.236545 -384.287524) (xy 52.288519 -384.287524)
			(xy 52.339854 -384.295654) (xy 52.389284 -384.311715) (xy 52.435594 -384.335311) (xy 52.477642 -384.365861)
			(xy 52.514393 -384.402612) (xy 52.544943 -384.44466) (xy 52.568539 -384.49097) (xy 52.5846 -384.5404)
			(xy 52.59273 -384.591735) (xy 52.59324 -384.617722) (xy 52.59273 -384.643709) (xy 53.13223 -384.643709)
			(xy 53.13223 -384.591735) (xy 53.14036 -384.5404) (xy 53.156421 -384.49097) (xy 53.180017 -384.44466)
			(xy 53.210567 -384.402612) (xy 53.247318 -384.365861) (xy 53.289366 -384.335311) (xy 53.335676 -384.311715)
			(xy 53.385106 -384.295654) (xy 53.436441 -384.287524) (xy 53.488415 -384.287524) (xy 53.53975 -384.295654)
			(xy 53.58918 -384.311715) (xy 53.63549 -384.335311) (xy 53.677538 -384.365861) (xy 53.714289 -384.402612)
			(xy 53.744839 -384.44466) (xy 53.768435 -384.49097) (xy 53.784496 -384.5404) (xy 53.792626 -384.591735)
			(xy 53.793136 -384.617722) (xy 53.792626 -384.643709) (xy 54.332126 -384.643709) (xy 54.332126 -384.591735)
			(xy 54.340256 -384.5404) (xy 54.356317 -384.49097) (xy 54.379913 -384.44466) (xy 54.410463 -384.402612)
			(xy 54.447214 -384.365861) (xy 54.489262 -384.335311) (xy 54.535572 -384.311715) (xy 54.585002 -384.295654)
			(xy 54.636337 -384.287524) (xy 54.688311 -384.287524) (xy 54.739646 -384.295654) (xy 54.789076 -384.311715)
			(xy 54.835386 -384.335311) (xy 54.877434 -384.365861) (xy 54.914185 -384.402612) (xy 54.944735 -384.44466)
			(xy 54.968331 -384.49097) (xy 54.984392 -384.5404) (xy 54.992522 -384.591735) (xy 54.993032 -384.617722)
			(xy 54.992522 -384.643709) (xy 54.984392 -384.695044) (xy 54.968331 -384.744474) (xy 54.944735 -384.790784)
			(xy 54.914185 -384.832832) (xy 54.877434 -384.869583) (xy 54.835386 -384.900133) (xy 54.789076 -384.923729)
			(xy 54.739646 -384.93979) (xy 54.688311 -384.94792) (xy 54.636337 -384.94792) (xy 54.585002 -384.93979)
			(xy 54.535572 -384.923729) (xy 54.489262 -384.900133) (xy 54.447214 -384.869583) (xy 54.410463 -384.832832)
			(xy 54.379913 -384.790784) (xy 54.356317 -384.744474) (xy 54.340256 -384.695044) (xy 54.332126 -384.643709)
			(xy 53.792626 -384.643709) (xy 53.784496 -384.695044) (xy 53.768435 -384.744474) (xy 53.744839 -384.790784)
			(xy 53.714289 -384.832832) (xy 53.677538 -384.869583) (xy 53.63549 -384.900133) (xy 53.58918 -384.923729)
			(xy 53.53975 -384.93979) (xy 53.488415 -384.94792) (xy 53.436441 -384.94792) (xy 53.385106 -384.93979)
			(xy 53.335676 -384.923729) (xy 53.289366 -384.900133) (xy 53.247318 -384.869583) (xy 53.210567 -384.832832)
			(xy 53.180017 -384.790784) (xy 53.156421 -384.744474) (xy 53.14036 -384.695044) (xy 53.13223 -384.643709)
			(xy 52.59273 -384.643709) (xy 52.5846 -384.695044) (xy 52.568539 -384.744474) (xy 52.544943 -384.790784)
			(xy 52.514393 -384.832832) (xy 52.477642 -384.869583) (xy 52.435594 -384.900133) (xy 52.389284 -384.923729)
			(xy 52.339854 -384.93979) (xy 52.288519 -384.94792) (xy 52.236545 -384.94792) (xy 52.18521 -384.93979)
			(xy 52.13578 -384.923729) (xy 52.08947 -384.900133) (xy 52.047422 -384.869583) (xy 52.010671 -384.832832)
			(xy 51.980121 -384.790784) (xy 51.956525 -384.744474) (xy 51.940464 -384.695044) (xy 51.932334 -384.643709)
			(xy 51.39258 -384.643709) (xy 51.38445 -384.695044) (xy 51.368389 -384.744474) (xy 51.344793 -384.790784)
			(xy 51.314243 -384.832832) (xy 51.277492 -384.869583) (xy 51.235444 -384.900133) (xy 51.189134 -384.923729)
			(xy 51.139704 -384.93979) (xy 51.088369 -384.94792) (xy 51.036395 -384.94792) (xy 50.98506 -384.93979)
			(xy 50.93563 -384.923729) (xy 50.88932 -384.900133) (xy 50.847272 -384.869583) (xy 50.810521 -384.832832)
			(xy 50.779971 -384.790784) (xy 50.756375 -384.744474) (xy 50.740314 -384.695044) (xy 50.732184 -384.643709)
			(xy 50.192684 -384.643709) (xy 50.184554 -384.695044) (xy 50.168493 -384.744474) (xy 50.144897 -384.790784)
			(xy 50.114347 -384.832832) (xy 50.077596 -384.869583) (xy 50.035548 -384.900133) (xy 49.989238 -384.923729)
			(xy 49.939808 -384.93979) (xy 49.888473 -384.94792) (xy 49.836499 -384.94792) (xy 49.785164 -384.93979)
			(xy 49.735734 -384.923729) (xy 49.689424 -384.900133) (xy 49.647376 -384.869583) (xy 49.610625 -384.832832)
			(xy 49.580075 -384.790784) (xy 49.556479 -384.744474) (xy 49.540418 -384.695044) (xy 49.532288 -384.643709)
			(xy 48.992534 -384.643709) (xy 48.984404 -384.695044) (xy 48.968343 -384.744474) (xy 48.944747 -384.790784)
			(xy 48.914197 -384.832832) (xy 48.877446 -384.869583) (xy 48.835398 -384.900133) (xy 48.789088 -384.923729)
			(xy 48.739658 -384.93979) (xy 48.688323 -384.94792) (xy 48.636349 -384.94792) (xy 48.585014 -384.93979)
			(xy 48.535584 -384.923729) (xy 48.489274 -384.900133) (xy 48.447226 -384.869583) (xy 48.410475 -384.832832)
			(xy 48.379925 -384.790784) (xy 48.356329 -384.744474) (xy 48.340268 -384.695044) (xy 48.332138 -384.643709)
			(xy 47.792638 -384.643709) (xy 47.784508 -384.695044) (xy 47.768447 -384.744474) (xy 47.744851 -384.790784)
			(xy 47.714301 -384.832832) (xy 47.67755 -384.869583) (xy 47.635502 -384.900133) (xy 47.589192 -384.923729)
			(xy 47.539762 -384.93979) (xy 47.488427 -384.94792) (xy 47.436453 -384.94792) (xy 47.385118 -384.93979)
			(xy 47.335688 -384.923729) (xy 47.289378 -384.900133) (xy 47.24733 -384.869583) (xy 47.210579 -384.832832)
			(xy 47.180029 -384.790784) (xy 47.156433 -384.744474) (xy 47.140372 -384.695044) (xy 47.132242 -384.643709)
			(xy 45.566587 -384.643709) (xy 45.527982 -384.663379) (xy 45.478552 -384.67944) (xy 45.427217 -384.68757)
			(xy 45.375243 -384.68757) (xy 45.323908 -384.67944) (xy 45.274478 -384.663379) (xy 45.228168 -384.639783)
			(xy 45.18612 -384.609233) (xy 45.149369 -384.572482) (xy 45.118819 -384.530434) (xy 45.095223 -384.484124)
			(xy 45.079162 -384.434694) (xy 45.071032 -384.383359) (xy 44.325928 -384.383359) (xy 44.331101 -384.387664)
			(xy 44.368318 -384.429201) (xy 44.399091 -384.475714) (xy 44.422763 -384.526211) (xy 44.438831 -384.579618)
			(xy 44.446951 -384.634794) (xy 44.44746 -384.66268) (xy 44.446951 -384.690566) (xy 44.438831 -384.745742)
			(xy 44.422763 -384.799149) (xy 44.399091 -384.849646) (xy 44.368318 -384.896159) (xy 44.331101 -384.937696)
			(xy 44.288233 -384.973371) (xy 44.240627 -385.002425) (xy 44.189298 -385.024237) (xy 44.135341 -385.038343)
			(xy 44.079904 -385.044443) (xy 44.02417 -385.042406) (xy 43.969327 -385.032276) (xy 43.916543 -385.014269)
			(xy 43.866943 -384.988768) (xy 43.821585 -384.956317) (xy 43.781436 -384.917608) (xy 43.74735 -384.873465)
			(xy 43.720054 -384.82483) (xy 43.700131 -384.772739) (xy 43.688005 -384.718302) (xy 43.683934 -384.66268)
			(xy 39.97198 -384.66268) (xy 39.517066 -385.117594) (xy 39.510211 -385.124989) (xy 39.502464 -385.143588)
			(xy 39.50208 -385.153662) (xy 39.50208 -385.614121) (xy 40.687746 -385.614121) (xy 40.687746 -385.550199)
			(xy 40.695757 -385.486781) (xy 40.711654 -385.424867) (xy 40.735186 -385.365434) (xy 40.76598 -385.309419)
			(xy 40.803553 -385.257704) (xy 40.84731 -385.211107) (xy 40.896563 -385.170362) (xy 40.950534 -385.136111)
			(xy 41.008373 -385.108894) (xy 41.069166 -385.089141) (xy 41.131956 -385.077163) (xy 41.195752 -385.07315)
			(xy 41.259548 -385.077163) (xy 41.322338 -385.089141) (xy 41.383131 -385.108894) (xy 41.44097 -385.136111)
			(xy 41.494941 -385.170362) (xy 41.544194 -385.211107) (xy 41.587951 -385.257704) (xy 41.625524 -385.309419)
			(xy 41.656318 -385.365434) (xy 41.67985 -385.424867) (xy 41.695747 -385.486781) (xy 41.703758 -385.550199)
			(xy 41.70426 -385.58216) (xy 43.683934 -385.58216) (xy 43.688005 -385.526538) (xy 43.700131 -385.472101)
			(xy 43.720054 -385.42001) (xy 43.74735 -385.371375) (xy 43.781436 -385.327232) (xy 43.821585 -385.288523)
			(xy 43.866943 -385.256072) (xy 43.916543 -385.230571) (xy 43.969327 -385.212564) (xy 44.02417 -385.202434)
			(xy 44.079904 -385.200397) (xy 44.135341 -385.206497) (xy 44.189298 -385.220603) (xy 44.240627 -385.242415)
			(xy 44.288233 -385.271469) (xy 44.331101 -385.307144) (xy 44.368318 -385.348681) (xy 44.399091 -385.395194)
			(xy 44.422763 -385.445691) (xy 44.438831 -385.499098) (xy 44.446951 -385.554274) (xy 44.44746 -385.58216)
			(xy 44.446951 -385.610046) (xy 44.444203 -385.628721) (xy 44.649646 -385.628721) (xy 44.649646 -385.576747)
			(xy 44.657776 -385.525412) (xy 44.673837 -385.475982) (xy 44.697433 -385.429672) (xy 44.727983 -385.387624)
			(xy 44.764734 -385.350873) (xy 44.806782 -385.320323) (xy 44.853092 -385.296727) (xy 44.902522 -385.280666)
			(xy 44.953857 -385.272536) (xy 45.005831 -385.272536) (xy 45.057166 -385.280666) (xy 45.106596 -385.296727)
			(xy 45.133392 -385.31038) (xy 47.460662 -385.31038) (xy 47.461183 -385.284394) (xy 47.469316 -385.233062)
			(xy 47.485377 -385.183633) (xy 47.508973 -385.137326) (xy 47.539522 -385.095279) (xy 47.576271 -385.058528)
			(xy 47.618317 -385.027978) (xy 47.664624 -385.004381) (xy 47.714052 -384.988318) (xy 47.765384 -384.980184)
			(xy 47.79137 -384.979672) (xy 47.817379 -384.980169) (xy 47.868755 -384.988323) (xy 47.91822 -385.00442)
			(xy 47.964556 -385.028062) (xy 48.00662 -385.058666) (xy 48.043373 -385.095477) (xy 48.073911 -385.137589)
			(xy 48.09748 -385.183962) (xy 48.113499 -385.233453) (xy 48.118014 -385.259072) (xy 48.119538 -385.26847)
			(xy 48.143764 -385.31038) (xy 48.660558 -385.31038) (xy 48.661083 -385.284394) (xy 48.669215 -385.233062)
			(xy 48.685277 -385.183634) (xy 48.708872 -385.137327) (xy 48.739421 -385.09528) (xy 48.77617 -385.05853)
			(xy 48.818215 -385.02798) (xy 48.864521 -385.004382) (xy 48.913948 -384.988319) (xy 48.96528 -384.980184)
			(xy 48.991266 -384.979672) (xy 49.017275 -384.980172) (xy 49.068651 -384.988326) (xy 49.118116 -385.004422)
			(xy 49.164452 -385.028063) (xy 49.206515 -385.058667) (xy 49.243269 -385.095479) (xy 49.273807 -385.13759)
			(xy 49.297376 -385.183963) (xy 49.313395 -385.233453) (xy 49.31791 -385.259072) (xy 49.319434 -385.26847)
			(xy 49.34366 -385.31038) (xy 49.860708 -385.31038) (xy 49.861183 -385.284391) (xy 49.869317 -385.233055)
			(xy 49.885382 -385.183623) (xy 49.908982 -385.137312) (xy 49.939535 -385.095263) (xy 49.976291 -385.058512)
			(xy 50.018343 -385.027963) (xy 50.064656 -385.004368) (xy 50.11409 -384.988309) (xy 50.165427 -384.98018)
			(xy 50.191416 -384.979672) (xy 50.21746 -384.980119) (xy 50.268902 -384.988309) (xy 50.318426 -385.004453)
			(xy 50.364811 -385.028153) (xy 50.406913 -385.058824) (xy 50.443693 -385.09571) (xy 50.474243 -385.137899)
			(xy 50.49781 -385.184352) (xy 50.513813 -385.233923) (xy 50.518314 -385.25958) (xy 50.519584 -385.268978)
			(xy 50.54352 -385.31038) (xy 51.060604 -385.31038) (xy 51.061083 -385.284392) (xy 51.069217 -385.233055)
			(xy 51.085282 -385.183623) (xy 51.108881 -385.137313) (xy 51.139434 -385.095265) (xy 51.176189 -385.058513)
			(xy 51.21824 -385.027964) (xy 51.264553 -385.004369) (xy 51.313987 -384.98831) (xy 51.365324 -384.980181)
			(xy 51.391312 -384.979672) (xy 51.417322 -384.980131) (xy 51.4687 -384.988291) (xy 51.518166 -385.004394)
			(xy 51.564502 -385.028041) (xy 51.606565 -385.05865) (xy 51.643318 -385.095466) (xy 51.673855 -385.137581)
			(xy 51.697423 -385.183958) (xy 51.713441 -385.233452) (xy 51.717956 -385.259072) (xy 51.71948 -385.26847)
			(xy 51.743706 -385.31038) (xy 52.2605 -385.31038) (xy 52.260983 -385.284392) (xy 52.269117 -385.233056)
			(xy 52.285181 -385.183624) (xy 52.30878 -385.137314) (xy 52.339333 -385.095266) (xy 52.376087 -385.058515)
			(xy 52.418138 -385.027966) (xy 52.46445 -385.00437) (xy 52.513883 -384.98831) (xy 52.56522 -384.980181)
			(xy 52.591208 -384.979672) (xy 52.617218 -384.980134) (xy 52.668595 -384.988294) (xy 52.718062 -385.004396)
			(xy 52.764398 -385.028043) (xy 52.806461 -385.058651) (xy 52.843214 -385.095467) (xy 52.873751 -385.137582)
			(xy 52.897319 -385.183958) (xy 52.913337 -385.233452) (xy 52.917852 -385.259072) (xy 52.919376 -385.26847)
			(xy 52.943602 -385.31038) (xy 53.46065 -385.31038) (xy 53.461183 -385.284394) (xy 53.469315 -385.233063)
			(xy 53.485376 -385.183636) (xy 53.508971 -385.137329) (xy 53.539518 -385.095283) (xy 53.576266 -385.058533)
			(xy 53.61831 -385.027983) (xy 53.664616 -385.004385) (xy 53.714042 -384.98832) (xy 53.765372 -384.980185)
			(xy 53.791358 -384.979672) (xy 53.81737 -384.980089) (xy 53.868749 -384.988256) (xy 53.918216 -385.004365)
			(xy 53.964552 -385.028018) (xy 54.006615 -385.058633) (xy 54.043367 -385.095453) (xy 54.073903 -385.137573)
			(xy 54.09747 -385.183953) (xy 54.113487 -385.23345) (xy 54.118002 -385.259072) (xy 54.119526 -385.26847)
			(xy 54.143752 -385.31038) (xy 54.660546 -385.31038) (xy 54.661083 -385.284395) (xy 54.669215 -385.233064)
			(xy 54.685276 -385.183637) (xy 54.70887 -385.13733) (xy 54.739417 -385.095285) (xy 54.776165 -385.058534)
			(xy 54.818208 -385.027984) (xy 54.864513 -385.004386) (xy 54.913939 -384.988321) (xy 54.965269 -384.980185)
			(xy 54.991254 -384.979672) (xy 55.017266 -384.980092) (xy 55.068645 -384.988259) (xy 55.118112 -385.004368)
			(xy 55.164448 -385.02802) (xy 55.206511 -385.058634) (xy 55.243263 -385.095455) (xy 55.273799 -385.137574)
			(xy 55.297366 -385.183953) (xy 55.313383 -385.23345) (xy 55.317898 -385.259072) (xy 55.319422 -385.26847)
			(xy 55.592218 -385.740402) (xy 55.599584 -385.746244) (xy 55.618362 -385.762046) (xy 55.65148 -385.798262)
			(xy 55.67889 -385.83897) (xy 55.699991 -385.883278) (xy 55.714321 -385.930216) (xy 55.721566 -385.978754)
			(xy 55.722012 -386.003292) (xy 55.721758 -386.015484) (xy 55.721504 -386.025136) (xy 55.7276 -386.04317)
			(xy 55.786274 -386.11048) (xy 55.803038 -386.119116) (xy 55.812944 -386.120132) (xy 55.839711 -386.123455)
			(xy 55.891734 -386.137685) (xy 55.94076 -386.160166) (xy 55.985489 -386.190303) (xy 56.024735 -386.227298)
			(xy 56.05746 -386.27017) (xy 56.082795 -386.317783) (xy 56.10007 -386.368876) (xy 56.108827 -386.422095)
			(xy 56.109362 -386.449062) (xy 56.108811 -386.476346) (xy 56.099858 -386.530175) (xy 56.082189 -386.581804)
			(xy 56.056283 -386.62983) (xy 56.022843 -386.672952) (xy 56.00319 -386.691886) (xy 55.995791 -386.699409)
			(xy 55.987265 -386.718688) (xy 55.98668 -386.729224) (xy 55.98668 -386.8039) (xy 55.987201 -386.81445)
			(xy 55.995743 -386.833745) (xy 56.00319 -386.841238) (xy 56.02284 -386.860173) (xy 56.056271 -386.9033)
			(xy 56.082172 -386.951327) (xy 56.099842 -387.002953) (xy 56.108801 -387.056779) (xy 56.109362 -387.084062)
			(xy 56.10891 -387.108178) (xy 56.101914 -387.1559) (xy 56.088065 -387.202101) (xy 56.067656 -387.245802)
			(xy 56.054752 -387.26618) (xy 56.04891 -387.27507) (xy 56.045354 -387.295136) (xy 56.066436 -387.387338)
			(xy 56.078628 -387.404102) (xy 56.087518 -387.409436) (xy 56.108315 -387.422297) (xy 56.146222 -387.453185)
			(xy 56.179165 -387.489319) (xy 56.206427 -387.529911) (xy 56.227413 -387.574076) (xy 56.241665 -387.62085)
			(xy 56.248873 -387.669213) (xy 56.249316 -387.693662) (xy 56.248889 -387.718035) (xy 56.241744 -387.766254)
			(xy 56.227602 -387.812903) (xy 56.20677 -387.856973) (xy 56.179698 -387.89751) (xy 56.146973 -387.933637)
			(xy 56.128412 -387.94944) (xy 56.119522 -387.956552) (xy 56.110124 -387.97611) (xy 56.10733 -388.075424)
			(xy 56.115966 -388.09549) (xy 56.124348 -388.10311) (xy 56.142796 -388.120573) (xy 56.174143 -388.160543)
			(xy 56.19844 -388.205152) (xy 56.215017 -388.253167) (xy 56.223417 -388.303264) (xy 56.223916 -388.328662)
			(xy 56.223847 -388.338021) (xy 56.222704 -388.356703) (xy 56.22163 -388.366) (xy 56.220614 -388.37489)
			(xy 56.224424 -388.391654) (xy 56.268366 -388.461504) (xy 56.282082 -388.471918) (xy 56.290464 -388.474712)
			(xy 56.314554 -388.483211) (xy 56.359846 -388.506832) (xy 56.400743 -388.537438) (xy 56.436176 -388.574232)
			(xy 56.46522 -388.616252) (xy 56.487117 -388.662402) (xy 56.49468 -388.686802) (xy 56.496204 -388.692644)
			(xy 56.81599 -389.245602) (xy 56.820054 -389.24992) (xy 56.836251 -389.267621) (xy 56.863614 -389.307032)
			(xy 56.884697 -389.35013) (xy 56.899016 -389.395923) (xy 56.90624 -389.443354) (xy 56.906668 -389.467344)
			(xy 56.906223 -389.492135) (xy 56.89846 -389.541105) (xy 56.883133 -389.588259) (xy 56.860619 -389.632434)
			(xy 56.831473 -389.672544) (xy 56.796411 -389.707601) (xy 56.756296 -389.736742) (xy 56.712118 -389.75925)
			(xy 56.664962 -389.77457) (xy 56.615991 -389.782326) (xy 56.5912 -389.782812) (xy 56.565806 -389.782312)
			(xy 56.515672 -389.774181) (xy 56.467486 -389.758129) (xy 56.422492 -389.734571) (xy 56.381849 -389.704114)
			(xy 56.346607 -389.667543) (xy 56.317673 -389.625801) (xy 56.295795 -389.579967) (xy 56.288178 -389.555736)
			(xy 56.286654 -389.549894) (xy 55.966106 -388.995412) (xy 55.962042 -388.991094) (xy 55.945941 -388.973435)
			(xy 55.918754 -388.934135) (xy 55.897802 -388.891186) (xy 55.883566 -388.845568) (xy 55.876371 -388.798326)
			(xy 55.875936 -388.774432) (xy 55.876017 -388.762384) (xy 55.877799 -388.738355) (xy 55.879492 -388.726426)
			(xy 55.880762 -388.717536) (xy 55.877714 -388.700518) (xy 55.83555 -388.629652) (xy 55.822342 -388.618476)
			(xy 55.81396 -388.615428) (xy 55.79221 -388.607038) (xy 55.751352 -388.584596) (xy 55.714382 -388.556202)
			(xy 55.682159 -388.522515) (xy 55.655434 -388.484321) (xy 55.634829 -388.442506) (xy 55.620821 -388.398045)
			(xy 55.613738 -388.35197) (xy 55.6133 -388.328662) (xy 55.613826 -388.303267) (xy 55.622235 -388.253178)
			(xy 55.638815 -388.205171) (xy 55.663109 -388.160568) (xy 55.694448 -388.120599) (xy 55.712868 -388.10311)
			(xy 55.72125 -388.09549) (xy 55.729886 -388.075424) (xy 55.727092 -387.97611) (xy 55.717694 -387.956552)
			(xy 55.708804 -387.94944) (xy 55.690257 -387.933624) (xy 55.657539 -387.897494) (xy 55.630471 -387.856958)
			(xy 55.609639 -387.812892) (xy 55.595493 -387.766247) (xy 55.588337 -387.718033) (xy 55.5879 -387.693662)
			(xy 55.588306 -387.669544) (xy 55.595314 -387.62182) (xy 55.609176 -387.575619) (xy 55.629599 -387.53192)
			(xy 55.64251 -387.511544) (xy 55.648352 -387.502654) (xy 55.651908 -387.482588) (xy 55.630826 -387.390386)
			(xy 55.618634 -387.373622) (xy 55.609744 -387.368288) (xy 55.588949 -387.355424) (xy 55.551044 -387.324535)
			(xy 55.518102 -387.288401) (xy 55.490841 -387.247809) (xy 55.469854 -387.203645) (xy 55.455601 -387.156872)
			(xy 55.448391 -387.10851) (xy 55.447946 -387.084062) (xy 55.44851 -387.056778) (xy 55.457459 -387.00295)
			(xy 55.475125 -386.951321) (xy 55.501028 -386.903294) (xy 55.534466 -386.860172) (xy 55.554118 -386.841238)
			(xy 55.561508 -386.833707) (xy 55.570038 -386.814434) (xy 55.570628 -386.8039) (xy 55.570628 -386.729224)
			(xy 55.570091 -386.718675) (xy 55.561561 -386.69938) (xy 55.554118 -386.691886) (xy 55.534481 -386.672938)
			(xy 55.501049 -386.629815) (xy 55.475145 -386.581791) (xy 55.457472 -386.530168) (xy 55.448509 -386.476344)
			(xy 55.447946 -386.449062) (xy 55.4482 -386.43687) (xy 55.448454 -386.427218) (xy 55.442358 -386.409184)
			(xy 55.383684 -386.341874) (xy 55.36692 -386.333238) (xy 55.357014 -386.332222) (xy 55.330113 -386.328808)
			(xy 55.277828 -386.314452) (xy 55.228585 -386.291761) (xy 55.183701 -386.261343) (xy 55.14438 -386.224011)
			(xy 55.111674 -386.180766) (xy 55.086459 -386.132766) (xy 55.06941 -386.081296) (xy 55.06466 -386.0546)
			(xy 55.063136 -386.045202) (xy 54.79034 -385.57327) (xy 54.782974 -385.567428) (xy 54.764222 -385.551598)
			(xy 54.731103 -385.515386) (xy 54.703691 -385.474683) (xy 54.682586 -385.430381) (xy 54.66825 -385.38345)
			(xy 54.660996 -385.334916) (xy 54.660546 -385.31038) (xy 54.143752 -385.31038) (xy 54.392322 -385.740402)
			(xy 54.399688 -385.746244) (xy 54.418467 -385.762045) (xy 54.451585 -385.798261) (xy 54.478995 -385.83897)
			(xy 54.500096 -385.883278) (xy 54.514425 -385.930216) (xy 54.52167 -385.978754) (xy 54.522116 -386.003292)
			(xy 54.521862 -386.015484) (xy 54.521608 -386.025136) (xy 54.527704 -386.04317) (xy 54.586378 -386.11048)
			(xy 54.603142 -386.119116) (xy 54.612794 -386.120132) (xy 54.639555 -386.123496) (xy 54.691578 -386.137718)
			(xy 54.740604 -386.160192) (xy 54.785333 -386.190323) (xy 54.824581 -386.227313) (xy 54.857307 -386.270181)
			(xy 54.882643 -386.31779) (xy 54.899919 -386.36888) (xy 54.908676 -386.422096) (xy 54.909212 -386.449062)
			(xy 54.908677 -386.476347) (xy 54.899723 -386.530177) (xy 54.88205 -386.581807) (xy 54.85614 -386.629833)
			(xy 54.822696 -386.672954) (xy 54.80304 -386.691886) (xy 54.795649 -386.699416) (xy 54.787117 -386.71869)
			(xy 54.78653 -386.729224) (xy 54.78653 -386.8039) (xy 54.787037 -386.814453) (xy 54.795587 -386.833748)
			(xy 54.80304 -386.841238) (xy 54.822681 -386.860183) (xy 54.856115 -386.903306) (xy 54.882019 -386.95133)
			(xy 54.89969 -387.002955) (xy 54.908651 -387.056779) (xy 54.909212 -387.084062) (xy 54.908768 -387.108178)
			(xy 54.901771 -387.155901) (xy 54.88792 -387.202102) (xy 54.867508 -387.245803) (xy 54.854602 -387.26618)
			(xy 54.84876 -387.27507) (xy 54.845204 -387.295136) (xy 54.866286 -387.387338) (xy 54.878478 -387.404102)
			(xy 54.887368 -387.409436) (xy 54.908177 -387.422279) (xy 54.94608 -387.453172) (xy 54.979021 -387.48931)
			(xy 55.006281 -387.529905) (xy 55.027265 -387.574072) (xy 55.041516 -387.620848) (xy 55.048723 -387.669213)
			(xy 55.049166 -387.693662) (xy 55.048757 -387.718036) (xy 55.041611 -387.766256) (xy 55.027467 -387.812907)
			(xy 55.006631 -387.856977) (xy 54.979555 -387.897513) (xy 54.946825 -387.933639) (xy 54.928262 -387.94944)
			(xy 54.919372 -387.956552) (xy 54.909974 -387.97611) (xy 54.90718 -388.075424) (xy 54.915816 -388.09549)
			(xy 54.924198 -388.10311) (xy 54.942636 -388.120583) (xy 54.973986 -388.16055) (xy 54.998287 -388.205155)
			(xy 55.014866 -388.253169) (xy 55.023266 -388.303264) (xy 55.023766 -388.328662) (xy 55.023697 -388.338021)
			(xy 55.022554 -388.356703) (xy 55.02148 -388.366) (xy 55.020464 -388.37489) (xy 55.024274 -388.391654)
			(xy 55.068216 -388.461504) (xy 55.081932 -388.471918) (xy 55.090314 -388.474712) (xy 55.114337 -388.483194)
			(xy 55.15951 -388.506743) (xy 55.200316 -388.537239) (xy 55.235696 -388.573892) (xy 55.264733 -388.615749)
			(xy 55.286672 -388.661725) (xy 55.294276 -388.68604) (xy 55.2958 -388.691882) (xy 55.616094 -389.245602)
			(xy 55.620158 -389.24992) (xy 55.636356 -389.267621) (xy 55.663718 -389.307032) (xy 55.684801 -389.35013)
			(xy 55.69912 -389.395923) (xy 55.706344 -389.443354) (xy 55.706772 -389.467344) (xy 55.706323 -389.492135)
			(xy 55.69856 -389.541105) (xy 55.683234 -389.588258) (xy 55.66072 -389.632433) (xy 55.631574 -389.672543)
			(xy 55.596512 -389.7076) (xy 55.556399 -389.736741) (xy 55.512221 -389.759249) (xy 55.465066 -389.77457)
			(xy 55.416095 -389.782326) (xy 55.391304 -389.782812) (xy 55.36591 -389.782308) (xy 55.315776 -389.774178)
			(xy 55.267591 -389.758127) (xy 55.222596 -389.734569) (xy 55.181954 -389.704112) (xy 55.146711 -389.667542)
			(xy 55.117777 -389.625801) (xy 55.095899 -389.579966) (xy 55.088282 -389.555736) (xy 55.086758 -389.549894)
			(xy 54.766464 -388.996174) (xy 54.7624 -388.991856) (xy 54.746197 -388.974147) (xy 54.718772 -388.934757)
			(xy 54.69763 -388.891667) (xy 54.683256 -388.845873) (xy 54.675982 -388.79843) (xy 54.675532 -388.774432)
			(xy 54.675674 -388.76238) (xy 54.67758 -388.73835) (xy 54.679342 -388.726426) (xy 54.680612 -388.717536)
			(xy 54.677564 -388.700518) (xy 54.6354 -388.629652) (xy 54.622192 -388.618476) (xy 54.61381 -388.615428)
			(xy 54.592071 -388.607011) (xy 54.551211 -388.584575) (xy 54.514239 -388.556186) (xy 54.482015 -388.522504)
			(xy 54.455288 -388.484313) (xy 54.434681 -388.442501) (xy 54.420672 -388.398042) (xy 54.413588 -388.351969)
			(xy 54.41315 -388.328662) (xy 54.41366 -388.303266) (xy 54.42207 -388.253176) (xy 54.438653 -388.205167)
			(xy 54.462952 -388.160565) (xy 54.494295 -388.120597) (xy 54.512718 -388.10311) (xy 54.5211 -388.09549)
			(xy 54.529736 -388.075424) (xy 54.526942 -387.97611) (xy 54.517544 -387.956552) (xy 54.508654 -387.94944)
			(xy 54.490117 -387.933612) (xy 54.457396 -387.897486) (xy 54.430326 -387.856953) (xy 54.409492 -387.812889)
			(xy 54.395343 -387.766246) (xy 54.388188 -387.718033) (xy 54.38775 -387.693662) (xy 54.388164 -387.669544)
			(xy 54.395171 -387.621821) (xy 54.409031 -387.57562) (xy 54.429451 -387.53192) (xy 54.44236 -387.511544)
			(xy 54.448202 -387.502654) (xy 54.451758 -387.482588) (xy 54.430676 -387.390386) (xy 54.418484 -387.373622)
			(xy 54.409594 -387.368288) (xy 54.38881 -387.355406) (xy 54.350903 -387.324522) (xy 54.317959 -387.288392)
			(xy 54.290695 -387.247803) (xy 54.269707 -387.203642) (xy 54.255452 -387.15687) (xy 54.248241 -387.10851)
			(xy 54.247796 -387.084062) (xy 54.248344 -387.056777) (xy 54.257295 -387.002948) (xy 54.274964 -386.951318)
			(xy 54.300871 -386.903291) (xy 54.334313 -386.860171) (xy 54.353968 -386.841238) (xy 54.36135 -386.8337)
			(xy 54.369887 -386.814433) (xy 54.370478 -386.8039) (xy 54.370478 -386.729224) (xy 54.369956 -386.718673)
			(xy 54.361417 -386.699378) (xy 54.353968 -386.691886) (xy 54.33434 -386.672928) (xy 54.300904 -386.629809)
			(xy 54.274998 -386.581788) (xy 54.257323 -386.530166) (xy 54.248359 -386.476344) (xy 54.247796 -386.449062)
			(xy 54.24805 -386.43687) (xy 54.248304 -386.427218) (xy 54.242208 -386.409184) (xy 54.183534 -386.341874)
			(xy 54.16677 -386.333238) (xy 54.157118 -386.332222) (xy 54.130207 -386.328884) (xy 54.07792 -386.314514)
			(xy 54.028677 -386.291809) (xy 53.983795 -386.261379) (xy 53.944476 -386.224037) (xy 53.911772 -386.180783)
			(xy 53.88656 -386.132775) (xy 53.869513 -386.081299) (xy 53.864764 -386.0546) (xy 53.86324 -386.045202)
			(xy 53.590444 -385.57327) (xy 53.583078 -385.567428) (xy 53.564327 -385.551597) (xy 53.531208 -385.515385)
			(xy 53.503796 -385.474683) (xy 53.48269 -385.430381) (xy 53.468354 -385.383449) (xy 53.4611 -385.334916)
			(xy 53.46065 -385.31038) (xy 52.943602 -385.31038) (xy 53.192172 -385.740402) (xy 53.199538 -385.746244)
			(xy 53.218327 -385.762032) (xy 53.251443 -385.798253) (xy 53.27885 -385.838965) (xy 53.299948 -385.883275)
			(xy 53.314277 -385.930214) (xy 53.321521 -385.978753) (xy 53.321966 -386.003292) (xy 53.321712 -386.015484)
			(xy 53.321458 -386.025136) (xy 53.327554 -386.04317) (xy 53.386228 -386.11048) (xy 53.402992 -386.119116)
			(xy 53.412898 -386.120132) (xy 53.43966 -386.123493) (xy 53.491683 -386.137715) (xy 53.540708 -386.16019)
			(xy 53.585438 -386.190322) (xy 53.624685 -386.227312) (xy 53.657411 -386.27018) (xy 53.682748 -386.31779)
			(xy 53.700023 -386.36888) (xy 53.70878 -386.422096) (xy 53.709316 -386.449062) (xy 53.708888 -386.473264)
			(xy 53.701815 -386.521148) (xy 53.687829 -386.567488) (xy 53.667231 -386.61129) (xy 53.654198 -386.631688)
			(xy 53.649412 -386.639646) (xy 53.645376 -386.657756) (xy 53.646324 -386.666994) (xy 53.650642 -386.697982)
			(xy 53.652312 -386.707281) (xy 53.6616 -386.723722) (xy 53.668676 -386.729986) (xy 53.690767 -386.748665)
			(xy 53.730538 -386.790678) (xy 53.764699 -386.837366) (xy 53.792706 -386.887987) (xy 53.814113 -386.941732)
			(xy 53.828578 -386.997746) (xy 53.835871 -387.055136) (xy 53.836316 -387.084062) (xy 53.835728 -387.117384)
			(xy 53.826065 -387.183322) (xy 53.806938 -387.247161) (xy 53.79339 -387.27761) (xy 53.789138 -387.288074)
			(xy 53.789252 -387.310634) (xy 53.798988 -387.330986) (xy 53.80736 -387.33857) (xy 53.829582 -387.357273)
			(xy 53.869648 -387.399322) (xy 53.904072 -387.446103) (xy 53.932301 -387.496863) (xy 53.95388 -387.550787)
			(xy 53.968464 -387.607007) (xy 53.975817 -387.664621) (xy 53.97627 -387.693662) (xy 53.975787 -387.722667)
			(xy 53.968476 -387.780213) (xy 53.953955 -387.836376) (xy 53.932455 -387.890253) (xy 53.904322 -387.940984)
			(xy 53.870006 -387.987754) (xy 53.830057 -388.029815) (xy 53.807868 -388.0485) (xy 53.800756 -388.054088)
			(xy 53.791612 -388.069328) (xy 53.776372 -388.152132) (xy 53.779166 -388.169404) (xy 53.783738 -388.177532)
			(xy 53.796313 -388.200719) (xy 53.814187 -388.25034) (xy 53.823288 -388.302291) (xy 53.82387 -388.328662)
			(xy 53.823801 -388.338021) (xy 53.822658 -388.356703) (xy 53.821584 -388.366) (xy 53.820568 -388.37489)
			(xy 53.824378 -388.391654) (xy 53.86832 -388.461504) (xy 53.882036 -388.471918) (xy 53.890418 -388.474712)
			(xy 53.914442 -388.483192) (xy 53.959615 -388.506741) (xy 54.000421 -388.537238) (xy 54.035801 -388.573891)
			(xy 54.064837 -388.615749) (xy 54.086777 -388.661725) (xy 54.09438 -388.68604) (xy 54.095904 -388.691882)
			(xy 54.416198 -389.245602) (xy 54.420262 -389.24992) (xy 54.43646 -389.26762) (xy 54.463822 -389.307032)
			(xy 54.484905 -389.35013) (xy 54.499224 -389.395922) (xy 54.506448 -389.443354) (xy 54.506876 -389.467344)
			(xy 54.506423 -389.492134) (xy 54.49866 -389.541104) (xy 54.483334 -389.588257) (xy 54.460821 -389.632432)
			(xy 54.431675 -389.672541) (xy 54.396614 -389.707598) (xy 54.356501 -389.73674) (xy 54.312323 -389.759248)
			(xy 54.265169 -389.774569) (xy 54.216198 -389.782325) (xy 54.191408 -389.782812) (xy 54.166014 -389.782304)
			(xy 54.115881 -389.774175) (xy 54.067695 -389.758125) (xy 54.022701 -389.734568) (xy 53.982058 -389.704111)
			(xy 53.946815 -389.667541) (xy 53.917881 -389.6258) (xy 53.896003 -389.579966) (xy 53.888386 -389.555736)
			(xy 53.886862 -389.549894) (xy 53.566568 -388.996174) (xy 53.562504 -388.991856) (xy 53.546302 -388.974147)
			(xy 53.518877 -388.934756) (xy 53.497734 -388.891667) (xy 53.48336 -388.845873) (xy 53.476086 -388.79843)
			(xy 53.475636 -388.774432) (xy 53.475778 -388.76238) (xy 53.477684 -388.73835) (xy 53.479446 -388.726426)
			(xy 53.480716 -388.717536) (xy 53.477668 -388.700518) (xy 53.435504 -388.629652) (xy 53.422296 -388.618476)
			(xy 53.413914 -388.615428) (xy 53.392176 -388.607009) (xy 53.351316 -388.584573) (xy 53.314344 -388.556185)
			(xy 53.282119 -388.522503) (xy 53.255392 -388.484312) (xy 53.234785 -388.442501) (xy 53.220776 -388.398042)
			(xy 53.213692 -388.351969) (xy 53.213254 -388.328662) (xy 53.213826 -388.302289) (xy 53.222907 -388.250331)
			(xy 53.240793 -388.200711) (xy 53.253386 -388.177532) (xy 53.257958 -388.169404) (xy 53.260752 -388.152132)
			(xy 53.245512 -388.069328) (xy 53.236368 -388.054088) (xy 53.229256 -388.0485) (xy 53.207076 -388.029805)
			(xy 53.167131 -387.98774) (xy 53.132816 -387.94097) (xy 53.104679 -387.890242) (xy 53.083171 -387.836368)
			(xy 53.068635 -387.78021) (xy 53.061305 -387.722666) (xy 53.060854 -387.693662) (xy 53.061453 -387.660341)
			(xy 53.071112 -387.594403) (xy 53.090234 -387.530563) (xy 53.10378 -387.500114) (xy 53.108019 -387.489645)
			(xy 53.107914 -387.467087) (xy 53.098181 -387.446737) (xy 53.08981 -387.439154) (xy 53.067545 -387.420501)
			(xy 53.027482 -387.378442) (xy 52.993063 -387.331652) (xy 52.96484 -387.280883) (xy 52.943268 -387.226952)
			(xy 52.928692 -387.170725) (xy 52.921348 -387.113105) (xy 52.9209 -387.084062) (xy 52.921334 -387.055135)
			(xy 52.928618 -386.997741) (xy 52.943079 -386.941723) (xy 52.964485 -386.887975) (xy 52.992495 -386.837354)
			(xy 53.026663 -386.790667) (xy 53.066442 -386.748658) (xy 53.08854 -386.729986) (xy 53.095508 -386.723635)
			(xy 53.104769 -386.707234) (xy 53.106574 -386.697982) (xy 53.110892 -386.666994) (xy 53.111789 -386.657757)
			(xy 53.107768 -386.639658) (xy 53.103018 -386.631688) (xy 53.090032 -386.611264) (xy 53.069451 -386.567463)
			(xy 53.055463 -386.521132) (xy 53.048367 -386.473259) (xy 53.0479 -386.449062) (xy 53.048154 -386.43687)
			(xy 53.048408 -386.427218) (xy 53.042312 -386.409184) (xy 52.983638 -386.341874) (xy 52.966874 -386.333238)
			(xy 52.956968 -386.332222) (xy 52.930062 -386.328844) (xy 52.877776 -386.314481) (xy 52.828533 -386.291784)
			(xy 52.78365 -386.26136) (xy 52.74433 -386.224023) (xy 52.711625 -386.180774) (xy 52.686411 -386.132771)
			(xy 52.669364 -386.081298) (xy 52.664614 -386.0546) (xy 52.66309 -386.045202) (xy 52.390294 -385.57327)
			(xy 52.382928 -385.567428) (xy 52.364166 -385.551608) (xy 52.331051 -385.515393) (xy 52.303641 -385.474688)
			(xy 52.282538 -385.430384) (xy 52.268203 -385.383451) (xy 52.26095 -385.334917) (xy 52.2605 -385.31038)
			(xy 51.743706 -385.31038) (xy 51.992276 -385.740402) (xy 51.999642 -385.746244) (xy 52.018432 -385.762031)
			(xy 52.051547 -385.798252) (xy 52.078954 -385.838964) (xy 52.100053 -385.883275) (xy 52.114381 -385.930214)
			(xy 52.121625 -385.978753) (xy 52.12207 -386.003292) (xy 52.121816 -386.015484) (xy 52.121562 -386.025136)
			(xy 52.127658 -386.04317) (xy 52.186332 -386.11048) (xy 52.203096 -386.119116) (xy 52.212748 -386.120132)
			(xy 52.239515 -386.123452) (xy 52.291539 -386.137682) (xy 52.340564 -386.160164) (xy 52.385293 -386.190301)
			(xy 52.42454 -386.227296) (xy 52.457264 -386.270169) (xy 52.482599 -386.317783) (xy 52.499874 -386.368876)
			(xy 52.508631 -386.422095) (xy 52.509166 -386.449062) (xy 52.508656 -386.475049) (xy 52.500526 -386.526384)
			(xy 52.484465 -386.575814) (xy 52.460869 -386.622124) (xy 52.430319 -386.664172) (xy 52.393568 -386.700923)
			(xy 52.35152 -386.731473) (xy 52.30521 -386.755069) (xy 52.25578 -386.77113) (xy 52.204445 -386.77926)
			(xy 52.152471 -386.77926) (xy 52.101136 -386.77113) (xy 52.051706 -386.755069) (xy 52.005396 -386.731473)
			(xy 51.963348 -386.700923) (xy 51.926597 -386.664172) (xy 51.896047 -386.622124) (xy 51.872451 -386.575814)
			(xy 51.85639 -386.526384) (xy 51.84826 -386.475049) (xy 51.84775 -386.449062) (xy 51.848004 -386.43687)
			(xy 51.848258 -386.427218) (xy 51.842162 -386.409184) (xy 51.783488 -386.341874) (xy 51.766724 -386.333238)
			(xy 51.757072 -386.332222) (xy 51.730167 -386.328841) (xy 51.677881 -386.314479) (xy 51.628637 -386.291782)
			(xy 51.583755 -386.261358) (xy 51.544434 -386.224022) (xy 51.511729 -386.180774) (xy 51.486516 -386.13277)
			(xy 51.469468 -386.081297) (xy 51.464718 -386.0546) (xy 51.463194 -386.045202) (xy 51.190398 -385.57327)
			(xy 51.183032 -385.567428) (xy 51.164271 -385.551608) (xy 51.131155 -385.515393) (xy 51.103746 -385.474688)
			(xy 51.082642 -385.430384) (xy 51.068307 -385.383451) (xy 51.061054 -385.334917) (xy 51.060604 -385.31038)
			(xy 50.54352 -385.31038) (xy 50.792126 -385.740402) (xy 50.799492 -385.746244) (xy 50.818272 -385.762044)
			(xy 50.851389 -385.798261) (xy 50.878799 -385.838969) (xy 50.8999 -385.883278) (xy 50.914229 -385.930215)
			(xy 50.921474 -385.978754) (xy 50.92192 -386.003292) (xy 50.921666 -386.015484) (xy 50.921412 -386.025136)
			(xy 50.927508 -386.04317) (xy 50.986182 -386.11048) (xy 51.002946 -386.119116) (xy 51.012852 -386.120132)
			(xy 51.039609 -386.12353) (xy 51.091631 -386.137745) (xy 51.140657 -386.160214) (xy 51.185387 -386.19034)
			(xy 51.224636 -386.227326) (xy 51.257363 -386.27019) (xy 51.2827 -386.317796) (xy 51.299977 -386.368884)
			(xy 51.308734 -386.422097) (xy 51.30927 -386.449062) (xy 51.308748 -386.476348) (xy 51.299793 -386.530179)
			(xy 51.282118 -386.58181) (xy 51.256205 -386.629836) (xy 51.222756 -386.672955) (xy 51.203098 -386.691886)
			(xy 51.1957 -386.699411) (xy 51.187174 -386.718688) (xy 51.186588 -386.729224) (xy 51.186588 -386.8039)
			(xy 51.187107 -386.814451) (xy 51.19565 -386.833746) (xy 51.203098 -386.841238) (xy 51.222731 -386.860191)
			(xy 51.256168 -386.90331) (xy 51.282074 -386.951333) (xy 51.299747 -387.002956) (xy 51.308709 -387.05678)
			(xy 51.30927 -387.084062) (xy 51.308817 -387.108178) (xy 51.301821 -387.1559) (xy 51.287972 -387.202101)
			(xy 51.267564 -387.245802) (xy 51.25466 -387.26618) (xy 51.248818 -387.27507) (xy 51.245262 -387.295136)
			(xy 51.266344 -387.387338) (xy 51.278536 -387.404102) (xy 51.287426 -387.409436) (xy 51.308225 -387.422294)
			(xy 51.346131 -387.453183) (xy 51.379074 -387.489317) (xy 51.406336 -387.52991) (xy 51.427321 -387.574075)
			(xy 51.441573 -387.62085) (xy 51.448781 -387.669213) (xy 51.449224 -387.693662) (xy 51.448794 -387.718035)
			(xy 51.441649 -387.766254) (xy 51.427508 -387.812903) (xy 51.406676 -387.856972) (xy 51.379605 -387.89751)
			(xy 51.34688 -387.933637) (xy 51.32832 -387.94944) (xy 51.31943 -387.956552) (xy 51.310032 -387.97611)
			(xy 51.307238 -388.075424) (xy 51.315874 -388.09549) (xy 51.324256 -388.10311) (xy 51.342705 -388.120572)
			(xy 51.374052 -388.160542) (xy 51.398349 -388.205151) (xy 51.414925 -388.253167) (xy 51.423325 -388.303264)
			(xy 51.423824 -388.328662) (xy 52.013104 -388.328662) (xy 52.013626 -388.303407) (xy 52.021939 -388.253585)
			(xy 52.03834 -388.205811) (xy 52.062381 -388.161388) (xy 52.093405 -388.121528) (xy 52.130567 -388.087318)
			(xy 52.172853 -388.059692) (xy 52.219109 -388.039402) (xy 52.268074 -388.027002) (xy 52.318412 -388.022831)
			(xy 52.36875 -388.027002) (xy 52.417715 -388.039402) (xy 52.463971 -388.059692) (xy 52.506257 -388.087318)
			(xy 52.543419 -388.121528) (xy 52.574443 -388.161388) (xy 52.598484 -388.205811) (xy 52.614885 -388.253585)
			(xy 52.623198 -388.303407) (xy 52.62372 -388.328662) (xy 52.623651 -388.338021) (xy 52.622508 -388.356703)
			(xy 52.621434 -388.366) (xy 52.620418 -388.37489) (xy 52.624228 -388.391654) (xy 52.66817 -388.461504)
			(xy 52.681886 -388.471918) (xy 52.690268 -388.474712) (xy 52.714282 -388.483218) (xy 52.759456 -388.506761)
			(xy 52.800264 -388.537252) (xy 52.835646 -388.5739) (xy 52.864684 -388.615753) (xy 52.886626 -388.661726)
			(xy 52.89423 -388.68604) (xy 52.895754 -388.691882) (xy 53.216048 -389.245602) (xy 53.220112 -389.24992)
			(xy 53.236306 -389.267637) (xy 53.263731 -389.307025) (xy 53.284875 -389.350113) (xy 53.299252 -389.395905)
			(xy 53.306528 -389.443346) (xy 53.30698 -389.467344) (xy 53.306547 -389.492149) (xy 53.298776 -389.541146)
			(xy 53.283433 -389.588324) (xy 53.260896 -389.632519) (xy 53.231721 -389.672643) (xy 53.196625 -389.707707)
			(xy 53.156475 -389.736846) (xy 53.112259 -389.759343) (xy 53.065068 -389.774643) (xy 53.016063 -389.782369)
			(xy 52.991258 -389.782812) (xy 52.965862 -389.782348) (xy 52.915727 -389.774211) (xy 52.867541 -389.758154)
			(xy 52.822546 -389.73459) (xy 52.781904 -389.704127) (xy 52.746662 -389.667552) (xy 52.717729 -389.625806)
			(xy 52.695852 -389.579968) (xy 52.688236 -389.555736) (xy 52.686712 -389.549894) (xy 52.366418 -388.996174)
			(xy 52.362354 -388.991856) (xy 52.346195 -388.974122) (xy 52.318826 -388.93472) (xy 52.297736 -388.89163)
			(xy 52.283408 -388.845845) (xy 52.276174 -388.798419) (xy 52.27574 -388.774432) (xy 52.275821 -388.762384)
			(xy 52.277603 -388.738355) (xy 52.279296 -388.726426) (xy 52.280566 -388.717536) (xy 52.277518 -388.700518)
			(xy 52.235354 -388.629652) (xy 52.222146 -388.618476) (xy 52.213764 -388.615428) (xy 52.192015 -388.607036)
			(xy 52.151157 -388.584594) (xy 52.114186 -388.5562) (xy 52.081964 -388.522514) (xy 52.055239 -388.48432)
			(xy 52.034633 -388.442506) (xy 52.020625 -388.398044) (xy 52.013542 -388.35197) (xy 52.013104 -388.328662)
			(xy 51.423824 -388.328662) (xy 51.423755 -388.338021) (xy 51.422612 -388.356703) (xy 51.421538 -388.366)
			(xy 51.420522 -388.37489) (xy 51.424332 -388.391654) (xy 51.468274 -388.461504) (xy 51.48199 -388.471918)
			(xy 51.490372 -388.474712) (xy 51.514387 -388.483216) (xy 51.559561 -388.50676) (xy 51.600368 -388.537251)
			(xy 51.63575 -388.573899) (xy 51.664789 -388.615753) (xy 51.68673 -388.661726) (xy 51.694334 -388.68604)
			(xy 51.695858 -388.691882) (xy 52.016152 -389.245602) (xy 52.020216 -389.24992) (xy 52.03641 -389.267636)
			(xy 52.063835 -389.307025) (xy 52.08498 -389.350113) (xy 52.099356 -389.395905) (xy 52.106632 -389.443346)
			(xy 52.107084 -389.467344) (xy 52.106647 -389.492149) (xy 52.098876 -389.541146) (xy 52.083534 -389.588323)
			(xy 52.060997 -389.632518) (xy 52.031822 -389.672642) (xy 51.996727 -389.707705) (xy 51.956577 -389.736845)
			(xy 51.912362 -389.759342) (xy 51.865171 -389.774642) (xy 51.816167 -389.782369) (xy 51.791362 -389.782812)
			(xy 51.765966 -389.782345) (xy 51.715831 -389.774208) (xy 51.667645 -389.758151) (xy 51.622651 -389.734588)
			(xy 51.582008 -389.704126) (xy 51.546766 -389.667551) (xy 51.517833 -389.625806) (xy 51.495956 -389.579968)
			(xy 51.48834 -389.555736) (xy 51.486816 -389.549894) (xy 51.166522 -388.996174) (xy 51.162458 -388.991856)
			(xy 51.146299 -388.974121) (xy 51.118931 -388.93472) (xy 51.09784 -388.89163) (xy 51.083512 -388.845845)
			(xy 51.076278 -388.798419) (xy 51.075844 -388.774432) (xy 51.075925 -388.762384) (xy 51.077707 -388.738355)
			(xy 51.0794 -388.726426) (xy 51.08067 -388.717536) (xy 51.077622 -388.700518) (xy 51.035458 -388.629652)
			(xy 51.02225 -388.618476) (xy 51.013868 -388.615428) (xy 50.99212 -388.607034) (xy 50.951261 -388.584593)
			(xy 50.914291 -388.556199) (xy 50.882068 -388.522514) (xy 50.855343 -388.484319) (xy 50.834737 -388.442506)
			(xy 50.820729 -388.398044) (xy 50.813646 -388.35197) (xy 50.813208 -388.328662) (xy 50.813731 -388.303267)
			(xy 50.822141 -388.253178) (xy 50.838721 -388.20517) (xy 50.863016 -388.160567) (xy 50.894355 -388.120599)
			(xy 50.912776 -388.10311) (xy 50.921158 -388.09549) (xy 50.929794 -388.075424) (xy 50.927 -387.97611)
			(xy 50.917602 -387.956552) (xy 50.908712 -387.94944) (xy 50.890167 -387.933622) (xy 50.857448 -387.897493)
			(xy 50.83038 -387.856957) (xy 50.809547 -387.812891) (xy 50.795401 -387.766247) (xy 50.788245 -387.718033)
			(xy 50.787808 -387.693662) (xy 50.788229 -387.669545) (xy 50.795235 -387.621822) (xy 50.809093 -387.575621)
			(xy 50.82951 -387.531921) (xy 50.842418 -387.511544) (xy 50.84826 -387.502654) (xy 50.851816 -387.482588)
			(xy 50.830734 -387.390386) (xy 50.818542 -387.373622) (xy 50.809652 -387.368288) (xy 50.788859 -387.355422)
			(xy 50.750954 -387.324533) (xy 50.718011 -387.288399) (xy 50.690749 -387.247808) (xy 50.669763 -387.203645)
			(xy 50.655509 -387.156872) (xy 50.648299 -387.10851) (xy 50.647854 -387.084062) (xy 50.648415 -387.056778)
			(xy 50.657365 -387.00295) (xy 50.675031 -386.951321) (xy 50.700935 -386.903294) (xy 50.734373 -386.860172)
			(xy 50.754026 -386.841238) (xy 50.761402 -386.833694) (xy 50.769944 -386.814432) (xy 50.770536 -386.8039)
			(xy 50.770536 -386.729224) (xy 50.769997 -386.718676) (xy 50.761468 -386.699381) (xy 50.754026 -386.691886)
			(xy 50.73439 -386.672936) (xy 50.700958 -386.629814) (xy 50.675053 -386.58179) (xy 50.65738 -386.530167)
			(xy 50.648417 -386.476344) (xy 50.647854 -386.449062) (xy 50.648108 -386.43687) (xy 50.648362 -386.427218)
			(xy 50.642266 -386.409184) (xy 50.583592 -386.341874) (xy 50.566828 -386.333238) (xy 50.556922 -386.332222)
			(xy 50.530011 -386.328881) (xy 50.477725 -386.314511) (xy 50.428481 -386.291807) (xy 50.383599 -386.261377)
			(xy 50.34428 -386.224036) (xy 50.311577 -386.180782) (xy 50.286364 -386.132775) (xy 50.269317 -386.081299)
			(xy 50.264568 -386.0546) (xy 50.263044 -386.045202) (xy 49.989994 -385.572762) (xy 49.982882 -385.56692)
			(xy 49.964147 -385.551143) (xy 49.931093 -385.515001) (xy 49.903737 -385.474374) (xy 49.882678 -385.430155)
			(xy 49.868379 -385.383311) (xy 49.861151 -385.334869) (xy 49.860708 -385.31038) (xy 49.34366 -385.31038)
			(xy 49.59223 -385.740402) (xy 49.599596 -385.746244) (xy 49.618376 -385.762043) (xy 49.651494 -385.79826)
			(xy 49.678903 -385.838969) (xy 49.700004 -385.883278) (xy 49.714333 -385.930215) (xy 49.721578 -385.978754)
			(xy 49.722024 -386.003292) (xy 49.72177 -386.015484) (xy 49.721516 -386.025136) (xy 49.727612 -386.04317)
			(xy 49.786286 -386.11048) (xy 49.80305 -386.119116) (xy 49.812956 -386.120132) (xy 49.839713 -386.123527)
			(xy 49.891735 -386.137743) (xy 49.940761 -386.160212) (xy 49.985492 -386.190339) (xy 50.02474 -386.227324)
			(xy 50.057467 -386.270189) (xy 50.082804 -386.317796) (xy 50.100081 -386.368883) (xy 50.108838 -386.422097)
			(xy 50.109374 -386.449062) (xy 50.108851 -386.476348) (xy 50.099896 -386.530179) (xy 50.082221 -386.581809)
			(xy 50.056308 -386.629836) (xy 50.02286 -386.672955) (xy 50.003202 -386.691886) (xy 49.995805 -386.699411)
			(xy 49.987278 -386.718689) (xy 49.986692 -386.729224) (xy 49.986692 -386.8039) (xy 49.98721 -386.814451)
			(xy 49.995753 -386.833746) (xy 50.003202 -386.841238) (xy 50.022836 -386.86019) (xy 50.056272 -386.90331)
			(xy 50.082178 -386.951333) (xy 50.099851 -387.002956) (xy 50.108813 -387.05678) (xy 50.109374 -387.084062)
			(xy 50.10892 -387.108178) (xy 50.101924 -387.1559) (xy 50.088076 -387.202101) (xy 50.067668 -387.245802)
			(xy 50.054764 -387.26618) (xy 50.048922 -387.27507) (xy 50.045366 -387.295136) (xy 50.066448 -387.387338)
			(xy 50.07864 -387.404102) (xy 50.08753 -387.409436) (xy 50.10833 -387.422293) (xy 50.146236 -387.453182)
			(xy 50.179179 -387.489317) (xy 50.20644 -387.52991) (xy 50.227426 -387.574075) (xy 50.241677 -387.62085)
			(xy 50.248885 -387.669213) (xy 50.249328 -387.693662) (xy 50.248897 -387.718035) (xy 50.241752 -387.766253)
			(xy 50.227611 -387.812902) (xy 50.206779 -387.856972) (xy 50.179708 -387.897509) (xy 50.146984 -387.933637)
			(xy 50.128424 -387.94944) (xy 50.119534 -387.956552) (xy 50.110136 -387.97611) (xy 50.107342 -388.075424)
			(xy 50.115978 -388.09549) (xy 50.12436 -388.10311) (xy 50.14281 -388.120571) (xy 50.174156 -388.160542)
			(xy 50.198453 -388.205151) (xy 50.21503 -388.253166) (xy 50.223429 -388.303264) (xy 50.223928 -388.328662)
			(xy 50.223859 -388.338021) (xy 50.222716 -388.356703) (xy 50.221642 -388.366) (xy 50.220626 -388.37489)
			(xy 50.224436 -388.391654) (xy 50.268378 -388.461504) (xy 50.282094 -388.471918) (xy 50.290476 -388.474712)
			(xy 50.314569 -388.483205) (xy 50.35986 -388.506827) (xy 50.400756 -388.537435) (xy 50.436189 -388.57423)
			(xy 50.465233 -388.616251) (xy 50.48713 -388.662401) (xy 50.494692 -388.686802) (xy 50.496216 -388.692644)
			(xy 50.816002 -389.245602) (xy 50.820066 -389.24992) (xy 50.836265 -389.267619) (xy 50.863627 -389.307031)
			(xy 50.88471 -389.35013) (xy 50.899028 -389.395922) (xy 50.906252 -389.443354) (xy 50.90668 -389.467344)
			(xy 50.906223 -389.492134) (xy 50.898461 -389.541103) (xy 50.883134 -389.588256) (xy 50.860622 -389.63243)
			(xy 50.831476 -389.67254) (xy 50.796416 -389.707597) (xy 50.756303 -389.736738) (xy 50.712126 -389.759247)
			(xy 50.664972 -389.774568) (xy 50.616002 -389.782325) (xy 50.591212 -389.782812) (xy 50.565818 -389.782301)
			(xy 50.515685 -389.774172) (xy 50.4675 -389.758123) (xy 50.422505 -389.734566) (xy 50.381862 -389.70411)
			(xy 50.346619 -389.66754) (xy 50.317685 -389.6258) (xy 50.295807 -389.579966) (xy 50.28819 -389.555736)
			(xy 50.286666 -389.549894) (xy 49.966118 -388.995412) (xy 49.962054 -388.991094) (xy 49.945955 -388.973433)
			(xy 49.918767 -388.934134) (xy 49.897815 -388.891185) (xy 49.883578 -388.845568) (xy 49.876383 -388.798326)
			(xy 49.875948 -388.774432) (xy 49.876029 -388.762384) (xy 49.877811 -388.738355) (xy 49.879504 -388.726426)
			(xy 49.880774 -388.717536) (xy 49.877726 -388.700518) (xy 49.835562 -388.629652) (xy 49.822354 -388.618476)
			(xy 49.813972 -388.615428) (xy 49.792225 -388.607032) (xy 49.751366 -388.584591) (xy 49.714395 -388.556198)
			(xy 49.682173 -388.522513) (xy 49.655447 -388.484319) (xy 49.634841 -388.442505) (xy 49.620833 -388.398044)
			(xy 49.61375 -388.35197) (xy 49.613312 -388.328662) (xy 49.613834 -388.303267) (xy 49.622243 -388.253177)
			(xy 49.638824 -388.20517) (xy 49.663119 -388.160567) (xy 49.694459 -388.120598) (xy 49.71288 -388.10311)
			(xy 49.721262 -388.09549) (xy 49.729898 -388.075424) (xy 49.727104 -387.97611) (xy 49.717706 -387.956552)
			(xy 49.708816 -387.94944) (xy 49.690271 -387.933621) (xy 49.657553 -387.897492) (xy 49.630484 -387.856957)
			(xy 49.609652 -387.812891) (xy 49.595505 -387.766247) (xy 49.588349 -387.718033) (xy 49.587912 -387.693662)
			(xy 49.588332 -387.669545) (xy 49.595338 -387.621822) (xy 49.609197 -387.575621) (xy 49.629614 -387.531921)
			(xy 49.642522 -387.511544) (xy 49.648364 -387.502654) (xy 49.65192 -387.482588) (xy 49.630838 -387.390386)
			(xy 49.618646 -387.373622) (xy 49.609756 -387.368288) (xy 49.588964 -387.35542) (xy 49.551059 -387.324532)
			(xy 49.518116 -387.288399) (xy 49.490854 -387.247808) (xy 49.469867 -387.203644) (xy 49.455613 -387.156872)
			(xy 49.448403 -387.10851) (xy 49.447958 -387.084062) (xy 49.448518 -387.056778) (xy 49.457468 -387.002949)
			(xy 49.475135 -386.951321) (xy 49.501039 -386.903294) (xy 49.534477 -386.860172) (xy 49.55413 -386.841238)
			(xy 49.561507 -386.833695) (xy 49.570048 -386.814432) (xy 49.57064 -386.8039) (xy 49.57064 -386.729224)
			(xy 49.5701 -386.718676) (xy 49.561571 -386.699381) (xy 49.55413 -386.691886) (xy 49.534495 -386.672935)
			(xy 49.501062 -386.629813) (xy 49.475158 -386.58179) (xy 49.457484 -386.530167) (xy 49.448521 -386.476344)
			(xy 49.447958 -386.449062) (xy 49.448212 -386.43687) (xy 49.448466 -386.427218) (xy 49.44237 -386.409184)
			(xy 49.383696 -386.341874) (xy 49.366932 -386.333238) (xy 49.357026 -386.332222) (xy 49.330115 -386.328878)
			(xy 49.277829 -386.314508) (xy 49.228586 -386.291805) (xy 49.183704 -386.261376) (xy 49.144384 -386.224035)
			(xy 49.111681 -386.180782) (xy 49.086468 -386.132775) (xy 49.069421 -386.081299) (xy 49.064672 -386.0546)
			(xy 49.063148 -386.045202) (xy 48.790352 -385.57327) (xy 48.782986 -385.567428) (xy 48.764236 -385.551595)
			(xy 48.731117 -385.515384) (xy 48.703705 -385.474682) (xy 48.682599 -385.430381) (xy 48.668262 -385.383449)
			(xy 48.661008 -385.334916) (xy 48.660558 -385.31038) (xy 48.143764 -385.31038) (xy 48.392334 -385.740402)
			(xy 48.3997 -385.746244) (xy 48.418481 -385.762042) (xy 48.451599 -385.79826) (xy 48.479008 -385.838969)
			(xy 48.500108 -385.883277) (xy 48.514438 -385.930215) (xy 48.521682 -385.978754) (xy 48.522128 -386.003292)
			(xy 48.521874 -386.015484) (xy 48.52162 -386.025136) (xy 48.527716 -386.04317) (xy 48.58639 -386.11048)
			(xy 48.603154 -386.119116) (xy 48.612806 -386.120132) (xy 48.639569 -386.123487) (xy 48.691591 -386.13771)
			(xy 48.740617 -386.160186) (xy 48.785347 -386.190318) (xy 48.824594 -386.227309) (xy 48.85732 -386.270178)
			(xy 48.882656 -386.317789) (xy 48.899931 -386.368879) (xy 48.908688 -386.422096) (xy 48.909224 -386.449062)
			(xy 48.908685 -386.476347) (xy 48.899731 -386.530177) (xy 48.88206 -386.581806) (xy 48.856151 -386.629833)
			(xy 48.822707 -386.672953) (xy 48.803052 -386.691886) (xy 48.795662 -386.699418) (xy 48.787129 -386.71869)
			(xy 48.786542 -386.729224) (xy 48.786542 -386.8039) (xy 48.787045 -386.814453) (xy 48.795597 -386.833749)
			(xy 48.803052 -386.841238) (xy 48.822695 -386.860181) (xy 48.856128 -386.903304) (xy 48.882031 -386.951329)
			(xy 48.899703 -387.002954) (xy 48.908663 -387.056779) (xy 48.909224 -387.084062) (xy 48.908778 -387.108178)
			(xy 48.901781 -387.155901) (xy 48.887931 -387.202102) (xy 48.867519 -387.245803) (xy 48.854614 -387.26618)
			(xy 48.848772 -387.27507) (xy 48.845216 -387.295136) (xy 48.866298 -387.387338) (xy 48.87849 -387.404102)
			(xy 48.88738 -387.409436) (xy 48.908169 -387.422311) (xy 48.946077 -387.453195) (xy 48.979022 -387.489326)
			(xy 49.006286 -387.529916) (xy 49.027273 -387.574079) (xy 49.041527 -387.620852) (xy 49.048735 -387.669214)
			(xy 49.049178 -387.693662) (xy 49.048765 -387.718036) (xy 49.041619 -387.766256) (xy 49.027475 -387.812906)
			(xy 49.00664 -387.856976) (xy 48.979566 -387.897513) (xy 48.946836 -387.933638) (xy 48.928274 -387.94944)
			(xy 48.919384 -387.956552) (xy 48.909986 -387.97611) (xy 48.907192 -388.075424) (xy 48.915828 -388.09549)
			(xy 48.92421 -388.10311) (xy 48.94265 -388.120581) (xy 48.974 -388.160548) (xy 48.998299 -388.205154)
			(xy 49.014878 -388.253168) (xy 49.023278 -388.303264) (xy 49.023778 -388.328662) (xy 49.023709 -388.338021)
			(xy 49.022566 -388.356703) (xy 49.021492 -388.366) (xy 49.020476 -388.37489) (xy 49.024286 -388.391654)
			(xy 49.068228 -388.461504) (xy 49.081944 -388.471918) (xy 49.090326 -388.474712) (xy 49.114352 -388.483187)
			(xy 49.159524 -388.506738) (xy 49.20033 -388.537236) (xy 49.235709 -388.57389) (xy 49.264746 -388.615748)
			(xy 49.286685 -388.661725) (xy 49.294288 -388.68604) (xy 49.295812 -388.691882) (xy 49.616106 -389.245602)
			(xy 49.62017 -389.24992) (xy 49.63637 -389.267619) (xy 49.663731 -389.307031) (xy 49.684814 -389.35013)
			(xy 49.699132 -389.395922) (xy 49.706356 -389.443354) (xy 49.706784 -389.467344) (xy 49.706323 -389.492134)
			(xy 49.698561 -389.541103) (xy 49.683235 -389.588255) (xy 49.660722 -389.632429) (xy 49.631577 -389.672539)
			(xy 49.596517 -389.707595) (xy 49.556405 -389.736737) (xy 49.512229 -389.759246) (xy 49.465076 -389.774567)
			(xy 49.416106 -389.782325) (xy 49.391316 -389.782812) (xy 49.365922 -389.782297) (xy 49.315789 -389.774169)
			(xy 49.267604 -389.75812) (xy 49.22261 -389.734564) (xy 49.181967 -389.704108) (xy 49.146724 -389.667539)
			(xy 49.11779 -389.625799) (xy 49.095911 -389.579966) (xy 49.088294 -389.555736) (xy 49.08677 -389.549894)
			(xy 48.766476 -388.996174) (xy 48.762412 -388.991856) (xy 48.746211 -388.974145) (xy 48.718786 -388.934756)
			(xy 48.697642 -388.891667) (xy 48.683268 -388.845873) (xy 48.675994 -388.79843) (xy 48.675544 -388.774432)
			(xy 48.675686 -388.76238) (xy 48.677592 -388.73835) (xy 48.679354 -388.726426) (xy 48.680624 -388.717536)
			(xy 48.677576 -388.700518) (xy 48.635412 -388.629652) (xy 48.622204 -388.618476) (xy 48.613822 -388.615428)
			(xy 48.592085 -388.607004) (xy 48.551225 -388.58457) (xy 48.514253 -388.556182) (xy 48.482028 -388.522501)
			(xy 48.455301 -388.484311) (xy 48.434693 -388.4425) (xy 48.420684 -388.398041) (xy 48.4136 -388.351969)
			(xy 48.413162 -388.328662) (xy 48.413668 -388.303266) (xy 48.422079 -388.253175) (xy 48.438663 -388.205166)
			(xy 48.462962 -388.160564) (xy 48.494307 -388.120597) (xy 48.51273 -388.10311) (xy 48.521112 -388.09549)
			(xy 48.529748 -388.075424) (xy 48.526954 -387.97611) (xy 48.517556 -387.956552) (xy 48.508666 -387.94944)
			(xy 48.490132 -387.933609) (xy 48.45741 -387.897484) (xy 48.430339 -387.856952) (xy 48.409504 -387.812888)
			(xy 48.395356 -387.766246) (xy 48.3882 -387.718033) (xy 48.387762 -387.693662) (xy 48.388174 -387.669544)
			(xy 48.395181 -387.621821) (xy 48.409042 -387.57562) (xy 48.429462 -387.53192) (xy 48.442372 -387.511544)
			(xy 48.448214 -387.502654) (xy 48.45177 -387.482588) (xy 48.430688 -387.390386) (xy 48.418496 -387.373622)
			(xy 48.409606 -387.368288) (xy 48.388825 -387.355402) (xy 48.350917 -387.324519) (xy 48.317972 -387.28839)
			(xy 48.290708 -387.247802) (xy 48.269719 -387.203641) (xy 48.255464 -387.15687) (xy 48.248253 -387.108509)
			(xy 48.247808 -387.084062) (xy 48.248352 -387.056777) (xy 48.257303 -387.002947) (xy 48.274973 -386.951317)
			(xy 48.300881 -386.903291) (xy 48.334325 -386.86017) (xy 48.35398 -386.841238) (xy 48.361364 -386.833702)
			(xy 48.369899 -386.814433) (xy 48.37049 -386.8039) (xy 48.37049 -386.729224) (xy 48.369964 -386.718674)
			(xy 48.361427 -386.699378) (xy 48.35398 -386.691886) (xy 48.334354 -386.672926) (xy 48.300918 -386.629808)
			(xy 48.275011 -386.581787) (xy 48.257335 -386.530166) (xy 48.248371 -386.476344) (xy 48.247808 -386.449062)
			(xy 48.248062 -386.43687) (xy 48.248316 -386.427218) (xy 48.24222 -386.409184) (xy 48.183546 -386.341874)
			(xy 48.166782 -386.333238) (xy 48.15713 -386.332222) (xy 48.13022 -386.328874) (xy 48.077934 -386.314506)
			(xy 48.02869 -386.291803) (xy 47.983808 -386.261374) (xy 47.944489 -386.224034) (xy 47.911785 -386.180781)
			(xy 47.886572 -386.132774) (xy 47.869526 -386.081299) (xy 47.864776 -386.0546) (xy 47.863252 -386.045202)
			(xy 47.590456 -385.57327) (xy 47.58309 -385.567428) (xy 47.564341 -385.551594) (xy 47.531222 -385.515383)
			(xy 47.503809 -385.474682) (xy 47.482703 -385.43038) (xy 47.468366 -385.383449) (xy 47.461112 -385.334916)
			(xy 47.460662 -385.31038) (xy 45.133392 -385.31038) (xy 45.152906 -385.320323) (xy 45.194954 -385.350873)
			(xy 45.231705 -385.387624) (xy 45.262255 -385.429672) (xy 45.285851 -385.475982) (xy 45.301912 -385.525412)
			(xy 45.310042 -385.576747) (xy 45.310552 -385.602734) (xy 45.310042 -385.628721) (xy 45.301912 -385.680056)
			(xy 45.285851 -385.729486) (xy 45.262255 -385.775796) (xy 45.231705 -385.817844) (xy 45.194954 -385.854595)
			(xy 45.16614 -385.87553) (xy 46.834044 -385.87553) (xy 46.834554 -385.849543) (xy 46.842684 -385.798208)
			(xy 46.858745 -385.748778) (xy 46.882341 -385.702468) (xy 46.912891 -385.66042) (xy 46.949642 -385.623669)
			(xy 46.99169 -385.593119) (xy 47.038 -385.569523) (xy 47.08743 -385.553462) (xy 47.138765 -385.545332)
			(xy 47.190739 -385.545332) (xy 47.242074 -385.553462) (xy 47.291504 -385.569523) (xy 47.337814 -385.593119)
			(xy 47.379862 -385.623669) (xy 47.416613 -385.66042) (xy 47.447163 -385.702468) (xy 47.470759 -385.748778)
			(xy 47.48682 -385.798208) (xy 47.49495 -385.849543) (xy 47.49546 -385.87553) (xy 47.495076 -385.899206)
			(xy 47.488343 -385.946077) (xy 47.474978 -385.991503) (xy 47.465488 -386.013198) (xy 47.46117 -386.022596)
			(xy 47.460408 -386.042662) (xy 47.492666 -386.129022) (xy 47.506382 -386.143754) (xy 47.51578 -386.148072)
			(xy 47.540156 -386.159749) (xy 47.585024 -386.189879) (xy 47.624401 -386.2269) (xy 47.657238 -386.269828)
			(xy 47.682663 -386.317521) (xy 47.7 -386.368711) (xy 47.708789 -386.422039) (xy 47.709328 -386.449062)
			(xy 47.708788 -386.476347) (xy 47.699834 -386.530177) (xy 47.682163 -386.581806) (xy 47.656254 -386.629832)
			(xy 47.622811 -386.672953) (xy 47.603156 -386.691886) (xy 47.595767 -386.699418) (xy 47.587233 -386.71869)
			(xy 47.586646 -386.729224) (xy 47.586646 -386.8039) (xy 47.587148 -386.814453) (xy 47.595701 -386.833749)
			(xy 47.603156 -386.841238) (xy 47.6228 -386.86018) (xy 47.656233 -386.903304) (xy 47.682136 -386.951329)
			(xy 47.699807 -387.002954) (xy 47.708767 -387.056779) (xy 47.709328 -387.084062) (xy 47.708882 -387.108178)
			(xy 47.701885 -387.155901) (xy 47.688034 -387.202102) (xy 47.667623 -387.245803) (xy 47.654718 -387.26618)
			(xy 47.648876 -387.27507) (xy 47.64532 -387.295136) (xy 47.666402 -387.387338) (xy 47.678594 -387.404102)
			(xy 47.687484 -387.409436) (xy 47.708274 -387.422309) (xy 47.746181 -387.453194) (xy 47.779127 -387.489325)
			(xy 47.80639 -387.529915) (xy 47.827378 -387.574079) (xy 47.841631 -387.620852) (xy 47.848839 -387.669214)
			(xy 47.849282 -387.693662) (xy 47.848868 -387.718035) (xy 47.841721 -387.766256) (xy 47.827578 -387.812906)
			(xy 47.806744 -387.856976) (xy 47.779669 -387.897512) (xy 47.74694 -387.933638) (xy 47.728378 -387.94944)
			(xy 47.719488 -387.956552) (xy 47.71009 -387.97611) (xy 47.707296 -388.075424) (xy 47.715932 -388.09549)
			(xy 47.724314 -388.10311) (xy 47.742755 -388.12058) (xy 47.774104 -388.160548) (xy 47.798404 -388.205154)
			(xy 47.814982 -388.253168) (xy 47.823382 -388.303264) (xy 47.823882 -388.328662) (xy 47.823813 -388.338021)
			(xy 47.82267 -388.356703) (xy 47.821596 -388.366) (xy 47.82058 -388.37489) (xy 47.82439 -388.391654)
			(xy 47.868332 -388.461504) (xy 47.882048 -388.471918) (xy 47.89043 -388.474712) (xy 47.914456 -388.483185)
			(xy 47.959629 -388.506737) (xy 48.000434 -388.537235) (xy 48.035814 -388.573889) (xy 48.06485 -388.615747)
			(xy 48.086789 -388.661725) (xy 48.094392 -388.68604) (xy 48.095916 -388.691882) (xy 48.41621 -389.245602)
			(xy 48.420274 -389.24992) (xy 48.436474 -389.267618) (xy 48.463836 -389.30703) (xy 48.484918 -389.350129)
			(xy 48.499236 -389.395922) (xy 48.50646 -389.443354) (xy 48.506888 -389.467344) (xy 48.506423 -389.492134)
			(xy 48.498661 -389.541102) (xy 48.483335 -389.588254) (xy 48.460823 -389.632428) (xy 48.431678 -389.672537)
			(xy 48.396619 -389.707594) (xy 48.356507 -389.736736) (xy 48.312332 -389.759244) (xy 48.265179 -389.774566)
			(xy 48.21621 -389.782325) (xy 48.19142 -389.782812) (xy 48.166026 -389.782294) (xy 48.115893 -389.774166)
			(xy 48.067708 -389.758118) (xy 48.022714 -389.734562) (xy 47.982071 -389.704107) (xy 47.946828 -389.667538)
			(xy 47.917894 -389.625799) (xy 47.896015 -389.579966) (xy 47.888398 -389.555736) (xy 47.886874 -389.549894)
			(xy 47.56658 -388.996174) (xy 47.562516 -388.991856) (xy 47.546316 -388.974145) (xy 47.51889 -388.934755)
			(xy 47.497746 -388.891667) (xy 47.483372 -388.845873) (xy 47.476098 -388.79843) (xy 47.475648 -388.774432)
			(xy 47.47579 -388.76238) (xy 47.477696 -388.73835) (xy 47.479458 -388.726426) (xy 47.480728 -388.717536)
			(xy 47.47768 -388.700518) (xy 47.435516 -388.629652) (xy 47.422308 -388.618476) (xy 47.413926 -388.615428)
			(xy 47.392169 -388.607057) (xy 47.351311 -388.58461) (xy 47.314343 -388.556212) (xy 47.282122 -388.522523)
			(xy 47.255398 -388.484326) (xy 47.234793 -388.44251) (xy 47.220787 -388.398047) (xy 47.213704 -388.351971)
			(xy 47.213266 -388.328662) (xy 47.213803 -388.303268) (xy 47.222211 -388.25318) (xy 47.238789 -388.205173)
			(xy 47.26308 -388.16057) (xy 47.294416 -388.1206) (xy 47.312834 -388.10311) (xy 47.321216 -388.09549)
			(xy 47.329852 -388.075424) (xy 47.327058 -387.97611) (xy 47.31766 -387.956552) (xy 47.30877 -387.94944)
			(xy 47.290236 -387.933608) (xy 47.257514 -387.897484) (xy 47.230443 -387.856951) (xy 47.209608 -387.812888)
			(xy 47.19546 -387.766245) (xy 47.188304 -387.718032) (xy 47.187866 -387.693662) (xy 47.188277 -387.669544)
			(xy 47.195285 -387.621821) (xy 47.209145 -387.57562) (xy 47.229566 -387.53192) (xy 47.242476 -387.511544)
			(xy 47.248318 -387.502654) (xy 47.251874 -387.482588) (xy 47.230792 -387.390386) (xy 47.2186 -387.373622)
			(xy 47.20971 -387.368288) (xy 47.18893 -387.355401) (xy 47.151022 -387.324518) (xy 47.118077 -387.288389)
			(xy 47.090812 -387.247801) (xy 47.069823 -387.20364) (xy 47.055568 -387.15687) (xy 47.048357 -387.108509)
			(xy 47.047912 -387.084062) (xy 47.048455 -387.056777) (xy 47.057406 -387.002947) (xy 47.075076 -386.951317)
			(xy 47.100985 -386.90329) (xy 47.134428 -386.86017) (xy 47.154084 -386.841238) (xy 47.161469 -386.833702)
			(xy 47.170003 -386.814433) (xy 47.170594 -386.8039) (xy 47.170594 -386.729224) (xy 47.170067 -386.718674)
			(xy 47.161531 -386.699379) (xy 47.154084 -386.691886) (xy 47.134459 -386.672925) (xy 47.101022 -386.629807)
			(xy 47.075115 -386.581787) (xy 47.05744 -386.530166) (xy 47.048475 -386.476344) (xy 47.047912 -386.449062)
			(xy 47.048296 -386.425386) (xy 47.055029 -386.378515) (xy 47.068394 -386.333089) (xy 47.077884 -386.311394)
			(xy 47.082202 -386.301996) (xy 47.082964 -386.28193) (xy 47.050706 -386.19557) (xy 47.03699 -386.180838)
			(xy 47.027592 -386.17652) (xy 47.00323 -386.164816) (xy 46.958358 -386.134694) (xy 46.918978 -386.097679)
			(xy 46.886138 -386.054756) (xy 46.86071 -386.007066) (xy 46.843372 -385.955878) (xy 46.834583 -385.902552)
			(xy 46.834044 -385.87553) (xy 45.16614 -385.87553) (xy 45.152906 -385.885145) (xy 45.106596 -385.908741)
			(xy 45.057166 -385.924802) (xy 45.005831 -385.932932) (xy 44.953857 -385.932932) (xy 44.902522 -385.924802)
			(xy 44.853092 -385.908741) (xy 44.806782 -385.885145) (xy 44.764734 -385.854595) (xy 44.727983 -385.817844)
			(xy 44.697433 -385.775796) (xy 44.673837 -385.729486) (xy 44.657776 -385.680056) (xy 44.649646 -385.628721)
			(xy 44.444203 -385.628721) (xy 44.438831 -385.665222) (xy 44.422763 -385.718629) (xy 44.399091 -385.769126)
			(xy 44.368318 -385.815639) (xy 44.331101 -385.857176) (xy 44.288233 -385.892851) (xy 44.240627 -385.921905)
			(xy 44.189298 -385.943717) (xy 44.135341 -385.957823) (xy 44.079904 -385.963923) (xy 44.02417 -385.961886)
			(xy 43.969327 -385.951756) (xy 43.916543 -385.933749) (xy 43.866943 -385.908248) (xy 43.821585 -385.875797)
			(xy 43.781436 -385.837088) (xy 43.74735 -385.792945) (xy 43.720054 -385.74431) (xy 43.700131 -385.692219)
			(xy 43.688005 -385.637782) (xy 43.683934 -385.58216) (xy 41.70426 -385.58216) (xy 41.703758 -385.614121)
			(xy 41.695747 -385.677539) (xy 41.67985 -385.739453) (xy 41.656318 -385.798886) (xy 41.625524 -385.854901)
			(xy 41.587951 -385.906616) (xy 41.544194 -385.953213) (xy 41.494941 -385.993958) (xy 41.44097 -386.028209)
			(xy 41.383131 -386.055426) (xy 41.322338 -386.075179) (xy 41.259548 -386.087157) (xy 41.195752 -386.091171)
			(xy 41.131956 -386.087157) (xy 41.069166 -386.075179) (xy 41.008373 -386.055426) (xy 40.950534 -386.028209)
			(xy 40.896563 -385.993958) (xy 40.84731 -385.953213) (xy 40.803553 -385.906616) (xy 40.76598 -385.854901)
			(xy 40.735186 -385.798886) (xy 40.711654 -385.739453) (xy 40.695757 -385.677539) (xy 40.687746 -385.614121)
			(xy 39.50208 -385.614121) (xy 39.50208 -387.47192) (xy 40.003982 -387.47192) (xy 40.008053 -387.416298)
			(xy 40.020179 -387.361861) (xy 40.040102 -387.30977) (xy 40.067398 -387.261135) (xy 40.101484 -387.216992)
			(xy 40.141633 -387.178283) (xy 40.186991 -387.145832) (xy 40.236591 -387.120331) (xy 40.289375 -387.102324)
			(xy 40.344218 -387.092194) (xy 40.399952 -387.090157) (xy 40.455389 -387.096257) (xy 40.509346 -387.110363)
			(xy 40.560675 -387.132175) (xy 40.608281 -387.161229) (xy 40.651149 -387.196904) (xy 40.688366 -387.238441)
			(xy 40.719139 -387.284954) (xy 40.742811 -387.335451) (xy 40.758879 -387.388858) (xy 40.766999 -387.444034)
			(xy 40.767508 -387.47192) (xy 40.766999 -387.499806) (xy 40.758879 -387.554982) (xy 40.742811 -387.608389)
			(xy 40.719139 -387.658886) (xy 40.688366 -387.705399) (xy 40.651149 -387.746936) (xy 40.608281 -387.782611)
			(xy 40.596708 -387.789674) (xy 40.901112 -387.789674) (xy 40.901112 -386.926074) (xy 40.9016 -386.898805)
			(xy 40.909365 -386.844823) (xy 40.924732 -386.792495) (xy 40.947389 -386.742887) (xy 40.976876 -386.697007)
			(xy 41.01259 -386.65579) (xy 41.053807 -386.620076) (xy 41.099687 -386.590589) (xy 41.149295 -386.567932)
			(xy 41.201623 -386.552565) (xy 41.255605 -386.5448) (xy 41.282874 -386.544312) (xy 41.297989 -386.544481)
			(xy 41.328124 -386.546893) (xy 41.343072 -386.549138) (xy 41.35374 -386.550916) (xy 41.374568 -386.545328)
			(xy 41.45026 -386.484622) (xy 41.459912 -386.465572) (xy 41.46042 -386.45465) (xy 41.462623 -386.425842)
			(xy 41.474614 -386.369325) (xy 41.494986 -386.31526) (xy 41.523273 -386.264884) (xy 41.558829 -386.219345)
			(xy 41.600841 -386.179685) (xy 41.648351 -386.146809) (xy 41.700272 -386.121469) (xy 41.755419 -386.104242)
			(xy 41.812533 -386.095524) (xy 41.84142 -386.094986) (xy 41.86867 -386.095485) (xy 41.922615 -386.103244)
			(xy 41.974906 -386.1186) (xy 42.02448 -386.141242) (xy 42.070327 -386.170709) (xy 42.111514 -386.2064)
			(xy 42.147203 -386.247589) (xy 42.176667 -386.293438) (xy 42.199307 -386.343013) (xy 42.21466 -386.395305)
			(xy 42.222416 -386.44925) (xy 42.222416 -386.489448) (xy 44.75099 -386.489448) (xy 44.7515 -386.463461)
			(xy 44.75963 -386.412126) (xy 44.775691 -386.362696) (xy 44.799287 -386.316386) (xy 44.829837 -386.274338)
			(xy 44.866588 -386.237587) (xy 44.908636 -386.207037) (xy 44.954946 -386.183441) (xy 45.004376 -386.16738)
			(xy 45.055711 -386.15925) (xy 45.107685 -386.15925) (xy 45.15902 -386.16738) (xy 45.20845 -386.183441)
			(xy 45.25476 -386.207037) (xy 45.296808 -386.237587) (xy 45.333559 -386.274338) (xy 45.364109 -386.316386)
			(xy 45.387705 -386.362696) (xy 45.403766 -386.412126) (xy 45.411896 -386.463461) (xy 45.412406 -386.489448)
			(xy 45.411867 -386.516777) (xy 45.402873 -386.570691) (xy 45.385136 -386.622392) (xy 45.35914 -386.670473)
			(xy 45.34281 -386.692394) (xy 45.337222 -386.69976) (xy 45.331634 -386.716524) (xy 45.33519 -386.800598)
			(xy 45.342048 -386.816854) (xy 45.348144 -386.823712) (xy 45.36453 -386.842108) (xy 45.39218 -386.882882)
			(xy 45.413481 -386.927304) (xy 45.427961 -386.974393) (xy 45.435302 -387.023108) (xy 45.435774 -387.04774)
			(xy 45.435264 -387.073727) (xy 45.427134 -387.125062) (xy 45.411073 -387.174492) (xy 45.387477 -387.220802)
			(xy 45.356927 -387.26285) (xy 45.320176 -387.299601) (xy 45.278128 -387.330151) (xy 45.231818 -387.353747)
			(xy 45.182388 -387.369808) (xy 45.131053 -387.377938) (xy 45.079079 -387.377938) (xy 45.027744 -387.369808)
			(xy 44.978314 -387.353747) (xy 44.932004 -387.330151) (xy 44.889956 -387.299601) (xy 44.853205 -387.26285)
			(xy 44.822655 -387.220802) (xy 44.799059 -387.174492) (xy 44.782998 -387.125062) (xy 44.774868 -387.073727)
			(xy 44.774358 -387.04774) (xy 44.774951 -387.020413) (xy 44.78393 -386.966502) (xy 44.801651 -386.914801)
			(xy 44.827632 -386.866718) (xy 44.843954 -386.844794) (xy 44.849542 -386.837428) (xy 44.85513 -386.820664)
			(xy 44.851574 -386.73659) (xy 44.844716 -386.720334) (xy 44.83862 -386.713476) (xy 44.822286 -386.695035)
			(xy 44.794626 -386.654275) (xy 44.773315 -386.609864) (xy 44.758822 -386.562785) (xy 44.751468 -386.514077)
			(xy 44.75099 -386.489448) (xy 42.222416 -386.489448) (xy 42.222416 -386.50375) (xy 42.21466 -386.557695)
			(xy 42.199307 -386.609987) (xy 42.176667 -386.659562) (xy 42.147203 -386.705411) (xy 42.111514 -386.7466)
			(xy 42.070327 -386.782291) (xy 42.02448 -386.811758) (xy 41.974906 -386.8344) (xy 41.922615 -386.849756)
			(xy 41.86867 -386.857515) (xy 41.84142 -386.858002) (xy 41.818914 -386.857649) (xy 41.774219 -386.852303)
			(xy 41.752266 -386.847334) (xy 41.74078 -386.845186) (xy 41.718016 -386.850351) (xy 41.708578 -386.85724)
			(xy 41.683432 -386.87756) (xy 41.674637 -386.885296) (xy 41.66472 -386.90649) (xy 41.664382 -386.9182)
			(xy 41.664636 -386.926074) (xy 41.664636 -387.789674) (xy 41.664184 -387.815582) (xy 41.657147 -387.86692)
			(xy 41.64325 -387.916839) (xy 41.633394 -387.940804) (xy 41.627552 -387.954012) (xy 41.631362 -387.981952)
			(xy 41.706038 -388.0739) (xy 41.732454 -388.083552) (xy 41.746424 -388.080758) (xy 41.764902 -388.077321)
			(xy 41.802307 -388.073627) (xy 41.8211 -388.073392) (xy 41.848351 -388.073878) (xy 41.902299 -388.081634)
			(xy 41.954594 -388.096989) (xy 42.004171 -388.119631) (xy 42.050021 -388.149097) (xy 42.091212 -388.184788)
			(xy 42.126903 -388.225979) (xy 42.156369 -388.271829) (xy 42.168173 -388.297674) (xy 43.808902 -388.297674)
			(xy 43.812973 -388.242052) (xy 43.825099 -388.187615) (xy 43.845022 -388.135524) (xy 43.872318 -388.086889)
			(xy 43.906404 -388.042746) (xy 43.946553 -388.004037) (xy 43.991911 -387.971586) (xy 44.041511 -387.946085)
			(xy 44.094295 -387.928078) (xy 44.149138 -387.917948) (xy 44.204872 -387.915911) (xy 44.260309 -387.922011)
			(xy 44.314266 -387.936117) (xy 44.365595 -387.957929) (xy 44.413201 -387.986983) (xy 44.456069 -388.022658)
			(xy 44.493286 -388.064195) (xy 44.524059 -388.110708) (xy 44.547731 -388.161205) (xy 44.563799 -388.214612)
			(xy 44.571919 -388.269788) (xy 44.572428 -388.297674) (xy 44.571981 -388.322137) (xy 44.774868 -388.322137)
			(xy 44.774868 -388.270163) (xy 44.782998 -388.218828) (xy 44.799059 -388.169398) (xy 44.822655 -388.123088)
			(xy 44.853205 -388.08104) (xy 44.889956 -388.044289) (xy 44.932004 -388.013739) (xy 44.978314 -387.990143)
			(xy 45.027744 -387.974082) (xy 45.079079 -387.965952) (xy 45.131053 -387.965952) (xy 45.182388 -387.974082)
			(xy 45.231818 -387.990143) (xy 45.278128 -388.013739) (xy 45.320176 -388.044289) (xy 45.356927 -388.08104)
			(xy 45.387477 -388.123088) (xy 45.411073 -388.169398) (xy 45.427134 -388.218828) (xy 45.435264 -388.270163)
			(xy 45.435774 -388.29615) (xy 45.435264 -388.322137) (xy 45.427134 -388.373472) (xy 45.411073 -388.422902)
			(xy 45.387477 -388.469212) (xy 45.356927 -388.51126) (xy 45.320176 -388.548011) (xy 45.278128 -388.578561)
			(xy 45.231818 -388.602157) (xy 45.182388 -388.618218) (xy 45.131053 -388.626348) (xy 45.079079 -388.626348)
			(xy 45.027744 -388.618218) (xy 44.978314 -388.602157) (xy 44.932004 -388.578561) (xy 44.889956 -388.548011)
			(xy 44.853205 -388.51126) (xy 44.822655 -388.469212) (xy 44.799059 -388.422902) (xy 44.782998 -388.373472)
			(xy 44.774868 -388.322137) (xy 44.571981 -388.322137) (xy 44.571919 -388.32556) (xy 44.563799 -388.380736)
			(xy 44.547731 -388.434143) (xy 44.524059 -388.48464) (xy 44.493286 -388.531153) (xy 44.456069 -388.57269)
			(xy 44.413201 -388.608365) (xy 44.365595 -388.637419) (xy 44.314266 -388.659231) (xy 44.260309 -388.673337)
			(xy 44.204872 -388.679437) (xy 44.149138 -388.6774) (xy 44.094295 -388.66727) (xy 44.041511 -388.649263)
			(xy 43.991911 -388.623762) (xy 43.946553 -388.591311) (xy 43.906404 -388.552602) (xy 43.872318 -388.508459)
			(xy 43.845022 -388.459824) (xy 43.825099 -388.407733) (xy 43.812973 -388.353296) (xy 43.808902 -388.297674)
			(xy 42.168173 -388.297674) (xy 42.179011 -388.321406) (xy 42.194366 -388.373701) (xy 42.202122 -388.427649)
			(xy 42.202122 -388.482151) (xy 42.194366 -388.536099) (xy 42.179011 -388.588394) (xy 42.156369 -388.637971)
			(xy 42.126903 -388.683821) (xy 42.091212 -388.725012) (xy 42.050021 -388.760703) (xy 42.004171 -388.790169)
			(xy 41.954594 -388.812811) (xy 41.902299 -388.828166) (xy 41.848351 -388.835922) (xy 41.793849 -388.835922)
			(xy 41.739901 -388.828166) (xy 41.687606 -388.812811) (xy 41.638029 -388.790169) (xy 41.592179 -388.760703)
			(xy 41.550988 -388.725012) (xy 41.515297 -388.683821) (xy 41.485831 -388.637971) (xy 41.463189 -388.588394)
			(xy 41.447834 -388.536099) (xy 41.440078 -388.482151) (xy 41.439592 -388.4549) (xy 41.440014 -388.428989)
			(xy 41.447044 -388.377647) (xy 41.46096 -388.327729) (xy 41.470834 -388.30377) (xy 41.476422 -388.290816)
			(xy 41.472612 -388.262876) (xy 41.39819 -388.170674) (xy 41.37152 -388.161022) (xy 41.35755 -388.163816)
			(xy 41.339081 -388.167336) (xy 41.301674 -388.171149) (xy 41.282874 -388.171436) (xy 41.255603 -388.171)
			(xy 41.201616 -388.163234) (xy 41.149284 -388.147864) (xy 41.099672 -388.125203) (xy 41.05379 -388.095712)
			(xy 41.012572 -388.059991) (xy 40.976857 -388.018768) (xy 40.947372 -387.972882) (xy 40.924718 -387.923267)
			(xy 40.909355 -387.870933) (xy 40.901597 -387.816945) (xy 40.901112 -387.789674) (xy 40.596708 -387.789674)
			(xy 40.560675 -387.811665) (xy 40.509346 -387.833477) (xy 40.455389 -387.847583) (xy 40.399952 -387.853683)
			(xy 40.344218 -387.851646) (xy 40.289375 -387.841516) (xy 40.236591 -387.823509) (xy 40.186991 -387.798008)
			(xy 40.141633 -387.765557) (xy 40.101484 -387.726848) (xy 40.067398 -387.682705) (xy 40.040102 -387.63407)
			(xy 40.020179 -387.581979) (xy 40.008053 -387.527542) (xy 40.003982 -387.47192) (xy 39.50208 -387.47192)
			(xy 39.50208 -390.626092) (xy 44.762674 -390.626092) (xy 44.763091 -390.602859) (xy 44.769584 -390.556849)
			(xy 44.782457 -390.512202) (xy 44.801454 -390.469797) (xy 44.826202 -390.43047) (xy 44.840906 -390.412478)
			(xy 44.847002 -390.405366) (xy 44.853098 -390.388856) (xy 44.853098 -390.304528) (xy 44.847002 -390.288018)
			(xy 44.840906 -390.280906) (xy 44.826187 -390.262925) (xy 44.801442 -390.223593) (xy 44.782444 -390.181186)
			(xy 44.769568 -390.136537) (xy 44.763067 -390.090526) (xy 44.762674 -390.067292) (xy 44.763184 -390.041305)
			(xy 44.771314 -389.98997) (xy 44.787375 -389.94054) (xy 44.810971 -389.89423) (xy 44.841521 -389.852182)
			(xy 44.878272 -389.815431) (xy 44.92032 -389.784881) (xy 44.96663 -389.761285) (xy 45.01606 -389.745224)
			(xy 45.067395 -389.737094) (xy 45.119369 -389.737094) (xy 45.170704 -389.745224) (xy 45.220134 -389.761285)
			(xy 45.266444 -389.784881) (xy 45.308492 -389.815431) (xy 45.345243 -389.852182) (xy 45.375793 -389.89423)
			(xy 45.399389 -389.94054) (xy 45.41545 -389.98997) (xy 45.42358 -390.041305) (xy 45.42409 -390.067292)
			(xy 45.42373 -390.090527) (xy 45.417224 -390.13654) (xy 45.410453 -390.160002) (xy 47.085262 -390.160002)
			(xy 47.089222 -390.110948) (xy 47.100999 -390.063164) (xy 47.12029 -390.017888) (xy 47.146593 -389.976292)
			(xy 47.179228 -389.939455) (xy 47.217349 -389.90833) (xy 47.25997 -389.883723) (xy 47.305986 -389.866271)
			(xy 47.354205 -389.856427) (xy 47.40338 -389.854446) (xy 47.452235 -389.860378) (xy 47.499506 -389.87407)
			(xy 47.543968 -389.895168) (xy 47.584471 -389.923124) (xy 47.619964 -389.957216) (xy 47.649529 -389.99656)
			(xy 47.6724 -390.040137) (xy 47.687984 -390.086818) (xy 47.695879 -390.135395) (xy 47.696374 -390.160002)
			(xy 48.285412 -390.160002) (xy 48.289372 -390.110948) (xy 48.301149 -390.063164) (xy 48.32044 -390.017888)
			(xy 48.346743 -389.976292) (xy 48.379378 -389.939455) (xy 48.417499 -389.90833) (xy 48.46012 -389.883723)
			(xy 48.506136 -389.866271) (xy 48.554355 -389.856427) (xy 48.60353 -389.854446) (xy 48.652385 -389.860378)
			(xy 48.699656 -389.87407) (xy 48.744118 -389.895168) (xy 48.784621 -389.923124) (xy 48.820114 -389.957216)
			(xy 48.849679 -389.99656) (xy 48.87255 -390.040137) (xy 48.888134 -390.086818) (xy 48.896029 -390.135395)
			(xy 48.896524 -390.160002) (xy 49.485562 -390.160002) (xy 49.489522 -390.110948) (xy 49.501299 -390.063164)
			(xy 49.52059 -390.017888) (xy 49.546893 -389.976292) (xy 49.579528 -389.939455) (xy 49.617649 -389.90833)
			(xy 49.66027 -389.883723) (xy 49.706286 -389.866271) (xy 49.754505 -389.856427) (xy 49.80368 -389.854446)
			(xy 49.852535 -389.860378) (xy 49.899806 -389.87407) (xy 49.944268 -389.895168) (xy 49.984771 -389.923124)
			(xy 50.020264 -389.957216) (xy 50.049829 -389.99656) (xy 50.0727 -390.040137) (xy 50.088284 -390.086818)
			(xy 50.096179 -390.135395) (xy 50.096674 -390.160002) (xy 50.685458 -390.160002) (xy 50.689418 -390.110948)
			(xy 50.701195 -390.063164) (xy 50.720486 -390.017888) (xy 50.746789 -389.976292) (xy 50.779424 -389.939455)
			(xy 50.817545 -389.90833) (xy 50.860166 -389.883723) (xy 50.906182 -389.866271) (xy 50.954401 -389.856427)
			(xy 51.003576 -389.854446) (xy 51.052431 -389.860378) (xy 51.099702 -389.87407) (xy 51.144164 -389.895168)
			(xy 51.184667 -389.923124) (xy 51.22016 -389.957216) (xy 51.249725 -389.99656) (xy 51.272596 -390.040137)
			(xy 51.28818 -390.086818) (xy 51.296075 -390.135395) (xy 51.29657 -390.160002) (xy 51.885608 -390.160002)
			(xy 51.889568 -390.110948) (xy 51.901345 -390.063164) (xy 51.920636 -390.017888) (xy 51.946939 -389.976292)
			(xy 51.979574 -389.939455) (xy 52.017695 -389.90833) (xy 52.060316 -389.883723) (xy 52.106332 -389.866271)
			(xy 52.154551 -389.856427) (xy 52.203726 -389.854446) (xy 52.252581 -389.860378) (xy 52.299852 -389.87407)
			(xy 52.344314 -389.895168) (xy 52.384817 -389.923124) (xy 52.42031 -389.957216) (xy 52.449875 -389.99656)
			(xy 52.472746 -390.040137) (xy 52.48833 -390.086818) (xy 52.496225 -390.135395) (xy 52.49672 -390.160002)
			(xy 53.085504 -390.160002) (xy 53.089464 -390.110948) (xy 53.101241 -390.063164) (xy 53.120532 -390.017888)
			(xy 53.146835 -389.976292) (xy 53.17947 -389.939455) (xy 53.217591 -389.90833) (xy 53.260212 -389.883723)
			(xy 53.306228 -389.866271) (xy 53.354447 -389.856427) (xy 53.403622 -389.854446) (xy 53.452477 -389.860378)
			(xy 53.499748 -389.87407) (xy 53.54421 -389.895168) (xy 53.584713 -389.923124) (xy 53.620206 -389.957216)
			(xy 53.649771 -389.99656) (xy 53.672642 -390.040137) (xy 53.688226 -390.086818) (xy 53.696121 -390.135395)
			(xy 53.696616 -390.160002) (xy 54.2854 -390.160002) (xy 54.28936 -390.110948) (xy 54.301137 -390.063164)
			(xy 54.320428 -390.017888) (xy 54.346731 -389.976292) (xy 54.379366 -389.939455) (xy 54.417487 -389.90833)
			(xy 54.460108 -389.883723) (xy 54.506124 -389.866271) (xy 54.554343 -389.856427) (xy 54.603518 -389.854446)
			(xy 54.652373 -389.860378) (xy 54.699644 -389.87407) (xy 54.744106 -389.895168) (xy 54.784609 -389.923124)
			(xy 54.820102 -389.957216) (xy 54.849667 -389.99656) (xy 54.872538 -390.040137) (xy 54.888122 -390.086818)
			(xy 54.896017 -390.135395) (xy 54.896512 -390.160002) (xy 55.48555 -390.160002) (xy 55.48951 -390.110948)
			(xy 55.501287 -390.063164) (xy 55.520578 -390.017888) (xy 55.546881 -389.976292) (xy 55.579516 -389.939455)
			(xy 55.617637 -389.90833) (xy 55.660258 -389.883723) (xy 55.706274 -389.866271) (xy 55.754493 -389.856427)
			(xy 55.803668 -389.854446) (xy 55.852523 -389.860378) (xy 55.899794 -389.87407) (xy 55.944256 -389.895168)
			(xy 55.984759 -389.923124) (xy 56.020252 -389.957216) (xy 56.049817 -389.99656) (xy 56.072688 -390.040137)
			(xy 56.088272 -390.086818) (xy 56.096167 -390.135395) (xy 56.096662 -390.160002) (xy 56.685446 -390.160002)
			(xy 56.689406 -390.110948) (xy 56.701183 -390.063164) (xy 56.720474 -390.017888) (xy 56.746777 -389.976292)
			(xy 56.779412 -389.939455) (xy 56.817533 -389.90833) (xy 56.860154 -389.883723) (xy 56.90617 -389.866271)
			(xy 56.954389 -389.856427) (xy 57.003564 -389.854446) (xy 57.052419 -389.860378) (xy 57.09969 -389.87407)
			(xy 57.144152 -389.895168) (xy 57.184655 -389.923124) (xy 57.220148 -389.957216) (xy 57.249713 -389.99656)
			(xy 57.272584 -390.040137) (xy 57.288168 -390.086818) (xy 57.296063 -390.135395) (xy 57.296558 -390.160002)
			(xy 57.885596 -390.160002) (xy 57.889556 -390.110948) (xy 57.901333 -390.063164) (xy 57.920624 -390.017888)
			(xy 57.946927 -389.976292) (xy 57.979562 -389.939455) (xy 58.017683 -389.90833) (xy 58.060304 -389.883723)
			(xy 58.10632 -389.866271) (xy 58.154539 -389.856427) (xy 58.203714 -389.854446) (xy 58.252569 -389.860378)
			(xy 58.29984 -389.87407) (xy 58.344302 -389.895168) (xy 58.384805 -389.923124) (xy 58.420298 -389.957216)
			(xy 58.449863 -389.99656) (xy 58.472734 -390.040137) (xy 58.488318 -390.086818) (xy 58.496213 -390.135395)
			(xy 58.496708 -390.160002) (xy 59.085492 -390.160002) (xy 59.089452 -390.110948) (xy 59.101229 -390.063164)
			(xy 59.12052 -390.017888) (xy 59.146823 -389.976292) (xy 59.179458 -389.939455) (xy 59.217579 -389.90833)
			(xy 59.2602 -389.883723) (xy 59.306216 -389.866271) (xy 59.354435 -389.856427) (xy 59.40361 -389.854446)
			(xy 59.452465 -389.860378) (xy 59.499736 -389.87407) (xy 59.544198 -389.895168) (xy 59.584701 -389.923124)
			(xy 59.620194 -389.957216) (xy 59.649759 -389.99656) (xy 59.67263 -390.040137) (xy 59.688214 -390.086818)
			(xy 59.696109 -390.135395) (xy 59.696604 -390.160002) (xy 60.285388 -390.160002) (xy 60.289348 -390.110948)
			(xy 60.301125 -390.063164) (xy 60.320416 -390.017888) (xy 60.346719 -389.976292) (xy 60.379354 -389.939455)
			(xy 60.417475 -389.90833) (xy 60.460096 -389.883723) (xy 60.506112 -389.866271) (xy 60.554331 -389.856427)
			(xy 60.603506 -389.854446) (xy 60.652361 -389.860378) (xy 60.699632 -389.87407) (xy 60.744094 -389.895168)
			(xy 60.784597 -389.923124) (xy 60.82009 -389.957216) (xy 60.849655 -389.99656) (xy 60.872526 -390.040137)
			(xy 60.88811 -390.086818) (xy 60.896005 -390.135395) (xy 60.8965 -390.160002) (xy 61.485538 -390.160002)
			(xy 61.489498 -390.110948) (xy 61.501275 -390.063164) (xy 61.520566 -390.017888) (xy 61.546869 -389.976292)
			(xy 61.579504 -389.939455) (xy 61.617625 -389.90833) (xy 61.660246 -389.883723) (xy 61.706262 -389.866271)
			(xy 61.754481 -389.856427) (xy 61.803656 -389.854446) (xy 61.852511 -389.860378) (xy 61.899782 -389.87407)
			(xy 61.944244 -389.895168) (xy 61.984747 -389.923124) (xy 62.02024 -389.957216) (xy 62.049805 -389.99656)
			(xy 62.072676 -390.040137) (xy 62.08826 -390.086818) (xy 62.096155 -390.135395) (xy 62.09665 -390.160002)
			(xy 62.685434 -390.160002) (xy 62.689394 -390.110948) (xy 62.701171 -390.063164) (xy 62.720462 -390.017888)
			(xy 62.746765 -389.976292) (xy 62.7794 -389.939455) (xy 62.817521 -389.90833) (xy 62.860142 -389.883723)
			(xy 62.906158 -389.866271) (xy 62.954377 -389.856427) (xy 63.003552 -389.854446) (xy 63.052407 -389.860378)
			(xy 63.099678 -389.87407) (xy 63.14414 -389.895168) (xy 63.184643 -389.923124) (xy 63.220136 -389.957216)
			(xy 63.249701 -389.99656) (xy 63.272572 -390.040137) (xy 63.288156 -390.086818) (xy 63.296051 -390.135395)
			(xy 63.296546 -390.160002) (xy 63.885584 -390.160002) (xy 63.889544 -390.110948) (xy 63.901321 -390.063164)
			(xy 63.920612 -390.017888) (xy 63.946915 -389.976292) (xy 63.97955 -389.939455) (xy 64.017671 -389.90833)
			(xy 64.060292 -389.883723) (xy 64.106308 -389.866271) (xy 64.154527 -389.856427) (xy 64.203702 -389.854446)
			(xy 64.252557 -389.860378) (xy 64.299828 -389.87407) (xy 64.34429 -389.895168) (xy 64.384793 -389.923124)
			(xy 64.420286 -389.957216) (xy 64.449851 -389.99656) (xy 64.472722 -390.040137) (xy 64.488306 -390.086818)
			(xy 64.496201 -390.135395) (xy 64.496696 -390.160002) (xy 65.08548 -390.160002) (xy 65.08944 -390.110948)
			(xy 65.101217 -390.063164) (xy 65.120508 -390.017888) (xy 65.146811 -389.976292) (xy 65.179446 -389.939455)
			(xy 65.217567 -389.90833) (xy 65.260188 -389.883723) (xy 65.306204 -389.866271) (xy 65.354423 -389.856427)
			(xy 65.403598 -389.854446) (xy 65.452453 -389.860378) (xy 65.499724 -389.87407) (xy 65.544186 -389.895168)
			(xy 65.584689 -389.923124) (xy 65.620182 -389.957216) (xy 65.649747 -389.99656) (xy 65.672618 -390.040137)
			(xy 65.688202 -390.086818) (xy 65.696097 -390.135395) (xy 65.696592 -390.160002) (xy 65.696097 -390.184609)
			(xy 65.688202 -390.233186) (xy 65.672618 -390.279867) (xy 65.649747 -390.323444) (xy 65.620182 -390.362788)
			(xy 65.584689 -390.39688) (xy 65.544186 -390.424836) (xy 65.499724 -390.445934) (xy 65.452453 -390.459626)
			(xy 65.403598 -390.465558) (xy 65.354423 -390.463577) (xy 65.306204 -390.453733) (xy 65.260188 -390.436281)
			(xy 65.217567 -390.411674) (xy 65.179446 -390.380549) (xy 65.146811 -390.343712) (xy 65.120508 -390.302116)
			(xy 65.101217 -390.25684) (xy 65.08944 -390.209056) (xy 65.08548 -390.160002) (xy 64.496696 -390.160002)
			(xy 64.496201 -390.184609) (xy 64.488306 -390.233186) (xy 64.472722 -390.279867) (xy 64.449851 -390.323444)
			(xy 64.420286 -390.362788) (xy 64.384793 -390.39688) (xy 64.34429 -390.424836) (xy 64.299828 -390.445934)
			(xy 64.252557 -390.459626) (xy 64.203702 -390.465558) (xy 64.154527 -390.463577) (xy 64.106308 -390.453733)
			(xy 64.060292 -390.436281) (xy 64.017671 -390.411674) (xy 63.97955 -390.380549) (xy 63.946915 -390.343712)
			(xy 63.920612 -390.302116) (xy 63.901321 -390.25684) (xy 63.889544 -390.209056) (xy 63.885584 -390.160002)
			(xy 63.296546 -390.160002) (xy 63.296051 -390.184609) (xy 63.288156 -390.233186) (xy 63.272572 -390.279867)
			(xy 63.249701 -390.323444) (xy 63.220136 -390.362788) (xy 63.184643 -390.39688) (xy 63.14414 -390.424836)
			(xy 63.099678 -390.445934) (xy 63.052407 -390.459626) (xy 63.003552 -390.465558) (xy 62.954377 -390.463577)
			(xy 62.906158 -390.453733) (xy 62.860142 -390.436281) (xy 62.817521 -390.411674) (xy 62.7794 -390.380549)
			(xy 62.746765 -390.343712) (xy 62.720462 -390.302116) (xy 62.701171 -390.25684) (xy 62.689394 -390.209056)
			(xy 62.685434 -390.160002) (xy 62.09665 -390.160002) (xy 62.096155 -390.184609) (xy 62.08826 -390.233186)
			(xy 62.072676 -390.279867) (xy 62.049805 -390.323444) (xy 62.02024 -390.362788) (xy 61.984747 -390.39688)
			(xy 61.944244 -390.424836) (xy 61.899782 -390.445934) (xy 61.852511 -390.459626) (xy 61.803656 -390.465558)
			(xy 61.754481 -390.463577) (xy 61.706262 -390.453733) (xy 61.660246 -390.436281) (xy 61.617625 -390.411674)
			(xy 61.579504 -390.380549) (xy 61.546869 -390.343712) (xy 61.520566 -390.302116) (xy 61.501275 -390.25684)
			(xy 61.489498 -390.209056) (xy 61.485538 -390.160002) (xy 60.8965 -390.160002) (xy 60.896005 -390.184609)
			(xy 60.88811 -390.233186) (xy 60.872526 -390.279867) (xy 60.849655 -390.323444) (xy 60.82009 -390.362788)
			(xy 60.784597 -390.39688) (xy 60.744094 -390.424836) (xy 60.699632 -390.445934) (xy 60.652361 -390.459626)
			(xy 60.603506 -390.465558) (xy 60.554331 -390.463577) (xy 60.506112 -390.453733) (xy 60.460096 -390.436281)
			(xy 60.417475 -390.411674) (xy 60.379354 -390.380549) (xy 60.346719 -390.343712) (xy 60.320416 -390.302116)
			(xy 60.301125 -390.25684) (xy 60.289348 -390.209056) (xy 60.285388 -390.160002) (xy 59.696604 -390.160002)
			(xy 59.696109 -390.184609) (xy 59.688214 -390.233186) (xy 59.67263 -390.279867) (xy 59.649759 -390.323444)
			(xy 59.620194 -390.362788) (xy 59.584701 -390.39688) (xy 59.544198 -390.424836) (xy 59.499736 -390.445934)
			(xy 59.452465 -390.459626) (xy 59.40361 -390.465558) (xy 59.354435 -390.463577) (xy 59.306216 -390.453733)
			(xy 59.2602 -390.436281) (xy 59.217579 -390.411674) (xy 59.179458 -390.380549) (xy 59.146823 -390.343712)
			(xy 59.12052 -390.302116) (xy 59.101229 -390.25684) (xy 59.089452 -390.209056) (xy 59.085492 -390.160002)
			(xy 58.496708 -390.160002) (xy 58.496213 -390.184609) (xy 58.488318 -390.233186) (xy 58.472734 -390.279867)
			(xy 58.449863 -390.323444) (xy 58.420298 -390.362788) (xy 58.384805 -390.39688) (xy 58.344302 -390.424836)
			(xy 58.29984 -390.445934) (xy 58.252569 -390.459626) (xy 58.203714 -390.465558) (xy 58.154539 -390.463577)
			(xy 58.10632 -390.453733) (xy 58.060304 -390.436281) (xy 58.017683 -390.411674) (xy 57.979562 -390.380549)
			(xy 57.946927 -390.343712) (xy 57.920624 -390.302116) (xy 57.901333 -390.25684) (xy 57.889556 -390.209056)
			(xy 57.885596 -390.160002) (xy 57.296558 -390.160002) (xy 57.296063 -390.184609) (xy 57.288168 -390.233186)
			(xy 57.272584 -390.279867) (xy 57.249713 -390.323444) (xy 57.220148 -390.362788) (xy 57.184655 -390.39688)
			(xy 57.144152 -390.424836) (xy 57.09969 -390.445934) (xy 57.052419 -390.459626) (xy 57.003564 -390.465558)
			(xy 56.954389 -390.463577) (xy 56.90617 -390.453733) (xy 56.860154 -390.436281) (xy 56.817533 -390.411674)
			(xy 56.779412 -390.380549) (xy 56.746777 -390.343712) (xy 56.720474 -390.302116) (xy 56.701183 -390.25684)
			(xy 56.689406 -390.209056) (xy 56.685446 -390.160002) (xy 56.096662 -390.160002) (xy 56.096167 -390.184609)
			(xy 56.088272 -390.233186) (xy 56.072688 -390.279867) (xy 56.049817 -390.323444) (xy 56.020252 -390.362788)
			(xy 55.984759 -390.39688) (xy 55.944256 -390.424836) (xy 55.899794 -390.445934) (xy 55.852523 -390.459626)
			(xy 55.803668 -390.465558) (xy 55.754493 -390.463577) (xy 55.706274 -390.453733) (xy 55.660258 -390.436281)
			(xy 55.617637 -390.411674) (xy 55.579516 -390.380549) (xy 55.546881 -390.343712) (xy 55.520578 -390.302116)
			(xy 55.501287 -390.25684) (xy 55.48951 -390.209056) (xy 55.48555 -390.160002) (xy 54.896512 -390.160002)
			(xy 54.896017 -390.184609) (xy 54.888122 -390.233186) (xy 54.872538 -390.279867) (xy 54.849667 -390.323444)
			(xy 54.820102 -390.362788) (xy 54.784609 -390.39688) (xy 54.744106 -390.424836) (xy 54.699644 -390.445934)
			(xy 54.652373 -390.459626) (xy 54.603518 -390.465558) (xy 54.554343 -390.463577) (xy 54.506124 -390.453733)
			(xy 54.460108 -390.436281) (xy 54.417487 -390.411674) (xy 54.379366 -390.380549) (xy 54.346731 -390.343712)
			(xy 54.320428 -390.302116) (xy 54.301137 -390.25684) (xy 54.28936 -390.209056) (xy 54.2854 -390.160002)
			(xy 53.696616 -390.160002) (xy 53.696121 -390.184609) (xy 53.688226 -390.233186) (xy 53.672642 -390.279867)
			(xy 53.649771 -390.323444) (xy 53.620206 -390.362788) (xy 53.584713 -390.39688) (xy 53.54421 -390.424836)
			(xy 53.499748 -390.445934) (xy 53.452477 -390.459626) (xy 53.403622 -390.465558) (xy 53.354447 -390.463577)
			(xy 53.306228 -390.453733) (xy 53.260212 -390.436281) (xy 53.217591 -390.411674) (xy 53.17947 -390.380549)
			(xy 53.146835 -390.343712) (xy 53.120532 -390.302116) (xy 53.101241 -390.25684) (xy 53.089464 -390.209056)
			(xy 53.085504 -390.160002) (xy 52.49672 -390.160002) (xy 52.496225 -390.184609) (xy 52.48833 -390.233186)
			(xy 52.472746 -390.279867) (xy 52.449875 -390.323444) (xy 52.42031 -390.362788) (xy 52.384817 -390.39688)
			(xy 52.344314 -390.424836) (xy 52.299852 -390.445934) (xy 52.252581 -390.459626) (xy 52.203726 -390.465558)
			(xy 52.154551 -390.463577) (xy 52.106332 -390.453733) (xy 52.060316 -390.436281) (xy 52.017695 -390.411674)
			(xy 51.979574 -390.380549) (xy 51.946939 -390.343712) (xy 51.920636 -390.302116) (xy 51.901345 -390.25684)
			(xy 51.889568 -390.209056) (xy 51.885608 -390.160002) (xy 51.29657 -390.160002) (xy 51.296075 -390.184609)
			(xy 51.28818 -390.233186) (xy 51.272596 -390.279867) (xy 51.249725 -390.323444) (xy 51.22016 -390.362788)
			(xy 51.184667 -390.39688) (xy 51.144164 -390.424836) (xy 51.099702 -390.445934) (xy 51.052431 -390.459626)
			(xy 51.003576 -390.465558) (xy 50.954401 -390.463577) (xy 50.906182 -390.453733) (xy 50.860166 -390.436281)
			(xy 50.817545 -390.411674) (xy 50.779424 -390.380549) (xy 50.746789 -390.343712) (xy 50.720486 -390.302116)
			(xy 50.701195 -390.25684) (xy 50.689418 -390.209056) (xy 50.685458 -390.160002) (xy 50.096674 -390.160002)
			(xy 50.096179 -390.184609) (xy 50.088284 -390.233186) (xy 50.0727 -390.279867) (xy 50.049829 -390.323444)
			(xy 50.020264 -390.362788) (xy 49.984771 -390.39688) (xy 49.944268 -390.424836) (xy 49.899806 -390.445934)
			(xy 49.852535 -390.459626) (xy 49.80368 -390.465558) (xy 49.754505 -390.463577) (xy 49.706286 -390.453733)
			(xy 49.66027 -390.436281) (xy 49.617649 -390.411674) (xy 49.579528 -390.380549) (xy 49.546893 -390.343712)
			(xy 49.52059 -390.302116) (xy 49.501299 -390.25684) (xy 49.489522 -390.209056) (xy 49.485562 -390.160002)
			(xy 48.896524 -390.160002) (xy 48.896029 -390.184609) (xy 48.888134 -390.233186) (xy 48.87255 -390.279867)
			(xy 48.849679 -390.323444) (xy 48.820114 -390.362788) (xy 48.784621 -390.39688) (xy 48.744118 -390.424836)
			(xy 48.699656 -390.445934) (xy 48.652385 -390.459626) (xy 48.60353 -390.465558) (xy 48.554355 -390.463577)
			(xy 48.506136 -390.453733) (xy 48.46012 -390.436281) (xy 48.417499 -390.411674) (xy 48.379378 -390.380549)
			(xy 48.346743 -390.343712) (xy 48.32044 -390.302116) (xy 48.301149 -390.25684) (xy 48.289372 -390.209056)
			(xy 48.285412 -390.160002) (xy 47.696374 -390.160002) (xy 47.695879 -390.184609) (xy 47.687984 -390.233186)
			(xy 47.6724 -390.279867) (xy 47.649529 -390.323444) (xy 47.619964 -390.362788) (xy 47.584471 -390.39688)
			(xy 47.543968 -390.424836) (xy 47.499506 -390.445934) (xy 47.452235 -390.459626) (xy 47.40338 -390.465558)
			(xy 47.354205 -390.463577) (xy 47.305986 -390.453733) (xy 47.25997 -390.436281) (xy 47.217349 -390.411674)
			(xy 47.179228 -390.380549) (xy 47.146593 -390.343712) (xy 47.12029 -390.302116) (xy 47.100999 -390.25684)
			(xy 47.089222 -390.209056) (xy 47.085262 -390.160002) (xy 45.410453 -390.160002) (xy 45.404339 -390.181188)
			(xy 45.385329 -390.223592) (xy 45.360569 -390.262917) (xy 45.345858 -390.280906) (xy 45.339762 -390.288018)
			(xy 45.333666 -390.304528) (xy 45.333666 -390.388856) (xy 45.339762 -390.405366) (xy 45.345858 -390.412478)
			(xy 45.360564 -390.430469) (xy 45.385312 -390.469797) (xy 45.404313 -390.512202) (xy 45.417192 -390.556849)
			(xy 45.423696 -390.602858) (xy 45.42409 -390.626092) (xy 45.423677 -390.650185) (xy 45.416698 -390.697862)
			(xy 45.402886 -390.744025) (xy 45.393102 -390.766046) (xy 45.387768 -390.777476) (xy 45.389038 -390.802622)
			(xy 45.445172 -390.896602) (xy 45.466762 -390.909556) (xy 45.479462 -390.910318) (xy 45.504458 -390.912162)
			(xy 45.553503 -390.922494) (xy 45.600427 -390.940108) (xy 45.644155 -390.964601) (xy 45.683688 -390.995411)
			(xy 45.718119 -391.031834) (xy 45.746659 -391.073035) (xy 45.768657 -391.118071) (xy 45.783606 -391.16591)
			(xy 45.791166 -391.215458) (xy 45.791628 -391.240518) (xy 45.791118 -391.266505) (xy 45.782988 -391.31784)
			(xy 45.766927 -391.36727) (xy 45.743331 -391.41358) (xy 45.712781 -391.455628) (xy 45.67603 -391.492379)
			(xy 45.633982 -391.522929) (xy 45.587672 -391.546525) (xy 45.538242 -391.562586) (xy 45.486907 -391.570716)
			(xy 45.434933 -391.570716) (xy 45.383598 -391.562586) (xy 45.334168 -391.546525) (xy 45.287858 -391.522929)
			(xy 45.24581 -391.492379) (xy 45.209059 -391.455628) (xy 45.178509 -391.41358) (xy 45.154913 -391.36727)
			(xy 45.138852 -391.31784) (xy 45.130722 -391.266505) (xy 45.130212 -391.240518) (xy 45.130628 -391.216425)
			(xy 45.137606 -391.168748) (xy 45.151416 -391.122585) (xy 45.1612 -391.100564) (xy 45.166534 -391.089134)
			(xy 45.165264 -391.063988) (xy 45.10913 -390.970008) (xy 45.08754 -390.957054) (xy 45.07484 -390.956292)
			(xy 45.049845 -390.954436) (xy 45.000801 -390.944105) (xy 44.953878 -390.926492) (xy 44.91015 -390.902001)
			(xy 44.870618 -390.871191) (xy 44.836187 -390.83477) (xy 44.807646 -390.79357) (xy 44.785648 -390.748536)
			(xy 44.770698 -390.700698) (xy 44.763136 -390.651152) (xy 44.762674 -390.626092) (xy 39.50208 -390.626092)
			(xy 39.50208 -391.2235) (xy 41.439082 -391.2235) (xy 41.443153 -391.167878) (xy 41.455279 -391.113441)
			(xy 41.475202 -391.06135) (xy 41.502498 -391.012715) (xy 41.536584 -390.968572) (xy 41.576733 -390.929863)
			(xy 41.622091 -390.897412) (xy 41.671691 -390.871911) (xy 41.724475 -390.853904) (xy 41.779318 -390.843774)
			(xy 41.835052 -390.841737) (xy 41.890489 -390.847837) (xy 41.944446 -390.861943) (xy 41.995775 -390.883755)
			(xy 42.043381 -390.912809) (xy 42.086249 -390.948484) (xy 42.123466 -390.990021) (xy 42.154239 -391.036534)
			(xy 42.177911 -391.087031) (xy 42.193979 -391.140438) (xy 42.202099 -391.195614) (xy 42.202608 -391.2235)
			(xy 42.202099 -391.251386) (xy 42.193979 -391.306562) (xy 42.177911 -391.359969) (xy 42.154239 -391.410466)
			(xy 42.123466 -391.456979) (xy 42.086249 -391.498516) (xy 42.043381 -391.534191) (xy 41.995775 -391.563245)
			(xy 41.944446 -391.585057) (xy 41.890489 -391.599163) (xy 41.835052 -391.605263) (xy 41.779318 -391.603226)
			(xy 41.724475 -391.593096) (xy 41.671691 -391.575089) (xy 41.622091 -391.549588) (xy 41.576733 -391.517137)
			(xy 41.536584 -391.478428) (xy 41.502498 -391.434285) (xy 41.475202 -391.38565) (xy 41.455279 -391.333559)
			(xy 41.443153 -391.279122) (xy 41.439082 -391.2235) (xy 39.50208 -391.2235) (xy 39.50208 -391.691114)
			(xy 39.519098 -391.716768) (xy 39.533576 -391.72261) (xy 39.559393 -391.733821) (xy 39.60769 -391.76272)
			(xy 39.65122 -391.798398) (xy 39.689039 -391.84008) (xy 39.720328 -391.886865) (xy 39.744407 -391.937736)
			(xy 39.744806 -391.939051) (xy 42.857395 -391.939051) (xy 42.857395 -391.884549) (xy 42.865152 -391.830602)
			(xy 42.880507 -391.778308) (xy 42.903149 -391.728732) (xy 42.932616 -391.682883) (xy 42.968308 -391.641694)
			(xy 43.009499 -391.606004) (xy 43.055349 -391.576539) (xy 43.104927 -391.5539) (xy 43.157222 -391.538548)
			(xy 43.211169 -391.530794) (xy 43.23842 -391.530332) (xy 43.267535 -391.530871) (xy 43.325091 -391.539704)
			(xy 43.380637 -391.557177) (xy 43.432885 -391.582885) (xy 43.480621 -391.616231) (xy 43.522739 -391.65644)
			(xy 43.540934 -391.679176) (xy 43.550639 -391.690819) (xy 43.575361 -391.708326) (xy 43.604129 -391.717815)
			(xy 43.634415 -391.718452) (xy 43.663558 -391.710183) (xy 43.688995 -391.693733) (xy 43.708492 -391.670548)
			(xy 43.714924 -391.656824) (xy 43.726242 -391.631265) (xy 43.755266 -391.583495) (xy 43.790949 -391.540469)
			(xy 43.832525 -391.503108) (xy 43.879107 -391.472212) (xy 43.929697 -391.44844) (xy 43.983214 -391.432302)
			(xy 44.038512 -391.424143) (xy 44.06646 -391.423652) (xy 44.093712 -391.424193) (xy 44.147661 -391.431944)
			(xy 44.199959 -391.447295) (xy 44.249539 -391.469933) (xy 44.295392 -391.499397) (xy 44.336585 -391.535087)
			(xy 44.372279 -391.576276) (xy 44.401748 -391.622126) (xy 44.424391 -391.671704) (xy 44.439747 -391.723999)
			(xy 44.447505 -391.777948) (xy 44.447505 -391.832452) (xy 44.439747 -391.886401) (xy 44.424391 -391.938696)
			(xy 44.401748 -391.988274) (xy 44.372279 -392.034124) (xy 44.336585 -392.075313) (xy 44.295392 -392.111003)
			(xy 44.249539 -392.140467) (xy 44.199959 -392.163105) (xy 44.147661 -392.178456) (xy 44.093712 -392.186207)
			(xy 44.06646 -392.186668) (xy 44.037344 -392.186143) (xy 43.979788 -392.177307) (xy 43.924241 -392.159831)
			(xy 43.871994 -392.134121) (xy 43.824258 -392.100773) (xy 43.782141 -392.060561) (xy 43.763946 -392.037824)
			(xy 43.754266 -392.026159) (xy 43.729537 -392.008653) (xy 43.700763 -391.999165) (xy 43.670472 -391.998531)
			(xy 43.641326 -392.006804) (xy 43.615886 -392.023259) (xy 43.596388 -392.046449) (xy 43.589956 -392.060176)
			(xy 43.578654 -392.085742) (xy 43.549628 -392.133513) (xy 43.513943 -392.176539) (xy 43.472364 -392.2139)
			(xy 43.42578 -392.244795) (xy 43.375188 -392.268565) (xy 43.321669 -392.284701) (xy 43.266369 -392.292858)
			(xy 43.23842 -392.293348) (xy 43.211169 -392.292806) (xy 43.157222 -392.285052) (xy 43.104927 -392.2697)
			(xy 43.055349 -392.247061) (xy 43.009499 -392.217596) (xy 42.968308 -392.181906) (xy 42.932616 -392.140717)
			(xy 42.903149 -392.094868) (xy 42.880507 -392.045292) (xy 42.865152 -391.992998) (xy 42.857395 -391.939051)
			(xy 39.744806 -391.939051) (xy 39.760756 -391.991592) (xy 39.76902 -392.047265) (xy 39.769019 -392.103547)
			(xy 39.760754 -392.15922) (xy 39.744403 -392.213075) (xy 39.720321 -392.263946) (xy 39.689031 -392.310729)
			(xy 39.651211 -392.352411) (xy 39.60768 -392.388087) (xy 39.559382 -392.416984) (xy 39.533576 -392.428222)
			(xy 39.519098 -392.434064) (xy 39.50208 -392.459718) (xy 39.50208 -392.624818) (xy 39.501653 -392.634886)
			(xy 39.493932 -392.653484) (xy 39.487094 -392.660886) (xy 38.854126 -393.293854) (xy 38.847285 -393.301254)
			(xy 38.839567 -393.319853) (xy 38.83914 -393.329922) (xy 38.83914 -393.530074) (xy 39.144954 -393.530074)
			(xy 39.149025 -393.474452) (xy 39.161151 -393.420015) (xy 39.181074 -393.367924) (xy 39.20837 -393.319289)
			(xy 39.242456 -393.275146) (xy 39.282605 -393.236437) (xy 39.327963 -393.203986) (xy 39.377563 -393.178485)
			(xy 39.430347 -393.160478) (xy 39.48519 -393.150348) (xy 39.540924 -393.148311) (xy 39.596361 -393.154411)
			(xy 39.650318 -393.168517) (xy 39.701647 -393.190329) (xy 39.749253 -393.219383) (xy 39.792121 -393.255058)
			(xy 39.829338 -393.296595) (xy 39.860111 -393.343108) (xy 39.883783 -393.393605) (xy 39.899851 -393.447012)
			(xy 39.907971 -393.502188) (xy 39.90848 -393.530074) (xy 39.907971 -393.55796) (xy 39.899851 -393.613136)
			(xy 39.883783 -393.666543) (xy 39.860111 -393.71704) (xy 39.829338 -393.763553) (xy 39.792121 -393.80509)
			(xy 39.749253 -393.840765) (xy 39.701647 -393.869819) (xy 39.650318 -393.891631) (xy 39.596361 -393.905737)
			(xy 39.540924 -393.911837) (xy 39.48519 -393.9098) (xy 39.430347 -393.89967) (xy 39.377563 -393.881663)
			(xy 39.327963 -393.856162) (xy 39.282605 -393.823711) (xy 39.242456 -393.785002) (xy 39.20837 -393.740859)
			(xy 39.181074 -393.692224) (xy 39.161151 -393.640133) (xy 39.149025 -393.585696) (xy 39.144954 -393.530074)
			(xy 38.83914 -393.530074) (xy 38.83914 -395.160754) (xy 40.296592 -395.160754) (xy 40.297092 -395.133385)
			(xy 40.304902 -395.079207) (xy 40.320383 -395.026705) (xy 40.343217 -394.976957) (xy 40.372934 -394.930989)
			(xy 40.390572 -394.910056) (xy 40.396668 -394.902944) (xy 40.403018 -394.885926) (xy 40.403018 -394.800582)
			(xy 40.396668 -394.783564) (xy 40.390572 -394.776452) (xy 40.372939 -394.755515) (xy 40.343228 -394.709543)
			(xy 40.320391 -394.659797) (xy 40.304898 -394.607297) (xy 40.297068 -394.553123) (xy 40.296592 -394.525754)
			(xy 40.297035 -394.498502) (xy 40.304798 -394.444552) (xy 40.320159 -394.392257) (xy 40.342805 -394.342679)
			(xy 40.372276 -394.296829) (xy 40.407972 -394.25564) (xy 40.449166 -394.219949) (xy 40.49502 -394.190483)
			(xy 40.5446 -394.167843) (xy 40.596897 -394.152488) (xy 40.650848 -394.144732) (xy 40.6781 -394.144246)
			(xy 40.707827 -394.144812) (xy 40.766559 -394.154046) (xy 40.823149 -394.172276) (xy 40.876228 -394.199061)
			(xy 40.924511 -394.233753) (xy 40.94607 -394.254228) (xy 40.953471 -394.260781) (xy 40.971757 -394.268237)
			(xy 40.98163 -394.268706) (xy 41.035224 -394.268706) (xy 41.04386 -394.259562) (xy 41.050412 -394.252241)
			(xy 41.057845 -394.23407) (xy 41.058338 -394.224256) (xy 41.058338 -394.192252) (xy 41.057857 -394.182437)
			(xy 41.050407 -394.164274) (xy 41.04386 -394.156946) (xy 41.023711 -394.135425) (xy 40.989562 -394.087372)
			(xy 40.963211 -394.034638) (xy 40.945284 -393.978478) (xy 40.936209 -393.92023) (xy 40.935656 -393.890754)
			(xy 40.936135 -393.863503) (xy 40.943897 -393.809557) (xy 40.959256 -393.757265) (xy 40.9819 -393.70769)
			(xy 41.011367 -393.661841) (xy 41.047059 -393.620652) (xy 41.088249 -393.584961) (xy 41.134098 -393.555495)
			(xy 41.183674 -393.532852) (xy 41.235967 -393.517495) (xy 41.289913 -393.509734) (xy 41.317164 -393.509246)
			(xy 41.344534 -393.509722) (xy 41.398713 -393.517536) (xy 41.451217 -393.533022) (xy 41.500964 -393.555862)
			(xy 41.54693 -393.585585) (xy 41.567862 -393.603226) (xy 41.574974 -393.609322) (xy 41.591992 -393.615672)
			(xy 41.677336 -393.615672) (xy 41.694354 -393.609322) (xy 41.701466 -393.603226) (xy 41.722399 -393.585585)
			(xy 41.768367 -393.555861) (xy 41.818113 -393.533015) (xy 41.870615 -393.517519) (xy 41.924793 -393.50969)
			(xy 41.979535 -393.50969) (xy 42.033713 -393.517519) (xy 42.086215 -393.533015) (xy 42.135961 -393.555861)
			(xy 42.181929 -393.585585) (xy 42.202862 -393.603226) (xy 42.209974 -393.609322) (xy 42.226992 -393.615672)
			(xy 42.312336 -393.615672) (xy 42.329354 -393.609322) (xy 42.336466 -393.603226) (xy 42.357399 -393.585585)
			(xy 42.403367 -393.555861) (xy 42.453113 -393.533015) (xy 42.505615 -393.517519) (xy 42.559793 -393.50969)
			(xy 42.614535 -393.50969) (xy 42.668713 -393.517519) (xy 42.721215 -393.533015) (xy 42.770961 -393.555861)
			(xy 42.816929 -393.585585) (xy 42.837862 -393.603226) (xy 42.844974 -393.609322) (xy 42.861992 -393.615672)
			(xy 42.947336 -393.615672) (xy 42.964354 -393.609322) (xy 42.971466 -393.603226) (xy 42.992403 -393.585593)
			(xy 43.038374 -393.55588) (xy 43.08812 -393.533042) (xy 43.14062 -393.51755) (xy 43.194795 -393.50972)
			(xy 43.222164 -393.509246) (xy 43.249412 -393.509812) (xy 43.303355 -393.517562) (xy 43.355645 -393.53291)
			(xy 43.405219 -393.555544) (xy 43.451067 -393.585002) (xy 43.492257 -393.620685) (xy 43.527949 -393.661867)
			(xy 43.557417 -393.707709) (xy 43.580061 -393.757278) (xy 43.595421 -393.809565) (xy 43.603183 -393.863506)
			(xy 43.603672 -393.890754) (xy 43.603186 -393.918124) (xy 43.595374 -393.972302) (xy 43.57989 -394.024805)
			(xy 43.557052 -394.074552) (xy 43.527332 -394.12052) (xy 43.509692 -394.141452) (xy 43.503596 -394.148564)
			(xy 43.497246 -394.165582) (xy 43.497246 -394.250926) (xy 43.503596 -394.267944) (xy 43.509692 -394.275056)
			(xy 43.51147 -394.277088) (xy 43.519011 -394.285016) (xy 43.538894 -394.294095) (xy 43.549824 -394.294614)
			(xy 43.62704 -394.294614) (xy 43.637962 -394.294055) (xy 43.657837 -394.284991) (xy 43.665394 -394.277088)
			(xy 43.683618 -394.256649) (xy 43.724871 -394.220643) (xy 43.770851 -394.190907) (xy 43.82061 -394.168053)
			(xy 43.873127 -394.15255) (xy 43.927321 -394.144719) (xy 43.9547 -394.144246) (xy 43.981949 -394.144778)
			(xy 44.035893 -394.152533) (xy 44.088184 -394.167886) (xy 44.137758 -394.190524) (xy 44.183606 -394.219986)
			(xy 44.224795 -394.255672) (xy 44.260487 -394.296857) (xy 44.289954 -394.342701) (xy 44.312598 -394.392273)
			(xy 44.327957 -394.444562) (xy 44.335719 -394.498505) (xy 44.336208 -394.525754) (xy 44.335713 -394.553123)
			(xy 44.327902 -394.607301) (xy 44.312419 -394.659804) (xy 44.289584 -394.709551) (xy 44.259866 -394.755519)
			(xy 44.242228 -394.776452) (xy 44.236132 -394.783564) (xy 44.229782 -394.800582) (xy 44.229782 -394.885926)
			(xy 44.236132 -394.902944) (xy 44.242228 -394.910056) (xy 44.259864 -394.93099) (xy 44.289576 -394.976963)
			(xy 44.312412 -395.02671) (xy 44.327903 -395.07921) (xy 44.335733 -395.133385) (xy 44.336208 -395.160754)
			(xy 44.335702 -395.188006) (xy 44.327951 -395.241955) (xy 44.312601 -395.294252) (xy 44.289964 -395.343832)
			(xy 44.260501 -395.389686) (xy 44.224811 -395.430879) (xy 44.183622 -395.466573) (xy 44.137773 -395.496042)
			(xy 44.088195 -395.518685) (xy 44.0359 -395.534041) (xy 43.981952 -395.541799) (xy 43.9547 -395.542262)
			(xy 43.92732 -395.54182) (xy 43.873124 -395.533978) (xy 43.820606 -395.51847) (xy 43.770844 -395.495614)
			(xy 43.724859 -395.46588) (xy 43.683598 -395.429878) (xy 43.665394 -395.40942) (xy 43.657866 -395.401477)
			(xy 43.637973 -395.392406) (xy 43.62704 -395.391894) (xy 43.549824 -395.391894) (xy 43.538899 -395.39243)
			(xy 43.519024 -395.40151) (xy 43.51147 -395.40942) (xy 43.493267 -395.429878) (xy 43.452009 -395.465882)
			(xy 43.406025 -395.495616) (xy 43.356261 -395.518467) (xy 43.303741 -395.533965) (xy 43.249544 -395.541792)
			(xy 43.222164 -395.542262) (xy 43.194793 -395.541826) (xy 43.140612 -395.534003) (xy 43.088108 -395.518507)
			(xy 43.038362 -395.495658) (xy 42.992396 -395.465927) (xy 42.971466 -395.448282) (xy 42.964354 -395.442186)
			(xy 42.947336 -395.435836) (xy 42.861992 -395.435836) (xy 42.844974 -395.442186) (xy 42.837862 -395.448282)
			(xy 42.816929 -395.465923) (xy 42.770961 -395.495647) (xy 42.721215 -395.518493) (xy 42.668713 -395.533989)
			(xy 42.614535 -395.541818) (xy 42.559793 -395.541818) (xy 42.505615 -395.533989) (xy 42.453113 -395.518493)
			(xy 42.403367 -395.495647) (xy 42.357399 -395.465923) (xy 42.336466 -395.448282) (xy 42.329354 -395.442186)
			(xy 42.312336 -395.435836) (xy 42.226992 -395.435836) (xy 42.209974 -395.442186) (xy 42.202862 -395.448282)
			(xy 42.181929 -395.465923) (xy 42.135961 -395.495647) (xy 42.086215 -395.518493) (xy 42.033713 -395.533989)
			(xy 41.979535 -395.541818) (xy 41.924793 -395.541818) (xy 41.870615 -395.533989) (xy 41.818113 -395.518493)
			(xy 41.768367 -395.495647) (xy 41.722399 -395.465923) (xy 41.701466 -395.448282) (xy 41.694354 -395.442186)
			(xy 41.677336 -395.435836) (xy 41.591992 -395.435836) (xy 41.574974 -395.442186) (xy 41.567862 -395.448282)
			(xy 41.546915 -395.465903) (xy 41.500947 -395.495618) (xy 41.451203 -395.518458) (xy 41.398705 -395.533953)
			(xy 41.344532 -395.541786) (xy 41.317164 -395.542262) (xy 41.289594 -395.541789) (xy 41.235029 -395.533858)
			(xy 41.182174 -395.518151) (xy 41.132132 -395.494996) (xy 41.085947 -395.464876) (xy 41.064942 -395.447012)
			(xy 41.05783 -395.440662) (xy 41.040558 -395.434312) (xy 40.954706 -395.434312) (xy 40.937434 -395.440662)
			(xy 40.930322 -395.447012) (xy 40.909327 -395.464886) (xy 40.863134 -395.494993) (xy 40.813089 -395.518139)
			(xy 40.760234 -395.533842) (xy 40.705669 -395.541777) (xy 40.6781 -395.542262) (xy 40.650845 -395.541845)
			(xy 40.59689 -395.534086) (xy 40.544589 -395.518728) (xy 40.495005 -395.496082) (xy 40.44915 -395.46661)
			(xy 40.407956 -395.430911) (xy 40.372263 -395.389713) (xy 40.342796 -395.343854) (xy 40.320156 -395.294268)
			(xy 40.304804 -395.241965) (xy 40.297052 -395.188009) (xy 40.296592 -395.160754) (xy 38.83914 -395.160754)
			(xy 38.83914 -395.61516) (xy 38.86327 -395.643354) (xy 38.882066 -395.646402) (xy 38.908617 -395.6511)
			(xy 38.960141 -395.666991) (xy 39.008914 -395.689979) (xy 39.053963 -395.719606) (xy 39.094391 -395.755282)
			(xy 39.129393 -395.796296) (xy 39.15827 -395.84183) (xy 39.180447 -395.890977) (xy 39.195482 -395.942757)
			(xy 39.203075 -395.996138) (xy 39.203076 -396.050057) (xy 39.195483 -396.103438) (xy 39.180449 -396.155219)
			(xy 39.158272 -396.204366) (xy 39.129396 -396.2499) (xy 39.094395 -396.290914) (xy 39.053967 -396.326591)
			(xy 39.008918 -396.356219) (xy 38.960146 -396.379207) (xy 38.908622 -396.395099) (xy 38.882066 -396.399766)
			(xy 38.86327 -396.402814) (xy 38.83914 -396.431008) (xy 38.83914 -396.50924) (xy 38.86327 -396.537434)
			(xy 38.882066 -396.540482) (xy 38.908618 -396.54518) (xy 38.960145 -396.561071) (xy 39.008921 -396.58406)
			(xy 39.053973 -396.613688) (xy 39.094403 -396.649366) (xy 39.129407 -396.690382) (xy 39.158286 -396.735918)
			(xy 39.180464 -396.785067) (xy 39.195501 -396.83685) (xy 39.203095 -396.890234) (xy 39.203096 -396.944155)
			(xy 39.195503 -396.997539) (xy 39.180468 -397.049322) (xy 39.158291 -397.098472) (xy 39.129414 -397.144009)
			(xy 39.094411 -397.185026) (xy 39.053982 -397.220705) (xy 39.00893 -397.250334) (xy 38.960156 -397.273325)
			(xy 38.908629 -397.289217) (xy 38.882066 -397.293846) (xy 38.86327 -397.296894) (xy 38.83914 -397.325088)
			(xy 38.83914 -398.810734) (xy 40.757856 -398.810734) (xy 40.75842 -398.775837) (xy 40.767967 -398.706698)
			(xy 40.786887 -398.639517) (xy 40.814823 -398.575557) (xy 40.851249 -398.516023) (xy 40.872918 -398.488662)
			(xy 40.87903 -398.480371) (xy 40.884701 -398.460587) (xy 40.882215 -398.440157) (xy 40.87749 -398.431004)
			(xy 40.861165 -398.401809) (xy 40.835435 -398.340067) (xy 40.818015 -398.275485) (xy 40.809208 -398.209178)
			(xy 40.808656 -398.175734) (xy 40.809123 -398.145038) (xy 40.816528 -398.084093) (xy 40.831222 -398.024484)
			(xy 40.852991 -397.96708) (xy 40.881518 -397.912718) (xy 40.898572 -397.88719) (xy 40.904018 -397.878423)
			(xy 40.908158 -397.858228) (xy 40.90404 -397.838029) (xy 40.898572 -397.829278) (xy 40.881538 -397.803739)
			(xy 40.853027 -397.749372) (xy 40.831263 -397.69197) (xy 40.816561 -397.632367) (xy 40.809137 -397.571428)
			(xy 40.808656 -397.540734) (xy 40.809123 -397.510038) (xy 40.816528 -397.449093) (xy 40.831222 -397.389484)
			(xy 40.852991 -397.33208) (xy 40.881518 -397.277718) (xy 40.898572 -397.25219) (xy 40.904018 -397.243423)
			(xy 40.908158 -397.223228) (xy 40.90404 -397.203029) (xy 40.898572 -397.194278) (xy 40.881538 -397.168739)
			(xy 40.853027 -397.114372) (xy 40.831263 -397.05697) (xy 40.816561 -396.997367) (xy 40.809137 -396.936428)
			(xy 40.808656 -396.905734) (xy 40.809188 -396.875005) (xy 40.816592 -396.813995) (xy 40.831296 -396.754322)
			(xy 40.853085 -396.696857) (xy 40.881642 -396.642437) (xy 40.916551 -396.591855) (xy 40.957301 -396.545851)
			(xy 41.0033 -396.505094) (xy 41.053877 -396.470178) (xy 41.108293 -396.441614) (xy 41.165755 -396.419816)
			(xy 41.225426 -396.405104) (xy 41.286435 -396.397692) (xy 41.317164 -396.397226) (xy 41.347861 -396.397681)
			(xy 41.408807 -396.405087) (xy 41.468416 -396.419783) (xy 41.525819 -396.441555) (xy 41.580181 -396.470086)
			(xy 41.605708 -396.487142) (xy 41.61446 -396.492613) (xy 41.634664 -396.496741) (xy 41.654868 -396.492613)
			(xy 41.66362 -396.487142) (xy 41.689157 -396.470105) (xy 41.743525 -396.441595) (xy 41.800927 -396.419832)
			(xy 41.860531 -396.405131) (xy 41.92147 -396.397707) (xy 41.952164 -396.397226) (xy 41.982861 -396.397681)
			(xy 42.043807 -396.405087) (xy 42.103416 -396.419783) (xy 42.160819 -396.441555) (xy 42.215181 -396.470086)
			(xy 42.240708 -396.487142) (xy 42.24946 -396.492613) (xy 42.269664 -396.496741) (xy 42.289868 -396.492613)
			(xy 42.29862 -396.487142) (xy 42.324157 -396.470105) (xy 42.378525 -396.441595) (xy 42.435927 -396.419832)
			(xy 42.495531 -396.405131) (xy 42.55647 -396.397707) (xy 42.587164 -396.397226) (xy 42.617861 -396.397681)
			(xy 42.678807 -396.405087) (xy 42.738416 -396.419783) (xy 42.795819 -396.441555) (xy 42.850181 -396.470086)
			(xy 42.875708 -396.487142) (xy 42.88446 -396.492613) (xy 42.904664 -396.496741) (xy 42.924868 -396.492613)
			(xy 42.93362 -396.487142) (xy 42.959157 -396.470105) (xy 43.013525 -396.441595) (xy 43.070927 -396.419832)
			(xy 43.130531 -396.405131) (xy 43.19147 -396.397707) (xy 43.222164 -396.397226) (xy 43.252897 -396.397672)
			(xy 43.313914 -396.405077) (xy 43.373594 -396.419783) (xy 43.431066 -396.441577) (xy 43.485492 -396.47014)
			(xy 43.536077 -396.505055) (xy 43.582085 -396.545814) (xy 43.622844 -396.591821) (xy 43.657759 -396.642407)
			(xy 43.686322 -396.696832) (xy 43.708116 -396.754304) (xy 43.722823 -396.813984) (xy 43.730228 -396.875001)
			(xy 43.730672 -396.905734) (xy 43.730202 -396.93643) (xy 43.722799 -396.997376) (xy 43.708107 -397.056984)
			(xy 43.686338 -397.114388) (xy 43.65781 -397.168751) (xy 43.640756 -397.194278) (xy 43.635258 -397.203015)
			(xy 43.631143 -397.223228) (xy 43.635281 -397.243437) (xy 43.640756 -397.25219) (xy 43.657779 -397.277735)
			(xy 43.686292 -397.332101) (xy 43.708058 -397.389501) (xy 43.722762 -397.449103) (xy 43.730189 -397.51004)
			(xy 43.730672 -397.540734) (xy 43.730202 -397.57143) (xy 43.722799 -397.632376) (xy 43.708107 -397.691984)
			(xy 43.686338 -397.749388) (xy 43.65781 -397.803751) (xy 43.640756 -397.829278) (xy 43.635258 -397.838015)
			(xy 43.631143 -397.858228) (xy 43.635281 -397.878437) (xy 43.640756 -397.88719) (xy 43.657779 -397.912735)
			(xy 43.686292 -397.967101) (xy 43.708058 -398.024501) (xy 43.722762 -398.084103) (xy 43.730189 -398.14504)
			(xy 43.730672 -398.175734) (xy 43.730084 -398.21063) (xy 43.720541 -398.279767) (xy 43.701627 -398.346948)
			(xy 43.673697 -398.410908) (xy 43.637276 -398.470444) (xy 43.61561 -398.497806) (xy 43.609524 -398.506114)
			(xy 43.603841 -398.525888) (xy 43.606317 -398.546312) (xy 43.611038 -398.555464) (xy 43.627392 -398.584644)
			(xy 43.653115 -398.646392) (xy 43.670526 -398.710978) (xy 43.679325 -398.777288) (xy 43.679872 -398.810734)
			(xy 43.679494 -398.841468) (xy 43.672081 -398.902488) (xy 43.657367 -398.962169) (xy 43.635566 -399.019642)
			(xy 43.606996 -399.074068) (xy 43.572075 -399.124653) (xy 43.53131 -399.17066) (xy 43.485298 -399.211418)
			(xy 43.434708 -399.246332) (xy 43.380278 -399.274894) (xy 43.322802 -399.296687) (xy 43.263119 -399.311394)
			(xy 43.202098 -399.318798) (xy 43.171364 -399.319242) (xy 43.140668 -399.318761) (xy 43.079724 -399.311359)
			(xy 43.020115 -399.296668) (xy 42.962711 -399.274902) (xy 42.908348 -399.246378) (xy 42.88282 -399.229326)
			(xy 42.874068 -399.223855) (xy 42.853864 -399.219727) (xy 42.83366 -399.223855) (xy 42.824908 -399.229326)
			(xy 42.799361 -399.246347) (xy 42.744996 -399.27486) (xy 42.687596 -399.296627) (xy 42.627995 -399.311331)
			(xy 42.567058 -399.318759) (xy 42.536364 -399.319242) (xy 42.505668 -399.318761) (xy 42.444724 -399.311359)
			(xy 42.385115 -399.296668) (xy 42.327711 -399.274902) (xy 42.273348 -399.246378) (xy 42.24782 -399.229326)
			(xy 42.239068 -399.223855) (xy 42.218864 -399.219727) (xy 42.19866 -399.223855) (xy 42.189908 -399.229326)
			(xy 42.164361 -399.246347) (xy 42.109996 -399.27486) (xy 42.052596 -399.296627) (xy 41.992995 -399.311331)
			(xy 41.932058 -399.318759) (xy 41.901364 -399.319242) (xy 41.870668 -399.318761) (xy 41.809724 -399.311359)
			(xy 41.750115 -399.296668) (xy 41.692711 -399.274902) (xy 41.638348 -399.246378) (xy 41.61282 -399.229326)
			(xy 41.604068 -399.223855) (xy 41.583864 -399.219727) (xy 41.56366 -399.223855) (xy 41.554908 -399.229326)
			(xy 41.529361 -399.246347) (xy 41.474996 -399.27486) (xy 41.417596 -399.296627) (xy 41.357995 -399.311331)
			(xy 41.297058 -399.318759) (xy 41.266364 -399.319242) (xy 41.235634 -399.318778) (xy 41.174621 -399.311366)
			(xy 41.114947 -399.296655) (xy 41.057481 -399.274858) (xy 41.00306 -399.246294) (xy 40.95248 -399.21138)
			(xy 40.906476 -399.170623) (xy 40.865719 -399.124619) (xy 40.830805 -399.074038) (xy 40.802241 -399.019618)
			(xy 40.780445 -398.962151) (xy 40.765733 -398.902477) (xy 40.758322 -398.841464) (xy 40.757856 -398.810734)
			(xy 38.83914 -398.810734) (xy 38.83914 -399.980658) (xy 38.839575 -399.990723) (xy 38.847309 -400.009308)
			(xy 38.854126 -400.016726) (xy 39.737538 -400.900138) (xy 39.745173 -400.907149) (xy 39.764376 -400.914902)
			(xy 39.785079 -400.914438) (xy 39.794688 -400.910552) (xy 39.87806 -400.873007) (xy 40.047501 -400.804227)
			(xy 40.219732 -400.742766) (xy 40.394437 -400.688736) (xy 40.571295 -400.642238) (xy 40.749983 -400.603356)
			(xy 40.930171 -400.572161) (xy 41.11153 -400.548712) (xy 41.293727 -400.53305) (xy 41.476428 -400.525204)
			(xy 41.567862 -400.524726) (xy 41.662002 -400.525239) (xy 41.850099 -400.533537) (xy 42.037647 -400.550124)
			(xy 42.224281 -400.574968) (xy 42.409637 -400.608019) (xy 42.593355 -400.649213) (xy 42.775077 -400.698471)
			(xy 42.95445 -400.755696) (xy 43.131124 -400.820777) (xy 43.304756 -400.893588) (xy 43.475007 -400.973986)
			(xy 43.641546 -401.061815) (xy 43.723052 -401.108926) (xy 43.728988 -401.112093) (xy 43.741981 -401.115567)
			(xy 43.748706 -401.115784)
		)
		(stroke
			(width 0)
			(type solid)
		)
		(fill yes)
		(layer "In15.Cu")
		(net "P0V9_CPU1_RT0_2A_2D")
	)
	(gr_poly
		(pts
			(xy 429.527208 -371.572536) (xy 429.537276 -371.57211) (xy 429.555872 -371.564386) (xy 429.563276 -371.55755)
			(xy 432.331622 -368.789204) (xy 432.337661 -368.782627) (xy 432.345122 -368.766416) (xy 432.346578 -368.748631)
			(xy 432.344576 -368.739928) (xy 432.317652 -368.64163) (xy 432.298094 -368.62258) (xy 432.284886 -368.619024)
			(xy 432.257879 -368.611612) (xy 432.20623 -368.58996) (xy 432.158301 -368.560993) (xy 432.11512 -368.525331)
			(xy 432.077614 -368.483741) (xy 432.04659 -368.437117) (xy 432.022714 -368.386458) (xy 432.006498 -368.332854)
			(xy 431.99829 -368.277455) (xy 431.997866 -368.249454) (xy 431.998355 -368.222204) (xy 432.006117 -368.16826)
			(xy 432.021475 -368.115969) (xy 432.044119 -368.066396) (xy 432.073586 -368.02055) (xy 432.109277 -367.979363)
			(xy 432.150466 -367.943674) (xy 432.196314 -367.914209) (xy 432.245888 -367.891568) (xy 432.29818 -367.876212)
			(xy 432.352124 -367.868453) (xy 432.379374 -367.867946) (xy 432.407374 -367.868437) (xy 432.462772 -367.876623)
			(xy 432.516377 -367.892823) (xy 432.567037 -367.916687) (xy 432.613662 -367.947704) (xy 432.65525 -367.985206)
			(xy 432.690906 -368.028387) (xy 432.719864 -368.076318) (xy 432.741501 -368.127968) (xy 432.748944 -368.154966)
			(xy 432.7525 -368.168174) (xy 432.77155 -368.187732) (xy 432.869848 -368.214656) (xy 432.878545 -368.216689)
			(xy 432.896335 -368.215223) (xy 432.912542 -368.20774) (xy 432.919124 -368.201702) (xy 435.761892 -365.358934)
			(xy 435.769289 -365.352083) (xy 435.787887 -365.34434) (xy 435.79796 -365.343948) (xy 463.471514 -365.343948)
			(xy 463.481582 -365.343521) (xy 463.500178 -365.335797) (xy 463.507582 -365.328962) (xy 466.160104 -362.67644)
			(xy 466.166941 -362.669038) (xy 466.174653 -362.65044) (xy 466.17509 -362.640372) (xy 466.17509 -350.453452)
			(xy 466.17509 -350.45269) (xy 466.174346 -350.441967) (xy 466.165289 -350.422502) (xy 466.149114 -350.408385)
			(xy 466.139022 -350.404684) (xy 466.137752 -350.40443) (xy 466.043264 -350.378522) (xy 466.032482 -350.376115)
			(xy 466.010716 -350.379738) (xy 465.9925 -350.392192) (xy 465.986368 -350.401382) (xy 465.934289 -350.487699)
			(xy 465.824412 -350.656747) (xy 465.708152 -350.821471) (xy 465.585678 -350.981628) (xy 465.45717 -351.136985)
			(xy 465.322815 -351.287315) (xy 465.18281 -351.432398) (xy 465.037361 -351.572021) (xy 464.886678 -351.705981)
			(xy 464.730984 -351.834081) (xy 464.570506 -351.956134) (xy 464.405478 -352.071961) (xy 464.236141 -352.181394)
			(xy 464.062745 -352.284271) (xy 463.885541 -352.380444) (xy 463.704789 -352.46977) (xy 463.520755 -352.552119)
			(xy 463.333705 -352.627372) (xy 463.143916 -352.695417) (xy 462.951663 -352.756155) (xy 462.757228 -352.809498)
			(xy 462.560896 -352.855367) (xy 462.362954 -352.893696) (xy 462.163691 -352.924427) (xy 461.963398 -352.947517)
			(xy 461.762369 -352.962932) (xy 461.560898 -352.970648) (xy 461.460088 -352.9711) (xy 461.357861 -352.970604)
			(xy 461.153561 -352.962676) (xy 460.949722 -352.946832) (xy 460.74665 -352.923096) (xy 460.544652 -352.891503)
			(xy 460.34403 -352.852102) (xy 460.145088 -352.804951) (xy 459.948123 -352.750122) (xy 459.753432 -352.687697)
			(xy 459.561308 -352.617769) (xy 459.37204 -352.540444) (xy 459.185913 -352.455838) (xy 459.003207 -352.364079)
			(xy 458.824195 -352.265305) (xy 458.649149 -352.159663) (xy 458.47833 -352.047314) (xy 458.311996 -351.928425)
			(xy 458.150398 -351.803176) (xy 457.993777 -351.671756) (xy 457.84237 -351.534361) (xy 457.696404 -351.391198)
			(xy 457.5561 -351.242484) (xy 457.421667 -351.088441) (xy 457.293308 -350.929301) (xy 457.171217 -350.765303)
			(xy 457.055577 -350.596695) (xy 456.946561 -350.42373) (xy 456.844334 -350.246667) (xy 456.74905 -350.065774)
			(xy 456.660851 -349.881323) (xy 456.579871 -349.69359) (xy 456.506232 -349.502858) (xy 456.440043 -349.309414)
			(xy 456.381405 -349.113549) (xy 456.330406 -348.915558) (xy 456.287122 -348.715738) (xy 456.251619 -348.51439)
			(xy 456.22395 -348.311817) (xy 456.204157 -348.108324) (xy 456.192269 -347.904216) (xy 456.188304 -347.6998)
			(xy 456.192269 -347.495384) (xy 456.204157 -347.291276) (xy 456.22395 -347.087783) (xy 456.251619 -346.88521)
			(xy 456.287122 -346.683862) (xy 456.330406 -346.484042) (xy 456.381405 -346.286051) (xy 456.440043 -346.090186)
			(xy 456.506232 -345.896742) (xy 456.579871 -345.70601) (xy 456.660851 -345.518277) (xy 456.74905 -345.333826)
			(xy 456.844334 -345.152933) (xy 456.946561 -344.97587) (xy 457.055577 -344.802905) (xy 457.171217 -344.634297)
			(xy 457.293308 -344.470299) (xy 457.421667 -344.311159) (xy 457.5561 -344.157116) (xy 457.696404 -344.008402)
			(xy 457.84237 -343.865239) (xy 457.993777 -343.727844) (xy 458.150398 -343.596424) (xy 458.311996 -343.471175)
			(xy 458.47833 -343.352286) (xy 458.649149 -343.239937) (xy 458.824195 -343.134295) (xy 459.003207 -343.035521)
			(xy 459.185913 -342.943762) (xy 459.37204 -342.859156) (xy 459.561308 -342.781831) (xy 459.753432 -342.711903)
			(xy 459.948123 -342.649478) (xy 460.145088 -342.594649) (xy 460.34403 -342.547498) (xy 460.544652 -342.508097)
			(xy 460.74665 -342.476504) (xy 460.949722 -342.452768) (xy 461.153561 -342.436924) (xy 461.357861 -342.428996)
			(xy 461.460088 -342.428576) (xy 461.560898 -342.429054) (xy 461.762372 -342.43676) (xy 461.963404 -342.452165)
			(xy 462.163699 -342.475245) (xy 462.362965 -342.505969) (xy 462.560911 -342.544289) (xy 462.757247 -342.590152)
			(xy 462.951685 -342.643488) (xy 463.143941 -342.704221) (xy 463.333734 -342.772262) (xy 463.520787 -342.84751)
			(xy 463.704825 -342.929857) (xy 463.88558 -343.019181) (xy 464.062786 -343.115351) (xy 464.236186 -343.218228)
			(xy 464.405524 -343.32766) (xy 464.570554 -343.443488) (xy 464.731034 -343.565542) (xy 464.886729 -343.693643)
			(xy 465.037412 -343.827605) (xy 465.182862 -343.967231) (xy 465.322866 -344.112316) (xy 465.457219 -344.26265)
			(xy 465.585726 -344.418011) (xy 465.708197 -344.578172) (xy 465.824455 -344.7429) (xy 465.934328 -344.911953)
			(xy 465.986368 -344.998294) (xy 465.992527 -345.007445) (xy 466.010753 -345.01983) (xy 466.032483 -345.02349)
			(xy 466.043264 -345.021154) (xy 466.137752 -344.995246) (xy 466.139022 -344.994992) (xy 466.149201 -344.991428)
			(xy 466.165479 -344.977312) (xy 466.17452 -344.957754) (xy 466.17509 -344.946986) (xy 466.17509 -330.715112)
			(xy 466.174669 -330.705041) (xy 466.166956 -330.686434) (xy 466.160104 -330.679044) (xy 464.161886 -328.680826)
			(xy 464.154774 -328.67346) (xy 464.135978 -328.66584) (xy 418.681662 -328.66584) (xy 418.671596 -328.666271)
			(xy 418.653005 -328.674) (xy 418.645594 -328.680826) (xy 417.806124 -329.520296) (xy 446.645028 -329.520296)
			(xy 446.649099 -329.464674) (xy 446.661225 -329.410237) (xy 446.681148 -329.358146) (xy 446.708444 -329.309511)
			(xy 446.74253 -329.265368) (xy 446.782679 -329.226659) (xy 446.828037 -329.194208) (xy 446.877637 -329.168707)
			(xy 446.930421 -329.1507) (xy 446.985264 -329.14057) (xy 447.040998 -329.138533) (xy 447.096435 -329.144633)
			(xy 447.150392 -329.158739) (xy 447.201721 -329.180551) (xy 447.249327 -329.209605) (xy 447.292195 -329.24528)
			(xy 447.329412 -329.286817) (xy 447.360185 -329.33333) (xy 447.383857 -329.383827) (xy 447.399925 -329.437234)
			(xy 447.408045 -329.49241) (xy 447.408554 -329.520296) (xy 447.408045 -329.548182) (xy 447.399925 -329.603358)
			(xy 447.383857 -329.656765) (xy 447.360185 -329.707262) (xy 447.329412 -329.753775) (xy 447.292195 -329.795312)
			(xy 447.249327 -329.830987) (xy 447.201721 -329.860041) (xy 447.150392 -329.881853) (xy 447.096435 -329.895959)
			(xy 447.040998 -329.902059) (xy 446.985264 -329.900022) (xy 446.930421 -329.889892) (xy 446.877637 -329.871885)
			(xy 446.828037 -329.846384) (xy 446.782679 -329.813933) (xy 446.74253 -329.775224) (xy 446.708444 -329.731081)
			(xy 446.681148 -329.682446) (xy 446.661225 -329.630355) (xy 446.649099 -329.575918) (xy 446.645028 -329.520296)
			(xy 417.806124 -329.520296) (xy 412.011621 -335.314799) (xy 418.990283 -335.314799) (xy 418.994013 -335.261548)
			(xy 419.005129 -335.209336) (xy 419.023415 -335.159184) (xy 419.048513 -335.11207) (xy 419.079934 -335.068915)
			(xy 419.117063 -335.030562) (xy 419.137846 -335.013808) (xy 419.146607 -335.006246) (xy 419.156789 -334.985487)
			(xy 419.157404 -334.97393) (xy 419.157404 -334.893666) (xy 419.156794 -334.882103) (xy 419.146627 -334.861332)
			(xy 419.137846 -334.853788) (xy 419.117062 -334.837037) (xy 419.079932 -334.798683) (xy 419.048512 -334.755527)
			(xy 419.023414 -334.708414) (xy 419.005128 -334.658262) (xy 418.994012 -334.60605) (xy 418.990283 -334.552799)
			(xy 418.994013 -334.499548) (xy 419.005129 -334.447336) (xy 419.023415 -334.397184) (xy 419.048513 -334.35007)
			(xy 419.079934 -334.306915) (xy 419.117063 -334.268562) (xy 419.137846 -334.251808) (xy 419.146607 -334.244246)
			(xy 419.156789 -334.223487) (xy 419.157404 -334.21193) (xy 419.157404 -334.131666) (xy 419.156794 -334.120103)
			(xy 419.146627 -334.099332) (xy 419.137846 -334.091788) (xy 419.115346 -334.073617) (xy 419.075614 -334.031592)
			(xy 419.042678 -333.984052) (xy 419.017293 -333.932087) (xy 419.00004 -333.876887) (xy 418.991314 -333.819715)
			(xy 418.99078 -333.790798) (xy 418.991266 -333.763547) (xy 418.999022 -333.709599) (xy 419.014377 -333.657304)
			(xy 419.037019 -333.607727) (xy 419.066485 -333.561877) (xy 419.102176 -333.520686) (xy 419.143367 -333.484995)
			(xy 419.189217 -333.455529) (xy 419.238794 -333.432887) (xy 419.291089 -333.417532) (xy 419.345037 -333.409776)
			(xy 419.399539 -333.409776) (xy 419.453487 -333.417532) (xy 419.505782 -333.432887) (xy 419.555359 -333.455529)
			(xy 419.601209 -333.484995) (xy 419.6424 -333.520686) (xy 419.678091 -333.561877) (xy 419.707557 -333.607727)
			(xy 419.730199 -333.657304) (xy 419.745554 -333.709599) (xy 419.75331 -333.763547) (xy 419.753796 -333.790798)
			(xy 419.753278 -333.819715) (xy 419.744549 -333.876886) (xy 419.727291 -333.932085) (xy 419.701899 -333.984047)
			(xy 419.668956 -334.031581) (xy 419.629215 -334.073598) (xy 419.60673 -334.091788) (xy 419.597966 -334.099347)
			(xy 419.587787 -334.120109) (xy 419.587172 -334.131666) (xy 419.587172 -334.21193) (xy 419.587757 -334.223497)
			(xy 419.597939 -334.24427) (xy 419.60673 -334.251808) (xy 419.627512 -334.268563) (xy 419.664643 -334.306916)
			(xy 419.696065 -334.35007) (xy 419.721165 -334.397183) (xy 419.739452 -334.447335) (xy 419.750569 -334.499547)
			(xy 419.754299 -334.552799) (xy 419.750569 -334.60605) (xy 419.739453 -334.658262) (xy 419.721166 -334.708414)
			(xy 419.696067 -334.755528) (xy 419.664645 -334.798682) (xy 419.627513 -334.837035) (xy 419.60673 -334.853788)
			(xy 419.597966 -334.861347) (xy 419.587787 -334.882109) (xy 419.587172 -334.893666) (xy 419.587172 -334.97393)
			(xy 419.587757 -334.985497) (xy 419.597939 -335.00627) (xy 419.60673 -335.013808) (xy 419.627512 -335.030563)
			(xy 419.664643 -335.068916) (xy 419.696065 -335.11207) (xy 419.721165 -335.159183) (xy 419.739452 -335.209335)
			(xy 419.745683 -335.238599) (xy 421.403283 -335.238599) (xy 421.407013 -335.185348) (xy 421.418129 -335.133136)
			(xy 421.436415 -335.082984) (xy 421.461513 -335.03587) (xy 421.492934 -334.992715) (xy 421.530063 -334.954362)
			(xy 421.550846 -334.937608) (xy 421.559607 -334.930046) (xy 421.569789 -334.909287) (xy 421.570404 -334.89773)
			(xy 421.570404 -334.817466) (xy 421.569794 -334.805903) (xy 421.559627 -334.785132) (xy 421.550846 -334.777588)
			(xy 421.530062 -334.760837) (xy 421.492932 -334.722483) (xy 421.461512 -334.679327) (xy 421.436414 -334.632214)
			(xy 421.418128 -334.582062) (xy 421.407012 -334.52985) (xy 421.403283 -334.476599) (xy 421.407013 -334.423348)
			(xy 421.418129 -334.371136) (xy 421.436415 -334.320984) (xy 421.461513 -334.27387) (xy 421.492934 -334.230715)
			(xy 421.530063 -334.192362) (xy 421.550846 -334.175608) (xy 421.559607 -334.168046) (xy 421.569789 -334.147287)
			(xy 421.570404 -334.13573) (xy 421.570404 -334.055466) (xy 421.569794 -334.043903) (xy 421.559627 -334.023132)
			(xy 421.550846 -334.015588) (xy 421.528346 -333.997417) (xy 421.488614 -333.955392) (xy 421.455678 -333.907852)
			(xy 421.430293 -333.855887) (xy 421.41304 -333.800687) (xy 421.404314 -333.743515) (xy 421.40378 -333.714598)
			(xy 421.404266 -333.687347) (xy 421.412022 -333.633399) (xy 421.427377 -333.581104) (xy 421.450019 -333.531527)
			(xy 421.479485 -333.485677) (xy 421.515176 -333.444486) (xy 421.556367 -333.408795) (xy 421.602217 -333.379329)
			(xy 421.651794 -333.356687) (xy 421.704089 -333.341332) (xy 421.758037 -333.333576) (xy 421.812539 -333.333576)
			(xy 421.866487 -333.341332) (xy 421.918782 -333.356687) (xy 421.968359 -333.379329) (xy 422.014209 -333.408795)
			(xy 422.0554 -333.444486) (xy 422.091091 -333.485677) (xy 422.120557 -333.531527) (xy 422.143199 -333.581104)
			(xy 422.158554 -333.633399) (xy 422.16631 -333.687347) (xy 422.166796 -333.714598) (xy 422.166278 -333.743515)
			(xy 422.157549 -333.800686) (xy 422.140291 -333.855885) (xy 422.114899 -333.907847) (xy 422.081956 -333.955381)
			(xy 422.042215 -333.997398) (xy 422.01973 -334.015588) (xy 422.010966 -334.023147) (xy 422.000787 -334.043909)
			(xy 422.000172 -334.055466) (xy 422.000172 -334.13573) (xy 422.000757 -334.147297) (xy 422.010939 -334.16807)
			(xy 422.01973 -334.175608) (xy 422.040512 -334.192363) (xy 422.077643 -334.230716) (xy 422.109065 -334.27387)
			(xy 422.134165 -334.320983) (xy 422.152452 -334.371135) (xy 422.163569 -334.423347) (xy 422.167299 -334.476599)
			(xy 422.163569 -334.52985) (xy 422.152453 -334.582062) (xy 422.134166 -334.632214) (xy 422.109067 -334.679328)
			(xy 422.077645 -334.722482) (xy 422.040513 -334.760835) (xy 422.01973 -334.777588) (xy 422.010966 -334.785147)
			(xy 422.000787 -334.805909) (xy 422.000172 -334.817466) (xy 422.000172 -334.89773) (xy 422.000757 -334.909297)
			(xy 422.010939 -334.93007) (xy 422.01973 -334.937608) (xy 422.040512 -334.954363) (xy 422.077643 -334.992716)
			(xy 422.109065 -335.03587) (xy 422.134165 -335.082983) (xy 422.152452 -335.133135) (xy 422.163569 -335.185347)
			(xy 422.167299 -335.238599) (xy 425.060883 -335.238599) (xy 425.064613 -335.185348) (xy 425.075729 -335.133136)
			(xy 425.094015 -335.082984) (xy 425.119113 -335.03587) (xy 425.150534 -334.992715) (xy 425.187663 -334.954362)
			(xy 425.208446 -334.937608) (xy 425.217207 -334.930046) (xy 425.227389 -334.909287) (xy 425.228004 -334.89773)
			(xy 425.228004 -334.817466) (xy 425.227394 -334.805903) (xy 425.217227 -334.785132) (xy 425.208446 -334.777588)
			(xy 425.187662 -334.760837) (xy 425.150532 -334.722483) (xy 425.119112 -334.679327) (xy 425.094014 -334.632214)
			(xy 425.075728 -334.582062) (xy 425.064612 -334.52985) (xy 425.060883 -334.476599) (xy 425.064613 -334.423348)
			(xy 425.075729 -334.371136) (xy 425.094015 -334.320984) (xy 425.119113 -334.27387) (xy 425.150534 -334.230715)
			(xy 425.187663 -334.192362) (xy 425.208446 -334.175608) (xy 425.217207 -334.168046) (xy 425.227389 -334.147287)
			(xy 425.228004 -334.13573) (xy 425.228004 -334.055466) (xy 425.227394 -334.043903) (xy 425.217227 -334.023132)
			(xy 425.208446 -334.015588) (xy 425.185946 -333.997417) (xy 425.146214 -333.955392) (xy 425.113278 -333.907852)
			(xy 425.087893 -333.855887) (xy 425.07064 -333.800687) (xy 425.061914 -333.743515) (xy 425.06138 -333.714598)
			(xy 425.061866 -333.687347) (xy 425.069622 -333.633399) (xy 425.084977 -333.581104) (xy 425.107619 -333.531527)
			(xy 425.137085 -333.485677) (xy 425.172776 -333.444486) (xy 425.213967 -333.408795) (xy 425.259817 -333.379329)
			(xy 425.309394 -333.356687) (xy 425.361689 -333.341332) (xy 425.415637 -333.333576) (xy 425.470139 -333.333576)
			(xy 425.524087 -333.341332) (xy 425.576382 -333.356687) (xy 425.625959 -333.379329) (xy 425.671809 -333.408795)
			(xy 425.713 -333.444486) (xy 425.748691 -333.485677) (xy 425.778157 -333.531527) (xy 425.800799 -333.581104)
			(xy 425.816154 -333.633399) (xy 425.82391 -333.687347) (xy 425.824396 -333.714598) (xy 425.823878 -333.743515)
			(xy 425.815149 -333.800686) (xy 425.797891 -333.855885) (xy 425.772499 -333.907847) (xy 425.739556 -333.955381)
			(xy 425.699815 -333.997398) (xy 425.67733 -334.015588) (xy 425.668566 -334.023147) (xy 425.658387 -334.043909)
			(xy 425.657772 -334.055466) (xy 425.657772 -334.13573) (xy 425.658357 -334.147297) (xy 425.668539 -334.16807)
			(xy 425.67733 -334.175608) (xy 425.698112 -334.192363) (xy 425.735243 -334.230716) (xy 425.766665 -334.27387)
			(xy 425.791765 -334.320983) (xy 425.810052 -334.371135) (xy 425.821169 -334.423347) (xy 425.824899 -334.476599)
			(xy 425.821169 -334.52985) (xy 425.810053 -334.582062) (xy 425.791766 -334.632214) (xy 425.766667 -334.679328)
			(xy 425.735245 -334.722482) (xy 425.698113 -334.760835) (xy 425.67733 -334.777588) (xy 425.668566 -334.785147)
			(xy 425.658387 -334.805909) (xy 425.657772 -334.817466) (xy 425.657772 -334.89773) (xy 425.658357 -334.909297)
			(xy 425.668539 -334.93007) (xy 425.67733 -334.937608) (xy 425.698112 -334.954363) (xy 425.735243 -334.992716)
			(xy 425.766665 -335.03587) (xy 425.791765 -335.082983) (xy 425.810052 -335.133135) (xy 425.821169 -335.185347)
			(xy 425.824899 -335.238599) (xy 427.524683 -335.238599) (xy 427.528413 -335.185348) (xy 427.539529 -335.133136)
			(xy 427.557815 -335.082984) (xy 427.582913 -335.03587) (xy 427.614334 -334.992715) (xy 427.651463 -334.954362)
			(xy 427.672246 -334.937608) (xy 427.681007 -334.930046) (xy 427.691189 -334.909287) (xy 427.691804 -334.89773)
			(xy 427.691804 -334.817466) (xy 427.691194 -334.805903) (xy 427.681027 -334.785132) (xy 427.672246 -334.777588)
			(xy 427.651462 -334.760837) (xy 427.614332 -334.722483) (xy 427.582912 -334.679327) (xy 427.557814 -334.632214)
			(xy 427.539528 -334.582062) (xy 427.528412 -334.52985) (xy 427.524683 -334.476599) (xy 427.528413 -334.423348)
			(xy 427.539529 -334.371136) (xy 427.557815 -334.320984) (xy 427.582913 -334.27387) (xy 427.614334 -334.230715)
			(xy 427.651463 -334.192362) (xy 427.672246 -334.175608) (xy 427.681007 -334.168046) (xy 427.691189 -334.147287)
			(xy 427.691804 -334.13573) (xy 427.691804 -334.055466) (xy 427.691194 -334.043903) (xy 427.681027 -334.023132)
			(xy 427.672246 -334.015588) (xy 427.649746 -333.997417) (xy 427.610014 -333.955392) (xy 427.577078 -333.907852)
			(xy 427.551693 -333.855887) (xy 427.53444 -333.800687) (xy 427.525714 -333.743515) (xy 427.52518 -333.714598)
			(xy 427.525666 -333.687347) (xy 427.533422 -333.633399) (xy 427.548777 -333.581104) (xy 427.571419 -333.531527)
			(xy 427.600885 -333.485677) (xy 427.636576 -333.444486) (xy 427.677767 -333.408795) (xy 427.723617 -333.379329)
			(xy 427.773194 -333.356687) (xy 427.825489 -333.341332) (xy 427.879437 -333.333576) (xy 427.933939 -333.333576)
			(xy 427.987887 -333.341332) (xy 428.040182 -333.356687) (xy 428.089759 -333.379329) (xy 428.135609 -333.408795)
			(xy 428.1768 -333.444486) (xy 428.212491 -333.485677) (xy 428.241957 -333.531527) (xy 428.264599 -333.581104)
			(xy 428.279954 -333.633399) (xy 428.28771 -333.687347) (xy 428.288196 -333.714598) (xy 428.287678 -333.743515)
			(xy 428.278949 -333.800686) (xy 428.261691 -333.855885) (xy 428.236299 -333.907847) (xy 428.203356 -333.955381)
			(xy 428.163615 -333.997398) (xy 428.14113 -334.015588) (xy 428.132366 -334.023147) (xy 428.122187 -334.043909)
			(xy 428.121572 -334.055466) (xy 428.121572 -334.13573) (xy 428.122157 -334.147297) (xy 428.132339 -334.16807)
			(xy 428.14113 -334.175608) (xy 428.161912 -334.192363) (xy 428.199043 -334.230716) (xy 428.230465 -334.27387)
			(xy 428.255565 -334.320983) (xy 428.273852 -334.371135) (xy 428.284969 -334.423347) (xy 428.288699 -334.476599)
			(xy 428.284969 -334.52985) (xy 428.273853 -334.582062) (xy 428.255566 -334.632214) (xy 428.230467 -334.679328)
			(xy 428.199045 -334.722482) (xy 428.161913 -334.760835) (xy 428.14113 -334.777588) (xy 428.132366 -334.785147)
			(xy 428.122187 -334.805909) (xy 428.121572 -334.817466) (xy 428.121572 -334.89773) (xy 428.122157 -334.909297)
			(xy 428.132339 -334.93007) (xy 428.14113 -334.937608) (xy 428.161912 -334.954363) (xy 428.199043 -334.992716)
			(xy 428.230465 -335.03587) (xy 428.255565 -335.082983) (xy 428.273852 -335.133135) (xy 428.284969 -335.185347)
			(xy 428.28692 -335.213199) (xy 431.182283 -335.213199) (xy 431.186013 -335.159948) (xy 431.197129 -335.107736)
			(xy 431.215415 -335.057584) (xy 431.240513 -335.01047) (xy 431.271934 -334.967315) (xy 431.309063 -334.928962)
			(xy 431.329846 -334.912208) (xy 431.338607 -334.904646) (xy 431.348789 -334.883887) (xy 431.349404 -334.87233)
			(xy 431.349404 -334.792066) (xy 431.348794 -334.780503) (xy 431.338627 -334.759732) (xy 431.329846 -334.752188)
			(xy 431.309062 -334.735437) (xy 431.271932 -334.697083) (xy 431.240512 -334.653927) (xy 431.215414 -334.606814)
			(xy 431.197128 -334.556662) (xy 431.186012 -334.50445) (xy 431.182283 -334.451199) (xy 431.186013 -334.397948)
			(xy 431.197129 -334.345736) (xy 431.215415 -334.295584) (xy 431.240513 -334.24847) (xy 431.271934 -334.205315)
			(xy 431.309063 -334.166962) (xy 431.329846 -334.150208) (xy 431.338607 -334.142646) (xy 431.348789 -334.121887)
			(xy 431.349404 -334.11033) (xy 431.349404 -334.030066) (xy 431.348794 -334.018503) (xy 431.338627 -333.997732)
			(xy 431.329846 -333.990188) (xy 431.307346 -333.972017) (xy 431.267614 -333.929992) (xy 431.234678 -333.882452)
			(xy 431.209293 -333.830487) (xy 431.19204 -333.775287) (xy 431.183314 -333.718115) (xy 431.18278 -333.689198)
			(xy 431.183266 -333.661947) (xy 431.191022 -333.607999) (xy 431.206377 -333.555704) (xy 431.229019 -333.506127)
			(xy 431.258485 -333.460277) (xy 431.294176 -333.419086) (xy 431.335367 -333.383395) (xy 431.381217 -333.353929)
			(xy 431.430794 -333.331287) (xy 431.483089 -333.315932) (xy 431.537037 -333.308176) (xy 431.591539 -333.308176)
			(xy 431.645487 -333.315932) (xy 431.697782 -333.331287) (xy 431.747359 -333.353929) (xy 431.793209 -333.383395)
			(xy 431.8344 -333.419086) (xy 431.870091 -333.460277) (xy 431.899557 -333.506127) (xy 431.922199 -333.555704)
			(xy 431.937554 -333.607999) (xy 431.94531 -333.661947) (xy 431.945796 -333.689198) (xy 431.945278 -333.718115)
			(xy 431.936549 -333.775286) (xy 431.919291 -333.830485) (xy 431.893899 -333.882447) (xy 431.860956 -333.929981)
			(xy 431.821215 -333.971998) (xy 431.79873 -333.990188) (xy 431.789966 -333.997747) (xy 431.779787 -334.018509)
			(xy 431.779172 -334.030066) (xy 431.779172 -334.11033) (xy 431.779757 -334.121897) (xy 431.789939 -334.14267)
			(xy 431.79873 -334.150208) (xy 431.819512 -334.166963) (xy 431.856643 -334.205316) (xy 431.888065 -334.24847)
			(xy 431.913165 -334.295583) (xy 431.931452 -334.345735) (xy 431.942569 -334.397947) (xy 431.946299 -334.451199)
			(xy 431.942569 -334.50445) (xy 431.931453 -334.556662) (xy 431.913166 -334.606814) (xy 431.888067 -334.653928)
			(xy 431.856645 -334.697082) (xy 431.819513 -334.735435) (xy 431.79873 -334.752188) (xy 431.789966 -334.759747)
			(xy 431.779787 -334.780509) (xy 431.779172 -334.792066) (xy 431.779172 -334.87233) (xy 431.779757 -334.883897)
			(xy 431.789939 -334.90467) (xy 431.79873 -334.912208) (xy 431.819512 -334.928963) (xy 431.856643 -334.967316)
			(xy 431.888065 -335.01047) (xy 431.913165 -335.057583) (xy 431.931452 -335.107735) (xy 431.942569 -335.159947)
			(xy 431.946299 -335.213199) (xy 433.620683 -335.213199) (xy 433.624413 -335.159948) (xy 433.635529 -335.107736)
			(xy 433.653815 -335.057584) (xy 433.678913 -335.01047) (xy 433.710334 -334.967315) (xy 433.747463 -334.928962)
			(xy 433.768246 -334.912208) (xy 433.777007 -334.904646) (xy 433.787189 -334.883887) (xy 433.787804 -334.87233)
			(xy 433.787804 -334.792066) (xy 433.787194 -334.780503) (xy 433.777027 -334.759732) (xy 433.768246 -334.752188)
			(xy 433.747462 -334.735437) (xy 433.710332 -334.697083) (xy 433.678912 -334.653927) (xy 433.653814 -334.606814)
			(xy 433.635528 -334.556662) (xy 433.624412 -334.50445) (xy 433.620683 -334.451199) (xy 433.624413 -334.397948)
			(xy 433.635529 -334.345736) (xy 433.653815 -334.295584) (xy 433.678913 -334.24847) (xy 433.710334 -334.205315)
			(xy 433.747463 -334.166962) (xy 433.768246 -334.150208) (xy 433.777007 -334.142646) (xy 433.787189 -334.121887)
			(xy 433.787804 -334.11033) (xy 433.787804 -334.030066) (xy 433.787194 -334.018503) (xy 433.777027 -333.997732)
			(xy 433.768246 -333.990188) (xy 433.745746 -333.972017) (xy 433.706014 -333.929992) (xy 433.673078 -333.882452)
			(xy 433.647693 -333.830487) (xy 433.63044 -333.775287) (xy 433.621714 -333.718115) (xy 433.62118 -333.689198)
			(xy 433.621666 -333.661947) (xy 433.629422 -333.607999) (xy 433.644777 -333.555704) (xy 433.667419 -333.506127)
			(xy 433.696885 -333.460277) (xy 433.732576 -333.419086) (xy 433.773767 -333.383395) (xy 433.819617 -333.353929)
			(xy 433.869194 -333.331287) (xy 433.921489 -333.315932) (xy 433.975437 -333.308176) (xy 434.029939 -333.308176)
			(xy 434.083887 -333.315932) (xy 434.136182 -333.331287) (xy 434.185759 -333.353929) (xy 434.231609 -333.383395)
			(xy 434.2728 -333.419086) (xy 434.308491 -333.460277) (xy 434.337957 -333.506127) (xy 434.360599 -333.555704)
			(xy 434.375954 -333.607999) (xy 434.38371 -333.661947) (xy 434.384196 -333.689198) (xy 434.383678 -333.718115)
			(xy 434.374949 -333.775286) (xy 434.357691 -333.830485) (xy 434.332299 -333.882447) (xy 434.299356 -333.929981)
			(xy 434.259615 -333.971998) (xy 434.23713 -333.990188) (xy 434.228366 -333.997747) (xy 434.218187 -334.018509)
			(xy 434.217572 -334.030066) (xy 434.217572 -334.11033) (xy 434.218157 -334.121897) (xy 434.228339 -334.14267)
			(xy 434.23713 -334.150208) (xy 434.257912 -334.166963) (xy 434.295043 -334.205316) (xy 434.326465 -334.24847)
			(xy 434.351565 -334.295583) (xy 434.369852 -334.345735) (xy 434.380969 -334.397947) (xy 434.384699 -334.451199)
			(xy 434.380969 -334.50445) (xy 434.369853 -334.556662) (xy 434.351566 -334.606814) (xy 434.326467 -334.653928)
			(xy 434.295045 -334.697082) (xy 434.257913 -334.735435) (xy 434.23713 -334.752188) (xy 434.228366 -334.759747)
			(xy 434.218187 -334.780509) (xy 434.217572 -334.792066) (xy 434.217572 -334.87233) (xy 434.218157 -334.883897)
			(xy 434.228339 -334.90467) (xy 434.23713 -334.912208) (xy 434.257912 -334.928963) (xy 434.295043 -334.967316)
			(xy 434.326465 -335.01047) (xy 434.351565 -335.057583) (xy 434.361999 -335.086199) (xy 437.176683 -335.086199)
			(xy 437.180413 -335.032948) (xy 437.191529 -334.980736) (xy 437.209815 -334.930584) (xy 437.234913 -334.88347)
			(xy 437.266334 -334.840315) (xy 437.303463 -334.801962) (xy 437.324246 -334.785208) (xy 437.333007 -334.777646)
			(xy 437.343189 -334.756887) (xy 437.343804 -334.74533) (xy 437.343804 -334.665066) (xy 437.343194 -334.653503)
			(xy 437.333027 -334.632732) (xy 437.324246 -334.625188) (xy 437.303462 -334.608437) (xy 437.266332 -334.570083)
			(xy 437.234912 -334.526927) (xy 437.209814 -334.479814) (xy 437.191528 -334.429662) (xy 437.180412 -334.37745)
			(xy 437.176683 -334.324199) (xy 437.180413 -334.270948) (xy 437.191529 -334.218736) (xy 437.209815 -334.168584)
			(xy 437.234913 -334.12147) (xy 437.266334 -334.078315) (xy 437.303463 -334.039962) (xy 437.324246 -334.023208)
			(xy 437.333007 -334.015646) (xy 437.343189 -333.994887) (xy 437.343804 -333.98333) (xy 437.343804 -333.903066)
			(xy 437.343194 -333.891503) (xy 437.333027 -333.870732) (xy 437.324246 -333.863188) (xy 437.301746 -333.845017)
			(xy 437.262014 -333.802992) (xy 437.229078 -333.755452) (xy 437.203693 -333.703487) (xy 437.18644 -333.648287)
			(xy 437.177714 -333.591115) (xy 437.17718 -333.562198) (xy 437.177666 -333.534947) (xy 437.185422 -333.480999)
			(xy 437.200777 -333.428704) (xy 437.223419 -333.379127) (xy 437.252885 -333.333277) (xy 437.288576 -333.292086)
			(xy 437.329767 -333.256395) (xy 437.375617 -333.226929) (xy 437.425194 -333.204287) (xy 437.477489 -333.188932)
			(xy 437.531437 -333.181176) (xy 437.585939 -333.181176) (xy 437.639887 -333.188932) (xy 437.692182 -333.204287)
			(xy 437.741759 -333.226929) (xy 437.787609 -333.256395) (xy 437.8288 -333.292086) (xy 437.864491 -333.333277)
			(xy 437.893957 -333.379127) (xy 437.916599 -333.428704) (xy 437.931954 -333.480999) (xy 437.93971 -333.534947)
			(xy 437.940196 -333.562198) (xy 437.939678 -333.591115) (xy 437.930949 -333.648286) (xy 437.913691 -333.703485)
			(xy 437.888299 -333.755447) (xy 437.855356 -333.802981) (xy 437.815615 -333.844998) (xy 437.79313 -333.863188)
			(xy 437.784366 -333.870747) (xy 437.774187 -333.891509) (xy 437.773572 -333.903066) (xy 437.773572 -333.98333)
			(xy 437.774157 -333.994897) (xy 437.784339 -334.01567) (xy 437.79313 -334.023208) (xy 437.813912 -334.039963)
			(xy 437.851043 -334.078316) (xy 437.882465 -334.12147) (xy 437.907565 -334.168583) (xy 437.925852 -334.218735)
			(xy 437.936969 -334.270947) (xy 437.940699 -334.324199) (xy 437.936969 -334.37745) (xy 437.925853 -334.429662)
			(xy 437.907566 -334.479814) (xy 437.882467 -334.526928) (xy 437.851045 -334.570082) (xy 437.813913 -334.608435)
			(xy 437.79313 -334.625188) (xy 437.784366 -334.632747) (xy 437.774187 -334.653509) (xy 437.773572 -334.665066)
			(xy 437.773572 -334.74533) (xy 437.774157 -334.756897) (xy 437.784339 -334.77767) (xy 437.79313 -334.785208)
			(xy 437.813912 -334.801963) (xy 437.851043 -334.840316) (xy 437.882465 -334.88347) (xy 437.907565 -334.930583)
			(xy 437.925852 -334.980735) (xy 437.93587 -335.027786) (xy 439.724279 -335.027786) (xy 439.728011 -334.974532)
			(xy 439.739131 -334.922319) (xy 439.75742 -334.872165) (xy 439.782522 -334.82505) (xy 439.813947 -334.781895)
			(xy 439.851081 -334.743541) (xy 439.871866 -334.726788) (xy 439.88064 -334.719238) (xy 439.890814 -334.69847)
			(xy 439.891424 -334.68691) (xy 439.891424 -334.606646) (xy 439.890853 -334.595077) (xy 439.880662 -334.574305)
			(xy 439.871866 -334.566768) (xy 439.851061 -334.550041) (xy 439.81393 -334.511685) (xy 439.782508 -334.468527)
			(xy 439.757409 -334.421411) (xy 439.739123 -334.371255) (xy 439.728008 -334.319041) (xy 439.724279 -334.265786)
			(xy 439.728011 -334.212532) (xy 439.739131 -334.160319) (xy 439.75742 -334.110165) (xy 439.782522 -334.06305)
			(xy 439.813947 -334.019895) (xy 439.851081 -333.981541) (xy 439.871866 -333.964788) (xy 439.88064 -333.957238)
			(xy 439.890814 -333.93647) (xy 439.891424 -333.92491) (xy 439.891424 -333.844646) (xy 439.890853 -333.833077)
			(xy 439.880662 -333.812305) (xy 439.871866 -333.804768) (xy 439.84936 -333.786604) (xy 439.809628 -333.744577)
			(xy 439.776692 -333.697037) (xy 439.751308 -333.64507) (xy 439.734057 -333.589868) (xy 439.725332 -333.532695)
			(xy 439.7248 -333.503778) (xy 439.725286 -333.476527) (xy 439.733042 -333.422579) (xy 439.748397 -333.370284)
			(xy 439.771039 -333.320707) (xy 439.800505 -333.274857) (xy 439.836196 -333.233666) (xy 439.877387 -333.197975)
			(xy 439.923237 -333.168509) (xy 439.972814 -333.145867) (xy 440.025109 -333.130512) (xy 440.079057 -333.122756)
			(xy 440.133559 -333.122756) (xy 440.187507 -333.130512) (xy 440.239802 -333.145867) (xy 440.289379 -333.168509)
			(xy 440.335229 -333.197975) (xy 440.37642 -333.233666) (xy 440.412111 -333.274857) (xy 440.441577 -333.320707)
			(xy 440.464219 -333.370284) (xy 440.479574 -333.422579) (xy 440.48733 -333.476527) (xy 440.487816 -333.503778)
			(xy 440.487314 -333.532696) (xy 440.478586 -333.589869) (xy 440.461327 -333.64507) (xy 440.435932 -333.697032)
			(xy 440.402984 -333.744565) (xy 440.363238 -333.78658) (xy 440.34075 -333.804768) (xy 440.331998 -333.812339)
			(xy 440.321811 -333.833091) (xy 440.321192 -333.844646) (xy 440.321192 -333.92491) (xy 440.32176 -333.936478)
			(xy 440.331957 -333.957249) (xy 440.34075 -333.964788) (xy 440.361511 -333.981567) (xy 440.39864 -334.019918)
			(xy 440.430061 -334.06307) (xy 440.45516 -334.11018) (xy 440.473447 -334.160329) (xy 440.484564 -334.212538)
			(xy 440.488296 -334.265786) (xy 440.484568 -334.319035) (xy 440.473454 -334.371245) (xy 440.455171 -334.421395)
			(xy 440.430075 -334.468507) (xy 440.398658 -334.511661) (xy 440.361531 -334.550014) (xy 440.34075 -334.566768)
			(xy 440.331998 -334.574339) (xy 440.321811 -334.595091) (xy 440.321192 -334.606646) (xy 440.321192 -334.68691)
			(xy 440.32176 -334.698478) (xy 440.331957 -334.719249) (xy 440.34075 -334.726788) (xy 440.361511 -334.743567)
			(xy 440.39864 -334.781918) (xy 440.430061 -334.82507) (xy 440.45516 -334.87218) (xy 440.473447 -334.922329)
			(xy 440.484564 -334.974538) (xy 440.488296 -335.027786) (xy 440.484568 -335.081035) (xy 440.473454 -335.133245)
			(xy 440.455171 -335.183395) (xy 440.430075 -335.230507) (xy 440.398658 -335.273661) (xy 440.361531 -335.312014)
			(xy 440.34075 -335.328768) (xy 440.331998 -335.336339) (xy 440.321811 -335.357091) (xy 440.321192 -335.368646)
			(xy 440.321192 -335.44891) (xy 440.32176 -335.460478) (xy 440.331957 -335.481249) (xy 440.34075 -335.488788)
			(xy 440.363238 -335.506973) (xy 440.402971 -335.548996) (xy 440.435908 -335.596532) (xy 440.461295 -335.648494)
			(xy 440.478551 -335.703692) (xy 440.48728 -335.760862) (xy 440.487816 -335.789778) (xy 440.48733 -335.817029)
			(xy 440.479574 -335.870977) (xy 440.464219 -335.923272) (xy 440.441577 -335.972849) (xy 440.412111 -336.018699)
			(xy 440.37642 -336.05989) (xy 440.335229 -336.095581) (xy 440.289379 -336.125047) (xy 440.239802 -336.147689)
			(xy 440.187507 -336.163044) (xy 440.133559 -336.1708) (xy 440.079057 -336.1708) (xy 440.025109 -336.163044)
			(xy 439.972814 -336.147689) (xy 439.923237 -336.125047) (xy 439.877387 -336.095581) (xy 439.836196 -336.05989)
			(xy 439.800505 -336.018699) (xy 439.771039 -335.972849) (xy 439.748397 -335.923272) (xy 439.733042 -335.870977)
			(xy 439.725286 -335.817029) (xy 439.7248 -335.789778) (xy 439.725374 -335.760863) (xy 439.734092 -335.703695)
			(xy 439.751338 -335.648497) (xy 439.77672 -335.596535) (xy 439.809653 -335.548999) (xy 439.849385 -335.50698)
			(xy 439.871866 -335.488788) (xy 439.88064 -335.481238) (xy 439.890814 -335.46047) (xy 439.891424 -335.44891)
			(xy 439.891424 -335.368646) (xy 439.890853 -335.357077) (xy 439.880662 -335.336305) (xy 439.871866 -335.328768)
			(xy 439.851061 -335.312041) (xy 439.81393 -335.273685) (xy 439.782508 -335.230527) (xy 439.757409 -335.183411)
			(xy 439.739123 -335.133255) (xy 439.728008 -335.081041) (xy 439.724279 -335.027786) (xy 437.93587 -335.027786)
			(xy 437.936969 -335.032947) (xy 437.940699 -335.086199) (xy 437.936969 -335.13945) (xy 437.925853 -335.191662)
			(xy 437.907566 -335.241814) (xy 437.882467 -335.288928) (xy 437.851045 -335.332082) (xy 437.813913 -335.370435)
			(xy 437.79313 -335.387188) (xy 437.784366 -335.394747) (xy 437.774187 -335.415509) (xy 437.773572 -335.427066)
			(xy 437.773572 -335.50733) (xy 437.774157 -335.518897) (xy 437.784339 -335.53967) (xy 437.79313 -335.547208)
			(xy 437.815624 -335.565387) (xy 437.855357 -335.60741) (xy 437.888294 -335.654948) (xy 437.91368 -335.706911)
			(xy 437.930934 -335.762111) (xy 437.939662 -335.819281) (xy 437.940196 -335.848198) (xy 437.93971 -335.875449)
			(xy 437.931954 -335.929397) (xy 437.916599 -335.981692) (xy 437.893957 -336.031269) (xy 437.864491 -336.077119)
			(xy 437.8288 -336.11831) (xy 437.787609 -336.154001) (xy 437.741759 -336.183467) (xy 437.692182 -336.206109)
			(xy 437.639887 -336.221464) (xy 437.585939 -336.22922) (xy 437.531437 -336.22922) (xy 437.477489 -336.221464)
			(xy 437.425194 -336.206109) (xy 437.375617 -336.183467) (xy 437.329767 -336.154001) (xy 437.288576 -336.11831)
			(xy 437.252885 -336.077119) (xy 437.223419 -336.031269) (xy 437.200777 -335.981692) (xy 437.185422 -335.929397)
			(xy 437.177666 -335.875449) (xy 437.17718 -335.848198) (xy 437.177667 -335.81928) (xy 437.186398 -335.762105)
			(xy 437.20366 -335.706905) (xy 437.229058 -335.654942) (xy 437.262008 -335.60741) (xy 437.301757 -335.565396)
			(xy 437.324246 -335.547208) (xy 437.333007 -335.539646) (xy 437.343189 -335.518887) (xy 437.343804 -335.50733)
			(xy 437.343804 -335.427066) (xy 437.343194 -335.415503) (xy 437.333027 -335.394732) (xy 437.324246 -335.387188)
			(xy 437.303462 -335.370437) (xy 437.266332 -335.332083) (xy 437.234912 -335.288927) (xy 437.209814 -335.241814)
			(xy 437.191528 -335.191662) (xy 437.180412 -335.13945) (xy 437.176683 -335.086199) (xy 434.361999 -335.086199)
			(xy 434.369852 -335.107735) (xy 434.380969 -335.159947) (xy 434.384699 -335.213199) (xy 434.380969 -335.26645)
			(xy 434.369853 -335.318662) (xy 434.351566 -335.368814) (xy 434.326467 -335.415928) (xy 434.295045 -335.459082)
			(xy 434.257913 -335.497435) (xy 434.23713 -335.514188) (xy 434.228366 -335.521747) (xy 434.218187 -335.542509)
			(xy 434.217572 -335.554066) (xy 434.217572 -335.63433) (xy 434.218157 -335.645897) (xy 434.228339 -335.66667)
			(xy 434.23713 -335.674208) (xy 434.259624 -335.692387) (xy 434.299357 -335.73441) (xy 434.332294 -335.781948)
			(xy 434.35768 -335.833911) (xy 434.374934 -335.889111) (xy 434.383662 -335.946281) (xy 434.384196 -335.975198)
			(xy 434.38371 -336.002449) (xy 434.375954 -336.056397) (xy 434.360599 -336.108692) (xy 434.337957 -336.158269)
			(xy 434.308491 -336.204119) (xy 434.2728 -336.24531) (xy 434.231609 -336.281001) (xy 434.185759 -336.310467)
			(xy 434.136182 -336.333109) (xy 434.083887 -336.348464) (xy 434.029939 -336.35622) (xy 433.975437 -336.35622)
			(xy 433.921489 -336.348464) (xy 433.869194 -336.333109) (xy 433.819617 -336.310467) (xy 433.773767 -336.281001)
			(xy 433.732576 -336.24531) (xy 433.696885 -336.204119) (xy 433.667419 -336.158269) (xy 433.644777 -336.108692)
			(xy 433.629422 -336.056397) (xy 433.621666 -336.002449) (xy 433.62118 -335.975198) (xy 433.621667 -335.94628)
			(xy 433.630398 -335.889105) (xy 433.64766 -335.833905) (xy 433.673058 -335.781942) (xy 433.706008 -335.73441)
			(xy 433.745757 -335.692396) (xy 433.768246 -335.674208) (xy 433.777007 -335.666646) (xy 433.787189 -335.645887)
			(xy 433.787804 -335.63433) (xy 433.787804 -335.554066) (xy 433.787194 -335.542503) (xy 433.777027 -335.521732)
			(xy 433.768246 -335.514188) (xy 433.747462 -335.497437) (xy 433.710332 -335.459083) (xy 433.678912 -335.415927)
			(xy 433.653814 -335.368814) (xy 433.635528 -335.318662) (xy 433.624412 -335.26645) (xy 433.620683 -335.213199)
			(xy 431.946299 -335.213199) (xy 431.942569 -335.26645) (xy 431.931453 -335.318662) (xy 431.913166 -335.368814)
			(xy 431.888067 -335.415928) (xy 431.856645 -335.459082) (xy 431.819513 -335.497435) (xy 431.79873 -335.514188)
			(xy 431.789966 -335.521747) (xy 431.779787 -335.542509) (xy 431.779172 -335.554066) (xy 431.779172 -335.63433)
			(xy 431.779757 -335.645897) (xy 431.789939 -335.66667) (xy 431.79873 -335.674208) (xy 431.821224 -335.692387)
			(xy 431.860957 -335.73441) (xy 431.893894 -335.781948) (xy 431.91928 -335.833911) (xy 431.936534 -335.889111)
			(xy 431.945262 -335.946281) (xy 431.945796 -335.975198) (xy 431.94531 -336.002449) (xy 431.937554 -336.056397)
			(xy 431.922199 -336.108692) (xy 431.899557 -336.158269) (xy 431.870091 -336.204119) (xy 431.8344 -336.24531)
			(xy 431.793209 -336.281001) (xy 431.747359 -336.310467) (xy 431.697782 -336.333109) (xy 431.645487 -336.348464)
			(xy 431.591539 -336.35622) (xy 431.537037 -336.35622) (xy 431.483089 -336.348464) (xy 431.430794 -336.333109)
			(xy 431.381217 -336.310467) (xy 431.335367 -336.281001) (xy 431.294176 -336.24531) (xy 431.258485 -336.204119)
			(xy 431.229019 -336.158269) (xy 431.206377 -336.108692) (xy 431.191022 -336.056397) (xy 431.183266 -336.002449)
			(xy 431.18278 -335.975198) (xy 431.183267 -335.94628) (xy 431.191998 -335.889105) (xy 431.20926 -335.833905)
			(xy 431.234658 -335.781942) (xy 431.267608 -335.73441) (xy 431.307357 -335.692396) (xy 431.329846 -335.674208)
			(xy 431.338607 -335.666646) (xy 431.348789 -335.645887) (xy 431.349404 -335.63433) (xy 431.349404 -335.554066)
			(xy 431.348794 -335.542503) (xy 431.338627 -335.521732) (xy 431.329846 -335.514188) (xy 431.309062 -335.497437)
			(xy 431.271932 -335.459083) (xy 431.240512 -335.415927) (xy 431.215414 -335.368814) (xy 431.197128 -335.318662)
			(xy 431.186012 -335.26645) (xy 431.182283 -335.213199) (xy 428.28692 -335.213199) (xy 428.288699 -335.238599)
			(xy 428.284969 -335.29185) (xy 428.273853 -335.344062) (xy 428.255566 -335.394214) (xy 428.230467 -335.441328)
			(xy 428.199045 -335.484482) (xy 428.161913 -335.522835) (xy 428.14113 -335.539588) (xy 428.132366 -335.547147)
			(xy 428.122187 -335.567909) (xy 428.121572 -335.579466) (xy 428.121572 -335.65973) (xy 428.122157 -335.671297)
			(xy 428.132339 -335.69207) (xy 428.14113 -335.699608) (xy 428.163624 -335.717787) (xy 428.203357 -335.75981)
			(xy 428.236294 -335.807348) (xy 428.26168 -335.859311) (xy 428.278934 -335.914511) (xy 428.287662 -335.971681)
			(xy 428.288196 -336.000598) (xy 428.28771 -336.027849) (xy 428.279954 -336.081797) (xy 428.264599 -336.134092)
			(xy 428.241957 -336.183669) (xy 428.212491 -336.229519) (xy 428.1768 -336.27071) (xy 428.135609 -336.306401)
			(xy 428.089759 -336.335867) (xy 428.040182 -336.358509) (xy 427.987887 -336.373864) (xy 427.933939 -336.38162)
			(xy 427.879437 -336.38162) (xy 427.825489 -336.373864) (xy 427.773194 -336.358509) (xy 427.723617 -336.335867)
			(xy 427.677767 -336.306401) (xy 427.636576 -336.27071) (xy 427.600885 -336.229519) (xy 427.571419 -336.183669)
			(xy 427.548777 -336.134092) (xy 427.533422 -336.081797) (xy 427.525666 -336.027849) (xy 427.52518 -336.000598)
			(xy 427.525667 -335.97168) (xy 427.534398 -335.914505) (xy 427.55166 -335.859305) (xy 427.577058 -335.807342)
			(xy 427.610008 -335.75981) (xy 427.649757 -335.717796) (xy 427.672246 -335.699608) (xy 427.681007 -335.692046)
			(xy 427.691189 -335.671287) (xy 427.691804 -335.65973) (xy 427.691804 -335.579466) (xy 427.691194 -335.567903)
			(xy 427.681027 -335.547132) (xy 427.672246 -335.539588) (xy 427.651462 -335.522837) (xy 427.614332 -335.484483)
			(xy 427.582912 -335.441327) (xy 427.557814 -335.394214) (xy 427.539528 -335.344062) (xy 427.528412 -335.29185)
			(xy 427.524683 -335.238599) (xy 425.824899 -335.238599) (xy 425.821169 -335.29185) (xy 425.810053 -335.344062)
			(xy 425.791766 -335.394214) (xy 425.766667 -335.441328) (xy 425.735245 -335.484482) (xy 425.698113 -335.522835)
			(xy 425.67733 -335.539588) (xy 425.668566 -335.547147) (xy 425.658387 -335.567909) (xy 425.657772 -335.579466)
			(xy 425.657772 -335.65973) (xy 425.658357 -335.671297) (xy 425.668539 -335.69207) (xy 425.67733 -335.699608)
			(xy 425.699824 -335.717787) (xy 425.739557 -335.75981) (xy 425.772494 -335.807348) (xy 425.79788 -335.859311)
			(xy 425.815134 -335.914511) (xy 425.823862 -335.971681) (xy 425.824396 -336.000598) (xy 425.82391 -336.027849)
			(xy 425.816154 -336.081797) (xy 425.800799 -336.134092) (xy 425.778157 -336.183669) (xy 425.748691 -336.229519)
			(xy 425.713 -336.27071) (xy 425.671809 -336.306401) (xy 425.625959 -336.335867) (xy 425.576382 -336.358509)
			(xy 425.524087 -336.373864) (xy 425.470139 -336.38162) (xy 425.415637 -336.38162) (xy 425.361689 -336.373864)
			(xy 425.309394 -336.358509) (xy 425.259817 -336.335867) (xy 425.213967 -336.306401) (xy 425.172776 -336.27071)
			(xy 425.137085 -336.229519) (xy 425.107619 -336.183669) (xy 425.084977 -336.134092) (xy 425.069622 -336.081797)
			(xy 425.061866 -336.027849) (xy 425.06138 -336.000598) (xy 425.061867 -335.97168) (xy 425.070598 -335.914505)
			(xy 425.08786 -335.859305) (xy 425.113258 -335.807342) (xy 425.146208 -335.75981) (xy 425.185957 -335.717796)
			(xy 425.208446 -335.699608) (xy 425.217207 -335.692046) (xy 425.227389 -335.671287) (xy 425.228004 -335.65973)
			(xy 425.228004 -335.579466) (xy 425.227394 -335.567903) (xy 425.217227 -335.547132) (xy 425.208446 -335.539588)
			(xy 425.187662 -335.522837) (xy 425.150532 -335.484483) (xy 425.119112 -335.441327) (xy 425.094014 -335.394214)
			(xy 425.075728 -335.344062) (xy 425.064612 -335.29185) (xy 425.060883 -335.238599) (xy 422.167299 -335.238599)
			(xy 422.163569 -335.29185) (xy 422.152453 -335.344062) (xy 422.134166 -335.394214) (xy 422.109067 -335.441328)
			(xy 422.077645 -335.484482) (xy 422.040513 -335.522835) (xy 422.01973 -335.539588) (xy 422.010966 -335.547147)
			(xy 422.000787 -335.567909) (xy 422.000172 -335.579466) (xy 422.000172 -335.65973) (xy 422.000757 -335.671297)
			(xy 422.010939 -335.69207) (xy 422.01973 -335.699608) (xy 422.042224 -335.717787) (xy 422.081957 -335.75981)
			(xy 422.114894 -335.807348) (xy 422.14028 -335.859311) (xy 422.157534 -335.914511) (xy 422.166262 -335.971681)
			(xy 422.166796 -336.000598) (xy 422.16631 -336.027849) (xy 422.158554 -336.081797) (xy 422.143199 -336.134092)
			(xy 422.120557 -336.183669) (xy 422.091091 -336.229519) (xy 422.0554 -336.27071) (xy 422.014209 -336.306401)
			(xy 421.968359 -336.335867) (xy 421.918782 -336.358509) (xy 421.866487 -336.373864) (xy 421.812539 -336.38162)
			(xy 421.758037 -336.38162) (xy 421.704089 -336.373864) (xy 421.651794 -336.358509) (xy 421.602217 -336.335867)
			(xy 421.556367 -336.306401) (xy 421.515176 -336.27071) (xy 421.479485 -336.229519) (xy 421.450019 -336.183669)
			(xy 421.427377 -336.134092) (xy 421.412022 -336.081797) (xy 421.404266 -336.027849) (xy 421.40378 -336.000598)
			(xy 421.404267 -335.97168) (xy 421.412998 -335.914505) (xy 421.43026 -335.859305) (xy 421.455658 -335.807342)
			(xy 421.488608 -335.75981) (xy 421.528357 -335.717796) (xy 421.550846 -335.699608) (xy 421.559607 -335.692046)
			(xy 421.569789 -335.671287) (xy 421.570404 -335.65973) (xy 421.570404 -335.579466) (xy 421.569794 -335.567903)
			(xy 421.559627 -335.547132) (xy 421.550846 -335.539588) (xy 421.530062 -335.522837) (xy 421.492932 -335.484483)
			(xy 421.461512 -335.441327) (xy 421.436414 -335.394214) (xy 421.418128 -335.344062) (xy 421.407012 -335.29185)
			(xy 421.403283 -335.238599) (xy 419.745683 -335.238599) (xy 419.750569 -335.261547) (xy 419.754299 -335.314799)
			(xy 419.750569 -335.36805) (xy 419.739453 -335.420262) (xy 419.721166 -335.470414) (xy 419.696067 -335.517528)
			(xy 419.664645 -335.560682) (xy 419.627513 -335.599035) (xy 419.60673 -335.615788) (xy 419.597966 -335.623347)
			(xy 419.587787 -335.644109) (xy 419.587172 -335.655666) (xy 419.587172 -335.73593) (xy 419.587757 -335.747497)
			(xy 419.597939 -335.76827) (xy 419.60673 -335.775808) (xy 419.629224 -335.793987) (xy 419.668957 -335.83601)
			(xy 419.701894 -335.883548) (xy 419.72728 -335.935511) (xy 419.744534 -335.990711) (xy 419.753262 -336.047881)
			(xy 419.753796 -336.076798) (xy 419.75331 -336.104049) (xy 419.745554 -336.157997) (xy 419.730199 -336.210292)
			(xy 419.707557 -336.259869) (xy 419.678091 -336.305719) (xy 419.6424 -336.34691) (xy 419.601209 -336.382601)
			(xy 419.555359 -336.412067) (xy 419.505782 -336.434709) (xy 419.453487 -336.450064) (xy 419.399539 -336.45782)
			(xy 419.345037 -336.45782) (xy 419.291089 -336.450064) (xy 419.238794 -336.434709) (xy 419.189217 -336.412067)
			(xy 419.143367 -336.382601) (xy 419.102176 -336.34691) (xy 419.066485 -336.305719) (xy 419.037019 -336.259869)
			(xy 419.014377 -336.210292) (xy 418.999022 -336.157997) (xy 418.991266 -336.104049) (xy 418.99078 -336.076798)
			(xy 418.991267 -336.04788) (xy 418.999998 -335.990705) (xy 419.01726 -335.935505) (xy 419.042658 -335.883542)
			(xy 419.075608 -335.83601) (xy 419.115357 -335.793996) (xy 419.137846 -335.775808) (xy 419.146607 -335.768246)
			(xy 419.156789 -335.747487) (xy 419.157404 -335.73593) (xy 419.157404 -335.655666) (xy 419.156794 -335.644103)
			(xy 419.146627 -335.623332) (xy 419.137846 -335.615788) (xy 419.117062 -335.599037) (xy 419.079932 -335.560683)
			(xy 419.048512 -335.517527) (xy 419.023414 -335.470414) (xy 419.005128 -335.420262) (xy 418.994012 -335.36805)
			(xy 418.990283 -335.314799) (xy 412.011621 -335.314799) (xy 409.658566 -337.667854) (xy 409.6512 -337.674966)
			(xy 409.64358 -337.693762) (xy 409.64358 -340.097364) (xy 420.754302 -340.097364) (xy 420.754746 -340.069993)
			(xy 420.762569 -340.015813) (xy 420.778064 -339.96331) (xy 420.80091 -339.913563) (xy 420.830639 -339.867597)
			(xy 420.848282 -339.846666) (xy 420.854378 -339.839554) (xy 420.860728 -339.822536) (xy 420.860728 -339.737192)
			(xy 420.854378 -339.720174) (xy 420.848282 -339.713062) (xy 420.830608 -339.692157) (xy 420.800888 -339.646183)
			(xy 420.778048 -339.596432) (xy 420.762556 -339.543926) (xy 420.754732 -339.489745) (xy 420.754736 -339.435001)
			(xy 420.762568 -339.380821) (xy 420.778067 -339.328317) (xy 420.800914 -339.278569) (xy 420.830641 -339.2326)
			(xy 420.848282 -339.211666) (xy 420.854378 -339.204554) (xy 420.860728 -339.187536) (xy 420.860728 -339.102192)
			(xy 420.854378 -339.085174) (xy 420.848282 -339.078062) (xy 420.830608 -339.057157) (xy 420.800888 -339.011183)
			(xy 420.778048 -338.961432) (xy 420.762556 -338.908926) (xy 420.754732 -338.854745) (xy 420.754736 -338.800001)
			(xy 420.762568 -338.745821) (xy 420.778067 -338.693317) (xy 420.800914 -338.643569) (xy 420.830641 -338.5976)
			(xy 420.848282 -338.576666) (xy 420.854378 -338.569554) (xy 420.860728 -338.552536) (xy 420.860728 -338.467192)
			(xy 420.854378 -338.450174) (xy 420.848282 -338.443062) (xy 420.830608 -338.422157) (xy 420.800888 -338.376183)
			(xy 420.778048 -338.326432) (xy 420.762556 -338.273926) (xy 420.754732 -338.219745) (xy 420.754736 -338.165001)
			(xy 420.762568 -338.110821) (xy 420.778067 -338.058317) (xy 420.800914 -338.008569) (xy 420.830641 -337.9626)
			(xy 420.848282 -337.941666) (xy 420.854378 -337.934554) (xy 420.860728 -337.917536) (xy 420.860728 -337.832192)
			(xy 420.854378 -337.815174) (xy 420.848282 -337.808062) (xy 420.830656 -337.78712) (xy 420.800943 -337.741149)
			(xy 420.778104 -337.691404) (xy 420.76261 -337.638906) (xy 420.754778 -337.584732) (xy 420.754302 -337.557364)
			(xy 420.754851 -337.528447) (xy 420.763578 -337.471276) (xy 420.780841 -337.41608) (xy 420.806244 -337.364124)
			(xy 420.839205 -337.316603) (xy 420.858696 -337.295236) (xy 420.865046 -337.288378) (xy 420.872158 -337.271614)
			(xy 420.875714 -337.186016) (xy 420.869872 -337.168998) (xy 420.86403 -337.161632) (xy 420.848161 -337.141195)
			(xy 420.821462 -337.096874) (xy 420.800995 -337.049352) (xy 420.787135 -336.999501) (xy 420.780137 -336.948235)
			(xy 420.779702 -336.922364) (xy 420.780144 -336.895111) (xy 420.787906 -336.841162) (xy 420.803266 -336.788865)
			(xy 420.825912 -336.739287) (xy 420.855383 -336.693437) (xy 420.891079 -336.652247) (xy 420.932274 -336.616556)
			(xy 420.978128 -336.58709) (xy 421.027709 -336.56445) (xy 421.080007 -336.549096) (xy 421.133957 -336.541341)
			(xy 421.16121 -336.540856) (xy 421.188847 -336.54137) (xy 421.243542 -336.549358) (xy 421.296512 -336.565151)
			(xy 421.346651 -336.588419) (xy 421.39291 -336.618675) (xy 421.41394 -336.636614) (xy 421.421052 -336.64271)
			(xy 421.438324 -336.649314) (xy 421.524176 -336.649314) (xy 421.541448 -336.64271) (xy 421.54856 -336.636614)
			(xy 421.56957 -336.618647) (xy 421.615825 -336.588375) (xy 421.665968 -336.565101) (xy 421.718946 -336.549313)
			(xy 421.773649 -336.541341) (xy 421.80129 -336.540856) (xy 421.828311 -336.541308) (xy 421.881813 -336.548922)
			(xy 421.933705 -336.564012) (xy 421.982947 -336.586278) (xy 422.028552 -336.615272) (xy 422.069607 -336.650414)
			(xy 422.087802 -336.670396) (xy 422.094914 -336.678778) (xy 422.113964 -336.687414) (xy 422.210738 -336.689446)
			(xy 422.230042 -336.681572) (xy 422.237408 -336.673698) (xy 422.255473 -336.655456) (xy 422.295643 -336.623484)
			(xy 422.339736 -336.597186) (xy 422.386956 -336.577035) (xy 422.436451 -336.563395) (xy 422.487328 -336.556513)
			(xy 422.512998 -336.556096) (xy 422.540251 -336.556557) (xy 422.594202 -336.564314) (xy 422.6465 -336.57967)
			(xy 422.696081 -336.602313) (xy 422.741934 -336.631781) (xy 422.783127 -336.667475) (xy 422.81882 -336.708668)
			(xy 422.848288 -336.754521) (xy 422.870931 -336.804102) (xy 422.886286 -336.8564) (xy 422.894043 -336.910351)
			(xy 422.894506 -336.937604) (xy 422.894051 -336.964863) (xy 422.886283 -337.018824) (xy 422.870918 -337.071132)
			(xy 422.84827 -337.120723) (xy 422.818798 -337.166588) (xy 422.783103 -337.207795) (xy 422.74191 -337.243507)
			(xy 422.719246 -337.25866) (xy 422.71228 -337.263513) (xy 422.701759 -337.276822) (xy 422.696195 -337.292849)
			(xy 422.695878 -337.301332) (xy 422.695878 -337.386676) (xy 422.696243 -337.395151) (xy 422.701814 -337.411163)
			(xy 422.712292 -337.424491) (xy 422.719246 -337.429348) (xy 422.741892 -337.444527) (xy 422.78309 -337.480228)
			(xy 422.818788 -337.521429) (xy 422.84826 -337.567291) (xy 422.870905 -337.61688) (xy 422.886263 -337.669187)
			(xy 422.89402 -337.723147) (xy 422.894506 -337.750404) (xy 422.894041 -337.777774) (xy 422.886223 -337.831953)
			(xy 422.870733 -337.884456) (xy 422.847891 -337.934203) (xy 422.818167 -337.98017) (xy 422.800526 -338.001102)
			(xy 422.79443 -338.008214) (xy 422.78808 -338.025232) (xy 422.78808 -338.110576) (xy 422.79443 -338.127594)
			(xy 422.800526 -338.134706) (xy 422.818173 -338.155635) (xy 422.847901 -338.201602) (xy 422.870749 -338.251349)
			(xy 422.886247 -338.303852) (xy 422.894076 -338.358032) (xy 422.894076 -338.412774) (xy 422.886245 -338.466954)
			(xy 422.870747 -338.519457) (xy 422.847898 -338.569203) (xy 422.818169 -338.61517) (xy 422.800526 -338.636102)
			(xy 422.79443 -338.643214) (xy 422.78808 -338.660232) (xy 422.78808 -338.745576) (xy 422.79443 -338.762594)
			(xy 422.800526 -338.769706) (xy 422.818185 -338.790622) (xy 422.847893 -338.836599) (xy 422.870725 -338.886351)
			(xy 422.886211 -338.938855) (xy 422.894035 -338.993034) (xy 422.894287 -339.007704) (xy 424.464734 -339.007704)
			(xy 424.465194 -338.980333) (xy 424.473012 -338.926154) (xy 424.488502 -338.87365) (xy 424.511345 -338.823903)
			(xy 424.541072 -338.777937) (xy 424.558714 -338.757006) (xy 424.56481 -338.749894) (xy 424.57116 -338.732876)
			(xy 424.57116 -338.647532) (xy 424.56481 -338.630514) (xy 424.558714 -338.623402) (xy 424.541078 -338.602466)
			(xy 424.511354 -338.556498) (xy 424.488509 -338.506753) (xy 424.473013 -338.454251) (xy 424.465184 -338.400073)
			(xy 424.465184 -338.345333) (xy 424.473012 -338.291155) (xy 424.488507 -338.238653) (xy 424.511351 -338.188907)
			(xy 424.541074 -338.142939) (xy 424.558714 -338.122006) (xy 424.56481 -338.114894) (xy 424.57116 -338.097876)
			(xy 424.57116 -338.012532) (xy 424.56481 -337.995514) (xy 424.558714 -337.988402) (xy 424.541065 -337.967478)
			(xy 424.511354 -337.921503) (xy 424.48852 -337.871754) (xy 424.473031 -337.819251) (xy 424.465206 -337.765074)
			(xy 424.464734 -337.737704) (xy 424.465222 -337.710447) (xy 424.472988 -337.656488) (xy 424.488349 -337.604182)
			(xy 424.510993 -337.554593) (xy 424.540458 -337.508727) (xy 424.576147 -337.467518) (xy 424.617333 -337.431803)
			(xy 424.639994 -337.416648) (xy 424.64699 -337.411832) (xy 424.65751 -337.398509) (xy 424.663058 -337.382465)
			(xy 424.663362 -337.373976) (xy 424.663362 -337.288632) (xy 424.662974 -337.280159) (xy 424.65741 -337.26415)
			(xy 424.646942 -337.250821) (xy 424.639994 -337.24596) (xy 424.617338 -337.230795) (xy 424.576143 -337.19509)
			(xy 424.540447 -337.153885) (xy 424.510978 -337.108021) (xy 424.488335 -337.058431) (xy 424.472978 -337.006123)
			(xy 424.46522 -336.952162) (xy 424.464734 -336.924904) (xy 424.465159 -336.897649) (xy 424.472917 -336.843695)
			(xy 424.488274 -336.791394) (xy 424.510919 -336.741811) (xy 424.540391 -336.695956) (xy 424.576089 -336.654762)
			(xy 424.617286 -336.619068) (xy 424.663144 -336.589601) (xy 424.712729 -336.566961) (xy 424.765032 -336.551609)
			(xy 424.818987 -336.543856) (xy 424.846242 -336.543396) (xy 424.875756 -336.543918) (xy 424.934079 -336.553016)
			(xy 424.990305 -336.570987) (xy 425.043092 -336.597403) (xy 425.091181 -336.631634) (xy 425.112688 -336.651854)
			(xy 425.119546 -336.658712) (xy 425.13758 -336.666078) (xy 425.226734 -336.667602) (xy 425.245022 -336.660744)
			(xy 425.252134 -336.65414) (xy 425.273317 -336.635437) (xy 425.320209 -336.603906) (xy 425.37124 -336.579635)
			(xy 425.425291 -336.563155) (xy 425.481182 -336.554826) (xy 425.509436 -336.554318) (xy 425.537075 -336.554801)
			(xy 425.591771 -336.562795) (xy 425.644742 -336.578594) (xy 425.694881 -336.601869) (xy 425.741138 -336.632133)
			(xy 425.762166 -336.650076) (xy 425.769278 -336.656172) (xy 425.78655 -336.662776) (xy 425.872402 -336.662776)
			(xy 425.889674 -336.656172) (xy 425.896786 -336.650076) (xy 425.917819 -336.632138) (xy 425.964069 -336.601863)
			(xy 426.014206 -336.578584) (xy 426.067179 -336.562789) (xy 426.121877 -336.554809) (xy 426.149516 -336.554318)
			(xy 426.17677 -336.55474) (xy 426.230724 -336.5625) (xy 426.283025 -336.577859) (xy 426.332607 -336.600506)
			(xy 426.378461 -336.629978) (xy 426.419654 -336.665676) (xy 426.455348 -336.706873) (xy 426.484815 -336.75273)
			(xy 426.507455 -336.802315) (xy 426.522809 -336.854617) (xy 426.530563 -336.908571) (xy 426.531024 -336.935826)
			(xy 426.530592 -336.963198) (xy 426.522769 -337.017379) (xy 426.507273 -337.069883) (xy 426.484423 -337.11963)
			(xy 426.45469 -337.165594) (xy 426.437044 -337.186524) (xy 426.430948 -337.193636) (xy 426.424598 -337.210654)
			(xy 426.424598 -337.295998) (xy 426.430948 -337.313016) (xy 426.437044 -337.320128) (xy 426.454711 -337.34104)
			(xy 426.484437 -337.38701) (xy 426.507283 -337.43676) (xy 426.522778 -337.489265) (xy 426.530605 -337.543447)
			(xy 426.530602 -337.598192) (xy 426.52277 -337.652373) (xy 426.507269 -337.704877) (xy 426.484418 -337.754624)
			(xy 426.454688 -337.800592) (xy 426.437044 -337.821524) (xy 426.430948 -337.828636) (xy 426.424598 -337.845654)
			(xy 426.424598 -337.930998) (xy 426.430948 -337.948016) (xy 426.437044 -337.955128) (xy 426.454711 -337.97604)
			(xy 426.484437 -338.02201) (xy 426.507283 -338.07176) (xy 426.522778 -338.124265) (xy 426.530605 -338.178447)
			(xy 426.530602 -338.233192) (xy 426.52277 -338.287373) (xy 426.507269 -338.339877) (xy 426.484418 -338.389624)
			(xy 426.454688 -338.435592) (xy 426.437044 -338.456524) (xy 426.430948 -338.463636) (xy 426.424598 -338.480654)
			(xy 426.424598 -338.565998) (xy 426.430948 -338.583016) (xy 426.437044 -338.590128) (xy 426.454711 -338.61104)
			(xy 426.484437 -338.65701) (xy 426.507283 -338.70676) (xy 426.522778 -338.759265) (xy 426.530605 -338.813447)
			(xy 426.530602 -338.868192) (xy 426.52277 -338.922373) (xy 426.507269 -338.974877) (xy 426.484418 -339.024624)
			(xy 426.454688 -339.070592) (xy 426.437044 -339.091524) (xy 426.430948 -339.098636) (xy 426.424598 -339.115654)
			(xy 426.424598 -339.200998) (xy 426.430948 -339.218016) (xy 426.437044 -339.225128) (xy 426.454711 -339.24604)
			(xy 426.484437 -339.29201) (xy 426.507283 -339.34176) (xy 426.522778 -339.394265) (xy 426.530605 -339.448447)
			(xy 426.530602 -339.503192) (xy 426.52277 -339.557373) (xy 426.507269 -339.609877) (xy 426.484418 -339.659624)
			(xy 426.454688 -339.705592) (xy 426.437044 -339.726524) (xy 426.430948 -339.733636) (xy 426.424598 -339.750654)
			(xy 426.424598 -339.835998) (xy 426.430948 -339.853016) (xy 426.437044 -339.860128) (xy 426.45467 -339.88107)
			(xy 426.484382 -339.927041) (xy 426.50722 -339.976786) (xy 426.522715 -340.029284) (xy 426.530548 -340.083458)
			(xy 426.531024 -340.110826) (xy 426.530795 -340.122764) (xy 429.05553 -340.122764) (xy 429.055968 -340.095393)
			(xy 429.063791 -340.041212) (xy 429.079287 -339.988708) (xy 429.102135 -339.938962) (xy 429.131866 -339.892997)
			(xy 429.14951 -339.872066) (xy 429.155606 -339.864954) (xy 429.161956 -339.847936) (xy 429.161956 -339.762592)
			(xy 429.155606 -339.745574) (xy 429.14951 -339.738462) (xy 429.131835 -339.717557) (xy 429.102113 -339.671584)
			(xy 429.07927 -339.621833) (xy 429.063778 -339.569327) (xy 429.055953 -339.515145) (xy 429.055957 -339.460401)
			(xy 429.063789 -339.40622) (xy 429.07929 -339.353716) (xy 429.102139 -339.303968) (xy 429.131867 -339.257999)
			(xy 429.14951 -339.237066) (xy 429.155606 -339.229954) (xy 429.161956 -339.212936) (xy 429.161956 -339.127592)
			(xy 429.155606 -339.110574) (xy 429.14951 -339.103462) (xy 429.131835 -339.082557) (xy 429.102113 -339.036584)
			(xy 429.07927 -338.986833) (xy 429.063778 -338.934327) (xy 429.055953 -338.880145) (xy 429.055957 -338.825401)
			(xy 429.063789 -338.77122) (xy 429.07929 -338.718716) (xy 429.102139 -338.668968) (xy 429.131867 -338.622999)
			(xy 429.14951 -338.602066) (xy 429.155606 -338.594954) (xy 429.161956 -338.577936) (xy 429.161956 -338.492592)
			(xy 429.155606 -338.475574) (xy 429.14951 -338.468462) (xy 429.131835 -338.447557) (xy 429.102113 -338.401584)
			(xy 429.07927 -338.351833) (xy 429.063778 -338.299327) (xy 429.055953 -338.245145) (xy 429.055957 -338.190401)
			(xy 429.063789 -338.13622) (xy 429.07929 -338.083716) (xy 429.102139 -338.033968) (xy 429.131867 -337.987999)
			(xy 429.14951 -337.967066) (xy 429.155606 -337.959954) (xy 429.161956 -337.942936) (xy 429.161956 -337.857592)
			(xy 429.155606 -337.840574) (xy 429.14951 -337.833462) (xy 429.131835 -337.812557) (xy 429.102113 -337.766584)
			(xy 429.07927 -337.716833) (xy 429.063778 -337.664327) (xy 429.055953 -337.610145) (xy 429.055957 -337.555401)
			(xy 429.063789 -337.50122) (xy 429.07929 -337.448716) (xy 429.102139 -337.398968) (xy 429.131867 -337.352999)
			(xy 429.14951 -337.332066) (xy 429.155606 -337.324954) (xy 429.161956 -337.307936) (xy 429.161956 -337.222592)
			(xy 429.155606 -337.205574) (xy 429.14951 -337.198462) (xy 429.131888 -337.177516) (xy 429.102173 -337.131547)
			(xy 429.079334 -337.081803) (xy 429.063839 -337.029306) (xy 429.056006 -336.975132) (xy 429.05553 -336.947764)
			(xy 429.055922 -336.920508) (xy 429.063684 -336.866553) (xy 429.079047 -336.814251) (xy 429.101696 -336.764669)
			(xy 429.131172 -336.718814) (xy 429.166873 -336.67762) (xy 429.208073 -336.641927) (xy 429.253934 -336.612461)
			(xy 429.303521 -336.589821) (xy 429.355825 -336.574469) (xy 429.409782 -336.566716) (xy 429.437038 -336.566256)
			(xy 429.464676 -336.566754) (xy 429.519371 -336.574746) (xy 429.572342 -336.590543) (xy 429.62248 -336.613814)
			(xy 429.668738 -336.644074) (xy 429.689768 -336.662014) (xy 429.69688 -336.66811) (xy 429.714152 -336.674714)
			(xy 429.800004 -336.674714) (xy 429.817276 -336.66811) (xy 429.824388 -336.662014) (xy 429.845425 -336.644081)
			(xy 429.891673 -336.613804) (xy 429.941809 -336.590523) (xy 429.994781 -336.574727) (xy 430.049479 -336.566747)
			(xy 430.077118 -336.566256) (xy 430.103911 -336.56672) (xy 430.15697 -336.574227) (xy 430.208459 -336.589076)
			(xy 430.257366 -336.610977) (xy 430.302732 -336.639499) (xy 430.343666 -336.674082) (xy 430.361852 -336.693764)
			(xy 430.369218 -336.702146) (xy 430.388522 -336.710782) (xy 430.486058 -336.711036) (xy 430.505616 -336.7024)
			(xy 430.512982 -336.694272) (xy 430.531135 -336.674865) (xy 430.571932 -336.640812) (xy 430.617058 -336.612745)
			(xy 430.665639 -336.591208) (xy 430.716738 -336.576616) (xy 430.769367 -336.569252) (xy 430.795938 -336.568796)
			(xy 430.82319 -336.569242) (xy 430.87714 -336.577004) (xy 430.929435 -336.592364) (xy 430.979013 -336.61501)
			(xy 431.024863 -336.644481) (xy 431.066053 -336.680176) (xy 431.101744 -336.72137) (xy 431.13121 -336.767224)
			(xy 431.15385 -336.816804) (xy 431.169205 -336.869101) (xy 431.176961 -336.923052) (xy 431.177446 -336.950304)
			(xy 431.177009 -336.97628) (xy 431.169965 -337.027751) (xy 431.155996 -337.077789) (xy 431.135359 -337.125465)
			(xy 431.108438 -337.169896) (xy 431.075731 -337.210259) (xy 431.037845 -337.245806) (xy 431.016918 -337.2612)
			(xy 431.007401 -337.268805) (xy 430.996271 -337.290438) (xy 430.995582 -337.302602) (xy 430.995582 -337.385406)
			(xy 430.996285 -337.397567) (xy 431.007414 -337.41919) (xy 431.016918 -337.426808) (xy 431.037848 -337.442196)
			(xy 431.075726 -337.47775) (xy 431.108427 -337.518117) (xy 431.135345 -337.562549) (xy 431.155982 -337.610224)
			(xy 431.169955 -337.66026) (xy 431.177007 -337.711729) (xy 431.177446 -337.737704) (xy 431.176995 -337.765075)
			(xy 431.169176 -337.819255) (xy 431.153684 -337.871759) (xy 431.130838 -337.921506) (xy 431.10111 -337.967471)
			(xy 431.083466 -337.988402) (xy 431.07737 -337.995514) (xy 431.07102 -338.012532) (xy 431.07102 -338.097876)
			(xy 431.07737 -338.114894) (xy 431.083466 -338.122006) (xy 431.101111 -338.142935) (xy 431.130836 -338.188904)
			(xy 431.153682 -338.23865) (xy 431.169178 -338.291153) (xy 431.177006 -338.345332) (xy 431.177006 -338.400074)
			(xy 431.169177 -338.454253) (xy 431.15368 -338.506755) (xy 431.130833 -338.556502) (xy 431.101107 -338.602469)
			(xy 431.083466 -338.623402) (xy 431.07737 -338.630514) (xy 431.07102 -338.647532) (xy 431.07102 -338.732876)
			(xy 431.07737 -338.749894) (xy 431.083466 -338.757006) (xy 431.101116 -338.777929) (xy 431.130827 -338.823904)
			(xy 431.153662 -338.873654) (xy 431.16915 -338.926156) (xy 431.176974 -338.980334) (xy 431.177446 -339.007704)
			(xy 432.785774 -339.007704) (xy 432.786224 -338.980333) (xy 432.794043 -338.926153) (xy 432.809535 -338.873649)
			(xy 432.832381 -338.823902) (xy 432.86211 -338.777936) (xy 432.879754 -338.757006) (xy 432.88585 -338.749894)
			(xy 432.8922 -338.732876) (xy 432.8922 -338.647532) (xy 432.88585 -338.630514) (xy 432.879754 -338.623402)
			(xy 432.862116 -338.602467) (xy 432.832389 -338.5565) (xy 432.809542 -338.506754) (xy 432.794044 -338.454252)
			(xy 432.786215 -338.400074) (xy 432.786214 -338.345332) (xy 432.794043 -338.291153) (xy 432.80954 -338.238651)
			(xy 432.832386 -338.188905) (xy 432.862112 -338.142938) (xy 432.879754 -338.122006) (xy 432.88585 -338.114894)
			(xy 432.8922 -338.097876) (xy 432.8922 -338.012532) (xy 432.88585 -337.995514) (xy 432.879754 -337.988402)
			(xy 432.862111 -337.967473) (xy 432.832398 -337.9215) (xy 432.809562 -337.871752) (xy 432.794072 -337.81925)
			(xy 432.786246 -337.765074) (xy 432.785774 -337.737704) (xy 432.786209 -337.711728) (xy 432.793252 -337.660256)
			(xy 432.807221 -337.610218) (xy 432.827858 -337.562542) (xy 432.85478 -337.51811) (xy 432.887487 -337.477747)
			(xy 432.925374 -337.442202) (xy 432.946302 -337.426808) (xy 432.955801 -337.419184) (xy 432.966944 -337.397566)
			(xy 432.967638 -337.385406) (xy 432.967638 -337.302602) (xy 432.966982 -337.290435) (xy 432.955818 -337.268813)
			(xy 432.946302 -337.2612) (xy 432.925358 -337.24583) (xy 432.887484 -337.210271) (xy 432.854787 -337.1699)
			(xy 432.827872 -337.125464) (xy 432.807238 -337.077787) (xy 432.793265 -337.02775) (xy 432.786213 -336.97628)
			(xy 432.785774 -336.950304) (xy 432.786281 -336.923054) (xy 432.794037 -336.869108) (xy 432.809391 -336.816814)
			(xy 432.83203 -336.767238) (xy 432.861494 -336.721389) (xy 432.897183 -336.680199) (xy 432.938371 -336.644507)
			(xy 432.984219 -336.615041) (xy 433.033794 -336.592398) (xy 433.086086 -336.577042) (xy 433.140032 -336.569283)
			(xy 433.167282 -336.568796) (xy 433.197081 -336.569368) (xy 433.255951 -336.578646) (xy 433.312664 -336.596962)
			(xy 433.36584 -336.623873) (xy 433.414186 -336.658722) (xy 433.43576 -336.679286) (xy 433.442872 -336.686398)
			(xy 433.460652 -336.693764) (xy 433.551076 -336.695288) (xy 433.56911 -336.68843) (xy 433.576476 -336.681572)
			(xy 433.597798 -336.662565) (xy 433.64499 -336.630391) (xy 433.69645 -336.605608) (xy 433.751028 -336.588771)
			(xy 433.807506 -336.580254) (xy 433.836064 -336.579718) (xy 433.863703 -336.580185) (xy 433.9184 -336.588182)
			(xy 433.971372 -336.603985) (xy 434.02151 -336.627264) (xy 434.067766 -336.657532) (xy 434.088794 -336.675476)
			(xy 434.095906 -336.681572) (xy 434.113178 -336.688176) (xy 434.19903 -336.688176) (xy 434.216302 -336.681572)
			(xy 434.223414 -336.675476) (xy 434.244436 -336.657525) (xy 434.290689 -336.627252) (xy 434.340829 -336.603975)
			(xy 434.393804 -336.588183) (xy 434.448504 -336.580207) (xy 434.476144 -336.579718) (xy 434.503398 -336.580137)
			(xy 434.557349 -336.5879) (xy 434.609647 -336.603262) (xy 434.659226 -336.62591) (xy 434.705077 -336.655384)
			(xy 434.746268 -336.691082) (xy 434.781958 -336.732279) (xy 434.811423 -336.778136) (xy 434.834062 -336.827719)
			(xy 434.849415 -336.88002) (xy 434.857168 -336.933972) (xy 434.857652 -336.961226) (xy 434.857213 -336.988597)
			(xy 434.84939 -337.042778) (xy 434.833896 -337.095282) (xy 434.811048 -337.145028) (xy 434.781317 -337.190994)
			(xy 434.763672 -337.211924) (xy 434.757576 -337.219036) (xy 434.751226 -337.236054) (xy 434.751226 -337.321398)
			(xy 434.757576 -337.338416) (xy 434.763672 -337.345528) (xy 434.781338 -337.36644) (xy 434.811062 -337.412411)
			(xy 434.833906 -337.462161) (xy 434.8494 -337.514666) (xy 434.857226 -337.568848) (xy 434.857224 -337.623591)
			(xy 434.849392 -337.677772) (xy 434.833892 -337.730276) (xy 434.811043 -337.780023) (xy 434.781315 -337.825991)
			(xy 434.763672 -337.846924) (xy 434.757576 -337.854036) (xy 434.751226 -337.871054) (xy 434.751226 -337.956398)
			(xy 434.757576 -337.973416) (xy 434.763672 -337.980528) (xy 434.781338 -338.00144) (xy 434.811062 -338.047411)
			(xy 434.833906 -338.097161) (xy 434.8494 -338.149666) (xy 434.857226 -338.203848) (xy 434.857224 -338.258591)
			(xy 434.849392 -338.312772) (xy 434.833892 -338.365276) (xy 434.811043 -338.415023) (xy 434.781315 -338.460991)
			(xy 434.763672 -338.481924) (xy 434.757576 -338.489036) (xy 434.751226 -338.506054) (xy 434.751226 -338.591398)
			(xy 434.757576 -338.608416) (xy 434.763672 -338.615528) (xy 434.781338 -338.63644) (xy 434.811062 -338.682411)
			(xy 434.833906 -338.732161) (xy 434.8494 -338.784666) (xy 434.857226 -338.838848) (xy 434.857224 -338.893591)
			(xy 434.849392 -338.947772) (xy 434.833892 -339.000276) (xy 434.811043 -339.050023) (xy 434.781315 -339.095991)
			(xy 434.763672 -339.116924) (xy 434.757576 -339.124036) (xy 434.751226 -339.141054) (xy 434.751226 -339.226398)
			(xy 434.757576 -339.243416) (xy 434.763672 -339.250528) (xy 434.781338 -339.27144) (xy 434.811062 -339.317411)
			(xy 434.833906 -339.367161) (xy 434.8494 -339.419666) (xy 434.857226 -339.473848) (xy 434.857224 -339.528591)
			(xy 434.849392 -339.582772) (xy 434.833892 -339.635276) (xy 434.811043 -339.685023) (xy 434.781315 -339.730991)
			(xy 434.763672 -339.751924) (xy 434.757576 -339.759036) (xy 434.751226 -339.776054) (xy 434.751226 -339.861398)
			(xy 434.757576 -339.878416) (xy 434.763672 -339.885528) (xy 434.781286 -339.90648) (xy 434.811003 -339.952447)
			(xy 434.833844 -340.002189) (xy 434.849341 -340.054686) (xy 434.857175 -340.108858) (xy 434.857386 -340.120986)
			(xy 435.837076 -340.120986) (xy 435.837515 -340.093615) (xy 435.845337 -340.039434) (xy 435.860831 -339.98693)
			(xy 435.883679 -339.937183) (xy 435.913411 -339.891218) (xy 435.931056 -339.870288) (xy 435.937152 -339.863176)
			(xy 435.943502 -339.846158) (xy 435.943502 -339.760814) (xy 435.937152 -339.743796) (xy 435.931056 -339.736684)
			(xy 435.9134 -339.715763) (xy 435.883674 -339.669794) (xy 435.860828 -339.620046) (xy 435.845331 -339.567542)
			(xy 435.837503 -339.513361) (xy 435.837505 -339.458618) (xy 435.845336 -339.404438) (xy 435.860835 -339.351934)
			(xy 435.883684 -339.302188) (xy 435.913413 -339.25622) (xy 435.931056 -339.235288) (xy 435.937152 -339.228176)
			(xy 435.943502 -339.211158) (xy 435.943502 -339.125814) (xy 435.937152 -339.108796) (xy 435.931056 -339.101684)
			(xy 435.9134 -339.080763) (xy 435.883674 -339.034794) (xy 435.860828 -338.985046) (xy 435.845331 -338.932542)
			(xy 435.837503 -338.878361) (xy 435.837505 -338.823618) (xy 435.845336 -338.769438) (xy 435.860835 -338.716934)
			(xy 435.883684 -338.667188) (xy 435.913413 -338.62122) (xy 435.931056 -338.600288) (xy 435.937152 -338.593176)
			(xy 435.943502 -338.576158) (xy 435.943502 -338.490814) (xy 435.937152 -338.473796) (xy 435.931056 -338.466684)
			(xy 435.9134 -338.445763) (xy 435.883674 -338.399794) (xy 435.860828 -338.350046) (xy 435.845331 -338.297542)
			(xy 435.837503 -338.243361) (xy 435.837505 -338.188618) (xy 435.845336 -338.134438) (xy 435.860835 -338.081934)
			(xy 435.883684 -338.032188) (xy 435.913413 -337.98622) (xy 435.931056 -337.965288) (xy 435.937152 -337.958176)
			(xy 435.943502 -337.941158) (xy 435.943502 -337.855814) (xy 435.937152 -337.838796) (xy 435.931056 -337.831684)
			(xy 435.9134 -337.810763) (xy 435.883674 -337.764794) (xy 435.860828 -337.715046) (xy 435.845331 -337.662542)
			(xy 435.837503 -337.608361) (xy 435.837505 -337.553618) (xy 435.845336 -337.499438) (xy 435.860835 -337.446934)
			(xy 435.883684 -337.397188) (xy 435.913413 -337.35122) (xy 435.931056 -337.330288) (xy 435.937152 -337.323176)
			(xy 435.943502 -337.306158) (xy 435.943502 -337.220814) (xy 435.937152 -337.203796) (xy 435.931056 -337.196684)
			(xy 435.913436 -337.175737) (xy 435.883722 -337.129768) (xy 435.860883 -337.080024) (xy 435.845388 -337.027527)
			(xy 435.837553 -336.973354) (xy 435.837076 -336.945986) (xy 435.837565 -336.918735) (xy 435.845323 -336.864788)
			(xy 435.860679 -336.812495) (xy 435.88332 -336.762918) (xy 435.912787 -336.717069) (xy 435.948478 -336.675879)
			(xy 435.989667 -336.640188) (xy 436.035517 -336.610721) (xy 436.085093 -336.58808) (xy 436.137386 -336.572723)
			(xy 436.191333 -336.564965) (xy 436.218584 -336.564478) (xy 436.246221 -336.565002) (xy 436.300915 -336.572987)
			(xy 436.353886 -336.588777) (xy 436.404025 -336.612043) (xy 436.450284 -336.642298) (xy 436.471314 -336.660236)
			(xy 436.478426 -336.666332) (xy 436.495698 -336.672936) (xy 436.58155 -336.672936) (xy 436.598822 -336.666332)
			(xy 436.605934 -336.660236) (xy 436.626943 -336.642269) (xy 436.6732 -336.612) (xy 436.723343 -336.588727)
			(xy 436.776321 -336.572938) (xy 436.831024 -336.564965) (xy 436.858664 -336.564478) (xy 436.885915 -336.564989)
			(xy 436.939864 -336.57274) (xy 436.99216 -336.588091) (xy 437.041739 -336.610729) (xy 437.087592 -336.640191)
			(xy 437.128784 -336.67588) (xy 437.164479 -336.717068) (xy 437.193947 -336.762917) (xy 437.216591 -336.812493)
			(xy 437.231949 -336.864787) (xy 437.239708 -336.918735) (xy 437.240172 -336.945986) (xy 437.239705 -336.973356)
			(xy 437.231888 -337.027536) (xy 437.2164 -337.080039) (xy 437.193558 -337.129786) (xy 437.163833 -337.175752)
			(xy 437.146192 -337.196684) (xy 437.140096 -337.203796) (xy 437.133746 -337.220814) (xy 437.133746 -337.306158)
			(xy 437.140096 -337.323176) (xy 437.146192 -337.330288) (xy 437.163818 -337.351232) (xy 437.193542 -337.397198)
			(xy 437.216387 -337.446943) (xy 437.231884 -337.499443) (xy 437.239713 -337.55362) (xy 437.239715 -337.608359)
			(xy 437.231888 -337.662536) (xy 437.216395 -337.715037) (xy 437.193552 -337.764783) (xy 437.163831 -337.810751)
			(xy 437.146192 -337.831684) (xy 437.140096 -337.838796) (xy 437.133746 -337.855814) (xy 437.133746 -337.941158)
			(xy 437.140096 -337.958176) (xy 437.146192 -337.965288) (xy 437.163818 -337.986232) (xy 437.193542 -338.032198)
			(xy 437.216387 -338.081943) (xy 437.231884 -338.134443) (xy 437.239713 -338.18862) (xy 437.239715 -338.243359)
			(xy 437.231888 -338.297536) (xy 437.216395 -338.350037) (xy 437.193552 -338.399783) (xy 437.163831 -338.445751)
			(xy 437.146192 -338.466684) (xy 437.140096 -338.473796) (xy 437.133746 -338.490814) (xy 437.133746 -338.576158)
			(xy 437.140096 -338.593176) (xy 437.146192 -338.600288) (xy 437.163818 -338.621232) (xy 437.193542 -338.667198)
			(xy 437.216387 -338.716943) (xy 437.231884 -338.769443) (xy 437.239713 -338.82362) (xy 437.239715 -338.878359)
			(xy 437.231888 -338.932536) (xy 437.216395 -338.985037) (xy 437.193552 -339.034783) (xy 437.163831 -339.080751)
			(xy 437.146192 -339.101684) (xy 437.140096 -339.108796) (xy 437.133746 -339.125814) (xy 437.133746 -339.211158)
			(xy 437.140096 -339.228176) (xy 437.146192 -339.235288) (xy 437.163818 -339.256232) (xy 437.193542 -339.302198)
			(xy 437.216387 -339.351943) (xy 437.231884 -339.404443) (xy 437.239713 -339.45862) (xy 437.239715 -339.513359)
			(xy 437.231888 -339.567536) (xy 437.216395 -339.620037) (xy 437.193552 -339.669783) (xy 437.163831 -339.715751)
			(xy 437.146192 -339.736684) (xy 437.140096 -339.743796) (xy 437.133746 -339.760814) (xy 437.133746 -339.846158)
			(xy 437.140096 -339.863176) (xy 437.146192 -339.870288) (xy 437.163838 -339.891215) (xy 437.193549 -339.937189)
			(xy 437.216384 -339.986938) (xy 437.231873 -340.03944) (xy 437.239699 -340.093616) (xy 437.240172 -340.120986)
			(xy 437.239659 -340.148188) (xy 437.231907 -340.202038) (xy 437.216586 -340.254242) (xy 437.194007 -340.30374)
			(xy 437.164628 -340.349531) (xy 437.129044 -340.390686) (xy 437.087977 -340.42637) (xy 437.042258 -340.455861)
			(xy 436.992814 -340.47856) (xy 436.966868 -340.486746) (xy 436.9562 -340.490048) (xy 436.939944 -340.503764)
			(xy 436.898288 -340.592664) (xy 436.89778 -340.614) (xy 436.902352 -340.62416) (xy 436.91203 -340.647897)
			(xy 436.925611 -340.697328) (xy 436.932439 -340.748134) (xy 436.932832 -340.773766) (xy 436.932363 -340.801136)
			(xy 436.924548 -340.855316) (xy 436.909061 -340.90782) (xy 436.886219 -340.957567) (xy 436.856494 -341.003533)
			(xy 436.838852 -341.024464) (xy 436.832756 -341.031576) (xy 436.826406 -341.048594) (xy 436.826406 -341.133938)
			(xy 436.832756 -341.150956) (xy 436.838852 -341.158068) (xy 436.856482 -341.179007) (xy 436.886197 -341.224977)
			(xy 436.909035 -341.274723) (xy 436.924528 -341.327222) (xy 436.932358 -341.381397) (xy 436.932832 -341.408766)
			(xy 436.932346 -341.436017) (xy 436.92459 -341.489965) (xy 436.909235 -341.54226) (xy 436.886593 -341.591837)
			(xy 436.857127 -341.637687) (xy 436.821436 -341.678878) (xy 436.780245 -341.714569) (xy 436.734395 -341.744035)
			(xy 436.684818 -341.766677) (xy 436.632523 -341.782032) (xy 436.578575 -341.789788) (xy 436.524073 -341.789788)
			(xy 436.470125 -341.782032) (xy 436.41783 -341.766677) (xy 436.368253 -341.744035) (xy 436.322403 -341.714569)
			(xy 436.281212 -341.678878) (xy 436.245521 -341.637687) (xy 436.216055 -341.591837) (xy 436.193413 -341.54226)
			(xy 436.178058 -341.489965) (xy 436.170302 -341.436017) (xy 436.169816 -341.408766) (xy 436.170258 -341.381395)
			(xy 436.178081 -341.327215) (xy 436.193576 -341.274711) (xy 436.216423 -341.224965) (xy 436.246152 -341.178999)
			(xy 436.263796 -341.158068) (xy 436.269892 -341.150956) (xy 436.276242 -341.133938) (xy 436.276242 -341.048594)
			(xy 436.269892 -341.031576) (xy 436.263796 -341.024464) (xy 436.246173 -341.003519) (xy 436.216459 -340.95755)
			(xy 436.19362 -340.907806) (xy 436.178125 -340.855308) (xy 436.170292 -340.801134) (xy 436.169816 -340.773766)
			(xy 436.170198 -340.74901) (xy 436.176577 -340.69991) (xy 436.189251 -340.652046) (xy 436.198264 -340.628986)
			(xy 436.202582 -340.618572) (xy 436.201566 -340.596474) (xy 436.156608 -340.508082) (xy 436.139082 -340.494366)
			(xy 436.128414 -340.491572) (xy 436.1011 -340.484369) (xy 436.04878 -340.463081) (xy 436.000172 -340.434309)
			(xy 435.956338 -340.398684) (xy 435.918238 -340.356983) (xy 435.886704 -340.31012) (xy 435.862426 -340.259118)
			(xy 435.845936 -340.205094) (xy 435.837593 -340.149228) (xy 435.837076 -340.120986) (xy 434.857386 -340.120986)
			(xy 434.857652 -340.136226) (xy 434.857149 -340.164182) (xy 434.848973 -340.219492) (xy 434.832815 -340.273018)
			(xy 434.80902 -340.323614) (xy 434.778097 -340.370196) (xy 434.740709 -340.411768) (xy 434.697655 -340.44744)
			(xy 434.67401 -340.462362) (xy 434.66385 -340.468458) (xy 434.65115 -340.488016) (xy 434.638958 -340.590632)
			(xy 434.646324 -340.61273) (xy 434.654706 -340.621112) (xy 434.675432 -340.642729) (xy 434.710608 -340.691193)
			(xy 434.737775 -340.744559) (xy 434.756266 -340.801517) (xy 434.765626 -340.860664) (xy 434.766212 -340.890606)
			(xy 434.765747 -340.917976) (xy 434.757928 -340.972155) (xy 434.742439 -341.024658) (xy 434.719597 -341.074405)
			(xy 434.689873 -341.120372) (xy 434.672232 -341.141304) (xy 434.666136 -341.148416) (xy 434.659786 -341.165434)
			(xy 434.659786 -341.250778) (xy 434.666136 -341.267796) (xy 434.672232 -341.274908) (xy 434.689893 -341.295822)
			(xy 434.719601 -341.3418) (xy 434.742432 -341.391552) (xy 434.757918 -341.444057) (xy 434.765741 -341.498236)
			(xy 434.766212 -341.525606) (xy 434.765726 -341.552857) (xy 434.75797 -341.606805) (xy 434.742615 -341.6591)
			(xy 434.719973 -341.708677) (xy 434.690507 -341.754527) (xy 434.654816 -341.795718) (xy 434.613625 -341.831409)
			(xy 434.567775 -341.860875) (xy 434.518198 -341.883517) (xy 434.465903 -341.898872) (xy 434.411955 -341.906628)
			(xy 434.357453 -341.906628) (xy 434.303505 -341.898872) (xy 434.25121 -341.883517) (xy 434.201633 -341.860875)
			(xy 434.155783 -341.831409) (xy 434.114592 -341.795718) (xy 434.078901 -341.754527) (xy 434.049435 -341.708677)
			(xy 434.026793 -341.6591) (xy 434.011438 -341.606805) (xy 434.003682 -341.552857) (xy 434.003196 -341.525606)
			(xy 434.003667 -341.498236) (xy 434.011483 -341.444057) (xy 434.026972 -341.391554) (xy 434.049812 -341.341807)
			(xy 434.079535 -341.29584) (xy 434.097176 -341.274908) (xy 434.103272 -341.267796) (xy 434.109622 -341.250778)
			(xy 434.109622 -341.165434) (xy 434.103272 -341.148416) (xy 434.097176 -341.141304) (xy 434.079522 -341.120384)
			(xy 434.049813 -341.074408) (xy 434.02698 -341.024657) (xy 434.011493 -340.972154) (xy 434.003668 -340.917976)
			(xy 434.003196 -340.890606) (xy 434.0037 -340.863827) (xy 434.011197 -340.810795) (xy 434.026031 -340.759332)
			(xy 434.04791 -340.710446) (xy 434.076406 -340.665097) (xy 434.11096 -340.624175) (xy 434.150892 -340.588483)
			(xy 434.195421 -340.558721) (xy 434.21935 -340.54669) (xy 434.226894 -340.542743) (xy 434.238981 -340.530762)
			(xy 434.246458 -340.515475) (xy 434.247798 -340.507066) (xy 434.255164 -340.447122) (xy 434.234336 -340.431374)
			(xy 434.226716 -340.425024) (xy 434.208174 -340.419182) (xy 434.118512 -340.42604) (xy 434.100986 -340.434676)
			(xy 434.094382 -340.442042) (xy 434.076221 -340.461583) (xy 434.035386 -340.495913) (xy 433.990166 -340.524215)
			(xy 433.941442 -340.545939) (xy 433.890165 -340.56066) (xy 433.837338 -340.568091) (xy 433.810664 -340.568534)
			(xy 433.783413 -340.568056) (xy 433.729466 -340.560295) (xy 433.677173 -340.544937) (xy 433.627597 -340.522293)
			(xy 433.581749 -340.492826) (xy 433.540559 -340.457134) (xy 433.504868 -340.415943) (xy 433.475402 -340.370094)
			(xy 433.45276 -340.320517) (xy 433.437403 -340.268224) (xy 433.429644 -340.214277) (xy 433.429156 -340.187026)
			(xy 433.429624 -340.159656) (xy 433.437439 -340.105476) (xy 433.452927 -340.052972) (xy 433.475769 -340.003226)
			(xy 433.505494 -339.957259) (xy 433.523136 -339.936328) (xy 433.529232 -339.929216) (xy 433.535582 -339.912198)
			(xy 433.535582 -339.826854) (xy 433.529232 -339.809836) (xy 433.523136 -339.802724) (xy 433.5055 -339.781789)
			(xy 433.475787 -339.735818) (xy 433.45295 -339.686071) (xy 433.437458 -339.633571) (xy 433.42963 -339.579395)
			(xy 433.429156 -339.552026) (xy 433.429345 -339.533816) (xy 433.432778 -339.497558) (xy 433.436014 -339.479636)
			(xy 433.438808 -339.46592) (xy 433.429664 -339.440266) (xy 433.340764 -339.364828) (xy 433.31384 -339.360256)
			(xy 433.300886 -339.365082) (xy 433.268631 -339.376312) (xy 433.201427 -339.388452) (xy 433.167282 -339.389212)
			(xy 433.14003 -339.388739) (xy 433.086083 -339.38098) (xy 433.033788 -339.365623) (xy 432.984211 -339.34298)
			(xy 432.938361 -339.313512) (xy 432.897171 -339.277819) (xy 432.861479 -339.236628) (xy 432.832013 -339.190777)
			(xy 432.809372 -339.141199) (xy 432.794017 -339.088904) (xy 432.78626 -339.034956) (xy 432.785774 -339.007704)
			(xy 431.177446 -339.007704) (xy 431.176926 -339.034954) (xy 431.16917 -339.088898) (xy 431.153816 -339.14119)
			(xy 431.131177 -339.190765) (xy 431.101714 -339.236613) (xy 431.066026 -339.277802) (xy 431.02484 -339.313494)
			(xy 430.978995 -339.342961) (xy 430.929422 -339.365604) (xy 430.877131 -339.380963) (xy 430.823188 -339.388724)
			(xy 430.795938 -339.389212) (xy 430.769797 -339.388796) (xy 430.718005 -339.381658) (xy 430.667673 -339.367512)
			(xy 430.643538 -339.357462) (xy 430.63033 -339.35162) (xy 430.602898 -339.35543) (xy 430.510188 -339.428836)
			(xy 430.500536 -339.454998) (xy 430.503076 -339.468968) (xy 430.506064 -339.486211) (xy 430.509241 -339.521065)
			(xy 430.509426 -339.538564) (xy 430.508957 -339.565934) (xy 430.501143 -339.620114) (xy 430.485655 -339.672618)
			(xy 430.462814 -339.722365) (xy 430.433088 -339.768331) (xy 430.415446 -339.789262) (xy 430.40935 -339.796374)
			(xy 430.403 -339.813392) (xy 430.403 -339.898736) (xy 430.40935 -339.915754) (xy 430.415446 -339.922866)
			(xy 430.433074 -339.943807) (xy 430.46279 -339.989777) (xy 430.485628 -340.039522) (xy 430.501122 -340.092021)
			(xy 430.508952 -340.146195) (xy 430.509426 -340.173564) (xy 430.508911 -340.200815) (xy 430.50116 -340.254763)
			(xy 430.485809 -340.307059) (xy 430.463172 -340.356638) (xy 430.43371 -340.40249) (xy 430.398021 -340.443683)
			(xy 430.356834 -340.479377) (xy 430.310985 -340.508846) (xy 430.26141 -340.53149) (xy 430.209116 -340.546848)
			(xy 430.155169 -340.554607) (xy 430.127918 -340.555072) (xy 430.100148 -340.554573) (xy 430.045195 -340.546522)
			(xy 429.99199 -340.530587) (xy 429.941659 -340.507104) (xy 429.895264 -340.476571) (xy 429.853788 -340.439633)
			(xy 429.835564 -340.418674) (xy 429.82896 -340.410546) (xy 429.810926 -340.401402) (xy 429.7172 -340.394544)
			(xy 429.69815 -340.401148) (xy 429.690276 -340.408006) (xy 429.669251 -340.426064) (xy 429.622928 -340.45649)
			(xy 429.572688 -340.479887) (xy 429.519588 -340.495762) (xy 429.464749 -340.503779) (xy 429.437038 -340.504272)
			(xy 429.409784 -340.503809) (xy 429.355832 -340.496057) (xy 429.303532 -340.480703) (xy 429.253949 -340.458063)
			(xy 429.208094 -340.428595) (xy 429.1669 -340.392901) (xy 429.131206 -340.351707) (xy 429.101738 -340.305853)
			(xy 429.079097 -340.25627) (xy 429.063744 -340.20397) (xy 429.055991 -340.150018) (xy 429.05553 -340.122764)
			(xy 426.530795 -340.122764) (xy 426.530452 -340.140666) (xy 426.521195 -340.199624) (xy 426.50285 -340.256414)
			(xy 426.489876 -340.283292) (xy 426.484542 -340.293706) (xy 426.484034 -340.317074) (xy 426.52823 -340.411054)
			(xy 426.546264 -340.425532) (xy 426.557948 -340.428326) (xy 426.585683 -340.43513) (xy 426.638853 -340.45597)
			(xy 426.688319 -340.484506) (xy 426.732978 -340.520099) (xy 426.771829 -340.561954) (xy 426.804004 -340.609135)
			(xy 426.828784 -340.660586) (xy 426.845614 -340.715157) (xy 426.854118 -340.771628) (xy 426.85462 -340.800182)
			(xy 426.854163 -340.827553) (xy 426.846346 -340.881733) (xy 426.830856 -340.934237) (xy 426.808012 -340.983984)
			(xy 426.778283 -341.029949) (xy 426.76064 -341.05088) (xy 426.754544 -341.057992) (xy 426.748194 -341.07501)
			(xy 426.748194 -341.160354) (xy 426.754544 -341.177372) (xy 426.76064 -341.184484) (xy 426.778292 -341.205406)
			(xy 426.808 -341.251382) (xy 426.830833 -341.301132) (xy 426.846322 -341.353635) (xy 426.850763 -341.384382)
			(xy 428.175928 -341.384382) (xy 428.176377 -341.357011) (xy 428.184198 -341.302831) (xy 428.19969 -341.250327)
			(xy 428.222536 -341.200581) (xy 428.252265 -341.154615) (xy 428.269908 -341.133684) (xy 428.276004 -341.126572)
			(xy 428.282354 -341.109554) (xy 428.282354 -341.02421) (xy 428.276004 -341.007192) (xy 428.269908 -341.00008)
			(xy 428.252294 -340.979128) (xy 428.222578 -340.93316) (xy 428.199737 -340.883418) (xy 428.18424 -340.830922)
			(xy 428.176406 -340.77675) (xy 428.175928 -340.749382) (xy 428.176414 -340.722131) (xy 428.18417 -340.668183)
			(xy 428.199525 -340.615888) (xy 428.222167 -340.566311) (xy 428.251633 -340.520461) (xy 428.287324 -340.47927)
			(xy 428.328515 -340.443579) (xy 428.374365 -340.414113) (xy 428.423942 -340.391471) (xy 428.476237 -340.376116)
			(xy 428.530185 -340.36836) (xy 428.584687 -340.36836) (xy 428.638635 -340.376116) (xy 428.69093 -340.391471)
			(xy 428.740507 -340.414113) (xy 428.786357 -340.443579) (xy 428.827548 -340.47927) (xy 428.863239 -340.520461)
			(xy 428.892705 -340.566311) (xy 428.915347 -340.615888) (xy 428.930702 -340.668183) (xy 428.938458 -340.722131)
			(xy 428.938944 -340.749382) (xy 428.938481 -340.776752) (xy 428.930665 -340.830932) (xy 428.915176 -340.883436)
			(xy 428.892333 -340.933183) (xy 428.862606 -340.979149) (xy 428.844964 -341.00008) (xy 428.838868 -341.007192)
			(xy 428.832518 -341.02421) (xy 428.832518 -341.109554) (xy 428.838868 -341.126572) (xy 428.844964 -341.133684)
			(xy 428.862603 -341.154616) (xy 428.892316 -341.200588) (xy 428.915153 -341.250336) (xy 428.930644 -341.302837)
			(xy 428.938471 -341.357013) (xy 428.938944 -341.384382) (xy 428.938458 -341.411633) (xy 428.930702 -341.465581)
			(xy 428.915347 -341.517876) (xy 428.892705 -341.567453) (xy 428.863239 -341.613303) (xy 428.827548 -341.654494)
			(xy 428.786357 -341.690185) (xy 428.740507 -341.719651) (xy 428.69093 -341.742293) (xy 428.638635 -341.757648)
			(xy 428.584687 -341.765404) (xy 428.530185 -341.765404) (xy 428.476237 -341.757648) (xy 428.423942 -341.742293)
			(xy 428.374365 -341.719651) (xy 428.328515 -341.690185) (xy 428.287324 -341.654494) (xy 428.251633 -341.613303)
			(xy 428.222167 -341.567453) (xy 428.199525 -341.517876) (xy 428.18417 -341.465581) (xy 428.176414 -341.411633)
			(xy 428.175928 -341.384382) (xy 426.850763 -341.384382) (xy 426.854148 -341.407812) (xy 426.85462 -341.435182)
			(xy 426.854134 -341.462433) (xy 426.846378 -341.516381) (xy 426.831023 -341.568676) (xy 426.808381 -341.618253)
			(xy 426.778915 -341.664103) (xy 426.743224 -341.705294) (xy 426.702033 -341.740985) (xy 426.656183 -341.770451)
			(xy 426.606606 -341.793093) (xy 426.554311 -341.808448) (xy 426.500363 -341.816204) (xy 426.445861 -341.816204)
			(xy 426.391913 -341.808448) (xy 426.339618 -341.793093) (xy 426.290041 -341.770451) (xy 426.244191 -341.740985)
			(xy 426.203 -341.705294) (xy 426.167309 -341.664103) (xy 426.137843 -341.618253) (xy 426.115201 -341.568676)
			(xy 426.099846 -341.516381) (xy 426.09209 -341.462433) (xy 426.091604 -341.435182) (xy 426.092059 -341.407811)
			(xy 426.099879 -341.353632) (xy 426.115371 -341.301128) (xy 426.138215 -341.251382) (xy 426.167942 -341.205415)
			(xy 426.185584 -341.184484) (xy 426.19168 -341.177372) (xy 426.19803 -341.160354) (xy 426.19803 -341.07501)
			(xy 426.19168 -341.057992) (xy 426.185584 -341.05088) (xy 426.167966 -341.029931) (xy 426.138252 -340.983962)
			(xy 426.115412 -340.934219) (xy 426.099916 -340.881722) (xy 426.092082 -340.82755) (xy 426.091604 -340.800182)
			(xy 426.092176 -340.770342) (xy 426.101432 -340.711384) (xy 426.119778 -340.654594) (xy 426.132752 -340.627716)
			(xy 426.138086 -340.617302) (xy 426.138594 -340.593934) (xy 426.094398 -340.499954) (xy 426.076364 -340.485476)
			(xy 426.06468 -340.482682) (xy 426.036135 -340.475641) (xy 425.981486 -340.453963) (xy 425.930807 -340.424163)
			(xy 425.907708 -340.405974) (xy 425.900088 -340.399624) (xy 425.881546 -340.393782) (xy 425.791884 -340.40064)
			(xy 425.774358 -340.409276) (xy 425.767754 -340.416642) (xy 425.749607 -340.436197) (xy 425.708769 -340.470525)
			(xy 425.663546 -340.498826) (xy 425.614819 -340.520548) (xy 425.56354 -340.535266) (xy 425.510711 -340.542693)
			(xy 425.484036 -340.543134) (xy 425.456785 -340.542611) (xy 425.402838 -340.53486) (xy 425.350543 -340.51951)
			(xy 425.300964 -340.496873) (xy 425.255112 -340.467411) (xy 425.21392 -340.431724) (xy 425.178226 -340.390537)
			(xy 425.148756 -340.34469) (xy 425.126112 -340.295116) (xy 425.110753 -340.242823) (xy 425.102993 -340.188877)
			(xy 425.102528 -340.161626) (xy 425.103002 -340.134256) (xy 425.110817 -340.080077) (xy 425.126304 -340.027574)
			(xy 425.149144 -339.977827) (xy 425.178867 -339.93186) (xy 425.196508 -339.910928) (xy 425.202604 -339.903816)
			(xy 425.208954 -339.886798) (xy 425.208954 -339.801454) (xy 425.202604 -339.784436) (xy 425.196508 -339.777324)
			(xy 425.178868 -339.756393) (xy 425.149156 -339.71042) (xy 425.12632 -339.660672) (xy 425.110829 -339.608171)
			(xy 425.103002 -339.553995) (xy 425.102528 -339.526626) (xy 425.102647 -339.514206) (xy 425.1043 -339.489422)
			(xy 425.10583 -339.477096) (xy 425.107608 -339.463888) (xy 425.097702 -339.439504) (xy 425.010072 -339.36813)
			(xy 424.984164 -339.363558) (xy 424.971718 -339.36813) (xy 424.941292 -339.377996) (xy 424.878221 -339.388602)
			(xy 424.846242 -339.389212) (xy 424.81899 -339.388706) (xy 424.765041 -339.380954) (xy 424.712744 -339.365604)
			(xy 424.663165 -339.342967) (xy 424.617312 -339.313503) (xy 424.576118 -339.277814) (xy 424.540424 -339.236625)
			(xy 424.510955 -339.190776) (xy 424.488312 -339.141199) (xy 424.472955 -339.088904) (xy 424.465198 -339.034956)
			(xy 424.464734 -339.007704) (xy 422.894287 -339.007704) (xy 422.894506 -339.020404) (xy 422.894026 -339.047655)
			(xy 422.886269 -339.101603) (xy 422.870913 -339.153898) (xy 422.848271 -339.203476) (xy 422.818804 -339.249326)
			(xy 422.783112 -339.290517) (xy 422.741922 -339.326208) (xy 422.696071 -339.355674) (xy 422.646493 -339.378315)
			(xy 422.594198 -339.39367) (xy 422.540249 -339.401426) (xy 422.512998 -339.401912) (xy 422.486081 -339.4015)
			(xy 422.432782 -339.393939) (xy 422.381077 -339.378954) (xy 422.331995 -339.356843) (xy 422.286512 -339.328046)
			(xy 422.245533 -339.293135) (xy 422.209874 -339.252807) (xy 422.180244 -339.207861) (xy 422.16832 -339.183726)
			(xy 422.162646 -339.173243) (xy 422.143819 -339.15867) (xy 422.132252 -339.155786) (xy 422.074594 -339.144356)
			(xy 422.068084 -339.15171) (xy 422.060625 -339.169856) (xy 422.060116 -339.179662) (xy 422.060116 -339.211666)
			(xy 422.060573 -339.221484) (xy 422.068038 -339.239648) (xy 422.074594 -339.246972) (xy 422.094761 -339.268477)
			(xy 422.128905 -339.316536) (xy 422.155252 -339.369274) (xy 422.173175 -339.425437) (xy 422.182247 -339.483687)
			(xy 422.182798 -339.513164) (xy 422.182311 -339.540533) (xy 422.174499 -339.594712) (xy 422.159014 -339.647215)
			(xy 422.136177 -339.696962) (xy 422.106457 -339.74293) (xy 422.088818 -339.763862) (xy 422.082722 -339.770974)
			(xy 422.076372 -339.787992) (xy 422.076372 -339.873336) (xy 422.082722 -339.890354) (xy 422.088818 -339.897466)
			(xy 422.106457 -339.918398) (xy 422.136169 -339.964371) (xy 422.159004 -340.014119) (xy 422.174495 -340.066619)
			(xy 422.182324 -340.120795) (xy 422.182798 -340.148164) (xy 422.182311 -340.175416) (xy 422.174559 -340.229367)
			(xy 422.159207 -340.281665) (xy 422.136568 -340.331246) (xy 422.107103 -340.3771) (xy 422.071411 -340.418293)
			(xy 422.03022 -340.453987) (xy 421.984369 -340.483455) (xy 421.934789 -340.506098) (xy 421.882492 -340.521453)
			(xy 421.828542 -340.529209) (xy 421.80129 -340.529672) (xy 421.772613 -340.529168) (xy 421.715904 -340.520594)
			(xy 421.661119 -340.503624) (xy 421.609492 -340.478642) (xy 421.562188 -340.446211) (xy 421.520273 -340.407063)
			(xy 421.502078 -340.384892) (xy 421.495134 -340.377042) (xy 421.476655 -340.367203) (xy 421.466264 -340.365842)
			(xy 421.410892 -340.361524) (xy 421.404034 -340.368636) (xy 421.395906 -340.376764) (xy 421.388032 -340.397846)
			(xy 421.397176 -340.498938) (xy 421.408606 -340.518242) (xy 421.418004 -340.524846) (xy 421.439584 -340.540141)
			(xy 421.478668 -340.57578) (xy 421.512453 -340.616477) (xy 421.540292 -340.661452) (xy 421.56165 -340.709842)
			(xy 421.576118 -340.760718) (xy 421.583419 -340.813105) (xy 421.583866 -340.839552) (xy 421.583323 -340.868717)
			(xy 421.574438 -340.926367) (xy 421.556882 -340.981993) (xy 421.531064 -341.034299) (xy 421.514778 -341.0585)
			(xy 421.50919 -341.066628) (xy 421.504618 -341.085424) (xy 421.518334 -341.174578) (xy 421.52824 -341.191088)
			(xy 421.536114 -341.197184) (xy 421.558892 -341.215394) (xy 421.599226 -341.257505) (xy 421.632684 -341.305263)
			(xy 421.658486 -341.357555) (xy 421.67603 -341.413165) (xy 421.68491 -341.470796) (xy 421.685466 -341.499952)
			(xy 421.68498 -341.527203) (xy 421.677224 -341.581151) (xy 421.661869 -341.633446) (xy 421.639227 -341.683023)
			(xy 421.609761 -341.728873) (xy 421.57407 -341.770064) (xy 421.532879 -341.805755) (xy 421.487029 -341.835221)
			(xy 421.437452 -341.857863) (xy 421.385157 -341.873218) (xy 421.331209 -341.880974) (xy 421.276707 -341.880974)
			(xy 421.222759 -341.873218) (xy 421.170464 -341.857863) (xy 421.120887 -341.835221) (xy 421.075037 -341.805755)
			(xy 421.033846 -341.770064) (xy 420.998155 -341.728873) (xy 420.968689 -341.683023) (xy 420.946047 -341.633446)
			(xy 420.930692 -341.581151) (xy 420.922936 -341.527203) (xy 420.92245 -341.499952) (xy 420.922992 -341.470787)
			(xy 420.931877 -341.413137) (xy 420.949434 -341.357511) (xy 420.975252 -341.305205) (xy 420.991538 -341.281004)
			(xy 420.997126 -341.272876) (xy 421.001698 -341.25408) (xy 420.987982 -341.164926) (xy 420.978076 -341.148416)
			(xy 420.970202 -341.14232) (xy 420.947409 -341.12413) (xy 420.907079 -341.082012) (xy 420.873626 -341.034249)
			(xy 420.847827 -340.981953) (xy 420.830285 -340.926342) (xy 420.821406 -340.868708) (xy 420.82085 -340.839552)
			(xy 420.821456 -340.809358) (xy 420.830974 -340.749724) (xy 420.849765 -340.692334) (xy 420.87736 -340.638619)
			(xy 420.91307 -340.589921) (xy 420.934134 -340.56828) (xy 420.942262 -340.560152) (xy 420.950136 -340.53907)
			(xy 420.940992 -340.437978) (xy 420.929562 -340.418674) (xy 420.920164 -340.41207) (xy 420.898585 -340.396775)
			(xy 420.859502 -340.361135) (xy 420.825718 -340.320437) (xy 420.797879 -340.275462) (xy 420.776521 -340.227073)
			(xy 420.762052 -340.176197) (xy 420.75475 -340.123811) (xy 420.754302 -340.097364) (xy 409.64358 -340.097364)
			(xy 409.64358 -341.499952) (xy 416.60445 -341.499952) (xy 416.604987 -341.471036) (xy 416.613709 -341.413864)
			(xy 416.630962 -341.358665) (xy 416.65635 -341.306703) (xy 416.689292 -341.259169) (xy 416.729031 -341.217152)
			(xy 416.751516 -341.198962) (xy 416.760293 -341.191415) (xy 416.770468 -341.170645) (xy 416.771074 -341.159084)
			(xy 416.771074 -341.07882) (xy 416.770501 -341.067252) (xy 416.760309 -341.046481) (xy 416.751516 -341.038942)
			(xy 416.729056 -341.020723) (xy 416.689319 -340.97871) (xy 416.656376 -340.931181) (xy 416.630984 -340.879225)
			(xy 416.613723 -340.824032) (xy 416.604988 -340.766866) (xy 416.60445 -340.737952) (xy 416.604936 -340.710701)
			(xy 416.612692 -340.656753) (xy 416.628047 -340.604458) (xy 416.650689 -340.554881) (xy 416.680155 -340.509031)
			(xy 416.715846 -340.46784) (xy 416.757037 -340.432149) (xy 416.802887 -340.402683) (xy 416.852464 -340.380041)
			(xy 416.904759 -340.364686) (xy 416.958707 -340.35693) (xy 417.013209 -340.35693) (xy 417.067157 -340.364686)
			(xy 417.119452 -340.380041) (xy 417.169029 -340.402683) (xy 417.214879 -340.432149) (xy 417.25607 -340.46784)
			(xy 417.291761 -340.509031) (xy 417.321227 -340.554881) (xy 417.343869 -340.604458) (xy 417.359224 -340.656753)
			(xy 417.36698 -340.710701) (xy 417.367466 -340.737952) (xy 417.366926 -340.766868) (xy 417.358203 -340.824039)
			(xy 417.340951 -340.879238) (xy 417.315563 -340.9312) (xy 417.282623 -340.978734) (xy 417.242884 -341.020752)
			(xy 417.2204 -341.038942) (xy 417.211624 -341.04649) (xy 417.201448 -341.067259) (xy 417.200842 -341.07882)
			(xy 417.200842 -341.159084) (xy 417.201407 -341.170653) (xy 417.211604 -341.191425) (xy 417.2204 -341.198962)
			(xy 417.242865 -341.217174) (xy 417.282602 -341.25919) (xy 417.315543 -341.30672) (xy 417.340934 -341.358677)
			(xy 417.358195 -341.413871) (xy 417.366928 -341.471037) (xy 417.367466 -341.499952) (xy 418.76345 -341.499952)
			(xy 418.763987 -341.471036) (xy 418.772709 -341.413864) (xy 418.789962 -341.358665) (xy 418.81535 -341.306703)
			(xy 418.848292 -341.259169) (xy 418.888031 -341.217152) (xy 418.910516 -341.198962) (xy 418.919293 -341.191415)
			(xy 418.929468 -341.170645) (xy 418.930074 -341.159084) (xy 418.930074 -341.07882) (xy 418.929501 -341.067252)
			(xy 418.919309 -341.046481) (xy 418.910516 -341.038942) (xy 418.888056 -341.020723) (xy 418.848319 -340.97871)
			(xy 418.815376 -340.931181) (xy 418.789984 -340.879225) (xy 418.772723 -340.824032) (xy 418.763988 -340.766866)
			(xy 418.76345 -340.737952) (xy 418.763936 -340.710701) (xy 418.771692 -340.656753) (xy 418.787047 -340.604458)
			(xy 418.809689 -340.554881) (xy 418.839155 -340.509031) (xy 418.874846 -340.46784) (xy 418.916037 -340.432149)
			(xy 418.961887 -340.402683) (xy 419.011464 -340.380041) (xy 419.063759 -340.364686) (xy 419.117707 -340.35693)
			(xy 419.172209 -340.35693) (xy 419.226157 -340.364686) (xy 419.278452 -340.380041) (xy 419.328029 -340.402683)
			(xy 419.373879 -340.432149) (xy 419.41507 -340.46784) (xy 419.450761 -340.509031) (xy 419.480227 -340.554881)
			(xy 419.502869 -340.604458) (xy 419.518224 -340.656753) (xy 419.52598 -340.710701) (xy 419.526466 -340.737952)
			(xy 419.525926 -340.766868) (xy 419.517203 -340.824039) (xy 419.499951 -340.879238) (xy 419.474563 -340.9312)
			(xy 419.441623 -340.978734) (xy 419.401884 -341.020752) (xy 419.3794 -341.038942) (xy 419.370624 -341.04649)
			(xy 419.360448 -341.067259) (xy 419.359842 -341.07882) (xy 419.359842 -341.159084) (xy 419.360407 -341.170653)
			(xy 419.370604 -341.191425) (xy 419.3794 -341.198962) (xy 419.401865 -341.217174) (xy 419.441602 -341.25919)
			(xy 419.474543 -341.30672) (xy 419.499934 -341.358677) (xy 419.517195 -341.413871) (xy 419.525928 -341.471037)
			(xy 419.526466 -341.499952) (xy 419.52598 -341.527203) (xy 419.518224 -341.581151) (xy 419.502869 -341.633446)
			(xy 419.480227 -341.683023) (xy 419.450761 -341.728873) (xy 419.41507 -341.770064) (xy 419.373879 -341.805755)
			(xy 419.328029 -341.835221) (xy 419.278452 -341.857863) (xy 419.226157 -341.873218) (xy 419.172209 -341.880974)
			(xy 419.117707 -341.880974) (xy 419.063759 -341.873218) (xy 419.011464 -341.857863) (xy 418.961887 -341.835221)
			(xy 418.916037 -341.805755) (xy 418.874846 -341.770064) (xy 418.839155 -341.728873) (xy 418.809689 -341.683023)
			(xy 418.787047 -341.633446) (xy 418.771692 -341.581151) (xy 418.763936 -341.527203) (xy 418.76345 -341.499952)
			(xy 417.367466 -341.499952) (xy 417.36698 -341.527203) (xy 417.359224 -341.581151) (xy 417.343869 -341.633446)
			(xy 417.321227 -341.683023) (xy 417.291761 -341.728873) (xy 417.25607 -341.770064) (xy 417.214879 -341.805755)
			(xy 417.169029 -341.835221) (xy 417.119452 -341.857863) (xy 417.067157 -341.873218) (xy 417.013209 -341.880974)
			(xy 416.958707 -341.880974) (xy 416.904759 -341.873218) (xy 416.852464 -341.857863) (xy 416.802887 -341.835221)
			(xy 416.757037 -341.805755) (xy 416.715846 -341.770064) (xy 416.680155 -341.728873) (xy 416.650689 -341.683023)
			(xy 416.628047 -341.633446) (xy 416.612692 -341.581151) (xy 416.604936 -341.527203) (xy 416.60445 -341.499952)
			(xy 409.64358 -341.499952) (xy 409.64358 -352.769678) (xy 419.579552 -352.769678) (xy 419.580041 -352.741767)
			(xy 419.588178 -352.686542) (xy 419.604275 -352.633091) (xy 419.627988 -352.582556) (xy 419.658812 -352.536016)
			(xy 419.677088 -352.514916) (xy 419.683438 -352.507804) (xy 419.690042 -352.490532) (xy 419.690042 -352.40341)
			(xy 419.683438 -352.386138) (xy 419.677088 -352.379026) (xy 419.658799 -352.357936) (xy 419.627973 -352.311395)
			(xy 419.604261 -352.260858) (xy 419.588167 -352.207404) (xy 419.580036 -352.152176) (xy 419.579552 -352.124264)
			(xy 419.580038 -352.097013) (xy 419.587794 -352.043065) (xy 419.603149 -351.99077) (xy 419.625791 -351.941193)
			(xy 419.655257 -351.895343) (xy 419.690948 -351.854152) (xy 419.732139 -351.818461) (xy 419.777989 -351.788995)
			(xy 419.827566 -351.766353) (xy 419.879861 -351.750998) (xy 419.933809 -351.743242) (xy 419.988311 -351.743242)
			(xy 420.042259 -351.750998) (xy 420.094554 -351.766353) (xy 420.144131 -351.788995) (xy 420.189981 -351.818461)
			(xy 420.231172 -351.854152) (xy 420.266863 -351.895343) (xy 420.296329 -351.941193) (xy 420.318971 -351.99077)
			(xy 420.334326 -352.043065) (xy 420.342082 -352.097013) (xy 420.342568 -352.124264) (xy 420.342099 -352.152176)
			(xy 420.333956 -352.207402) (xy 420.317855 -352.260852) (xy 420.294137 -352.311386) (xy 420.26331 -352.357926)
			(xy 420.245032 -352.379026) (xy 420.238682 -352.386138) (xy 420.232078 -352.40341) (xy 420.232078 -352.490532)
			(xy 420.238682 -352.507804) (xy 420.245032 -352.514916) (xy 420.263297 -352.536026) (xy 420.294125 -352.582562)
			(xy 420.317842 -352.633094) (xy 420.333942 -352.686543) (xy 420.34208 -352.741768) (xy 420.342568 -352.769678)
			(xy 420.342082 -352.796929) (xy 420.334326 -352.850877) (xy 420.318971 -352.903172) (xy 420.296329 -352.952749)
			(xy 420.266863 -352.998599) (xy 420.231172 -353.03979) (xy 420.189981 -353.075481) (xy 420.144131 -353.104947)
			(xy 420.094554 -353.127589) (xy 420.042259 -353.142944) (xy 419.988311 -353.1507) (xy 419.933809 -353.1507)
			(xy 419.879861 -353.142944) (xy 419.827566 -353.127589) (xy 419.777989 -353.104947) (xy 419.732139 -353.075481)
			(xy 419.690948 -353.03979) (xy 419.655257 -352.998599) (xy 419.625791 -352.952749) (xy 419.603149 -352.903172)
			(xy 419.587794 -352.850877) (xy 419.580038 -352.796929) (xy 419.579552 -352.769678) (xy 409.64358 -352.769678)
			(xy 409.64358 -354.001324) (xy 420.537384 -354.001324) (xy 420.541455 -353.945702) (xy 420.553581 -353.891265)
			(xy 420.573504 -353.839174) (xy 420.6008 -353.790539) (xy 420.634886 -353.746396) (xy 420.675035 -353.707687)
			(xy 420.720393 -353.675236) (xy 420.769993 -353.649735) (xy 420.822777 -353.631728) (xy 420.87762 -353.621598)
			(xy 420.933354 -353.619561) (xy 420.988791 -353.625661) (xy 421.042748 -353.639767) (xy 421.094077 -353.661579)
			(xy 421.141683 -353.690633) (xy 421.184551 -353.726308) (xy 421.221768 -353.767845) (xy 421.249531 -353.809808)
			(xy 423.762932 -353.809808) (xy 423.762932 -351.607628) (xy 423.76335 -351.58363) (xy 423.770827 -351.536222)
			(xy 423.785646 -351.490572) (xy 423.807441 -351.447812) (xy 423.835673 -351.408999) (xy 423.85234 -351.391728)
			(xy 423.852594 -351.391728) (xy 424.074844 -351.169478) (xy 424.074844 -351.169224) (xy 424.092162 -351.152616)
			(xy 424.130987 -351.124426) (xy 424.173739 -351.102648) (xy 424.219368 -351.087817) (xy 424.266755 -351.080297)
			(xy 424.290744 -351.079816) (xy 426.742352 -351.079816) (xy 426.766351 -351.080223) (xy 426.813761 -351.087698)
			(xy 426.859411 -351.102519) (xy 426.902172 -351.124317) (xy 426.940983 -351.152554) (xy 426.958252 -351.169224)
			(xy 426.958252 -351.169478) (xy 427.214792 -351.426018) (xy 427.215046 -351.426018) (xy 427.231713 -351.443298)
			(xy 427.25997 -351.482109) (xy 427.281806 -351.524862) (xy 427.296685 -351.570506) (xy 427.30424 -351.617915)
			(xy 427.304708 -351.641918) (xy 427.304708 -352.541586) (xy 427.305056 -352.551634) (xy 427.31266 -352.570229)
			(xy 427.31944 -352.577654) (xy 427.536864 -352.795078) (xy 427.90618 -352.795078) (xy 427.906662 -352.767167)
			(xy 427.914799 -352.711941) (xy 427.930898 -352.65849) (xy 427.954613 -352.607955) (xy 427.985438 -352.561416)
			(xy 428.003716 -352.540316) (xy 428.010066 -352.533204) (xy 428.01667 -352.515932) (xy 428.01667 -352.42881)
			(xy 428.010066 -352.411538) (xy 428.003716 -352.404426) (xy 427.985431 -352.383332) (xy 427.954604 -352.336792)
			(xy 427.93089 -352.286256) (xy 427.914795 -352.232804) (xy 427.906664 -352.177576) (xy 427.90618 -352.149664)
			(xy 427.906666 -352.122413) (xy 427.914422 -352.068465) (xy 427.929777 -352.01617) (xy 427.952419 -351.966593)
			(xy 427.981885 -351.920743) (xy 428.017576 -351.879552) (xy 428.058767 -351.843861) (xy 428.104617 -351.814395)
			(xy 428.154194 -351.791753) (xy 428.206489 -351.776398) (xy 428.260437 -351.768642) (xy 428.314939 -351.768642)
			(xy 428.368887 -351.776398) (xy 428.421182 -351.791753) (xy 428.470759 -351.814395) (xy 428.516609 -351.843861)
			(xy 428.5578 -351.879552) (xy 428.593491 -351.920743) (xy 428.622957 -351.966593) (xy 428.645599 -352.01617)
			(xy 428.660954 -352.068465) (xy 428.66871 -352.122413) (xy 428.669196 -352.149664) (xy 428.66872 -352.177575)
			(xy 428.660578 -352.232801) (xy 428.644477 -352.286251) (xy 428.620762 -352.336785) (xy 428.589937 -352.383325)
			(xy 428.57166 -352.404426) (xy 428.56531 -352.411538) (xy 428.558706 -352.42881) (xy 428.558706 -352.515932)
			(xy 428.56531 -352.533204) (xy 428.57166 -352.540316) (xy 428.589929 -352.561423) (xy 428.620756 -352.60796)
			(xy 428.644472 -352.658493) (xy 428.660571 -352.711942) (xy 428.668708 -352.767167) (xy 428.669196 -352.795078)
			(xy 428.66871 -352.822329) (xy 428.660954 -352.876277) (xy 428.645599 -352.928572) (xy 428.622957 -352.978149)
			(xy 428.593491 -353.023999) (xy 428.5578 -353.06519) (xy 428.516609 -353.100881) (xy 428.470759 -353.130347)
			(xy 428.421182 -353.152989) (xy 428.368887 -353.168344) (xy 428.314939 -353.1761) (xy 428.260437 -353.1761)
			(xy 428.206489 -353.168344) (xy 428.154194 -353.152989) (xy 428.104617 -353.130347) (xy 428.058767 -353.100881)
			(xy 428.017576 -353.06519) (xy 427.981885 -353.023999) (xy 427.952419 -352.978149) (xy 427.929777 -352.928572)
			(xy 427.914422 -352.876277) (xy 427.906666 -352.822329) (xy 427.90618 -352.795078) (xy 427.536864 -352.795078)
			(xy 427.807374 -353.065588) (xy 427.807628 -353.065588) (xy 427.824249 -353.082895) (xy 427.852439 -353.121721)
			(xy 427.874215 -353.164476) (xy 427.889043 -353.210109) (xy 427.896558 -353.257498) (xy 427.897036 -353.281488)
			(xy 427.897036 -354.026724) (xy 428.864012 -354.026724) (xy 428.868083 -353.971102) (xy 428.880209 -353.916665)
			(xy 428.900132 -353.864574) (xy 428.927428 -353.815939) (xy 428.961514 -353.771796) (xy 429.001663 -353.733087)
			(xy 429.047021 -353.700636) (xy 429.096621 -353.675135) (xy 429.149405 -353.657128) (xy 429.204248 -353.646998)
			(xy 429.259982 -353.644961) (xy 429.315419 -353.651061) (xy 429.369376 -353.665167) (xy 429.420705 -353.686979)
			(xy 429.468311 -353.716033) (xy 429.511179 -353.751708) (xy 429.548396 -353.793245) (xy 429.579169 -353.839758)
			(xy 429.602841 -353.890255) (xy 429.618909 -353.943662) (xy 429.627029 -353.998838) (xy 429.627538 -354.026724)
			(xy 429.627029 -354.05461) (xy 429.618909 -354.109786) (xy 429.602841 -354.163193) (xy 429.579169 -354.21369)
			(xy 429.548396 -354.260203) (xy 429.511179 -354.30174) (xy 429.468311 -354.337415) (xy 429.420705 -354.366469)
			(xy 429.369376 -354.388281) (xy 429.315419 -354.402387) (xy 429.259982 -354.408487) (xy 429.204248 -354.40645)
			(xy 429.149405 -354.39632) (xy 429.096621 -354.378313) (xy 429.047021 -354.352812) (xy 429.001663 -354.320361)
			(xy 428.961514 -354.281652) (xy 428.927428 -354.237509) (xy 428.900132 -354.188874) (xy 428.880209 -354.136783)
			(xy 428.868083 -354.082346) (xy 428.864012 -354.026724) (xy 427.897036 -354.026724) (xy 427.897036 -354.922074)
			(xy 428.284892 -354.922074) (xy 428.288963 -354.866452) (xy 428.301089 -354.812015) (xy 428.321012 -354.759924)
			(xy 428.348308 -354.711289) (xy 428.382394 -354.667146) (xy 428.422543 -354.628437) (xy 428.467901 -354.595986)
			(xy 428.517501 -354.570485) (xy 428.570285 -354.552478) (xy 428.625128 -354.542348) (xy 428.680862 -354.540311)
			(xy 428.736299 -354.546411) (xy 428.790256 -354.560517) (xy 428.841585 -354.582329) (xy 428.889191 -354.611383)
			(xy 428.932059 -354.647058) (xy 428.969276 -354.688595) (xy 429.000049 -354.735108) (xy 429.023721 -354.785605)
			(xy 429.039789 -354.839012) (xy 429.047909 -354.894188) (xy 429.048418 -354.922074) (xy 429.047909 -354.94996)
			(xy 429.039789 -355.005136) (xy 429.023721 -355.058543) (xy 429.000049 -355.10904) (xy 428.969276 -355.155553)
			(xy 428.932059 -355.19709) (xy 428.889191 -355.232765) (xy 428.841585 -355.261819) (xy 428.790256 -355.283631)
			(xy 428.736299 -355.297737) (xy 428.680862 -355.303837) (xy 428.625128 -355.3018) (xy 428.570285 -355.29167)
			(xy 428.517501 -355.273663) (xy 428.467901 -355.248162) (xy 428.422543 -355.215711) (xy 428.382394 -355.177002)
			(xy 428.348308 -355.132859) (xy 428.321012 -355.084224) (xy 428.301089 -355.032133) (xy 428.288963 -354.977696)
			(xy 428.284892 -354.922074) (xy 427.897036 -354.922074) (xy 427.897036 -355.597714) (xy 429.623728 -355.597714)
			(xy 429.624216 -355.570239) (xy 429.632106 -355.51586) (xy 429.647726 -355.463177) (xy 429.67075 -355.413284)
			(xy 429.700702 -355.367216) (xy 429.71847 -355.346254) (xy 429.724566 -355.339142) (xy 429.730916 -355.322124)
			(xy 429.730916 -355.236272) (xy 429.724566 -355.219254) (xy 429.71847 -355.212142) (xy 429.70074 -355.191152)
			(xy 429.670811 -355.145078) (xy 429.647792 -355.09519) (xy 429.632158 -355.04252) (xy 429.624232 -354.988152)
			(xy 429.623728 -354.960682) (xy 429.624214 -354.933431) (xy 429.63197 -354.879483) (xy 429.647325 -354.827188)
			(xy 429.669967 -354.777611) (xy 429.699433 -354.731761) (xy 429.735124 -354.69057) (xy 429.776315 -354.654879)
			(xy 429.822165 -354.625413) (xy 429.871742 -354.602771) (xy 429.924037 -354.587416) (xy 429.977985 -354.57966)
			(xy 430.032487 -354.57966) (xy 430.086435 -354.587416) (xy 430.13873 -354.602771) (xy 430.188307 -354.625413)
			(xy 430.234157 -354.654879) (xy 430.275348 -354.69057) (xy 430.311039 -354.731761) (xy 430.340505 -354.777611)
			(xy 430.363147 -354.827188) (xy 430.378502 -354.879483) (xy 430.386258 -354.933431) (xy 430.386744 -354.960682)
			(xy 430.386261 -354.988157) (xy 430.37837 -355.042537) (xy 430.36275 -355.09522) (xy 430.360106 -355.100948)
			(xy 430.62859 -355.100948) (xy 430.62859 -355.046452) (xy 430.636345 -354.99251) (xy 430.651697 -354.940221)
			(xy 430.674334 -354.890648) (xy 430.703795 -354.844802) (xy 430.73948 -354.803614) (xy 430.780663 -354.767924)
			(xy 430.826506 -354.738457) (xy 430.876076 -354.715814) (xy 430.928363 -354.700455) (xy 430.982304 -354.692694)
			(xy 431.009552 -354.692204) (xy 431.034788 -354.692578) (xy 431.084823 -354.699203) (xy 431.133543 -354.712382)
			(xy 431.180094 -354.731886) (xy 431.202084 -354.744274) (xy 431.211736 -354.750116) (xy 431.233834 -354.752148)
			(xy 431.328322 -354.71862) (xy 431.344324 -354.703126) (xy 431.348388 -354.692712) (xy 431.359084 -354.665935)
			(xy 431.38737 -354.615692) (xy 431.422899 -354.570282) (xy 431.464861 -354.530738) (xy 431.512299 -354.497964)
			(xy 431.56413 -354.472707) (xy 431.619174 -354.455542) (xy 431.676175 -354.446861) (xy 431.705004 -354.446332)
			(xy 431.732259 -354.446752) (xy 431.786213 -354.45451) (xy 431.838514 -354.469869) (xy 431.888097 -354.492515)
			(xy 431.933952 -354.521987) (xy 431.975146 -354.557685) (xy 432.01084 -354.598883) (xy 432.040306 -354.644741)
			(xy 432.062947 -354.694327) (xy 432.078299 -354.74663) (xy 432.086051 -354.800585) (xy 432.086512 -354.82784)
			(xy 432.085851 -354.859403) (xy 432.075464 -354.921668) (xy 432.054979 -354.981377) (xy 432.040538 -355.00945)
			(xy 432.035712 -355.01834) (xy 432.03368 -355.037898) (xy 432.059334 -355.126036) (xy 432.07178 -355.14153)
			(xy 432.08067 -355.14661) (xy 432.105753 -355.161188) (xy 432.151636 -355.196686) (xy 432.191613 -355.238724)
			(xy 432.224761 -355.286333) (xy 432.250315 -355.338413) (xy 432.267685 -355.393763) (xy 432.276471 -355.451106)
			(xy 432.277012 -355.480112) (xy 432.276526 -355.507363) (xy 432.26877 -355.561311) (xy 432.253415 -355.613606)
			(xy 432.230773 -355.663183) (xy 432.201307 -355.709033) (xy 432.165616 -355.750224) (xy 432.124425 -355.785915)
			(xy 432.078575 -355.815381) (xy 432.028998 -355.838023) (xy 431.976703 -355.853378) (xy 431.922755 -355.861134)
			(xy 431.868253 -355.861134) (xy 431.814305 -355.853378) (xy 431.76201 -355.838023) (xy 431.712433 -355.815381)
			(xy 431.666583 -355.785915) (xy 431.625392 -355.750224) (xy 431.589701 -355.709033) (xy 431.560235 -355.663183)
			(xy 431.537593 -355.613606) (xy 431.522238 -355.561311) (xy 431.514482 -355.507363) (xy 431.513996 -355.480112)
			(xy 431.514637 -355.448548) (xy 431.525032 -355.386283) (xy 431.545525 -355.326574) (xy 431.55997 -355.298502)
			(xy 431.564796 -355.289612) (xy 431.566828 -355.270054) (xy 431.541174 -355.181916) (xy 431.528728 -355.166422)
			(xy 431.519838 -355.161342) (xy 431.512472 -355.157278) (xy 431.50282 -355.151436) (xy 431.480722 -355.149404)
			(xy 431.386234 -355.182932) (xy 431.370232 -355.198426) (xy 431.366168 -355.20884) (xy 431.355453 -355.235608)
			(xy 431.327166 -355.285847) (xy 431.291637 -355.331255) (xy 431.249678 -355.370797) (xy 431.202244 -355.403571)
			(xy 431.150416 -355.428831) (xy 431.095377 -355.446) (xy 431.03838 -355.454687) (xy 431.009552 -355.45522)
			(xy 430.982304 -355.454706) (xy 430.928363 -355.446945) (xy 430.876076 -355.431586) (xy 430.826506 -355.408943)
			(xy 430.780663 -355.379476) (xy 430.73948 -355.343786) (xy 430.703795 -355.302598) (xy 430.674334 -355.256752)
			(xy 430.651697 -355.207179) (xy 430.636345 -355.15489) (xy 430.62859 -355.100948) (xy 430.360106 -355.100948)
			(xy 430.339724 -355.145113) (xy 430.309771 -355.191181) (xy 430.292002 -355.212142) (xy 430.285906 -355.219254)
			(xy 430.279556 -355.236272) (xy 430.279556 -355.322124) (xy 430.285906 -355.339142) (xy 430.292002 -355.346254)
			(xy 430.309726 -355.367249) (xy 430.339657 -355.413322) (xy 430.362677 -355.463208) (xy 430.378312 -355.515877)
			(xy 430.386239 -355.570244) (xy 430.386744 -355.597714) (xy 430.386258 -355.624965) (xy 430.378502 -355.678913)
			(xy 430.363147 -355.731208) (xy 430.340505 -355.780785) (xy 430.311039 -355.826635) (xy 430.275348 -355.867826)
			(xy 430.234157 -355.903517) (xy 430.188307 -355.932983) (xy 430.13873 -355.955625) (xy 430.086435 -355.97098)
			(xy 430.032487 -355.978736) (xy 429.977985 -355.978736) (xy 429.924037 -355.97098) (xy 429.871742 -355.955625)
			(xy 429.822165 -355.932983) (xy 429.776315 -355.903517) (xy 429.735124 -355.867826) (xy 429.699433 -355.826635)
			(xy 429.669967 -355.780785) (xy 429.647325 -355.731208) (xy 429.63197 -355.678913) (xy 429.624214 -355.624965)
			(xy 429.623728 -355.597714) (xy 427.897036 -355.597714) (xy 427.897036 -356.387146) (xy 427.89748 -356.397213)
			(xy 427.905187 -356.415812) (xy 427.912022 -356.423214) (xy 428.551848 -357.06304) (xy 428.559322 -357.069743)
			(xy 428.577887 -357.077328) (xy 428.587916 -357.077772) (xy 432.359308 -357.077772) (xy 432.369352 -357.077388)
			(xy 432.387948 -357.069809) (xy 432.395376 -357.06304) (xy 432.93284 -356.525576) (xy 432.939532 -356.518094)
			(xy 432.947123 -356.499535) (xy 432.947572 -356.489508) (xy 432.947572 -354.900738) (xy 432.947216 -354.890691)
			(xy 432.939618 -354.872095) (xy 432.93284 -354.86467) (xy 432.179222 -354.111052) (xy 432.178968 -354.111052)
			(xy 432.162366 -354.093729) (xy 432.134173 -354.054906) (xy 432.112394 -354.012156) (xy 432.097561 -353.966527)
			(xy 432.090041 -353.919141) (xy 432.08956 -353.895152) (xy 432.08956 -351.714308) (xy 432.089958 -351.690309)
			(xy 432.097438 -351.642899) (xy 432.112261 -351.597249) (xy 432.134061 -351.554489) (xy 432.162298 -351.515678)
			(xy 432.178968 -351.498408) (xy 432.179222 -351.498408) (xy 432.482752 -351.194878) (xy 432.482752 -351.194624)
			(xy 432.500066 -351.178012) (xy 432.538892 -351.149823) (xy 432.581645 -351.128046) (xy 432.627275 -351.113216)
			(xy 432.674662 -351.105696) (xy 432.698652 -351.105216) (xy 438.254648 -351.105216) (xy 438.278646 -351.105625)
			(xy 438.326057 -351.1131) (xy 438.371707 -351.12792) (xy 438.414468 -351.149718) (xy 438.453279 -351.177954)
			(xy 438.470548 -351.194624) (xy 438.470548 -351.194878) (xy 438.61355 -351.33788) (xy 438.613804 -351.33788)
			(xy 438.630434 -351.355178) (xy 438.65862 -351.394008) (xy 438.680393 -351.436766) (xy 438.695219 -351.4824)
			(xy 438.702734 -351.529789) (xy 438.703212 -351.55378) (xy 438.703212 -362.536994) (xy 438.702824 -362.560993)
			(xy 438.695343 -362.608404) (xy 438.680517 -362.654054) (xy 438.658715 -362.696814) (xy 438.630475 -362.735625)
			(xy 438.613804 -362.752894) (xy 438.61355 -362.752894) (xy 438.435496 -362.930948) (xy 439.741056 -362.930948)
			(xy 439.741537 -362.903578) (xy 439.749349 -362.849399) (xy 439.764834 -362.796896) (xy 439.787673 -362.747148)
			(xy 439.817395 -362.701182) (xy 439.835036 -362.68025) (xy 439.841132 -362.673138) (xy 439.847482 -362.65612)
			(xy 439.847482 -362.570776) (xy 439.841132 -362.553758) (xy 439.835036 -362.546646) (xy 439.817411 -362.525703)
			(xy 439.787695 -362.479734) (xy 439.764856 -362.429989) (xy 439.749362 -362.377491) (xy 439.741531 -362.323317)
			(xy 439.741056 -362.295948) (xy 439.7416 -362.268698) (xy 439.749349 -362.214752) (xy 439.764697 -362.162458)
			(xy 439.787332 -362.11288) (xy 439.816791 -362.067028) (xy 439.852477 -362.025836) (xy 439.893661 -361.990142)
			(xy 439.939506 -361.960672) (xy 439.989079 -361.938027) (xy 440.04137 -361.922667) (xy 440.095314 -361.914906)
			(xy 440.122564 -361.91444) (xy 440.149934 -361.914917) (xy 440.204113 -361.922731) (xy 440.256616 -361.938217)
			(xy 440.306363 -361.961056) (xy 440.35233 -361.990779) (xy 440.373262 -362.00842) (xy 440.380374 -362.014516)
			(xy 440.397392 -362.020866) (xy 440.482736 -362.020866) (xy 440.499754 -362.014516) (xy 440.506866 -362.00842)
			(xy 440.527799 -361.990779) (xy 440.573767 -361.961055) (xy 440.623513 -361.938209) (xy 440.676015 -361.922713)
			(xy 440.730193 -361.914884) (xy 440.784935 -361.914884) (xy 440.839113 -361.922713) (xy 440.891615 -361.938209)
			(xy 440.941361 -361.961055) (xy 440.987329 -361.990779) (xy 441.008262 -362.00842) (xy 441.015374 -362.014516)
			(xy 441.032392 -362.020866) (xy 441.117736 -362.020866) (xy 441.134754 -362.014516) (xy 441.141866 -362.00842)
			(xy 441.162799 -361.990779) (xy 441.208767 -361.961055) (xy 441.258513 -361.938209) (xy 441.311015 -361.922713)
			(xy 441.365193 -361.914884) (xy 441.419935 -361.914884) (xy 441.474113 -361.922713) (xy 441.526615 -361.938209)
			(xy 441.576361 -361.961055) (xy 441.622329 -361.990779) (xy 441.643262 -362.00842) (xy 441.650374 -362.014516)
			(xy 441.667392 -362.020866) (xy 441.752736 -362.020866) (xy 441.769754 -362.014516) (xy 441.776866 -362.00842)
			(xy 441.780676 -362.005118) (xy 441.788794 -361.997516) (xy 441.798146 -361.977364) (xy 441.79871 -361.966256)
			(xy 441.79871 -361.88904) (xy 441.798164 -361.877927) (xy 441.788813 -361.857766) (xy 441.780676 -361.850178)
			(xy 441.759946 -361.831987) (xy 441.723478 -361.790614) (xy 441.693349 -361.744419) (xy 441.670187 -361.694367)
			(xy 441.654474 -361.641501) (xy 441.646539 -361.586924) (xy 441.646056 -361.559348) (xy 441.646537 -361.531978)
			(xy 441.654349 -361.477799) (xy 441.669834 -361.425296) (xy 441.692673 -361.375548) (xy 441.722395 -361.329582)
			(xy 441.740036 -361.30865) (xy 441.746132 -361.301538) (xy 441.752482 -361.28452) (xy 441.752482 -361.199176)
			(xy 441.746132 -361.182158) (xy 441.740036 -361.175046) (xy 441.722442 -361.154075) (xy 441.692715 -361.108114)
			(xy 441.669866 -361.058374) (xy 441.654365 -361.005878) (xy 441.646532 -360.951705) (xy 441.646527 -360.896968)
			(xy 441.65435 -360.842793) (xy 441.66984 -360.790293) (xy 441.69268 -360.740549) (xy 441.722398 -360.694582)
			(xy 441.740036 -360.67365) (xy 441.746132 -360.666538) (xy 441.752482 -360.64952) (xy 441.752482 -360.564176)
			(xy 441.746132 -360.547158) (xy 441.740036 -360.540046) (xy 441.722442 -360.519075) (xy 441.692715 -360.473114)
			(xy 441.669866 -360.423374) (xy 441.654365 -360.370878) (xy 441.646532 -360.316705) (xy 441.646527 -360.261968)
			(xy 441.65435 -360.207793) (xy 441.66984 -360.155293) (xy 441.69268 -360.105549) (xy 441.722398 -360.059582)
			(xy 441.740036 -360.03865) (xy 441.746132 -360.031538) (xy 441.752482 -360.01452) (xy 441.752482 -359.929176)
			(xy 441.746132 -359.912158) (xy 441.740036 -359.905046) (xy 441.722411 -359.884103) (xy 441.692695 -359.838134)
			(xy 441.669856 -359.788389) (xy 441.654362 -359.735891) (xy 441.646531 -359.681717) (xy 441.646056 -359.654348)
			(xy 441.646535 -359.626774) (xy 441.654482 -359.572201) (xy 441.670203 -359.51934) (xy 441.693371 -359.469294)
			(xy 441.723502 -359.423104) (xy 441.759969 -359.381733) (xy 441.780676 -359.363518) (xy 441.788794 -359.355916)
			(xy 441.798146 -359.335764) (xy 441.79871 -359.324656) (xy 441.79871 -359.24744) (xy 441.798164 -359.236327)
			(xy 441.788813 -359.216166) (xy 441.780676 -359.208578) (xy 441.776866 -359.205276) (xy 441.769754 -359.19918)
			(xy 441.752736 -359.19283) (xy 441.667392 -359.19283) (xy 441.650374 -359.19918) (xy 441.643262 -359.205276)
			(xy 441.622329 -359.222917) (xy 441.576361 -359.252641) (xy 441.526615 -359.275487) (xy 441.474113 -359.290983)
			(xy 441.419935 -359.298812) (xy 441.365193 -359.298812) (xy 441.311015 -359.290983) (xy 441.258513 -359.275487)
			(xy 441.208767 -359.252641) (xy 441.162799 -359.222917) (xy 441.141866 -359.205276) (xy 441.134754 -359.19918)
			(xy 441.117736 -359.19283) (xy 441.032392 -359.19283) (xy 441.015374 -359.19918) (xy 441.008262 -359.205276)
			(xy 440.987329 -359.222917) (xy 440.941361 -359.252641) (xy 440.891615 -359.275487) (xy 440.839113 -359.290983)
			(xy 440.784935 -359.298812) (xy 440.730193 -359.298812) (xy 440.676015 -359.290983) (xy 440.623513 -359.275487)
			(xy 440.573767 -359.252641) (xy 440.527799 -359.222917) (xy 440.506866 -359.205276) (xy 440.499754 -359.19918)
			(xy 440.482736 -359.19283) (xy 440.397392 -359.19283) (xy 440.380374 -359.19918) (xy 440.373262 -359.205276)
			(xy 440.352314 -359.222896) (xy 440.306346 -359.252611) (xy 440.256603 -359.275451) (xy 440.204105 -359.290947)
			(xy 440.149932 -359.29878) (xy 440.122564 -359.299256) (xy 440.095314 -359.298756) (xy 440.041369 -359.290996)
			(xy 439.989078 -359.275638) (xy 439.939504 -359.252997) (xy 439.893656 -359.223531) (xy 439.852467 -359.187841)
			(xy 439.816776 -359.146654) (xy 439.787309 -359.100807) (xy 439.764666 -359.051233) (xy 439.749307 -358.998942)
			(xy 439.741545 -358.944998) (xy 439.741056 -358.917748) (xy 439.741537 -358.890378) (xy 439.749349 -358.836199)
			(xy 439.764834 -358.783696) (xy 439.787673 -358.733948) (xy 439.817395 -358.687982) (xy 439.835036 -358.66705)
			(xy 439.841132 -358.659938) (xy 439.847482 -358.64292) (xy 439.847482 -358.557576) (xy 439.841132 -358.540558)
			(xy 439.835036 -358.533446) (xy 439.817411 -358.512503) (xy 439.787695 -358.466534) (xy 439.764856 -358.416789)
			(xy 439.749362 -358.364291) (xy 439.741531 -358.310117) (xy 439.741056 -358.282748) (xy 439.7416 -358.255498)
			(xy 439.749349 -358.201552) (xy 439.764697 -358.149258) (xy 439.787332 -358.09968) (xy 439.816791 -358.053828)
			(xy 439.852477 -358.012636) (xy 439.893661 -357.976942) (xy 439.939506 -357.947472) (xy 439.989079 -357.924827)
			(xy 440.04137 -357.909467) (xy 440.095314 -357.901706) (xy 440.122564 -357.90124) (xy 440.149934 -357.901717)
			(xy 440.204113 -357.909531) (xy 440.256616 -357.925017) (xy 440.306363 -357.947856) (xy 440.35233 -357.977579)
			(xy 440.373262 -357.99522) (xy 440.380374 -358.001316) (xy 440.397392 -358.007666) (xy 440.482736 -358.007666)
			(xy 440.499754 -358.001316) (xy 440.506866 -357.99522) (xy 440.527799 -357.977579) (xy 440.573767 -357.947855)
			(xy 440.623513 -357.925009) (xy 440.676015 -357.909513) (xy 440.730193 -357.901684) (xy 440.784935 -357.901684)
			(xy 440.839113 -357.909513) (xy 440.891615 -357.925009) (xy 440.941361 -357.947855) (xy 440.987329 -357.977579)
			(xy 441.008262 -357.99522) (xy 441.015374 -358.001316) (xy 441.032392 -358.007666) (xy 441.117736 -358.007666)
			(xy 441.134754 -358.001316) (xy 441.141866 -357.99522) (xy 441.162799 -357.977579) (xy 441.208767 -357.947855)
			(xy 441.258513 -357.925009) (xy 441.311015 -357.909513) (xy 441.365193 -357.901684) (xy 441.419935 -357.901684)
			(xy 441.474113 -357.909513) (xy 441.526615 -357.925009) (xy 441.576361 -357.947855) (xy 441.622329 -357.977579)
			(xy 441.643262 -357.99522) (xy 441.650374 -358.001316) (xy 441.667392 -358.007666) (xy 441.752736 -358.007666)
			(xy 441.769754 -358.001316) (xy 441.776866 -357.99522) (xy 441.797799 -357.977579) (xy 441.843767 -357.947855)
			(xy 441.893513 -357.925009) (xy 441.946015 -357.909513) (xy 442.000193 -357.901684) (xy 442.054935 -357.901684)
			(xy 442.109113 -357.909513) (xy 442.161615 -357.925009) (xy 442.211361 -357.947855) (xy 442.257329 -357.977579)
			(xy 442.278262 -357.99522) (xy 442.285374 -358.001316) (xy 442.302392 -358.007666) (xy 442.387736 -358.007666)
			(xy 442.404754 -358.001316) (xy 442.411866 -357.99522) (xy 442.432803 -357.977586) (xy 442.478774 -357.947873)
			(xy 442.52852 -357.925036) (xy 442.58102 -357.909543) (xy 442.635195 -357.901714) (xy 442.662564 -357.90124)
			(xy 442.689818 -357.901689) (xy 442.743772 -357.909442) (xy 442.796073 -357.924796) (xy 442.845656 -357.947438)
			(xy 442.891512 -357.976907) (xy 442.932706 -358.012602) (xy 442.968401 -358.053798) (xy 442.997868 -358.099654)
			(xy 443.020508 -358.149238) (xy 443.03586 -358.20154) (xy 443.043612 -358.255494) (xy 443.044072 -358.282748)
			(xy 443.043582 -358.310117) (xy 443.035771 -358.364296) (xy 443.020288 -358.416799) (xy 442.997451 -358.466546)
			(xy 442.967731 -358.512514) (xy 442.950092 -358.533446) (xy 442.943996 -358.540558) (xy 442.937646 -358.557576)
			(xy 442.937646 -358.64292) (xy 442.943996 -358.659938) (xy 442.950092 -358.66705) (xy 442.96772 -358.687991)
			(xy 442.997434 -358.733961) (xy 443.020272 -358.783707) (xy 443.035766 -358.836205) (xy 443.043597 -358.890379)
			(xy 443.044072 -358.917748) (xy 443.04358 -358.945322) (xy 443.035634 -358.999894) (xy 443.019915 -359.052754)
			(xy 442.99675 -359.1028) (xy 442.966622 -359.14899) (xy 442.930158 -359.190362) (xy 442.909452 -359.208578)
			(xy 442.90134 -359.216186) (xy 442.891984 -359.236334) (xy 442.891418 -359.24744) (xy 442.891418 -359.324656)
			(xy 442.891989 -359.335766) (xy 442.901325 -359.355925) (xy 442.909452 -359.363518) (xy 442.930165 -359.381727)
			(xy 442.966638 -359.423095) (xy 442.996771 -359.469285) (xy 443.019936 -359.519334) (xy 443.035652 -359.572197)
			(xy 443.043589 -359.626773) (xy 443.044072 -359.654348) (xy 443.043582 -359.681717) (xy 443.035771 -359.735896)
			(xy 443.020288 -359.788399) (xy 442.997451 -359.838146) (xy 442.967731 -359.884114) (xy 442.950092 -359.905046)
			(xy 442.943996 -359.912158) (xy 442.937646 -359.929176) (xy 442.937646 -360.01452) (xy 442.943996 -360.031538)
			(xy 442.950092 -360.03865) (xy 442.967779 -360.059545) (xy 442.9975 -360.10552) (xy 443.020342 -360.155272)
			(xy 443.035833 -360.20778) (xy 443.043657 -360.261963) (xy 443.043652 -360.316709) (xy 443.035818 -360.370891)
			(xy 443.020316 -360.423395) (xy 442.997465 -360.473144) (xy 442.967735 -360.519113) (xy 442.950092 -360.540046)
			(xy 442.943996 -360.547158) (xy 442.937646 -360.564176) (xy 442.937646 -360.64952) (xy 442.943996 -360.666538)
			(xy 442.950092 -360.67365) (xy 442.967779 -360.694545) (xy 442.9975 -360.74052) (xy 443.020342 -360.790272)
			(xy 443.035833 -360.84278) (xy 443.043657 -360.896963) (xy 443.043652 -360.951709) (xy 443.035818 -361.005891)
			(xy 443.020316 -361.058395) (xy 442.997465 -361.108144) (xy 442.967735 -361.154113) (xy 442.950092 -361.175046)
			(xy 442.943996 -361.182158) (xy 442.937646 -361.199176) (xy 442.937646 -361.28452) (xy 442.943996 -361.301538)
			(xy 442.950092 -361.30865) (xy 442.96772 -361.329591) (xy 442.997434 -361.375561) (xy 443.020272 -361.425307)
			(xy 443.035766 -361.477805) (xy 443.043597 -361.531979) (xy 443.044072 -361.559348) (xy 443.043667 -361.586602)
			(xy 443.035903 -361.640555) (xy 443.02054 -361.692853) (xy 442.99789 -361.742433) (xy 442.968416 -361.788285)
			(xy 442.932716 -361.829475) (xy 442.891517 -361.865166) (xy 442.845659 -361.894631) (xy 442.796074 -361.917269)
			(xy 442.743772 -361.932621) (xy 442.689818 -361.940373) (xy 442.662564 -361.940856) (xy 442.635192 -361.940422)
			(xy 442.581012 -361.932598) (xy 442.528508 -361.917102) (xy 442.478761 -361.894253) (xy 442.432796 -361.864521)
			(xy 442.411866 -361.846876) (xy 442.404754 -361.84078) (xy 442.387736 -361.83443) (xy 442.302392 -361.83443)
			(xy 442.285374 -361.84078) (xy 442.278262 -361.846876) (xy 442.274452 -361.850178) (xy 442.26634 -361.857786)
			(xy 442.256984 -361.877934) (xy 442.256418 -361.88904) (xy 442.256418 -361.966256) (xy 442.256989 -361.977366)
			(xy 442.266325 -361.997525) (xy 442.274452 -362.005118) (xy 442.295165 -362.023327) (xy 442.331638 -362.064695)
			(xy 442.361771 -362.110885) (xy 442.384936 -362.160934) (xy 442.400652 -362.213797) (xy 442.408589 -362.268373)
			(xy 442.409072 -362.295948) (xy 442.408667 -362.323202) (xy 442.400903 -362.377155) (xy 442.38554 -362.429453)
			(xy 442.36289 -362.479033) (xy 442.333416 -362.524885) (xy 442.297716 -362.566075) (xy 442.256517 -362.601766)
			(xy 442.210659 -362.631231) (xy 442.161074 -362.653869) (xy 442.108772 -362.669221) (xy 442.054818 -362.676973)
			(xy 442.027564 -362.677456) (xy 441.998087 -362.676888) (xy 441.939835 -362.667827) (xy 441.88367 -362.649912)
			(xy 441.83093 -362.623569) (xy 441.782872 -362.589424) (xy 441.761372 -362.569252) (xy 441.754047 -362.562706)
			(xy 441.735879 -362.555269) (xy 441.726066 -362.554774) (xy 441.672726 -362.554774) (xy 441.665868 -362.56214)
			(xy 441.659319 -362.569463) (xy 441.651883 -362.587632) (xy 441.65139 -362.597446) (xy 441.65139 -362.62945)
			(xy 441.651862 -362.639266) (xy 441.659317 -362.65743) (xy 441.665868 -362.664756) (xy 441.686023 -362.686272)
			(xy 441.72017 -362.734327) (xy 441.746519 -362.787062) (xy 441.764445 -362.843223) (xy 441.77352 -362.901472)
			(xy 441.774072 -362.930948) (xy 441.773667 -362.958202) (xy 441.765903 -363.012155) (xy 441.75054 -363.064453)
			(xy 441.72789 -363.114033) (xy 441.698416 -363.159885) (xy 441.662716 -363.201075) (xy 441.621517 -363.236766)
			(xy 441.575659 -363.266231) (xy 441.526074 -363.288869) (xy 441.473772 -363.304221) (xy 441.419818 -363.311973)
			(xy 441.392564 -363.312456) (xy 441.365192 -363.312022) (xy 441.311012 -363.304198) (xy 441.258508 -363.288702)
			(xy 441.208761 -363.265853) (xy 441.162796 -363.236121) (xy 441.141866 -363.218476) (xy 441.134754 -363.21238)
			(xy 441.117736 -363.20603) (xy 441.032392 -363.20603) (xy 441.015374 -363.21238) (xy 441.008262 -363.218476)
			(xy 440.987329 -363.236117) (xy 440.941361 -363.265841) (xy 440.891615 -363.288687) (xy 440.839113 -363.304183)
			(xy 440.784935 -363.312012) (xy 440.730193 -363.312012) (xy 440.676015 -363.304183) (xy 440.623513 -363.288687)
			(xy 440.573767 -363.265841) (xy 440.527799 -363.236117) (xy 440.506866 -363.218476) (xy 440.499754 -363.21238)
			(xy 440.482736 -363.20603) (xy 440.397392 -363.20603) (xy 440.380374 -363.21238) (xy 440.373262 -363.218476)
			(xy 440.352314 -363.236096) (xy 440.306346 -363.265811) (xy 440.256603 -363.288651) (xy 440.204105 -363.304147)
			(xy 440.149932 -363.31198) (xy 440.122564 -363.312456) (xy 440.095314 -363.311956) (xy 440.041369 -363.304196)
			(xy 439.989078 -363.288838) (xy 439.939504 -363.266197) (xy 439.893656 -363.236731) (xy 439.852467 -363.201041)
			(xy 439.816776 -363.159854) (xy 439.787309 -363.114007) (xy 439.764666 -363.064433) (xy 439.749307 -363.012142)
			(xy 439.741545 -362.958198) (xy 439.741056 -362.930948) (xy 438.435496 -362.930948) (xy 438.37098 -362.995464)
			(xy 438.37098 -362.995718) (xy 438.353697 -363.01238) (xy 438.314885 -363.04063) (xy 438.272131 -363.062461)
			(xy 438.226489 -363.077335) (xy 438.179082 -363.084888) (xy 438.15508 -363.08538) (xy 426.65142 -363.08538)
			(xy 426.627415 -363.084924) (xy 426.580001 -363.077379) (xy 426.534353 -363.062503) (xy 426.491598 -363.040663)
			(xy 426.452789 -363.012398) (xy 426.43552 -362.995718) (xy 426.43552 -362.995464) (xy 425.78655 -362.346494)
			(xy 425.786296 -362.346494) (xy 425.769653 -362.329208) (xy 425.741469 -362.290374) (xy 425.719698 -362.247614)
			(xy 425.704875 -362.201977) (xy 425.697364 -362.154586) (xy 425.696888 -362.130594) (xy 425.696888 -356.53091)
			(xy 425.69892 -356.528878) (xy 425.69892 -355.893116) (xy 425.698508 -355.883045) (xy 425.69078 -355.864446)
			(xy 425.683934 -355.857048) (xy 423.852594 -354.025708) (xy 423.85234 -354.025708) (xy 423.835712 -354.008408)
			(xy 423.807524 -353.969579) (xy 423.78575 -353.926822) (xy 423.770923 -353.881189) (xy 423.763409 -353.833799)
			(xy 423.762932 -353.809808) (xy 421.249531 -353.809808) (xy 421.252541 -353.814358) (xy 421.276213 -353.864855)
			(xy 421.292281 -353.918262) (xy 421.300401 -353.973438) (xy 421.30091 -354.001324) (xy 421.300401 -354.02921)
			(xy 421.292281 -354.084386) (xy 421.276213 -354.137793) (xy 421.252541 -354.18829) (xy 421.221768 -354.234803)
			(xy 421.184551 -354.27634) (xy 421.141683 -354.312015) (xy 421.094077 -354.341069) (xy 421.042748 -354.362881)
			(xy 420.988791 -354.376987) (xy 420.933354 -354.383087) (xy 420.87762 -354.38105) (xy 420.822777 -354.37092)
			(xy 420.769993 -354.352913) (xy 420.720393 -354.327412) (xy 420.675035 -354.294961) (xy 420.634886 -354.256252)
			(xy 420.6008 -354.212109) (xy 420.573504 -354.163474) (xy 420.553581 -354.111383) (xy 420.541455 -354.056946)
			(xy 420.537384 -354.001324) (xy 409.64358 -354.001324) (xy 409.64358 -354.613972) (xy 416.45408 -354.613972)
			(xy 416.458151 -354.55835) (xy 416.470277 -354.503913) (xy 416.4902 -354.451822) (xy 416.517496 -354.403187)
			(xy 416.551582 -354.359044) (xy 416.591731 -354.320335) (xy 416.637089 -354.287884) (xy 416.686689 -354.262383)
			(xy 416.739473 -354.244376) (xy 416.794316 -354.234246) (xy 416.85005 -354.232209) (xy 416.905487 -354.238309)
			(xy 416.959444 -354.252415) (xy 417.010773 -354.274227) (xy 417.058379 -354.303281) (xy 417.101247 -354.338956)
			(xy 417.138464 -354.380493) (xy 417.169237 -354.427006) (xy 417.192909 -354.477503) (xy 417.208977 -354.53091)
			(xy 417.217097 -354.586086) (xy 417.217606 -354.613972) (xy 417.217097 -354.641858) (xy 417.208977 -354.697034)
			(xy 417.192909 -354.750441) (xy 417.182464 -354.772722) (xy 418.51402 -354.772722) (xy 418.518091 -354.7171)
			(xy 418.530217 -354.662663) (xy 418.55014 -354.610572) (xy 418.577436 -354.561937) (xy 418.611522 -354.517794)
			(xy 418.651671 -354.479085) (xy 418.697029 -354.446634) (xy 418.746629 -354.421133) (xy 418.799413 -354.403126)
			(xy 418.854256 -354.392996) (xy 418.90999 -354.390959) (xy 418.965427 -354.397059) (xy 419.019384 -354.411165)
			(xy 419.070713 -354.432977) (xy 419.118319 -354.462031) (xy 419.161187 -354.497706) (xy 419.198404 -354.539243)
			(xy 419.229177 -354.585756) (xy 419.252849 -354.636253) (xy 419.268917 -354.68966) (xy 419.277037 -354.744836)
			(xy 419.277546 -354.772722) (xy 419.277037 -354.800608) (xy 419.268917 -354.855784) (xy 419.256615 -354.896674)
			(xy 419.958264 -354.896674) (xy 419.962335 -354.841052) (xy 419.974461 -354.786615) (xy 419.994384 -354.734524)
			(xy 420.02168 -354.685889) (xy 420.055766 -354.641746) (xy 420.095915 -354.603037) (xy 420.141273 -354.570586)
			(xy 420.190873 -354.545085) (xy 420.243657 -354.527078) (xy 420.2985 -354.516948) (xy 420.354234 -354.514911)
			(xy 420.409671 -354.521011) (xy 420.463628 -354.535117) (xy 420.514957 -354.556929) (xy 420.562563 -354.585983)
			(xy 420.605431 -354.621658) (xy 420.642648 -354.663195) (xy 420.673421 -354.709708) (xy 420.697093 -354.760205)
			(xy 420.713161 -354.813612) (xy 420.721281 -354.868788) (xy 420.72179 -354.896674) (xy 420.721281 -354.92456)
			(xy 420.713161 -354.979736) (xy 420.697093 -355.033143) (xy 420.673421 -355.08364) (xy 420.642648 -355.130153)
			(xy 420.605431 -355.17169) (xy 420.562563 -355.207365) (xy 420.514957 -355.236419) (xy 420.463628 -355.258231)
			(xy 420.409671 -355.272337) (xy 420.354234 -355.278437) (xy 420.2985 -355.2764) (xy 420.243657 -355.26627)
			(xy 420.190873 -355.248263) (xy 420.141273 -355.222762) (xy 420.095915 -355.190311) (xy 420.055766 -355.151602)
			(xy 420.02168 -355.107459) (xy 419.994384 -355.058824) (xy 419.974461 -355.006733) (xy 419.962335 -354.952296)
			(xy 419.958264 -354.896674) (xy 419.256615 -354.896674) (xy 419.252849 -354.909191) (xy 419.229177 -354.959688)
			(xy 419.198404 -355.006201) (xy 419.161187 -355.047738) (xy 419.118319 -355.083413) (xy 419.070713 -355.112467)
			(xy 419.019384 -355.134279) (xy 418.965427 -355.148385) (xy 418.90999 -355.154485) (xy 418.854256 -355.152448)
			(xy 418.799413 -355.142318) (xy 418.746629 -355.124311) (xy 418.697029 -355.09881) (xy 418.651671 -355.066359)
			(xy 418.611522 -355.02765) (xy 418.577436 -354.983507) (xy 418.55014 -354.934872) (xy 418.530217 -354.882781)
			(xy 418.518091 -354.828344) (xy 418.51402 -354.772722) (xy 417.182464 -354.772722) (xy 417.169237 -354.800938)
			(xy 417.138464 -354.847451) (xy 417.101247 -354.888988) (xy 417.058379 -354.924663) (xy 417.010773 -354.953717)
			(xy 416.959444 -354.975529) (xy 416.905487 -354.989635) (xy 416.85005 -354.995735) (xy 416.794316 -354.993698)
			(xy 416.739473 -354.983568) (xy 416.686689 -354.965561) (xy 416.637089 -354.94006) (xy 416.591731 -354.907609)
			(xy 416.551582 -354.8689) (xy 416.517496 -354.824757) (xy 416.4902 -354.776122) (xy 416.470277 -354.724031)
			(xy 416.458151 -354.669594) (xy 416.45408 -354.613972) (xy 409.64358 -354.613972) (xy 409.64358 -355.572314)
			(xy 421.2971 -355.572314) (xy 421.297595 -355.54484) (xy 421.305484 -355.49046) (xy 421.321103 -355.437778)
			(xy 421.344125 -355.387885) (xy 421.374075 -355.341816) (xy 421.391842 -355.320854) (xy 421.397938 -355.313742)
			(xy 421.404288 -355.296724) (xy 421.404288 -355.210872) (xy 421.397938 -355.193854) (xy 421.391842 -355.186742)
			(xy 421.374108 -355.165756) (xy 421.34418 -355.11968) (xy 421.321163 -355.069792) (xy 421.30553 -355.01712)
			(xy 421.297604 -354.962753) (xy 421.2971 -354.935282) (xy 421.297586 -354.908031) (xy 421.305342 -354.854083)
			(xy 421.320697 -354.801788) (xy 421.343339 -354.752211) (xy 421.372805 -354.706361) (xy 421.408496 -354.66517)
			(xy 421.449687 -354.629479) (xy 421.495537 -354.600013) (xy 421.545114 -354.577371) (xy 421.597409 -354.562016)
			(xy 421.651357 -354.55426) (xy 421.705859 -354.55426) (xy 421.759807 -354.562016) (xy 421.812102 -354.577371)
			(xy 421.861679 -354.600013) (xy 421.907529 -354.629479) (xy 421.94872 -354.66517) (xy 421.984411 -354.706361)
			(xy 422.013877 -354.752211) (xy 422.036519 -354.801788) (xy 422.051874 -354.854083) (xy 422.05963 -354.908031)
			(xy 422.060116 -354.935282) (xy 422.059615 -354.962756) (xy 422.051726 -355.017135) (xy 422.036109 -355.069817)
			(xy 422.033462 -355.075553) (xy 422.301867 -355.075553) (xy 422.301867 -355.021047) (xy 422.309625 -354.967096)
			(xy 422.324981 -354.914797) (xy 422.347625 -354.865217) (xy 422.377094 -354.819364) (xy 422.412789 -354.778172)
			(xy 422.453984 -354.74248) (xy 422.499838 -354.713014) (xy 422.54942 -354.690373) (xy 422.601719 -354.67502)
			(xy 422.655671 -354.667266) (xy 422.682924 -354.666804) (xy 422.70816 -354.66719) (xy 422.758194 -354.673811)
			(xy 422.806914 -354.686987) (xy 422.853466 -354.706488) (xy 422.875456 -354.718874) (xy 422.885108 -354.724716)
			(xy 422.907206 -354.726748) (xy 423.001694 -354.69322) (xy 423.017696 -354.677726) (xy 423.02176 -354.667312)
			(xy 423.032479 -354.640545) (xy 423.060763 -354.590304) (xy 423.096289 -354.544893) (xy 423.138247 -354.50535)
			(xy 423.185681 -354.472575) (xy 423.23751 -354.447315) (xy 423.29255 -354.430147) (xy 423.349548 -354.421463)
			(xy 423.378376 -354.420932) (xy 423.40563 -354.421378) (xy 423.459584 -354.429133) (xy 423.511884 -354.444488)
			(xy 423.561467 -354.46713) (xy 423.607322 -354.496599) (xy 423.648516 -354.532295) (xy 423.68421 -354.573491)
			(xy 423.713678 -354.619347) (xy 423.736318 -354.668931) (xy 423.751671 -354.721232) (xy 423.759423 -354.775186)
			(xy 423.759884 -354.80244) (xy 423.759227 -354.834003) (xy 423.748839 -354.896268) (xy 423.728352 -354.955977)
			(xy 423.71391 -354.98405) (xy 423.709084 -354.99294) (xy 423.707052 -355.012498) (xy 423.732706 -355.100636)
			(xy 423.745152 -355.11613) (xy 423.754042 -355.12121) (xy 423.779119 -355.135799) (xy 423.825003 -355.171294)
			(xy 423.864982 -355.21333) (xy 423.898131 -355.260936) (xy 423.923686 -355.313015) (xy 423.941057 -355.368365)
			(xy 423.949843 -355.425706) (xy 423.950384 -355.454712) (xy 423.949898 -355.481963) (xy 423.942142 -355.535911)
			(xy 423.926787 -355.588206) (xy 423.904145 -355.637783) (xy 423.874679 -355.683633) (xy 423.838988 -355.724824)
			(xy 423.797797 -355.760515) (xy 423.751947 -355.789981) (xy 423.70237 -355.812623) (xy 423.650075 -355.827978)
			(xy 423.596127 -355.835734) (xy 423.541625 -355.835734) (xy 423.487677 -355.827978) (xy 423.435382 -355.812623)
			(xy 423.385805 -355.789981) (xy 423.339955 -355.760515) (xy 423.298764 -355.724824) (xy 423.263073 -355.683633)
			(xy 423.233607 -355.637783) (xy 423.210965 -355.588206) (xy 423.19561 -355.535911) (xy 423.187854 -355.481963)
			(xy 423.187368 -355.454712) (xy 423.188012 -355.423149) (xy 423.198407 -355.360883) (xy 423.218898 -355.301174)
			(xy 423.233342 -355.273102) (xy 423.238168 -355.264212) (xy 423.2402 -355.244654) (xy 423.214546 -355.156516)
			(xy 423.2021 -355.141022) (xy 423.19321 -355.135942) (xy 423.185844 -355.131878) (xy 423.176192 -355.126036)
			(xy 423.154094 -355.124004) (xy 423.059606 -355.157532) (xy 423.043604 -355.173026) (xy 423.03954 -355.18344)
			(xy 423.028848 -355.210218) (xy 423.000558 -355.260458) (xy 422.965027 -355.305867) (xy 422.923064 -355.345408)
			(xy 422.875626 -355.378181) (xy 422.823795 -355.403439) (xy 422.768753 -355.420605) (xy 422.711753 -355.429289)
			(xy 422.682924 -355.42982) (xy 422.655671 -355.429334) (xy 422.601719 -355.42158) (xy 422.54942 -355.406227)
			(xy 422.499838 -355.383586) (xy 422.453984 -355.35412) (xy 422.412789 -355.318428) (xy 422.377094 -355.277236)
			(xy 422.347625 -355.231383) (xy 422.324981 -355.181803) (xy 422.309625 -355.129504) (xy 422.301867 -355.075553)
			(xy 422.033462 -355.075553) (xy 422.013088 -355.11971) (xy 421.98314 -355.165779) (xy 421.965374 -355.186742)
			(xy 421.959278 -355.193854) (xy 421.952928 -355.210872) (xy 421.952928 -355.296724) (xy 421.959278 -355.313742)
			(xy 421.965374 -355.320854) (xy 421.983109 -355.341839) (xy 422.013036 -355.387916) (xy 422.036053 -355.437804)
			(xy 422.051686 -355.490476) (xy 422.059612 -355.544843) (xy 422.060116 -355.572314) (xy 422.05963 -355.599565)
			(xy 422.051874 -355.653513) (xy 422.036519 -355.705808) (xy 422.013877 -355.755385) (xy 421.984411 -355.801235)
			(xy 421.94872 -355.842426) (xy 421.907529 -355.878117) (xy 421.861679 -355.907583) (xy 421.812102 -355.930225)
			(xy 421.759807 -355.94558) (xy 421.705859 -355.953336) (xy 421.651357 -355.953336) (xy 421.597409 -355.94558)
			(xy 421.545114 -355.930225) (xy 421.495537 -355.907583) (xy 421.449687 -355.878117) (xy 421.408496 -355.842426)
			(xy 421.372805 -355.801235) (xy 421.343339 -355.755385) (xy 421.320697 -355.705808) (xy 421.305342 -355.653513)
			(xy 421.297586 -355.599565) (xy 421.2971 -355.572314) (xy 409.64358 -355.572314) (xy 409.64358 -357.223822)
			(xy 416.449002 -357.223822) (xy 416.449535 -357.194906) (xy 416.458261 -357.137735) (xy 416.475516 -357.082537)
			(xy 416.500905 -357.030575) (xy 416.533846 -356.983041) (xy 416.573584 -356.941023) (xy 416.596068 -356.922832)
			(xy 416.604822 -356.915264) (xy 416.615007 -356.894509) (xy 416.615626 -356.882954) (xy 416.615626 -356.80269)
			(xy 416.615087 -356.791117) (xy 416.604873 -356.770345) (xy 416.596068 -356.762812) (xy 416.573584 -356.744622)
			(xy 416.53385 -356.702601) (xy 416.500912 -356.655066) (xy 416.475524 -356.603104) (xy 416.458268 -356.547907)
			(xy 416.449538 -356.490738) (xy 416.449002 -356.461822) (xy 416.449488 -356.434571) (xy 416.457244 -356.380623)
			(xy 416.472599 -356.328328) (xy 416.495241 -356.278751) (xy 416.524707 -356.232901) (xy 416.560398 -356.19171)
			(xy 416.601589 -356.156019) (xy 416.647439 -356.126553) (xy 416.697016 -356.103911) (xy 416.749311 -356.088556)
			(xy 416.803259 -356.0808) (xy 416.857761 -356.0808) (xy 416.911709 -356.088556) (xy 416.964004 -356.103911)
			(xy 417.013581 -356.126553) (xy 417.059431 -356.156019) (xy 417.100622 -356.19171) (xy 417.136313 -356.232901)
			(xy 417.165779 -356.278751) (xy 417.188421 -356.328328) (xy 417.203776 -356.380623) (xy 417.211532 -356.434571)
			(xy 417.212018 -356.461822) (xy 417.211475 -356.490738) (xy 417.202755 -356.54791) (xy 417.185504 -356.603109)
			(xy 417.160117 -356.655072) (xy 417.127177 -356.702606) (xy 417.087437 -356.744622) (xy 417.064952 -356.762812)
			(xy 417.056181 -356.770365) (xy 417.046005 -356.791131) (xy 417.045394 -356.80269) (xy 417.045394 -356.882954)
			(xy 417.045993 -356.894518) (xy 417.056168 -356.915289) (xy 417.064952 -356.922832) (xy 417.087462 -356.940992)
			(xy 417.127193 -356.98302) (xy 417.160127 -357.030561) (xy 417.185511 -357.082529) (xy 417.202762 -357.137731)
			(xy 417.211486 -357.194904) (xy 417.212018 -357.223822) (xy 417.211764 -357.240078) (xy 417.211002 -357.254556)
			(xy 417.224718 -357.279194) (xy 417.328096 -357.338122) (xy 417.35629 -357.33736) (xy 417.368482 -357.329486)
			(xy 417.391804 -357.314957) (xy 417.441716 -357.291983) (xy 417.494404 -357.276392) (xy 417.548781 -357.268504)
			(xy 417.576254 -357.268018) (xy 417.603511 -357.268406) (xy 417.65747 -357.276157) (xy 417.709776 -357.291509)
			(xy 417.759365 -357.314149) (xy 417.805228 -357.343616) (xy 417.84643 -357.379309) (xy 417.882133 -357.420504)
			(xy 417.91161 -357.46636) (xy 417.934261 -357.515944) (xy 417.949625 -357.568247) (xy 417.957388 -357.622204)
			(xy 417.957394 -357.676717) (xy 417.949641 -357.730676) (xy 417.934288 -357.782982) (xy 417.911648 -357.832571)
			(xy 417.88218 -357.878433) (xy 417.846486 -357.919635) (xy 417.805291 -357.955337) (xy 417.759435 -357.984813)
			(xy 417.70985 -358.007463) (xy 417.657547 -358.022826) (xy 417.603589 -358.030589) (xy 417.549076 -358.030593)
			(xy 417.495117 -358.02284) (xy 417.442811 -358.007486) (xy 417.393223 -357.984845) (xy 417.347361 -357.955376)
			(xy 417.30616 -357.919681) (xy 417.270459 -357.878486) (xy 417.240984 -357.832629) (xy 417.218334 -357.783044)
			(xy 417.202973 -357.73074) (xy 417.195211 -357.676782) (xy 417.194746 -357.649526) (xy 417.195 -357.63327)
			(xy 417.195762 -357.618792) (xy 417.182046 -357.594154) (xy 417.078668 -357.535226) (xy 417.050474 -357.535988)
			(xy 417.038282 -357.543862) (xy 417.014965 -357.5584) (xy 416.965051 -357.581373) (xy 416.912362 -357.596962)
			(xy 416.857983 -357.604846) (xy 416.83051 -357.60533) (xy 416.80326 -357.604812) (xy 416.749315 -357.597058)
			(xy 416.697022 -357.581705) (xy 416.647446 -357.559067) (xy 416.601597 -357.529604) (xy 416.560407 -357.493916)
			(xy 416.524716 -357.452729) (xy 416.495249 -357.406882) (xy 416.472606 -357.357308) (xy 416.457249 -357.305017)
			(xy 416.44949 -357.251072) (xy 416.449002 -357.223822) (xy 409.64358 -357.223822) (xy 409.64358 -358.836214)
			(xy 417.824664 -358.836214) (xy 417.828735 -358.780592) (xy 417.840861 -358.726155) (xy 417.860784 -358.674064)
			(xy 417.88808 -358.625429) (xy 417.922166 -358.581286) (xy 417.962315 -358.542577) (xy 418.007673 -358.510126)
			(xy 418.057273 -358.484625) (xy 418.110057 -358.466618) (xy 418.1649 -358.456488) (xy 418.220634 -358.454451)
			(xy 418.276071 -358.460551) (xy 418.330028 -358.474657) (xy 418.381357 -358.496469) (xy 418.428963 -358.525523)
			(xy 418.471831 -358.561198) (xy 418.509048 -358.602735) (xy 418.539821 -358.649248) (xy 418.563493 -358.699745)
			(xy 418.579561 -358.753152) (xy 418.587681 -358.808328) (xy 418.58819 -358.836214) (xy 418.587681 -358.8641)
			(xy 418.579561 -358.919276) (xy 418.563493 -358.972683) (xy 418.539821 -359.02318) (xy 418.509048 -359.069693)
			(xy 418.471831 -359.11123) (xy 418.428963 -359.146905) (xy 418.381357 -359.175959) (xy 418.330028 -359.197771)
			(xy 418.276071 -359.211877) (xy 418.220634 -359.217977) (xy 418.1649 -359.21594) (xy 418.110057 -359.20581)
			(xy 418.057273 -359.187803) (xy 418.007673 -359.162302) (xy 417.962315 -359.129851) (xy 417.922166 -359.091142)
			(xy 417.88808 -359.046999) (xy 417.860784 -358.998364) (xy 417.840861 -358.946273) (xy 417.828735 -358.891836)
			(xy 417.824664 -358.836214) (xy 409.64358 -358.836214) (xy 409.64358 -360.7943) (xy 412.920178 -360.7943)
			(xy 412.924249 -360.738678) (xy 412.936375 -360.684241) (xy 412.956298 -360.63215) (xy 412.983594 -360.583515)
			(xy 413.01768 -360.539372) (xy 413.057829 -360.500663) (xy 413.103187 -360.468212) (xy 413.152787 -360.442711)
			(xy 413.205571 -360.424704) (xy 413.260414 -360.414574) (xy 413.316148 -360.412537) (xy 413.371585 -360.418637)
			(xy 413.425542 -360.432743) (xy 413.476871 -360.454555) (xy 413.524477 -360.483609) (xy 413.567345 -360.519284)
			(xy 413.604562 -360.560821) (xy 413.635335 -360.607334) (xy 413.659007 -360.657831) (xy 413.675075 -360.711238)
			(xy 413.683195 -360.766414) (xy 413.683704 -360.7943) (xy 413.683195 -360.822186) (xy 413.675075 -360.877362)
			(xy 413.659007 -360.930769) (xy 413.635335 -360.981266) (xy 413.604562 -361.027779) (xy 413.567345 -361.069316)
			(xy 413.524477 -361.104991) (xy 413.476871 -361.134045) (xy 413.425542 -361.155857) (xy 413.371585 -361.169963)
			(xy 413.316148 -361.176063) (xy 413.260414 -361.174026) (xy 413.205571 -361.163896) (xy 413.152787 -361.145889)
			(xy 413.103187 -361.120388) (xy 413.057829 -361.087937) (xy 413.01768 -361.049228) (xy 412.983594 -361.005085)
			(xy 412.956298 -360.95645) (xy 412.936375 -360.904359) (xy 412.924249 -360.849922) (xy 412.920178 -360.7943)
			(xy 409.64358 -360.7943) (xy 409.64358 -362.804964) (xy 412.931864 -362.804964) (xy 412.932395 -362.774991)
			(xy 412.941711 -362.715776) (xy 412.960187 -362.65875) (xy 412.987366 -362.605322) (xy 413.022578 -362.556811)
			(xy 413.04337 -362.535216) (xy 414.052766 -361.526074) (xy 414.059605 -361.518673) (xy 414.067326 -361.500075)
			(xy 414.067752 -361.490006) (xy 414.067752 -360.90479) (xy 414.06824 -360.874816) (xy 414.077567 -360.815599)
			(xy 414.096054 -360.758573) (xy 414.123242 -360.705145) (xy 414.158462 -360.656635) (xy 414.179258 -360.635042)
			(xy 415.207958 -359.606342) (xy 415.229577 -359.585581) (xy 415.278096 -359.550394) (xy 415.33152 -359.523226)
			(xy 415.388535 -359.504746) (xy 415.447738 -359.495407) (xy 415.477706 -359.494836) (xy 420.936674 -359.494836)
			(xy 420.946744 -359.494414) (xy 420.965343 -359.486693) (xy 420.972742 -359.47985) (xy 421.537384 -358.914954)
			(xy 421.558993 -358.894183) (xy 421.607515 -358.858997) (xy 421.660941 -358.831831) (xy 421.717958 -358.813352)
			(xy 421.777163 -358.804017) (xy 421.807132 -358.803448) (xy 424.163744 -358.803448) (xy 424.193717 -358.803979)
			(xy 424.252932 -358.813296) (xy 424.309957 -358.831772) (xy 424.363385 -358.858951) (xy 424.411897 -358.894162)
			(xy 424.433492 -358.914954) (xy 425.085002 -359.566464) (xy 425.105774 -359.588073) (xy 425.140957 -359.636596)
			(xy 425.168122 -359.690022) (xy 425.186601 -359.747039) (xy 425.195938 -359.806244) (xy 425.196508 -359.836212)
			(xy 425.196034 -359.863452) (xy 425.188283 -359.917378) (xy 425.172939 -359.969653) (xy 425.150315 -360.019213)
			(xy 425.120871 -360.065051) (xy 425.085206 -360.106234) (xy 425.044045 -360.141926) (xy 424.998226 -360.171399)
			(xy 424.94868 -360.194054) (xy 424.896415 -360.209431) (xy 424.842494 -360.217217) (xy 424.815254 -360.21772)
			(xy 424.785275 -360.217165) (xy 424.726058 -360.207766) (xy 424.669039 -360.189224) (xy 424.615621 -360.161993)
			(xy 424.567118 -360.126744) (xy 424.545506 -360.10596) (xy 424.020742 -359.580942) (xy 424.013317 -359.574134)
			(xy 423.994737 -359.566394) (xy 423.984674 -359.565956) (xy 422.519856 -359.565956) (xy 422.510978 -359.566354)
			(xy 422.494299 -359.572451) (xy 422.480695 -359.583864) (xy 422.475914 -359.591356) (xy 422.42486 -359.678732)
			(xy 422.424606 -359.705656) (xy 422.431464 -359.717594) (xy 422.443113 -359.739109) (xy 422.461442 -359.784473)
			(xy 422.473835 -359.831804) (xy 422.48009 -359.880329) (xy 422.480486 -359.904792) (xy 422.480037 -359.932046)
			(xy 422.472281 -359.985998) (xy 422.456925 -360.038298) (xy 422.434281 -360.087879) (xy 422.404812 -360.133733)
			(xy 422.369117 -360.174927) (xy 422.327922 -360.210621) (xy 422.282067 -360.240088) (xy 422.232485 -360.262729)
			(xy 422.180185 -360.278084) (xy 422.126232 -360.285838) (xy 422.098978 -360.2863) (xy 422.07168 -360.285838)
			(xy 422.017641 -360.278052) (xy 421.965264 -360.262643) (xy 421.915618 -360.239924) (xy 421.869719 -360.21036)
			(xy 421.828502 -360.174555) (xy 421.792811 -360.13324) (xy 421.763373 -360.087259) (xy 421.740791 -360.037551)
			(xy 421.73271 -360.011472) (xy 421.7289 -359.998518) (xy 421.709596 -359.979722) (xy 421.611806 -359.954576)
			(xy 421.603176 -359.952806) (xy 421.585658 -359.954512) (xy 421.569757 -359.962056) (xy 421.563292 -359.968038)
			(xy 421.385492 -360.145838) (xy 421.363848 -360.166572) (xy 421.315336 -360.201763) (xy 421.261918 -360.228936)
			(xy 421.204909 -360.247423) (xy 421.14571 -360.25677) (xy 421.115744 -360.257344) (xy 415.656776 -360.257344)
			(xy 415.646704 -360.257745) (xy 415.628106 -360.265482) (xy 415.620708 -360.27233) (xy 414.845246 -361.047792)
			(xy 414.838423 -361.055206) (xy 414.830692 -361.073794) (xy 414.83026 -361.08386) (xy 414.83026 -361.3023)
			(xy 414.979356 -361.3023) (xy 414.983427 -361.246678) (xy 414.995553 -361.192241) (xy 415.015476 -361.14015)
			(xy 415.042772 -361.091515) (xy 415.076858 -361.047372) (xy 415.117007 -361.008663) (xy 415.162365 -360.976212)
			(xy 415.211965 -360.950711) (xy 415.264749 -360.932704) (xy 415.319592 -360.922574) (xy 415.375326 -360.920537)
			(xy 415.430763 -360.926637) (xy 415.48472 -360.940743) (xy 415.536049 -360.962555) (xy 415.583655 -360.991609)
			(xy 415.626523 -361.027284) (xy 415.66374 -361.068821) (xy 415.694513 -361.115334) (xy 415.718185 -361.165831)
			(xy 415.734253 -361.219238) (xy 415.742373 -361.274414) (xy 415.742882 -361.3023) (xy 415.742373 -361.330186)
			(xy 415.734253 -361.385362) (xy 415.718185 -361.438769) (xy 415.694513 -361.489266) (xy 415.66374 -361.535779)
			(xy 415.626523 -361.577316) (xy 415.583655 -361.612991) (xy 415.536049 -361.642045) (xy 415.48472 -361.663857)
			(xy 415.430763 -361.677963) (xy 415.375326 -361.684063) (xy 415.319592 -361.682026) (xy 415.264749 -361.671896)
			(xy 415.211965 -361.653889) (xy 415.162365 -361.628388) (xy 415.117007 -361.595937) (xy 415.076858 -361.557228)
			(xy 415.042772 -361.513085) (xy 415.015476 -361.46445) (xy 414.995553 -361.412359) (xy 414.983427 -361.357922)
			(xy 414.979356 -361.3023) (xy 414.83026 -361.3023) (xy 414.83026 -361.669076) (xy 414.829747 -361.699049)
			(xy 414.82311 -361.741212) (xy 421.89019 -361.741212) (xy 421.8907 -361.712991) (xy 421.899014 -361.657165)
			(xy 421.915463 -361.603173) (xy 421.939686 -361.552194) (xy 421.971156 -361.50534) (xy 422.009186 -361.463634)
			(xy 422.052946 -361.427986) (xy 422.10148 -361.399174) (xy 422.153729 -361.377828) (xy 422.18102 -361.370626)
			(xy 422.192196 -361.367832) (xy 422.209214 -361.354116) (xy 422.253918 -361.263946) (xy 422.254426 -361.241848)
			(xy 422.249854 -361.23118) (xy 422.239727 -361.206976) (xy 422.225476 -361.156479) (xy 422.218285 -361.104506)
			(xy 422.21785 -361.078272) (xy 422.218336 -361.051021) (xy 422.226092 -360.997073) (xy 422.241447 -360.944778)
			(xy 422.264089 -360.895201) (xy 422.293555 -360.849351) (xy 422.329246 -360.80816) (xy 422.370437 -360.772469)
			(xy 422.416287 -360.743003) (xy 422.465864 -360.720361) (xy 422.518159 -360.705006) (xy 422.572107 -360.69725)
			(xy 422.626609 -360.69725) (xy 422.680557 -360.705006) (xy 422.732852 -360.720361) (xy 422.782429 -360.743003)
			(xy 422.828279 -360.772469) (xy 422.86947 -360.80816) (xy 422.905161 -360.849351) (xy 422.934627 -360.895201)
			(xy 422.957269 -360.944778) (xy 422.972624 -360.997073) (xy 422.98038 -361.051021) (xy 422.980866 -361.078272)
			(xy 422.980375 -361.106494) (xy 422.972062 -361.162322) (xy 422.955613 -361.216317) (xy 422.931389 -361.267298)
			(xy 422.899916 -361.314153) (xy 422.861883 -361.355859) (xy 422.81812 -361.391506) (xy 422.769582 -361.420316)
			(xy 422.717329 -361.441658) (xy 422.690036 -361.448858) (xy 422.67886 -361.451652) (xy 422.661842 -361.465368)
			(xy 422.627464 -361.53471) (xy 424.407836 -361.53471) (xy 424.411907 -361.479088) (xy 424.424033 -361.424651)
			(xy 424.443956 -361.37256) (xy 424.471252 -361.323925) (xy 424.505338 -361.279782) (xy 424.545487 -361.241073)
			(xy 424.590845 -361.208622) (xy 424.640445 -361.183121) (xy 424.693229 -361.165114) (xy 424.748072 -361.154984)
			(xy 424.803806 -361.152947) (xy 424.859243 -361.159047) (xy 424.9132 -361.173153) (xy 424.964529 -361.194965)
			(xy 425.012135 -361.224019) (xy 425.055003 -361.259694) (xy 425.09222 -361.301231) (xy 425.122993 -361.347744)
			(xy 425.146665 -361.398241) (xy 425.162733 -361.451648) (xy 425.170853 -361.506824) (xy 425.171362 -361.53471)
			(xy 425.170853 -361.562596) (xy 425.162733 -361.617772) (xy 425.146665 -361.671179) (xy 425.122993 -361.721676)
			(xy 425.09222 -361.768189) (xy 425.055003 -361.809726) (xy 425.012135 -361.845401) (xy 424.964529 -361.874455)
			(xy 424.9132 -361.896267) (xy 424.859243 -361.910373) (xy 424.803806 -361.916473) (xy 424.748072 -361.914436)
			(xy 424.693229 -361.904306) (xy 424.640445 -361.886299) (xy 424.590845 -361.860798) (xy 424.545487 -361.828347)
			(xy 424.505338 -361.789638) (xy 424.471252 -361.745495) (xy 424.443956 -361.69686) (xy 424.424033 -361.644769)
			(xy 424.411907 -361.590332) (xy 424.407836 -361.53471) (xy 422.627464 -361.53471) (xy 422.617138 -361.555538)
			(xy 422.61663 -361.577636) (xy 422.621202 -361.588304) (xy 422.631327 -361.612509) (xy 422.645578 -361.663005)
			(xy 422.65277 -361.714978) (xy 422.653206 -361.741212) (xy 422.653111 -361.751457) (xy 422.651969 -361.771915)
			(xy 422.65092 -361.782106) (xy 422.649904 -361.792266) (xy 422.656 -361.812078) (xy 422.715944 -361.88396)
			(xy 422.734232 -361.893358) (xy 422.744392 -361.89412) (xy 422.772852 -361.89667) (xy 422.828568 -361.909356)
			(xy 422.88177 -361.930208) (xy 422.931268 -361.95876) (xy 422.975955 -361.994372) (xy 423.014833 -362.03625)
			(xy 423.047032 -362.083456) (xy 423.071833 -362.134936) (xy 423.088681 -362.189537) (xy 423.097199 -362.246041)
			(xy 423.097706 -362.274612) (xy 423.097235 -362.301594) (xy 423.089605 -362.355016) (xy 423.074527 -362.406832)
			(xy 423.052302 -362.456007) (xy 423.023372 -362.501561) (xy 422.988314 -362.542588) (xy 422.947828 -362.578267)
			(xy 422.902721 -362.607889) (xy 422.878504 -362.619798) (xy 422.870122 -362.623862) (xy 422.857168 -362.63707)
			(xy 422.823132 -362.716064) (xy 422.82237 -362.734606) (xy 422.825164 -362.743496) (xy 422.834042 -362.77241)
			(xy 422.843614 -362.832128) (xy 422.844214 -362.862368) (xy 422.843728 -362.889619) (xy 422.835972 -362.943567)
			(xy 422.820617 -362.995862) (xy 422.797975 -363.045439) (xy 422.768509 -363.091289) (xy 422.732818 -363.13248)
			(xy 422.691627 -363.168171) (xy 422.645777 -363.197637) (xy 422.5962 -363.220279) (xy 422.543905 -363.235634)
			(xy 422.489957 -363.24339) (xy 422.435455 -363.24339) (xy 422.381507 -363.235634) (xy 422.329212 -363.220279)
			(xy 422.279635 -363.197637) (xy 422.233785 -363.168171) (xy 422.192594 -363.13248) (xy 422.156903 -363.091289)
			(xy 422.127437 -363.045439) (xy 422.104795 -362.995862) (xy 422.08944 -362.943567) (xy 422.081684 -362.889619)
			(xy 422.081198 -362.862368) (xy 422.081733 -362.835388) (xy 422.089352 -362.781968) (xy 422.10442 -362.730155)
			(xy 422.126636 -362.68098) (xy 422.155557 -362.635425) (xy 422.190606 -362.594397) (xy 422.231085 -362.558716)
			(xy 422.276186 -362.529092) (xy 422.3004 -362.517182) (xy 422.308782 -362.513118) (xy 422.321736 -362.49991)
			(xy 422.355772 -362.420916) (xy 422.356534 -362.402374) (xy 422.35374 -362.393484) (xy 422.344857 -362.364572)
			(xy 422.335288 -362.304852) (xy 422.33469 -362.274612) (xy 422.334779 -362.264367) (xy 422.335925 -362.243909)
			(xy 422.336976 -362.233718) (xy 422.337992 -362.223558) (xy 422.331896 -362.203746) (xy 422.271952 -362.131864)
			(xy 422.253664 -362.122466) (xy 422.243504 -362.121704) (xy 422.215055 -362.119049) (xy 422.159343 -362.106377)
			(xy 422.106143 -362.085539) (xy 422.056646 -362.057001) (xy 422.011958 -362.021401) (xy 421.973078 -361.979535)
			(xy 421.940876 -361.932339) (xy 421.916072 -361.880869) (xy 421.899221 -361.826275) (xy 421.890699 -361.769779)
			(xy 421.89019 -361.741212) (xy 414.82311 -361.741212) (xy 414.820425 -361.758265) (xy 414.801945 -361.815291)
			(xy 414.774762 -361.868718) (xy 414.739547 -361.91723) (xy 414.718754 -361.938824) (xy 413.582866 -363.074712)
			(xy 413.561304 -363.095552) (xy 413.512792 -363.130801) (xy 413.459362 -363.158023) (xy 413.40233 -363.176549)
			(xy 413.343101 -363.18592) (xy 413.313118 -363.186472) (xy 413.285873 -363.185974) (xy 413.231938 -363.178218)
			(xy 413.179656 -363.162863) (xy 413.130093 -363.14022) (xy 413.084259 -363.110752) (xy 413.043088 -363.075058)
			(xy 413.007417 -363.033866) (xy 412.977975 -362.988015) (xy 412.955361 -362.938439) (xy 412.940035 -362.886149)
			(xy 412.932311 -362.832209) (xy 412.931864 -362.804964) (xy 409.64358 -362.804964) (xy 409.64358 -363.356144)
			(xy 415.065208 -363.356144) (xy 415.069279 -363.300522) (xy 415.081405 -363.246085) (xy 415.101328 -363.193994)
			(xy 415.128624 -363.145359) (xy 415.16271 -363.101216) (xy 415.202859 -363.062507) (xy 415.248217 -363.030056)
			(xy 415.297817 -363.004555) (xy 415.350601 -362.986548) (xy 415.405444 -362.976418) (xy 415.461178 -362.974381)
			(xy 415.516615 -362.980481) (xy 415.570572 -362.994587) (xy 415.621901 -363.016399) (xy 415.669507 -363.045453)
			(xy 415.712375 -363.081128) (xy 415.749592 -363.122665) (xy 415.780365 -363.169178) (xy 415.804037 -363.219675)
			(xy 415.820105 -363.273082) (xy 415.828225 -363.328258) (xy 415.828734 -363.356144) (xy 415.828225 -363.38403)
			(xy 415.820105 -363.439206) (xy 415.804037 -363.492613) (xy 415.780365 -363.54311) (xy 415.749592 -363.589623)
			(xy 415.712375 -363.63116) (xy 415.669507 -363.666835) (xy 415.621901 -363.695889) (xy 415.570572 -363.717701)
			(xy 415.516615 -363.731807) (xy 415.461178 -363.737907) (xy 415.405444 -363.73587) (xy 415.350601 -363.72574)
			(xy 415.297817 -363.707733) (xy 415.248217 -363.682232) (xy 415.202859 -363.649781) (xy 415.16271 -363.611072)
			(xy 415.128624 -363.566929) (xy 415.101328 -363.518294) (xy 415.081405 -363.466203) (xy 415.069279 -363.411766)
			(xy 415.065208 -363.356144) (xy 409.64358 -363.356144) (xy 409.64358 -364.079536) (xy 412.440372 -364.079536)
			(xy 412.444443 -364.023914) (xy 412.456569 -363.969477) (xy 412.476492 -363.917386) (xy 412.503788 -363.868751)
			(xy 412.537874 -363.824608) (xy 412.578023 -363.785899) (xy 412.623381 -363.753448) (xy 412.672981 -363.727947)
			(xy 412.725765 -363.70994) (xy 412.780608 -363.69981) (xy 412.836342 -363.697773) (xy 412.891779 -363.703873)
			(xy 412.945736 -363.717979) (xy 412.997065 -363.739791) (xy 413.044671 -363.768845) (xy 413.087539 -363.80452)
			(xy 413.124756 -363.846057) (xy 413.155529 -363.89257) (xy 413.179201 -363.943067) (xy 413.182585 -363.954314)
			(xy 425.230796 -363.954314) (xy 425.234867 -363.898692) (xy 425.246993 -363.844255) (xy 425.266916 -363.792164)
			(xy 425.294212 -363.743529) (xy 425.328298 -363.699386) (xy 425.368447 -363.660677) (xy 425.413805 -363.628226)
			(xy 425.463405 -363.602725) (xy 425.516189 -363.584718) (xy 425.571032 -363.574588) (xy 425.626766 -363.572551)
			(xy 425.682203 -363.578651) (xy 425.73616 -363.592757) (xy 425.787489 -363.614569) (xy 425.835095 -363.643623)
			(xy 425.877963 -363.679298) (xy 425.91518 -363.720835) (xy 425.945953 -363.767348) (xy 425.969625 -363.817845)
			(xy 425.985693 -363.871252) (xy 425.993813 -363.926428) (xy 425.994322 -363.954314) (xy 425.993813 -363.9822)
			(xy 425.985693 -364.037376) (xy 425.969625 -364.090783) (xy 425.945953 -364.14128) (xy 425.91518 -364.187793)
			(xy 425.877963 -364.22933) (xy 425.835095 -364.265005) (xy 425.787489 -364.294059) (xy 425.73616 -364.315871)
			(xy 425.682203 -364.329977) (xy 425.626766 -364.336077) (xy 425.571032 -364.33404) (xy 425.516189 -364.32391)
			(xy 425.463405 -364.305903) (xy 425.413805 -364.280402) (xy 425.368447 -364.247951) (xy 425.328298 -364.209242)
			(xy 425.294212 -364.165099) (xy 425.266916 -364.116464) (xy 425.246993 -364.064373) (xy 425.234867 -364.009936)
			(xy 425.230796 -363.954314) (xy 413.182585 -363.954314) (xy 413.195269 -363.996474) (xy 413.203389 -364.05165)
			(xy 413.203898 -364.079536) (xy 413.203389 -364.107422) (xy 413.195269 -364.162598) (xy 413.179201 -364.216005)
			(xy 413.155529 -364.266502) (xy 413.124756 -364.313015) (xy 413.087539 -364.354552) (xy 413.084102 -364.357412)
			(xy 416.135818 -364.357412) (xy 416.139889 -364.30179) (xy 416.152015 -364.247353) (xy 416.171938 -364.195262)
			(xy 416.199234 -364.146627) (xy 416.23332 -364.102484) (xy 416.273469 -364.063775) (xy 416.318827 -364.031324)
			(xy 416.368427 -364.005823) (xy 416.421211 -363.987816) (xy 416.476054 -363.977686) (xy 416.531788 -363.975649)
			(xy 416.587225 -363.981749) (xy 416.641182 -363.995855) (xy 416.692511 -364.017667) (xy 416.740117 -364.046721)
			(xy 416.782985 -364.082396) (xy 416.820202 -364.123933) (xy 416.850975 -364.170446) (xy 416.874647 -364.220943)
			(xy 416.890715 -364.27435) (xy 416.898835 -364.329526) (xy 416.899344 -364.357412) (xy 416.898835 -364.385298)
			(xy 416.890715 -364.440474) (xy 416.874647 -364.493881) (xy 416.86825 -364.507526) (xy 424.072048 -364.507526)
			(xy 424.076119 -364.451904) (xy 424.088245 -364.397467) (xy 424.108168 -364.345376) (xy 424.135464 -364.296741)
			(xy 424.16955 -364.252598) (xy 424.209699 -364.213889) (xy 424.255057 -364.181438) (xy 424.304657 -364.155937)
			(xy 424.357441 -364.13793) (xy 424.412284 -364.1278) (xy 424.468018 -364.125763) (xy 424.523455 -364.131863)
			(xy 424.577412 -364.145969) (xy 424.628741 -364.167781) (xy 424.676347 -364.196835) (xy 424.719215 -364.23251)
			(xy 424.756432 -364.274047) (xy 424.787205 -364.32056) (xy 424.81052 -364.370296) (xy 431.124356 -364.370296)
			(xy 431.124356 -364.2856) (xy 431.132407 -364.201286) (xy 431.148436 -364.11812) (xy 431.172297 -364.036853)
			(xy 431.203776 -363.958223) (xy 431.242587 -363.882942) (xy 431.288377 -363.81169) (xy 431.340733 -363.745114)
			(xy 431.399181 -363.683816) (xy 431.463191 -363.628351) (xy 431.532183 -363.579222) (xy 431.605533 -363.536873)
			(xy 431.682576 -363.501689) (xy 431.762615 -363.473987) (xy 431.844924 -363.454019) (xy 431.928759 -363.441966)
			(xy 432.01336 -363.437936) (xy 432.097961 -363.441966) (xy 432.181796 -363.454019) (xy 432.264105 -363.473987)
			(xy 432.344144 -363.501689) (xy 432.421187 -363.536873) (xy 432.494537 -363.579222) (xy 432.563529 -363.628351)
			(xy 432.627539 -363.683816) (xy 432.685987 -363.745114) (xy 432.738343 -363.81169) (xy 432.784133 -363.882942)
			(xy 432.822944 -363.958223) (xy 432.854423 -364.036853) (xy 432.878284 -364.11812) (xy 432.894313 -364.201286)
			(xy 432.902364 -364.2856) (xy 432.902868 -364.327948) (xy 432.902364 -364.370296) (xy 432.894313 -364.45461)
			(xy 432.878284 -364.537776) (xy 432.854423 -364.619043) (xy 432.822944 -364.697673) (xy 432.784133 -364.772954)
			(xy 432.738343 -364.844206) (xy 432.685987 -364.910782) (xy 432.627539 -364.97208) (xy 432.563529 -365.027545)
			(xy 432.494537 -365.076674) (xy 432.421187 -365.119023) (xy 432.344144 -365.154207) (xy 432.264105 -365.181909)
			(xy 432.181796 -365.201877) (xy 432.097961 -365.21393) (xy 432.01336 -365.217961) (xy 431.928759 -365.21393)
			(xy 431.844924 -365.201877) (xy 431.762615 -365.181909) (xy 431.682576 -365.154207) (xy 431.605533 -365.119023)
			(xy 431.532183 -365.076674) (xy 431.463191 -365.027545) (xy 431.399181 -364.97208) (xy 431.340733 -364.910782)
			(xy 431.288377 -364.844206) (xy 431.242587 -364.772954) (xy 431.203776 -364.697673) (xy 431.172297 -364.619043)
			(xy 431.148436 -364.537776) (xy 431.132407 -364.45461) (xy 431.124356 -364.370296) (xy 424.81052 -364.370296)
			(xy 424.810877 -364.371057) (xy 424.826945 -364.424464) (xy 424.835065 -364.47964) (xy 424.835574 -364.507526)
			(xy 424.835065 -364.535412) (xy 424.826945 -364.590588) (xy 424.810877 -364.643995) (xy 424.787205 -364.694492)
			(xy 424.756432 -364.741005) (xy 424.719215 -364.782542) (xy 424.676347 -364.818217) (xy 424.628741 -364.847271)
			(xy 424.577412 -364.869083) (xy 424.523455 -364.883189) (xy 424.468018 -364.889289) (xy 424.412284 -364.887252)
			(xy 424.357441 -364.877122) (xy 424.304657 -364.859115) (xy 424.255057 -364.833614) (xy 424.209699 -364.801163)
			(xy 424.16955 -364.762454) (xy 424.135464 -364.718311) (xy 424.108168 -364.669676) (xy 424.088245 -364.617585)
			(xy 424.076119 -364.563148) (xy 424.072048 -364.507526) (xy 416.86825 -364.507526) (xy 416.850975 -364.544378)
			(xy 416.820202 -364.590891) (xy 416.782985 -364.632428) (xy 416.740117 -364.668103) (xy 416.692511 -364.697157)
			(xy 416.641182 -364.718969) (xy 416.587225 -364.733075) (xy 416.531788 -364.739175) (xy 416.476054 -364.737138)
			(xy 416.421211 -364.727008) (xy 416.368427 -364.709001) (xy 416.318827 -364.6835) (xy 416.273469 -364.651049)
			(xy 416.23332 -364.61234) (xy 416.199234 -364.568197) (xy 416.171938 -364.519562) (xy 416.152015 -364.467471)
			(xy 416.139889 -364.413034) (xy 416.135818 -364.357412) (xy 413.084102 -364.357412) (xy 413.044671 -364.390227)
			(xy 412.997065 -364.419281) (xy 412.945736 -364.441093) (xy 412.891779 -364.455199) (xy 412.836342 -364.461299)
			(xy 412.780608 -364.459262) (xy 412.725765 -364.449132) (xy 412.672981 -364.431125) (xy 412.623381 -364.405624)
			(xy 412.578023 -364.373173) (xy 412.537874 -364.334464) (xy 412.503788 -364.290321) (xy 412.476492 -364.241686)
			(xy 412.456569 -364.189595) (xy 412.444443 -364.135158) (xy 412.440372 -364.079536) (xy 409.64358 -364.079536)
			(xy 409.64358 -364.878112) (xy 414.96564 -364.878112) (xy 414.969711 -364.82249) (xy 414.981837 -364.768053)
			(xy 415.00176 -364.715962) (xy 415.029056 -364.667327) (xy 415.063142 -364.623184) (xy 415.103291 -364.584475)
			(xy 415.148649 -364.552024) (xy 415.198249 -364.526523) (xy 415.251033 -364.508516) (xy 415.305876 -364.498386)
			(xy 415.36161 -364.496349) (xy 415.417047 -364.502449) (xy 415.471004 -364.516555) (xy 415.522333 -364.538367)
			(xy 415.569939 -364.567421) (xy 415.612807 -364.603096) (xy 415.650024 -364.644633) (xy 415.680797 -364.691146)
			(xy 415.704469 -364.741643) (xy 415.720537 -364.79505) (xy 415.728657 -364.850226) (xy 415.729166 -364.878112)
			(xy 415.728657 -364.905998) (xy 415.720537 -364.961174) (xy 415.704469 -365.014581) (xy 415.680797 -365.065078)
			(xy 415.650024 -365.111591) (xy 415.612807 -365.153128) (xy 415.569939 -365.188803) (xy 415.522333 -365.217857)
			(xy 415.471872 -365.2393) (xy 417.696648 -365.2393) (xy 417.700719 -365.183678) (xy 417.712845 -365.129241)
			(xy 417.732768 -365.07715) (xy 417.760064 -365.028515) (xy 417.79415 -364.984372) (xy 417.834299 -364.945663)
			(xy 417.879657 -364.913212) (xy 417.929257 -364.887711) (xy 417.982041 -364.869704) (xy 418.036884 -364.859574)
			(xy 418.092618 -364.857537) (xy 418.148055 -364.863637) (xy 418.202012 -364.877743) (xy 418.253341 -364.899555)
			(xy 418.300947 -364.928609) (xy 418.343815 -364.964284) (xy 418.381032 -365.005821) (xy 418.411805 -365.052334)
			(xy 418.435477 -365.102831) (xy 418.451545 -365.156238) (xy 418.458909 -365.20628) (xy 418.819582 -365.20628)
			(xy 418.823653 -365.150658) (xy 418.835779 -365.096221) (xy 418.855702 -365.04413) (xy 418.882998 -364.995495)
			(xy 418.917084 -364.951352) (xy 418.957233 -364.912643) (xy 419.002591 -364.880192) (xy 419.052191 -364.854691)
			(xy 419.104975 -364.836684) (xy 419.159818 -364.826554) (xy 419.215552 -364.824517) (xy 419.270989 -364.830617)
			(xy 419.324946 -364.844723) (xy 419.376275 -364.866535) (xy 419.423881 -364.895589) (xy 419.466749 -364.931264)
			(xy 419.503966 -364.972801) (xy 419.534739 -365.019314) (xy 419.558411 -365.069811) (xy 419.570736 -365.110776)
			(xy 420.772588 -365.110776) (xy 420.776659 -365.055154) (xy 420.788785 -365.000717) (xy 420.808708 -364.948626)
			(xy 420.836004 -364.899991) (xy 420.87009 -364.855848) (xy 420.910239 -364.817139) (xy 420.955597 -364.784688)
			(xy 421.005197 -364.759187) (xy 421.057981 -364.74118) (xy 421.112824 -364.73105) (xy 421.168558 -364.729013)
			(xy 421.223995 -364.735113) (xy 421.277952 -364.749219) (xy 421.329281 -364.771031) (xy 421.376887 -364.800085)
			(xy 421.419755 -364.83576) (xy 421.456972 -364.877297) (xy 421.487745 -364.92381) (xy 421.511417 -364.974307)
			(xy 421.527485 -365.027714) (xy 421.535605 -365.08289) (xy 421.536114 -365.110776) (xy 421.535605 -365.138662)
			(xy 421.527485 -365.193838) (xy 421.511417 -365.247245) (xy 421.487745 -365.297742) (xy 421.456972 -365.344255)
			(xy 421.419755 -365.385792) (xy 421.376887 -365.421467) (xy 421.329281 -365.450521) (xy 421.277952 -365.472333)
			(xy 421.223995 -365.486439) (xy 421.168558 -365.492539) (xy 421.112824 -365.490502) (xy 421.057981 -365.480372)
			(xy 421.005197 -365.462365) (xy 420.955597 -365.436864) (xy 420.910239 -365.404413) (xy 420.87009 -365.365704)
			(xy 420.836004 -365.321561) (xy 420.808708 -365.272926) (xy 420.788785 -365.220835) (xy 420.776659 -365.166398)
			(xy 420.772588 -365.110776) (xy 419.570736 -365.110776) (xy 419.574479 -365.123218) (xy 419.582599 -365.178394)
			(xy 419.583108 -365.20628) (xy 419.582599 -365.234166) (xy 419.574479 -365.289342) (xy 419.558411 -365.342749)
			(xy 419.534739 -365.393246) (xy 419.503966 -365.439759) (xy 419.466749 -365.481296) (xy 419.423881 -365.516971)
			(xy 419.376275 -365.546025) (xy 419.324946 -365.567837) (xy 419.270989 -365.581943) (xy 419.215552 -365.588043)
			(xy 419.159818 -365.586006) (xy 419.104975 -365.575876) (xy 419.052191 -365.557869) (xy 419.002591 -365.532368)
			(xy 418.957233 -365.499917) (xy 418.917084 -365.461208) (xy 418.882998 -365.417065) (xy 418.855702 -365.36843)
			(xy 418.835779 -365.316339) (xy 418.823653 -365.261902) (xy 418.819582 -365.20628) (xy 418.458909 -365.20628)
			(xy 418.459665 -365.211414) (xy 418.460174 -365.2393) (xy 418.459665 -365.267186) (xy 418.451545 -365.322362)
			(xy 418.435477 -365.375769) (xy 418.411805 -365.426266) (xy 418.381032 -365.472779) (xy 418.343815 -365.514316)
			(xy 418.300947 -365.549991) (xy 418.253341 -365.579045) (xy 418.202012 -365.600857) (xy 418.148055 -365.614963)
			(xy 418.092618 -365.621063) (xy 418.036884 -365.619026) (xy 417.982041 -365.608896) (xy 417.929257 -365.590889)
			(xy 417.879657 -365.565388) (xy 417.834299 -365.532937) (xy 417.79415 -365.494228) (xy 417.760064 -365.450085)
			(xy 417.732768 -365.40145) (xy 417.712845 -365.349359) (xy 417.700719 -365.294922) (xy 417.696648 -365.2393)
			(xy 415.471872 -365.2393) (xy 415.471004 -365.239669) (xy 415.417047 -365.253775) (xy 415.36161 -365.259875)
			(xy 415.305876 -365.257838) (xy 415.251033 -365.247708) (xy 415.198249 -365.229701) (xy 415.148649 -365.2042)
			(xy 415.103291 -365.171749) (xy 415.063142 -365.13304) (xy 415.029056 -365.088897) (xy 415.00176 -365.040262)
			(xy 414.981837 -364.988171) (xy 414.969711 -364.933734) (xy 414.96564 -364.878112) (xy 409.64358 -364.878112)
			(xy 409.64358 -365.962438) (xy 411.78302 -365.962438) (xy 411.787091 -365.906816) (xy 411.799217 -365.852379)
			(xy 411.81914 -365.800288) (xy 411.846436 -365.751653) (xy 411.880522 -365.70751) (xy 411.920671 -365.668801)
			(xy 411.966029 -365.63635) (xy 412.015629 -365.610849) (xy 412.068413 -365.592842) (xy 412.123256 -365.582712)
			(xy 412.17899 -365.580675) (xy 412.234427 -365.586775) (xy 412.288384 -365.600881) (xy 412.339713 -365.622693)
			(xy 412.387319 -365.651747) (xy 412.417899 -365.677196) (xy 416.787582 -365.677196) (xy 416.791653 -365.621574)
			(xy 416.803779 -365.567137) (xy 416.823702 -365.515046) (xy 416.850998 -365.466411) (xy 416.885084 -365.422268)
			(xy 416.925233 -365.383559) (xy 416.970591 -365.351108) (xy 417.020191 -365.325607) (xy 417.072975 -365.3076)
			(xy 417.127818 -365.29747) (xy 417.183552 -365.295433) (xy 417.238989 -365.301533) (xy 417.292946 -365.315639)
			(xy 417.344275 -365.337451) (xy 417.391881 -365.366505) (xy 417.434749 -365.40218) (xy 417.471966 -365.443717)
			(xy 417.502739 -365.49023) (xy 417.526411 -365.540727) (xy 417.542479 -365.594134) (xy 417.550599 -365.64931)
			(xy 417.551108 -365.677196) (xy 417.550599 -365.705082) (xy 417.542479 -365.760258) (xy 417.526411 -365.813665)
			(xy 417.502739 -365.864162) (xy 417.471966 -365.910675) (xy 417.434749 -365.952212) (xy 417.391881 -365.987887)
			(xy 417.344275 -366.016941) (xy 417.292946 -366.038753) (xy 417.238989 -366.052859) (xy 417.183552 -366.058959)
			(xy 417.127818 -366.056922) (xy 417.072975 -366.046792) (xy 417.020191 -366.028785) (xy 416.970591 -366.003284)
			(xy 416.925233 -365.970833) (xy 416.885084 -365.932124) (xy 416.850998 -365.887981) (xy 416.823702 -365.839346)
			(xy 416.803779 -365.787255) (xy 416.791653 -365.732818) (xy 416.787582 -365.677196) (xy 412.417899 -365.677196)
			(xy 412.430187 -365.687422) (xy 412.467404 -365.728959) (xy 412.498177 -365.775472) (xy 412.521849 -365.825969)
			(xy 412.537917 -365.879376) (xy 412.546037 -365.934552) (xy 412.546546 -365.962438) (xy 412.546037 -365.990324)
			(xy 412.537917 -366.0455) (xy 412.521849 -366.098907) (xy 412.498177 -366.149404) (xy 412.467404 -366.195917)
			(xy 412.430187 -366.237454) (xy 412.387319 -366.273129) (xy 412.339713 -366.302183) (xy 412.288384 -366.323995)
			(xy 412.234427 -366.338101) (xy 412.17899 -366.344201) (xy 412.123256 -366.342164) (xy 412.068413 -366.332034)
			(xy 412.015629 -366.314027) (xy 411.966029 -366.288526) (xy 411.920671 -366.256075) (xy 411.880522 -366.217366)
			(xy 411.846436 -366.173223) (xy 411.81914 -366.124588) (xy 411.799217 -366.072497) (xy 411.787091 -366.01806)
			(xy 411.78302 -365.962438) (xy 409.64358 -365.962438) (xy 409.64358 -366.652048) (xy 409.7688 -366.652048)
			(xy 409.772871 -366.596426) (xy 409.784997 -366.541989) (xy 409.80492 -366.489898) (xy 409.832216 -366.441263)
			(xy 409.866302 -366.39712) (xy 409.906451 -366.358411) (xy 409.951809 -366.32596) (xy 410.001409 -366.300459)
			(xy 410.054193 -366.282452) (xy 410.109036 -366.272322) (xy 410.16477 -366.270285) (xy 410.220207 -366.276385)
			(xy 410.274164 -366.290491) (xy 410.325493 -366.312303) (xy 410.373099 -366.341357) (xy 410.415967 -366.377032)
			(xy 410.453184 -366.418569) (xy 410.483957 -366.465082) (xy 410.507629 -366.515579) (xy 410.523697 -366.568986)
			(xy 410.531817 -366.624162) (xy 410.532326 -366.652048) (xy 410.531817 -366.679934) (xy 410.523697 -366.73511)
			(xy 410.510172 -366.780064) (xy 412.411162 -366.780064) (xy 412.415233 -366.724442) (xy 412.427359 -366.670005)
			(xy 412.447282 -366.617914) (xy 412.474578 -366.569279) (xy 412.508664 -366.525136) (xy 412.548813 -366.486427)
			(xy 412.594171 -366.453976) (xy 412.643771 -366.428475) (xy 412.696555 -366.410468) (xy 412.751398 -366.400338)
			(xy 412.807132 -366.398301) (xy 412.862569 -366.404401) (xy 412.916526 -366.418507) (xy 412.967855 -366.440319)
			(xy 413.015461 -366.469373) (xy 413.058329 -366.505048) (xy 413.095546 -366.546585) (xy 413.126319 -366.593098)
			(xy 413.149991 -366.643595) (xy 413.166059 -366.697002) (xy 413.174179 -366.752178) (xy 413.174688 -366.780064)
			(xy 413.174179 -366.80795) (xy 413.167256 -366.854994) (xy 423.83532 -366.854994) (xy 423.839391 -366.799372)
			(xy 423.851517 -366.744935) (xy 423.87144 -366.692844) (xy 423.898736 -366.644209) (xy 423.932822 -366.600066)
			(xy 423.972971 -366.561357) (xy 424.018329 -366.528906) (xy 424.067929 -366.503405) (xy 424.120713 -366.485398)
			(xy 424.175556 -366.475268) (xy 424.23129 -366.473231) (xy 424.286727 -366.479331) (xy 424.340684 -366.493437)
			(xy 424.392013 -366.515249) (xy 424.434289 -366.54105) (xy 427.288196 -366.54105) (xy 427.292267 -366.485428)
			(xy 427.304393 -366.430991) (xy 427.324316 -366.3789) (xy 427.351612 -366.330265) (xy 427.385698 -366.286122)
			(xy 427.425847 -366.247413) (xy 427.471205 -366.214962) (xy 427.520805 -366.189461) (xy 427.573589 -366.171454)
			(xy 427.628432 -366.161324) (xy 427.684166 -366.159287) (xy 427.739603 -366.165387) (xy 427.79356 -366.179493)
			(xy 427.844889 -366.201305) (xy 427.892495 -366.230359) (xy 427.935363 -366.266034) (xy 427.97258 -366.307571)
			(xy 428.003353 -366.354084) (xy 428.027025 -366.404581) (xy 428.043093 -366.457988) (xy 428.051213 -366.513164)
			(xy 428.051722 -366.54105) (xy 428.051213 -366.568936) (xy 428.043093 -366.624112) (xy 428.027025 -366.677519)
			(xy 428.003353 -366.728016) (xy 427.97258 -366.774529) (xy 427.935363 -366.816066) (xy 427.892495 -366.851741)
			(xy 427.844889 -366.880795) (xy 427.79356 -366.902607) (xy 427.739603 -366.916713) (xy 427.684166 -366.922813)
			(xy 427.628432 -366.920776) (xy 427.573589 -366.910646) (xy 427.520805 -366.892639) (xy 427.471205 -366.867138)
			(xy 427.425847 -366.834687) (xy 427.385698 -366.795978) (xy 427.351612 -366.751835) (xy 427.324316 -366.7032)
			(xy 427.304393 -366.651109) (xy 427.292267 -366.596672) (xy 427.288196 -366.54105) (xy 424.434289 -366.54105)
			(xy 424.439619 -366.544303) (xy 424.482487 -366.579978) (xy 424.519704 -366.621515) (xy 424.550477 -366.668028)
			(xy 424.574149 -366.718525) (xy 424.590217 -366.771932) (xy 424.598337 -366.827108) (xy 424.598846 -366.854994)
			(xy 424.598337 -366.88288) (xy 424.590217 -366.938056) (xy 424.574149 -366.991463) (xy 424.550477 -367.04196)
			(xy 424.519704 -367.088473) (xy 424.482487 -367.13001) (xy 424.439619 -367.165685) (xy 424.392013 -367.194739)
			(xy 424.340684 -367.216551) (xy 424.286727 -367.230657) (xy 424.23129 -367.236757) (xy 424.175556 -367.23472)
			(xy 424.120713 -367.22459) (xy 424.067929 -367.206583) (xy 424.018329 -367.181082) (xy 423.972971 -367.148631)
			(xy 423.932822 -367.109922) (xy 423.898736 -367.065779) (xy 423.87144 -367.017144) (xy 423.851517 -366.965053)
			(xy 423.839391 -366.910616) (xy 423.83532 -366.854994) (xy 413.167256 -366.854994) (xy 413.166059 -366.863126)
			(xy 413.149991 -366.916533) (xy 413.126319 -366.96703) (xy 413.095546 -367.013543) (xy 413.058329 -367.05508)
			(xy 413.015461 -367.090755) (xy 412.967855 -367.119809) (xy 412.916526 -367.141621) (xy 412.862569 -367.155727)
			(xy 412.807132 -367.161827) (xy 412.751398 -367.15979) (xy 412.696555 -367.14966) (xy 412.643771 -367.131653)
			(xy 412.594171 -367.106152) (xy 412.548813 -367.073701) (xy 412.508664 -367.034992) (xy 412.474578 -366.990849)
			(xy 412.447282 -366.942214) (xy 412.427359 -366.890123) (xy 412.415233 -366.835686) (xy 412.411162 -366.780064)
			(xy 410.510172 -366.780064) (xy 410.507629 -366.788517) (xy 410.483957 -366.839014) (xy 410.453184 -366.885527)
			(xy 410.415967 -366.927064) (xy 410.373099 -366.962739) (xy 410.325493 -366.991793) (xy 410.274164 -367.013605)
			(xy 410.220207 -367.027711) (xy 410.16477 -367.033811) (xy 410.109036 -367.031774) (xy 410.054193 -367.021644)
			(xy 410.001409 -367.003637) (xy 409.951809 -366.978136) (xy 409.906451 -366.945685) (xy 409.866302 -366.906976)
			(xy 409.832216 -366.862833) (xy 409.80492 -366.814198) (xy 409.784997 -366.762107) (xy 409.772871 -366.70767)
			(xy 409.7688 -366.652048) (xy 409.64358 -366.652048) (xy 409.64358 -367.473484) (xy 415.2044 -367.473484)
			(xy 415.208471 -367.417862) (xy 415.220597 -367.363425) (xy 415.24052 -367.311334) (xy 415.267816 -367.262699)
			(xy 415.301902 -367.218556) (xy 415.342051 -367.179847) (xy 415.387409 -367.147396) (xy 415.437009 -367.121895)
			(xy 415.489793 -367.103888) (xy 415.544636 -367.093758) (xy 415.60037 -367.091721) (xy 415.655807 -367.097821)
			(xy 415.709764 -367.111927) (xy 415.761093 -367.133739) (xy 415.808699 -367.162793) (xy 415.851567 -367.198468)
			(xy 415.888784 -367.240005) (xy 415.919557 -367.286518) (xy 415.943229 -367.337015) (xy 415.959297 -367.390422)
			(xy 415.967417 -367.445598) (xy 415.967926 -367.473484) (xy 416.4744 -367.473484) (xy 416.478471 -367.417862)
			(xy 416.490597 -367.363425) (xy 416.51052 -367.311334) (xy 416.537816 -367.262699) (xy 416.571902 -367.218556)
			(xy 416.612051 -367.179847) (xy 416.657409 -367.147396) (xy 416.707009 -367.121895) (xy 416.759793 -367.103888)
			(xy 416.814636 -367.093758) (xy 416.87037 -367.091721) (xy 416.925807 -367.097821) (xy 416.979764 -367.111927)
			(xy 417.031093 -367.133739) (xy 417.078699 -367.162793) (xy 417.121567 -367.198468) (xy 417.158784 -367.240005)
			(xy 417.189557 -367.286518) (xy 417.213229 -367.337015) (xy 417.229297 -367.390422) (xy 417.237417 -367.445598)
			(xy 417.237773 -367.465102) (xy 418.560502 -367.465102) (xy 418.564573 -367.40948) (xy 418.576699 -367.355043)
			(xy 418.596622 -367.302952) (xy 418.623918 -367.254317) (xy 418.658004 -367.210174) (xy 418.698153 -367.171465)
			(xy 418.743511 -367.139014) (xy 418.793111 -367.113513) (xy 418.845895 -367.095506) (xy 418.900738 -367.085376)
			(xy 418.956472 -367.083339) (xy 419.011909 -367.089439) (xy 419.065866 -367.103545) (xy 419.117195 -367.125357)
			(xy 419.164801 -367.154411) (xy 419.207669 -367.190086) (xy 419.244886 -367.231623) (xy 419.275659 -367.278136)
			(xy 419.299331 -367.328633) (xy 419.315399 -367.38204) (xy 419.323519 -367.437216) (xy 419.324028 -367.465102)
			(xy 419.323519 -367.492988) (xy 419.315399 -367.548164) (xy 419.299331 -367.601571) (xy 419.275659 -367.652068)
			(xy 419.244886 -367.698581) (xy 419.207669 -367.740118) (xy 419.164801 -367.775793) (xy 419.117195 -367.804847)
			(xy 419.065866 -367.826659) (xy 419.011909 -367.840765) (xy 418.956472 -367.846865) (xy 418.900738 -367.844828)
			(xy 418.845895 -367.834698) (xy 418.793111 -367.816691) (xy 418.743511 -367.79119) (xy 418.698153 -367.758739)
			(xy 418.658004 -367.72003) (xy 418.623918 -367.675887) (xy 418.596622 -367.627252) (xy 418.576699 -367.575161)
			(xy 418.564573 -367.520724) (xy 418.560502 -367.465102) (xy 417.237773 -367.465102) (xy 417.237926 -367.473484)
			(xy 417.237417 -367.50137) (xy 417.229297 -367.556546) (xy 417.213229 -367.609953) (xy 417.189557 -367.66045)
			(xy 417.158784 -367.706963) (xy 417.121567 -367.7485) (xy 417.078699 -367.784175) (xy 417.031093 -367.813229)
			(xy 416.979764 -367.835041) (xy 416.925807 -367.849147) (xy 416.87037 -367.855247) (xy 416.814636 -367.85321)
			(xy 416.759793 -367.84308) (xy 416.707009 -367.825073) (xy 416.657409 -367.799572) (xy 416.612051 -367.767121)
			(xy 416.571902 -367.728412) (xy 416.537816 -367.684269) (xy 416.51052 -367.635634) (xy 416.490597 -367.583543)
			(xy 416.478471 -367.529106) (xy 416.4744 -367.473484) (xy 415.967926 -367.473484) (xy 415.967417 -367.50137)
			(xy 415.959297 -367.556546) (xy 415.943229 -367.609953) (xy 415.919557 -367.66045) (xy 415.888784 -367.706963)
			(xy 415.851567 -367.7485) (xy 415.808699 -367.784175) (xy 415.761093 -367.813229) (xy 415.709764 -367.835041)
			(xy 415.655807 -367.849147) (xy 415.60037 -367.855247) (xy 415.544636 -367.85321) (xy 415.489793 -367.84308)
			(xy 415.437009 -367.825073) (xy 415.387409 -367.799572) (xy 415.342051 -367.767121) (xy 415.301902 -367.728412)
			(xy 415.267816 -367.684269) (xy 415.24052 -367.635634) (xy 415.220597 -367.583543) (xy 415.208471 -367.529106)
			(xy 415.2044 -367.473484) (xy 409.64358 -367.473484) (xy 409.64358 -368.686588) (xy 426.728634 -368.686588)
			(xy 426.732705 -368.630966) (xy 426.744831 -368.576529) (xy 426.764754 -368.524438) (xy 426.79205 -368.475803)
			(xy 426.826136 -368.43166) (xy 426.866285 -368.392951) (xy 426.911643 -368.3605) (xy 426.961243 -368.334999)
			(xy 427.014027 -368.316992) (xy 427.06887 -368.306862) (xy 427.124604 -368.304825) (xy 427.180041 -368.310925)
			(xy 427.233998 -368.325031) (xy 427.285327 -368.346843) (xy 427.332933 -368.375897) (xy 427.375801 -368.411572)
			(xy 427.413018 -368.453109) (xy 427.443791 -368.499622) (xy 427.467463 -368.550119) (xy 427.483531 -368.603526)
			(xy 427.491651 -368.658702) (xy 427.492039 -368.679984) (xy 428.63973 -368.679984) (xy 428.643801 -368.624362)
			(xy 428.655927 -368.569925) (xy 428.67585 -368.517834) (xy 428.703146 -368.469199) (xy 428.737232 -368.425056)
			(xy 428.777381 -368.386347) (xy 428.822739 -368.353896) (xy 428.872339 -368.328395) (xy 428.925123 -368.310388)
			(xy 428.979966 -368.300258) (xy 429.0357 -368.298221) (xy 429.091137 -368.304321) (xy 429.145094 -368.318427)
			(xy 429.196423 -368.340239) (xy 429.244029 -368.369293) (xy 429.286897 -368.404968) (xy 429.324114 -368.446505)
			(xy 429.354887 -368.493018) (xy 429.378559 -368.543515) (xy 429.394627 -368.596922) (xy 429.402747 -368.652098)
			(xy 429.403256 -368.679984) (xy 429.402747 -368.70787) (xy 429.394627 -368.763046) (xy 429.378559 -368.816453)
			(xy 429.354887 -368.86695) (xy 429.324114 -368.913463) (xy 429.286897 -368.955) (xy 429.244029 -368.990675)
			(xy 429.196423 -369.019729) (xy 429.145094 -369.041541) (xy 429.091137 -369.055647) (xy 429.0357 -369.061747)
			(xy 428.979966 -369.05971) (xy 428.925123 -369.04958) (xy 428.872339 -369.031573) (xy 428.822739 -369.006072)
			(xy 428.777381 -368.973621) (xy 428.737232 -368.934912) (xy 428.703146 -368.890769) (xy 428.67585 -368.842134)
			(xy 428.655927 -368.790043) (xy 428.643801 -368.735606) (xy 428.63973 -368.679984) (xy 427.492039 -368.679984)
			(xy 427.49216 -368.686588) (xy 427.491651 -368.714474) (xy 427.483531 -368.76965) (xy 427.467463 -368.823057)
			(xy 427.443791 -368.873554) (xy 427.413018 -368.920067) (xy 427.375801 -368.961604) (xy 427.332933 -368.997279)
			(xy 427.285327 -369.026333) (xy 427.233998 -369.048145) (xy 427.180041 -369.062251) (xy 427.124604 -369.068351)
			(xy 427.06887 -369.066314) (xy 427.014027 -369.056184) (xy 426.961243 -369.038177) (xy 426.911643 -369.012676)
			(xy 426.866285 -368.980225) (xy 426.826136 -368.941516) (xy 426.79205 -368.897373) (xy 426.764754 -368.848738)
			(xy 426.744831 -368.796647) (xy 426.732705 -368.74221) (xy 426.728634 -368.686588) (xy 409.64358 -368.686588)
			(xy 409.64358 -371.070124) (xy 409.644007 -371.080193) (xy 409.651725 -371.098793) (xy 409.658566 -371.106192)
			(xy 410.109924 -371.55755) (xy 410.117322 -371.564398) (xy 410.13592 -371.572131) (xy 410.145992 -371.572536)
		)
		(stroke
			(width 0)
			(type solid)
		)
		(fill yes)
		(layer "In15.Cu")
		(net "GND")
	)
	(gr_poly
		(pts
			(xy 456.640692 -440.621674) (xy 456.652279 -440.621056) (xy 456.673075 -440.610814) (xy 456.687312 -440.592519)
			(xy 456.690222 -440.581288) (xy 456.714352 -440.466226) (xy 456.698096 -440.434222) (xy 456.681586 -440.42711)
			(xy 456.58868 -440.385811) (xy 456.405768 -440.296982) (xy 456.226419 -440.201164) (xy 456.050898 -440.0985)
			(xy 455.879467 -439.989144) (xy 455.712381 -439.873257) (xy 455.549889 -439.751012) (xy 455.392233 -439.622591)
			(xy 455.239646 -439.488186) (xy 455.092357 -439.347995) (xy 454.950584 -439.202229) (xy 454.814539 -439.051103)
			(xy 454.684423 -438.894842) (xy 454.560431 -438.73368) (xy 454.442747 -438.567856) (xy 454.331545 -438.397616)
			(xy 454.226992 -438.223214) (xy 454.129243 -438.044909) (xy 454.038443 -437.862967) (xy 453.954728 -437.677659)
			(xy 453.878222 -437.489259) (xy 453.809039 -437.29805) (xy 453.747282 -437.104314) (xy 453.693043 -436.908341)
			(xy 453.646402 -436.710422) (xy 453.60743 -436.510851) (xy 453.576183 -436.309925) (xy 453.552708 -436.107944)
			(xy 453.537041 -435.905208) (xy 453.529205 -435.702018) (xy 453.528684 -435.600348) (xy 453.529191 -435.496851)
			(xy 453.537316 -435.290017) (xy 453.553554 -435.083661) (xy 453.577881 -434.878102) (xy 453.610259 -434.673657)
			(xy 453.650639 -434.47064) (xy 453.698957 -434.269365) (xy 453.75514 -434.070142) (xy 453.819102 -433.873278)
			(xy 453.890742 -433.679077) (xy 453.969951 -433.487838) (xy 454.056608 -433.299857) (xy 454.150577 -433.115422)
			(xy 454.251714 -432.934819) (xy 454.359864 -432.758325) (xy 454.474859 -432.586213) (xy 454.596523 -432.418749)
			(xy 454.724667 -432.25619) (xy 454.859094 -432.098787) (xy 454.999597 -431.946783) (xy 455.14596 -431.800412)
			(xy 455.297955 -431.6599) (xy 455.45535 -431.525464) (xy 455.617902 -431.39731) (xy 455.785359 -431.275637)
			(xy 455.957464 -431.160631) (xy 456.133951 -431.052471) (xy 456.314549 -430.951323) (xy 456.498978 -430.857343)
			(xy 456.686954 -430.770676) (xy 456.878188 -430.691455) (xy 457.072385 -430.619803) (xy 457.269245 -430.55583)
			(xy 457.468465 -430.499636) (xy 457.669737 -430.451305) (xy 457.872751 -430.410914) (xy 458.077195 -430.378523)
			(xy 458.282753 -430.354184) (xy 458.489108 -430.337934) (xy 458.695941 -430.329797) (xy 458.799438 -430.32934)
			(xy 458.8002 -430.32934) (xy 458.901433 -430.329823) (xy 459.10375 -430.337597) (xy 459.305619 -430.353135)
			(xy 459.506743 -430.376414) (xy 459.706824 -430.407398) (xy 459.905568 -430.446043) (xy 460.102682 -430.492291)
			(xy 460.297874 -430.546074) (xy 460.490857 -430.607313) (xy 460.681346 -430.675918) (xy 460.86906 -430.751786)
			(xy 461.053722 -430.834807) (xy 461.23506 -430.924858) (xy 461.412806 -431.021806) (xy 461.586699 -431.125508)
			(xy 461.75648 -431.235811) (xy 461.921901 -431.352552) (xy 462.082717 -431.475559) (xy 462.238691 -431.604651)
			(xy 462.389593 -431.739637) (xy 462.5352 -431.880318) (xy 462.675298 -432.026487) (xy 462.809679 -432.177928)
			(xy 462.938145 -432.334417) (xy 463.060508 -432.495724) (xy 463.176586 -432.661611) (xy 463.286209 -432.831833)
			(xy 463.389214 -433.006139) (xy 463.485449 -433.184272) (xy 463.574774 -433.365969) (xy 463.657055 -433.550962)
			(xy 463.695034 -433.644802) (xy 463.701892 -433.662074) (xy 463.733642 -433.679346) (xy 463.84972 -433.656994)
			(xy 463.861132 -433.654176) (xy 463.87982 -433.639962) (xy 463.890293 -433.618947) (xy 463.890868 -433.60721)
			(xy 463.890868 -408.086052) (xy 463.891299 -408.075985) (xy 463.899022 -408.05739) (xy 463.905854 -408.049984)
			(xy 466.986874 -404.968964) (xy 466.993718 -404.961565) (xy 467.001443 -404.942966) (xy 467.00186 -404.932896)
			(xy 467.00186 -376.167396) (xy 467.001435 -376.157327) (xy 466.993715 -376.138727) (xy 466.986874 -376.131328)
			(xy 466.112606 -375.25706) (xy 466.105211 -375.250206) (xy 466.086612 -375.24246) (xy 466.076538 -375.242074)
			(xy 450.033136 -375.242074) (xy 450.02307 -375.242508) (xy 450.00448 -375.250236) (xy 449.997068 -375.25706)
			(xy 449.762372 -375.49201) (xy 449.754976 -375.498862) (xy 449.736377 -375.5066) (xy 449.726304 -375.506996)
			(xy 442.624972 -375.506996) (xy 442.614904 -375.507424) (xy 442.596307 -375.515145) (xy 442.588904 -375.521982)
			(xy 441.752482 -376.358404) (xy 441.745627 -376.365799) (xy 441.737881 -376.384398) (xy 441.737496 -376.394472)
			(xy 441.737496 -383.388882) (xy 441.915547 -383.388882) (xy 441.919279 -383.335628) (xy 441.930398 -383.283415)
			(xy 441.948686 -383.233261) (xy 441.973787 -383.186146) (xy 442.005209 -383.14299) (xy 442.042341 -383.104634)
			(xy 442.063124 -383.08788) (xy 442.071934 -383.080276) (xy 442.082115 -383.059373) (xy 442.082682 -383.047748)
			(xy 442.082682 -382.967992) (xy 442.08214 -382.95636) (xy 442.071954 -382.93545) (xy 442.063124 -382.92786)
			(xy 442.042313 -382.911141) (xy 442.005185 -382.872782) (xy 441.973767 -382.829623) (xy 441.948671 -382.782505)
			(xy 441.930388 -382.73235) (xy 441.919274 -382.680135) (xy 441.915547 -382.626882) (xy 441.919279 -382.573628)
			(xy 441.930398 -382.521415) (xy 441.948686 -382.471261) (xy 441.973787 -382.424146) (xy 442.005209 -382.38099)
			(xy 442.042341 -382.342634) (xy 442.063124 -382.32588) (xy 442.071934 -382.318276) (xy 442.082115 -382.297373)
			(xy 442.082682 -382.285748) (xy 442.082682 -382.205992) (xy 442.08214 -382.19436) (xy 442.071954 -382.17345)
			(xy 442.063124 -382.16586) (xy 442.040626 -382.147685) (xy 442.000891 -382.105663) (xy 441.967953 -382.058125)
			(xy 441.942567 -382.00616) (xy 441.925314 -381.950959) (xy 441.91659 -381.893787) (xy 441.916058 -381.86487)
			(xy 441.916544 -381.837619) (xy 441.9243 -381.783671) (xy 441.939655 -381.731376) (xy 441.962297 -381.681799)
			(xy 441.991763 -381.635949) (xy 442.027454 -381.594758) (xy 442.068645 -381.559067) (xy 442.114495 -381.529601)
			(xy 442.164072 -381.506959) (xy 442.216367 -381.491604) (xy 442.270315 -381.483848) (xy 442.324817 -381.483848)
			(xy 442.378765 -381.491604) (xy 442.43106 -381.506959) (xy 442.480637 -381.529601) (xy 442.526487 -381.559067)
			(xy 442.567678 -381.594758) (xy 442.603369 -381.635949) (xy 442.632835 -381.681799) (xy 442.655477 -381.731376)
			(xy 442.670832 -381.783671) (xy 442.678588 -381.837619) (xy 442.679074 -381.86487) (xy 442.678544 -381.893787)
			(xy 442.669819 -381.950958) (xy 442.652564 -382.006157) (xy 442.627174 -382.058119) (xy 442.594232 -382.105653)
			(xy 442.554493 -382.14767) (xy 442.532008 -382.16586) (xy 442.52323 -382.173496) (xy 442.51303 -382.194375)
			(xy 442.51245 -382.205992) (xy 442.51245 -382.285748) (xy 442.512958 -382.297384) (xy 442.523167 -382.318295)
			(xy 442.532008 -382.32588) (xy 442.552763 -382.342668) (xy 442.589896 -382.381016) (xy 442.62132 -382.424166)
			(xy 442.646422 -382.471275) (xy 442.664711 -382.521424) (xy 442.675831 -382.573632) (xy 442.679563 -382.626882)
			(xy 442.675836 -382.680131) (xy 442.664721 -382.732341) (xy 442.646437 -382.782491) (xy 442.621339 -382.829603)
			(xy 442.589919 -382.872756) (xy 442.55279 -382.911107) (xy 442.532008 -382.92786) (xy 442.52323 -382.935496)
			(xy 442.51303 -382.956375) (xy 442.51245 -382.967992) (xy 442.51245 -383.047748) (xy 442.512958 -383.059384)
			(xy 442.523167 -383.080295) (xy 442.532008 -383.08788) (xy 442.552763 -383.104668) (xy 442.589896 -383.143016)
			(xy 442.62132 -383.186166) (xy 442.646422 -383.233275) (xy 442.664711 -383.283424) (xy 442.675831 -383.335632)
			(xy 442.679563 -383.388882) (xy 445.725547 -383.388882) (xy 445.729279 -383.335628) (xy 445.740398 -383.283415)
			(xy 445.758686 -383.233261) (xy 445.783787 -383.186146) (xy 445.815209 -383.14299) (xy 445.852341 -383.104634)
			(xy 445.873124 -383.08788) (xy 445.881934 -383.080276) (xy 445.892115 -383.059373) (xy 445.892682 -383.047748)
			(xy 445.892682 -382.967992) (xy 445.89214 -382.95636) (xy 445.881954 -382.93545) (xy 445.873124 -382.92786)
			(xy 445.852313 -382.911141) (xy 445.815185 -382.872782) (xy 445.783767 -382.829623) (xy 445.758671 -382.782505)
			(xy 445.740388 -382.73235) (xy 445.729274 -382.680135) (xy 445.725547 -382.626882) (xy 445.729279 -382.573628)
			(xy 445.740398 -382.521415) (xy 445.758686 -382.471261) (xy 445.783787 -382.424146) (xy 445.815209 -382.38099)
			(xy 445.852341 -382.342634) (xy 445.873124 -382.32588) (xy 445.881934 -382.318276) (xy 445.892115 -382.297373)
			(xy 445.892682 -382.285748) (xy 445.892682 -382.205992) (xy 445.89214 -382.19436) (xy 445.881954 -382.17345)
			(xy 445.873124 -382.16586) (xy 445.850626 -382.147685) (xy 445.810891 -382.105663) (xy 445.777953 -382.058125)
			(xy 445.752567 -382.00616) (xy 445.735314 -381.950959) (xy 445.72659 -381.893787) (xy 445.726058 -381.86487)
			(xy 445.726544 -381.837619) (xy 445.7343 -381.783671) (xy 445.749655 -381.731376) (xy 445.772297 -381.681799)
			(xy 445.801763 -381.635949) (xy 445.837454 -381.594758) (xy 445.878645 -381.559067) (xy 445.924495 -381.529601)
			(xy 445.974072 -381.506959) (xy 446.026367 -381.491604) (xy 446.080315 -381.483848) (xy 446.134817 -381.483848)
			(xy 446.188765 -381.491604) (xy 446.24106 -381.506959) (xy 446.290637 -381.529601) (xy 446.336487 -381.559067)
			(xy 446.377678 -381.594758) (xy 446.413369 -381.635949) (xy 446.442835 -381.681799) (xy 446.465477 -381.731376)
			(xy 446.480832 -381.783671) (xy 446.488588 -381.837619) (xy 446.489074 -381.86487) (xy 446.488544 -381.893787)
			(xy 446.479819 -381.950958) (xy 446.462564 -382.006157) (xy 446.437174 -382.058119) (xy 446.404232 -382.105653)
			(xy 446.364493 -382.14767) (xy 446.342008 -382.16586) (xy 446.33323 -382.173496) (xy 446.32303 -382.194375)
			(xy 446.32245 -382.205992) (xy 446.32245 -382.285748) (xy 446.322958 -382.297384) (xy 446.333167 -382.318295)
			(xy 446.342008 -382.32588) (xy 446.362763 -382.342668) (xy 446.399896 -382.381016) (xy 446.43132 -382.424166)
			(xy 446.456422 -382.471275) (xy 446.474711 -382.521424) (xy 446.485831 -382.573632) (xy 446.489563 -382.626882)
			(xy 446.485836 -382.680131) (xy 446.474721 -382.732341) (xy 446.456437 -382.782491) (xy 446.431339 -382.829603)
			(xy 446.399919 -382.872756) (xy 446.36279 -382.911107) (xy 446.342008 -382.92786) (xy 446.33323 -382.935496)
			(xy 446.32303 -382.956375) (xy 446.32245 -382.967992) (xy 446.32245 -383.047748) (xy 446.322958 -383.059384)
			(xy 446.333167 -383.080295) (xy 446.342008 -383.08788) (xy 446.362763 -383.104668) (xy 446.399896 -383.143016)
			(xy 446.43132 -383.186166) (xy 446.456422 -383.233275) (xy 446.474711 -383.283424) (xy 446.485831 -383.335632)
			(xy 446.489563 -383.388882) (xy 447.681347 -383.388882) (xy 447.685079 -383.335628) (xy 447.696198 -383.283415)
			(xy 447.714486 -383.233261) (xy 447.739587 -383.186146) (xy 447.771009 -383.14299) (xy 447.808141 -383.104634)
			(xy 447.828924 -383.08788) (xy 447.837734 -383.080276) (xy 447.847915 -383.059373) (xy 447.848482 -383.047748)
			(xy 447.848482 -382.967992) (xy 447.84794 -382.95636) (xy 447.837754 -382.93545) (xy 447.828924 -382.92786)
			(xy 447.808113 -382.911141) (xy 447.770985 -382.872782) (xy 447.739567 -382.829623) (xy 447.714471 -382.782505)
			(xy 447.696188 -382.73235) (xy 447.685074 -382.680135) (xy 447.681347 -382.626882) (xy 447.685079 -382.573628)
			(xy 447.696198 -382.521415) (xy 447.714486 -382.471261) (xy 447.739587 -382.424146) (xy 447.771009 -382.38099)
			(xy 447.808141 -382.342634) (xy 447.828924 -382.32588) (xy 447.837734 -382.318276) (xy 447.847915 -382.297373)
			(xy 447.848482 -382.285748) (xy 447.848482 -382.205992) (xy 447.84794 -382.19436) (xy 447.837754 -382.17345)
			(xy 447.828924 -382.16586) (xy 447.806426 -382.147685) (xy 447.766691 -382.105663) (xy 447.733753 -382.058125)
			(xy 447.708367 -382.00616) (xy 447.691114 -381.950959) (xy 447.68239 -381.893787) (xy 447.681858 -381.86487)
			(xy 447.682344 -381.837619) (xy 447.6901 -381.783671) (xy 447.705455 -381.731376) (xy 447.728097 -381.681799)
			(xy 447.757563 -381.635949) (xy 447.793254 -381.594758) (xy 447.834445 -381.559067) (xy 447.880295 -381.529601)
			(xy 447.929872 -381.506959) (xy 447.982167 -381.491604) (xy 448.036115 -381.483848) (xy 448.090617 -381.483848)
			(xy 448.144565 -381.491604) (xy 448.19686 -381.506959) (xy 448.246437 -381.529601) (xy 448.292287 -381.559067)
			(xy 448.333478 -381.594758) (xy 448.369169 -381.635949) (xy 448.398635 -381.681799) (xy 448.421277 -381.731376)
			(xy 448.436632 -381.783671) (xy 448.444388 -381.837619) (xy 448.444874 -381.86487) (xy 448.444344 -381.893787)
			(xy 448.435619 -381.950958) (xy 448.418364 -382.006157) (xy 448.392974 -382.058119) (xy 448.360032 -382.105653)
			(xy 448.320293 -382.14767) (xy 448.297808 -382.16586) (xy 448.28903 -382.173496) (xy 448.27883 -382.194375)
			(xy 448.27825 -382.205992) (xy 448.27825 -382.285748) (xy 448.278758 -382.297384) (xy 448.288967 -382.318295)
			(xy 448.297808 -382.32588) (xy 448.318563 -382.342668) (xy 448.355696 -382.381016) (xy 448.38712 -382.424166)
			(xy 448.412222 -382.471275) (xy 448.430511 -382.521424) (xy 448.441631 -382.573632) (xy 448.445363 -382.626882)
			(xy 448.441636 -382.680131) (xy 448.430521 -382.732341) (xy 448.412237 -382.782491) (xy 448.387139 -382.829603)
			(xy 448.355719 -382.872756) (xy 448.31859 -382.911107) (xy 448.297808 -382.92786) (xy 448.28903 -382.935496)
			(xy 448.27883 -382.956375) (xy 448.27825 -382.967992) (xy 448.27825 -383.047748) (xy 448.278758 -383.059384)
			(xy 448.288967 -383.080295) (xy 448.297808 -383.08788) (xy 448.318563 -383.104668) (xy 448.355696 -383.143016)
			(xy 448.38712 -383.186166) (xy 448.412222 -383.233275) (xy 448.430511 -383.283424) (xy 448.441631 -383.335632)
			(xy 448.445363 -383.388882) (xy 451.491347 -383.388882) (xy 451.495079 -383.335628) (xy 451.506198 -383.283415)
			(xy 451.524486 -383.233261) (xy 451.549587 -383.186146) (xy 451.581009 -383.14299) (xy 451.618141 -383.104634)
			(xy 451.638924 -383.08788) (xy 451.647734 -383.080276) (xy 451.657915 -383.059373) (xy 451.658482 -383.047748)
			(xy 451.658482 -382.967992) (xy 451.65794 -382.95636) (xy 451.647754 -382.93545) (xy 451.638924 -382.92786)
			(xy 451.618113 -382.911141) (xy 451.580985 -382.872782) (xy 451.549567 -382.829623) (xy 451.524471 -382.782505)
			(xy 451.506188 -382.73235) (xy 451.495074 -382.680135) (xy 451.491347 -382.626882) (xy 451.495079 -382.573628)
			(xy 451.506198 -382.521415) (xy 451.524486 -382.471261) (xy 451.549587 -382.424146) (xy 451.581009 -382.38099)
			(xy 451.618141 -382.342634) (xy 451.638924 -382.32588) (xy 451.647734 -382.318276) (xy 451.657915 -382.297373)
			(xy 451.658482 -382.285748) (xy 451.658482 -382.205992) (xy 451.65794 -382.19436) (xy 451.647754 -382.17345)
			(xy 451.638924 -382.16586) (xy 451.616426 -382.147685) (xy 451.576691 -382.105663) (xy 451.543753 -382.058125)
			(xy 451.518367 -382.00616) (xy 451.501114 -381.950959) (xy 451.49239 -381.893787) (xy 451.491858 -381.86487)
			(xy 451.492344 -381.837619) (xy 451.5001 -381.783671) (xy 451.515455 -381.731376) (xy 451.538097 -381.681799)
			(xy 451.567563 -381.635949) (xy 451.603254 -381.594758) (xy 451.644445 -381.559067) (xy 451.690295 -381.529601)
			(xy 451.739872 -381.506959) (xy 451.792167 -381.491604) (xy 451.846115 -381.483848) (xy 451.900617 -381.483848)
			(xy 451.954565 -381.491604) (xy 452.00686 -381.506959) (xy 452.056437 -381.529601) (xy 452.102287 -381.559067)
			(xy 452.143478 -381.594758) (xy 452.179169 -381.635949) (xy 452.208635 -381.681799) (xy 452.231277 -381.731376)
			(xy 452.246632 -381.783671) (xy 452.254388 -381.837619) (xy 452.254874 -381.86487) (xy 452.254344 -381.893787)
			(xy 452.245619 -381.950958) (xy 452.228364 -382.006157) (xy 452.202974 -382.058119) (xy 452.170032 -382.105653)
			(xy 452.130293 -382.14767) (xy 452.107808 -382.16586) (xy 452.09903 -382.173496) (xy 452.08883 -382.194375)
			(xy 452.08825 -382.205992) (xy 452.08825 -382.285748) (xy 452.088758 -382.297384) (xy 452.098967 -382.318295)
			(xy 452.107808 -382.32588) (xy 452.128563 -382.342668) (xy 452.165696 -382.381016) (xy 452.19712 -382.424166)
			(xy 452.222222 -382.471275) (xy 452.240511 -382.521424) (xy 452.251631 -382.573632) (xy 452.255363 -382.626882)
			(xy 452.251636 -382.680131) (xy 452.240521 -382.732341) (xy 452.222237 -382.782491) (xy 452.197139 -382.829603)
			(xy 452.165719 -382.872756) (xy 452.12859 -382.911107) (xy 452.107808 -382.92786) (xy 452.09903 -382.935496)
			(xy 452.08883 -382.956375) (xy 452.08825 -382.967992) (xy 452.08825 -383.047748) (xy 452.088758 -383.059384)
			(xy 452.098967 -383.080295) (xy 452.107808 -383.08788) (xy 452.128563 -383.104668) (xy 452.165696 -383.143016)
			(xy 452.19712 -383.186166) (xy 452.222222 -383.233275) (xy 452.240511 -383.283424) (xy 452.251631 -383.335632)
			(xy 452.255363 -383.388882) (xy 453.777347 -383.388882) (xy 453.781079 -383.335628) (xy 453.792198 -383.283415)
			(xy 453.810486 -383.233261) (xy 453.835587 -383.186146) (xy 453.867009 -383.14299) (xy 453.904141 -383.104634)
			(xy 453.924924 -383.08788) (xy 453.933734 -383.080276) (xy 453.943915 -383.059373) (xy 453.944482 -383.047748)
			(xy 453.944482 -382.967992) (xy 453.94394 -382.95636) (xy 453.933754 -382.93545) (xy 453.924924 -382.92786)
			(xy 453.904113 -382.911141) (xy 453.866985 -382.872782) (xy 453.835567 -382.829623) (xy 453.810471 -382.782505)
			(xy 453.792188 -382.73235) (xy 453.781074 -382.680135) (xy 453.777347 -382.626882) (xy 453.781079 -382.573628)
			(xy 453.792198 -382.521415) (xy 453.810486 -382.471261) (xy 453.835587 -382.424146) (xy 453.867009 -382.38099)
			(xy 453.904141 -382.342634) (xy 453.924924 -382.32588) (xy 453.933734 -382.318276) (xy 453.943915 -382.297373)
			(xy 453.944482 -382.285748) (xy 453.944482 -382.205992) (xy 453.94394 -382.19436) (xy 453.933754 -382.17345)
			(xy 453.924924 -382.16586) (xy 453.902426 -382.147685) (xy 453.862691 -382.105663) (xy 453.829753 -382.058125)
			(xy 453.804367 -382.00616) (xy 453.787114 -381.950959) (xy 453.77839 -381.893787) (xy 453.777858 -381.86487)
			(xy 453.778344 -381.837619) (xy 453.7861 -381.783671) (xy 453.801455 -381.731376) (xy 453.824097 -381.681799)
			(xy 453.853563 -381.635949) (xy 453.889254 -381.594758) (xy 453.930445 -381.559067) (xy 453.976295 -381.529601)
			(xy 454.025872 -381.506959) (xy 454.078167 -381.491604) (xy 454.132115 -381.483848) (xy 454.186617 -381.483848)
			(xy 454.240565 -381.491604) (xy 454.29286 -381.506959) (xy 454.342437 -381.529601) (xy 454.388287 -381.559067)
			(xy 454.429478 -381.594758) (xy 454.465169 -381.635949) (xy 454.494635 -381.681799) (xy 454.517277 -381.731376)
			(xy 454.532632 -381.783671) (xy 454.540388 -381.837619) (xy 454.540874 -381.86487) (xy 454.540344 -381.893787)
			(xy 454.531619 -381.950958) (xy 454.514364 -382.006157) (xy 454.488974 -382.058119) (xy 454.456032 -382.105653)
			(xy 454.416293 -382.14767) (xy 454.393808 -382.16586) (xy 454.38503 -382.173496) (xy 454.37483 -382.194375)
			(xy 454.37425 -382.205992) (xy 454.37425 -382.285748) (xy 454.374758 -382.297384) (xy 454.384967 -382.318295)
			(xy 454.393808 -382.32588) (xy 454.414563 -382.342668) (xy 454.451696 -382.381016) (xy 454.48312 -382.424166)
			(xy 454.508222 -382.471275) (xy 454.526511 -382.521424) (xy 454.537631 -382.573632) (xy 454.541363 -382.626882)
			(xy 454.537636 -382.680131) (xy 454.526521 -382.732341) (xy 454.508237 -382.782491) (xy 454.483139 -382.829603)
			(xy 454.451719 -382.872756) (xy 454.41459 -382.911107) (xy 454.393808 -382.92786) (xy 454.38503 -382.935496)
			(xy 454.37483 -382.956375) (xy 454.37425 -382.967992) (xy 454.37425 -383.047748) (xy 454.374758 -383.059384)
			(xy 454.384967 -383.080295) (xy 454.393808 -383.08788) (xy 454.414563 -383.104668) (xy 454.451696 -383.143016)
			(xy 454.48312 -383.186166) (xy 454.508222 -383.233275) (xy 454.526511 -383.283424) (xy 454.537631 -383.335632)
			(xy 454.541363 -383.388882) (xy 457.587347 -383.388882) (xy 457.591079 -383.335628) (xy 457.602198 -383.283415)
			(xy 457.620486 -383.233261) (xy 457.645587 -383.186146) (xy 457.677009 -383.14299) (xy 457.714141 -383.104634)
			(xy 457.734924 -383.08788) (xy 457.743734 -383.080276) (xy 457.753915 -383.059373) (xy 457.754482 -383.047748)
			(xy 457.754482 -382.967992) (xy 457.75394 -382.95636) (xy 457.743754 -382.93545) (xy 457.734924 -382.92786)
			(xy 457.714113 -382.911141) (xy 457.676985 -382.872782) (xy 457.645567 -382.829623) (xy 457.620471 -382.782505)
			(xy 457.602188 -382.73235) (xy 457.591074 -382.680135) (xy 457.587347 -382.626882) (xy 457.591079 -382.573628)
			(xy 457.602198 -382.521415) (xy 457.620486 -382.471261) (xy 457.645587 -382.424146) (xy 457.677009 -382.38099)
			(xy 457.714141 -382.342634) (xy 457.734924 -382.32588) (xy 457.743734 -382.318276) (xy 457.753915 -382.297373)
			(xy 457.754482 -382.285748) (xy 457.754482 -382.205992) (xy 457.75394 -382.19436) (xy 457.743754 -382.17345)
			(xy 457.734924 -382.16586) (xy 457.712426 -382.147685) (xy 457.672691 -382.105663) (xy 457.639753 -382.058125)
			(xy 457.614367 -382.00616) (xy 457.597114 -381.950959) (xy 457.58839 -381.893787) (xy 457.587858 -381.86487)
			(xy 457.588344 -381.837619) (xy 457.5961 -381.783671) (xy 457.611455 -381.731376) (xy 457.634097 -381.681799)
			(xy 457.663563 -381.635949) (xy 457.699254 -381.594758) (xy 457.740445 -381.559067) (xy 457.786295 -381.529601)
			(xy 457.835872 -381.506959) (xy 457.888167 -381.491604) (xy 457.942115 -381.483848) (xy 457.996617 -381.483848)
			(xy 458.050565 -381.491604) (xy 458.10286 -381.506959) (xy 458.152437 -381.529601) (xy 458.198287 -381.559067)
			(xy 458.239478 -381.594758) (xy 458.275169 -381.635949) (xy 458.304635 -381.681799) (xy 458.327277 -381.731376)
			(xy 458.342632 -381.783671) (xy 458.350388 -381.837619) (xy 458.350874 -381.86487) (xy 458.350344 -381.893787)
			(xy 458.341619 -381.950958) (xy 458.324364 -382.006157) (xy 458.298974 -382.058119) (xy 458.266032 -382.105653)
			(xy 458.226293 -382.14767) (xy 458.203808 -382.16586) (xy 458.19503 -382.173496) (xy 458.18483 -382.194375)
			(xy 458.18425 -382.205992) (xy 458.18425 -382.285748) (xy 458.184758 -382.297384) (xy 458.194967 -382.318295)
			(xy 458.203808 -382.32588) (xy 458.224563 -382.342668) (xy 458.261696 -382.381016) (xy 458.29312 -382.424166)
			(xy 458.318222 -382.471275) (xy 458.336511 -382.521424) (xy 458.347631 -382.573632) (xy 458.351363 -382.626882)
			(xy 458.347636 -382.680131) (xy 458.336521 -382.732341) (xy 458.318237 -382.782491) (xy 458.293139 -382.829603)
			(xy 458.261719 -382.872756) (xy 458.22459 -382.911107) (xy 458.203808 -382.92786) (xy 458.19503 -382.935496)
			(xy 458.18483 -382.956375) (xy 458.18425 -382.967992) (xy 458.18425 -383.047748) (xy 458.184758 -383.059384)
			(xy 458.194967 -383.080295) (xy 458.203808 -383.08788) (xy 458.224563 -383.104668) (xy 458.261696 -383.143016)
			(xy 458.29312 -383.186166) (xy 458.318222 -383.233275) (xy 458.336511 -383.283424) (xy 458.347631 -383.335632)
			(xy 458.351363 -383.388882) (xy 459.873347 -383.388882) (xy 459.877079 -383.335628) (xy 459.888198 -383.283415)
			(xy 459.906486 -383.233261) (xy 459.931587 -383.186146) (xy 459.963009 -383.14299) (xy 460.000141 -383.104634)
			(xy 460.020924 -383.08788) (xy 460.029734 -383.080276) (xy 460.039915 -383.059373) (xy 460.040482 -383.047748)
			(xy 460.040482 -382.967992) (xy 460.03994 -382.95636) (xy 460.029754 -382.93545) (xy 460.020924 -382.92786)
			(xy 460.000113 -382.911141) (xy 459.962985 -382.872782) (xy 459.931567 -382.829623) (xy 459.906471 -382.782505)
			(xy 459.888188 -382.73235) (xy 459.877074 -382.680135) (xy 459.873347 -382.626882) (xy 459.877079 -382.573628)
			(xy 459.888198 -382.521415) (xy 459.906486 -382.471261) (xy 459.931587 -382.424146) (xy 459.963009 -382.38099)
			(xy 460.000141 -382.342634) (xy 460.020924 -382.32588) (xy 460.029734 -382.318276) (xy 460.039915 -382.297373)
			(xy 460.040482 -382.285748) (xy 460.040482 -382.205992) (xy 460.03994 -382.19436) (xy 460.029754 -382.17345)
			(xy 460.020924 -382.16586) (xy 459.998426 -382.147685) (xy 459.958691 -382.105663) (xy 459.925753 -382.058125)
			(xy 459.900367 -382.00616) (xy 459.883114 -381.950959) (xy 459.87439 -381.893787) (xy 459.873858 -381.86487)
			(xy 459.874344 -381.837619) (xy 459.8821 -381.783671) (xy 459.897455 -381.731376) (xy 459.920097 -381.681799)
			(xy 459.949563 -381.635949) (xy 459.985254 -381.594758) (xy 460.026445 -381.559067) (xy 460.072295 -381.529601)
			(xy 460.121872 -381.506959) (xy 460.174167 -381.491604) (xy 460.228115 -381.483848) (xy 460.282617 -381.483848)
			(xy 460.336565 -381.491604) (xy 460.38886 -381.506959) (xy 460.438437 -381.529601) (xy 460.484287 -381.559067)
			(xy 460.525478 -381.594758) (xy 460.561169 -381.635949) (xy 460.590635 -381.681799) (xy 460.613277 -381.731376)
			(xy 460.628632 -381.783671) (xy 460.636388 -381.837619) (xy 460.636874 -381.86487) (xy 460.636344 -381.893787)
			(xy 460.627619 -381.950958) (xy 460.610364 -382.006157) (xy 460.584974 -382.058119) (xy 460.552032 -382.105653)
			(xy 460.512293 -382.14767) (xy 460.489808 -382.16586) (xy 460.48103 -382.173496) (xy 460.47083 -382.194375)
			(xy 460.47025 -382.205992) (xy 460.47025 -382.285748) (xy 460.470758 -382.297384) (xy 460.480967 -382.318295)
			(xy 460.489808 -382.32588) (xy 460.510563 -382.342668) (xy 460.547696 -382.381016) (xy 460.57912 -382.424166)
			(xy 460.604222 -382.471275) (xy 460.622511 -382.521424) (xy 460.633631 -382.573632) (xy 460.637363 -382.626882)
			(xy 460.633636 -382.680131) (xy 460.622521 -382.732341) (xy 460.604237 -382.782491) (xy 460.579139 -382.829603)
			(xy 460.547719 -382.872756) (xy 460.51059 -382.911107) (xy 460.489808 -382.92786) (xy 460.48103 -382.935496)
			(xy 460.47083 -382.956375) (xy 460.47025 -382.967992) (xy 460.47025 -383.047748) (xy 460.470758 -383.059384)
			(xy 460.480967 -383.080295) (xy 460.489808 -383.08788) (xy 460.510563 -383.104668) (xy 460.547696 -383.143016)
			(xy 460.57912 -383.186166) (xy 460.604222 -383.233275) (xy 460.622511 -383.283424) (xy 460.633631 -383.335632)
			(xy 460.637363 -383.388882) (xy 463.683347 -383.388882) (xy 463.687079 -383.335628) (xy 463.698198 -383.283415)
			(xy 463.716486 -383.233261) (xy 463.741587 -383.186146) (xy 463.773009 -383.14299) (xy 463.810141 -383.104634)
			(xy 463.830924 -383.08788) (xy 463.839734 -383.080276) (xy 463.849915 -383.059373) (xy 463.850482 -383.047748)
			(xy 463.850482 -382.967992) (xy 463.84994 -382.95636) (xy 463.839754 -382.93545) (xy 463.830924 -382.92786)
			(xy 463.810113 -382.911141) (xy 463.772985 -382.872782) (xy 463.741567 -382.829623) (xy 463.716471 -382.782505)
			(xy 463.698188 -382.73235) (xy 463.687074 -382.680135) (xy 463.683347 -382.626882) (xy 463.687079 -382.573628)
			(xy 463.698198 -382.521415) (xy 463.716486 -382.471261) (xy 463.741587 -382.424146) (xy 463.773009 -382.38099)
			(xy 463.810141 -382.342634) (xy 463.830924 -382.32588) (xy 463.839734 -382.318276) (xy 463.849915 -382.297373)
			(xy 463.850482 -382.285748) (xy 463.850482 -382.205992) (xy 463.84994 -382.19436) (xy 463.839754 -382.17345)
			(xy 463.830924 -382.16586) (xy 463.808426 -382.147685) (xy 463.768691 -382.105663) (xy 463.735753 -382.058125)
			(xy 463.710367 -382.00616) (xy 463.693114 -381.950959) (xy 463.68439 -381.893787) (xy 463.683858 -381.86487)
			(xy 463.684344 -381.837619) (xy 463.6921 -381.783671) (xy 463.707455 -381.731376) (xy 463.730097 -381.681799)
			(xy 463.759563 -381.635949) (xy 463.795254 -381.594758) (xy 463.836445 -381.559067) (xy 463.882295 -381.529601)
			(xy 463.931872 -381.506959) (xy 463.984167 -381.491604) (xy 464.038115 -381.483848) (xy 464.092617 -381.483848)
			(xy 464.146565 -381.491604) (xy 464.19886 -381.506959) (xy 464.248437 -381.529601) (xy 464.294287 -381.559067)
			(xy 464.335478 -381.594758) (xy 464.371169 -381.635949) (xy 464.400635 -381.681799) (xy 464.423277 -381.731376)
			(xy 464.438632 -381.783671) (xy 464.446388 -381.837619) (xy 464.446874 -381.86487) (xy 464.446344 -381.893787)
			(xy 464.437619 -381.950958) (xy 464.420364 -382.006157) (xy 464.394974 -382.058119) (xy 464.362032 -382.105653)
			(xy 464.322293 -382.14767) (xy 464.299808 -382.16586) (xy 464.29103 -382.173496) (xy 464.28083 -382.194375)
			(xy 464.28025 -382.205992) (xy 464.28025 -382.285748) (xy 464.280758 -382.297384) (xy 464.290967 -382.318295)
			(xy 464.299808 -382.32588) (xy 464.320563 -382.342668) (xy 464.357696 -382.381016) (xy 464.38912 -382.424166)
			(xy 464.414222 -382.471275) (xy 464.432511 -382.521424) (xy 464.443631 -382.573632) (xy 464.447363 -382.626882)
			(xy 464.443636 -382.680131) (xy 464.432521 -382.732341) (xy 464.414237 -382.782491) (xy 464.389139 -382.829603)
			(xy 464.357719 -382.872756) (xy 464.32059 -382.911107) (xy 464.299808 -382.92786) (xy 464.29103 -382.935496)
			(xy 464.28083 -382.956375) (xy 464.28025 -382.967992) (xy 464.28025 -383.047748) (xy 464.280758 -383.059384)
			(xy 464.290967 -383.080295) (xy 464.299808 -383.08788) (xy 464.320563 -383.104668) (xy 464.357696 -383.143016)
			(xy 464.38912 -383.186166) (xy 464.414222 -383.233275) (xy 464.432511 -383.283424) (xy 464.443631 -383.335632)
			(xy 464.447363 -383.388882) (xy 464.443636 -383.442131) (xy 464.432521 -383.494341) (xy 464.414237 -383.544491)
			(xy 464.389139 -383.591603) (xy 464.357719 -383.634756) (xy 464.32059 -383.673107) (xy 464.299808 -383.68986)
			(xy 464.29103 -383.697496) (xy 464.28083 -383.718375) (xy 464.28025 -383.729992) (xy 464.28025 -383.809748)
			(xy 464.280758 -383.821384) (xy 464.290967 -383.842295) (xy 464.299808 -383.84988) (xy 464.322284 -383.86808)
			(xy 464.362019 -383.910098) (xy 464.394959 -383.957631) (xy 464.420348 -384.009591) (xy 464.437606 -384.064787)
			(xy 464.446338 -384.121955) (xy 464.446874 -384.15087) (xy 464.446388 -384.178121) (xy 464.438632 -384.232069)
			(xy 464.423277 -384.284364) (xy 464.400635 -384.333941) (xy 464.371169 -384.379791) (xy 464.335478 -384.420982)
			(xy 464.294287 -384.456673) (xy 464.248437 -384.486139) (xy 464.19886 -384.508781) (xy 464.146565 -384.524136)
			(xy 464.092617 -384.531892) (xy 464.038115 -384.531892) (xy 463.984167 -384.524136) (xy 463.931872 -384.508781)
			(xy 463.882295 -384.486139) (xy 463.836445 -384.456673) (xy 463.795254 -384.420982) (xy 463.759563 -384.379791)
			(xy 463.730097 -384.333941) (xy 463.707455 -384.284364) (xy 463.6921 -384.232069) (xy 463.684344 -384.178121)
			(xy 463.683858 -384.15087) (xy 463.684405 -384.121954) (xy 463.693125 -384.064783) (xy 463.710376 -384.009584)
			(xy 463.735762 -383.957622) (xy 463.768702 -383.910087) (xy 463.80844 -383.86807) (xy 463.830924 -383.84988)
			(xy 463.839734 -383.842276) (xy 463.849915 -383.821373) (xy 463.850482 -383.809748) (xy 463.850482 -383.729992)
			(xy 463.84994 -383.71836) (xy 463.839754 -383.69745) (xy 463.830924 -383.68986) (xy 463.810113 -383.673141)
			(xy 463.772985 -383.634782) (xy 463.741567 -383.591623) (xy 463.716471 -383.544505) (xy 463.698188 -383.49435)
			(xy 463.687074 -383.442135) (xy 463.683347 -383.388882) (xy 460.637363 -383.388882) (xy 460.633636 -383.442131)
			(xy 460.622521 -383.494341) (xy 460.604237 -383.544491) (xy 460.579139 -383.591603) (xy 460.547719 -383.634756)
			(xy 460.51059 -383.673107) (xy 460.489808 -383.68986) (xy 460.48103 -383.697496) (xy 460.47083 -383.718375)
			(xy 460.47025 -383.729992) (xy 460.47025 -383.809748) (xy 460.470758 -383.821384) (xy 460.480967 -383.842295)
			(xy 460.489808 -383.84988) (xy 460.512284 -383.86808) (xy 460.552019 -383.910098) (xy 460.584959 -383.957631)
			(xy 460.610348 -384.009591) (xy 460.627606 -384.064787) (xy 460.636338 -384.121955) (xy 460.636874 -384.15087)
			(xy 460.636388 -384.178121) (xy 460.628632 -384.232069) (xy 460.613277 -384.284364) (xy 460.590635 -384.333941)
			(xy 460.561169 -384.379791) (xy 460.525478 -384.420982) (xy 460.484287 -384.456673) (xy 460.438437 -384.486139)
			(xy 460.38886 -384.508781) (xy 460.336565 -384.524136) (xy 460.282617 -384.531892) (xy 460.228115 -384.531892)
			(xy 460.174167 -384.524136) (xy 460.121872 -384.508781) (xy 460.072295 -384.486139) (xy 460.026445 -384.456673)
			(xy 459.985254 -384.420982) (xy 459.949563 -384.379791) (xy 459.920097 -384.333941) (xy 459.897455 -384.284364)
			(xy 459.8821 -384.232069) (xy 459.874344 -384.178121) (xy 459.873858 -384.15087) (xy 459.874405 -384.121954)
			(xy 459.883125 -384.064783) (xy 459.900376 -384.009584) (xy 459.925762 -383.957622) (xy 459.958702 -383.910087)
			(xy 459.99844 -383.86807) (xy 460.020924 -383.84988) (xy 460.029734 -383.842276) (xy 460.039915 -383.821373)
			(xy 460.040482 -383.809748) (xy 460.040482 -383.729992) (xy 460.03994 -383.71836) (xy 460.029754 -383.69745)
			(xy 460.020924 -383.68986) (xy 460.000113 -383.673141) (xy 459.962985 -383.634782) (xy 459.931567 -383.591623)
			(xy 459.906471 -383.544505) (xy 459.888188 -383.49435) (xy 459.877074 -383.442135) (xy 459.873347 -383.388882)
			(xy 458.351363 -383.388882) (xy 458.347636 -383.442131) (xy 458.336521 -383.494341) (xy 458.318237 -383.544491)
			(xy 458.293139 -383.591603) (xy 458.261719 -383.634756) (xy 458.22459 -383.673107) (xy 458.203808 -383.68986)
			(xy 458.19503 -383.697496) (xy 458.18483 -383.718375) (xy 458.18425 -383.729992) (xy 458.18425 -383.809748)
			(xy 458.184758 -383.821384) (xy 458.194967 -383.842295) (xy 458.203808 -383.84988) (xy 458.226284 -383.86808)
			(xy 458.266019 -383.910098) (xy 458.298959 -383.957631) (xy 458.324348 -384.009591) (xy 458.341606 -384.064787)
			(xy 458.350338 -384.121955) (xy 458.350874 -384.15087) (xy 458.350388 -384.178121) (xy 458.342632 -384.232069)
			(xy 458.327277 -384.284364) (xy 458.304635 -384.333941) (xy 458.275169 -384.379791) (xy 458.239478 -384.420982)
			(xy 458.198287 -384.456673) (xy 458.152437 -384.486139) (xy 458.10286 -384.508781) (xy 458.050565 -384.524136)
			(xy 457.996617 -384.531892) (xy 457.942115 -384.531892) (xy 457.888167 -384.524136) (xy 457.835872 -384.508781)
			(xy 457.786295 -384.486139) (xy 457.740445 -384.456673) (xy 457.699254 -384.420982) (xy 457.663563 -384.379791)
			(xy 457.634097 -384.333941) (xy 457.611455 -384.284364) (xy 457.5961 -384.232069) (xy 457.588344 -384.178121)
			(xy 457.587858 -384.15087) (xy 457.588405 -384.121954) (xy 457.597125 -384.064783) (xy 457.614376 -384.009584)
			(xy 457.639762 -383.957622) (xy 457.672702 -383.910087) (xy 457.71244 -383.86807) (xy 457.734924 -383.84988)
			(xy 457.743734 -383.842276) (xy 457.753915 -383.821373) (xy 457.754482 -383.809748) (xy 457.754482 -383.729992)
			(xy 457.75394 -383.71836) (xy 457.743754 -383.69745) (xy 457.734924 -383.68986) (xy 457.714113 -383.673141)
			(xy 457.676985 -383.634782) (xy 457.645567 -383.591623) (xy 457.620471 -383.544505) (xy 457.602188 -383.49435)
			(xy 457.591074 -383.442135) (xy 457.587347 -383.388882) (xy 454.541363 -383.388882) (xy 454.537636 -383.442131)
			(xy 454.526521 -383.494341) (xy 454.508237 -383.544491) (xy 454.483139 -383.591603) (xy 454.451719 -383.634756)
			(xy 454.41459 -383.673107) (xy 454.393808 -383.68986) (xy 454.38503 -383.697496) (xy 454.37483 -383.718375)
			(xy 454.37425 -383.729992) (xy 454.37425 -383.809748) (xy 454.374758 -383.821384) (xy 454.384967 -383.842295)
			(xy 454.393808 -383.84988) (xy 454.416284 -383.86808) (xy 454.456019 -383.910098) (xy 454.488959 -383.957631)
			(xy 454.514348 -384.009591) (xy 454.531606 -384.064787) (xy 454.540338 -384.121955) (xy 454.540874 -384.15087)
			(xy 454.540388 -384.178121) (xy 454.532632 -384.232069) (xy 454.517277 -384.284364) (xy 454.494635 -384.333941)
			(xy 454.465169 -384.379791) (xy 454.429478 -384.420982) (xy 454.388287 -384.456673) (xy 454.342437 -384.486139)
			(xy 454.29286 -384.508781) (xy 454.240565 -384.524136) (xy 454.186617 -384.531892) (xy 454.132115 -384.531892)
			(xy 454.078167 -384.524136) (xy 454.025872 -384.508781) (xy 453.976295 -384.486139) (xy 453.930445 -384.456673)
			(xy 453.889254 -384.420982) (xy 453.853563 -384.379791) (xy 453.824097 -384.333941) (xy 453.801455 -384.284364)
			(xy 453.7861 -384.232069) (xy 453.778344 -384.178121) (xy 453.777858 -384.15087) (xy 453.778405 -384.121954)
			(xy 453.787125 -384.064783) (xy 453.804376 -384.009584) (xy 453.829762 -383.957622) (xy 453.862702 -383.910087)
			(xy 453.90244 -383.86807) (xy 453.924924 -383.84988) (xy 453.933734 -383.842276) (xy 453.943915 -383.821373)
			(xy 453.944482 -383.809748) (xy 453.944482 -383.729992) (xy 453.94394 -383.71836) (xy 453.933754 -383.69745)
			(xy 453.924924 -383.68986) (xy 453.904113 -383.673141) (xy 453.866985 -383.634782) (xy 453.835567 -383.591623)
			(xy 453.810471 -383.544505) (xy 453.792188 -383.49435) (xy 453.781074 -383.442135) (xy 453.777347 -383.388882)
			(xy 452.255363 -383.388882) (xy 452.251636 -383.442131) (xy 452.240521 -383.494341) (xy 452.222237 -383.544491)
			(xy 452.197139 -383.591603) (xy 452.165719 -383.634756) (xy 452.12859 -383.673107) (xy 452.107808 -383.68986)
			(xy 452.09903 -383.697496) (xy 452.08883 -383.718375) (xy 452.08825 -383.729992) (xy 452.08825 -383.809748)
			(xy 452.088758 -383.821384) (xy 452.098967 -383.842295) (xy 452.107808 -383.84988) (xy 452.130284 -383.86808)
			(xy 452.170019 -383.910098) (xy 452.202959 -383.957631) (xy 452.228348 -384.009591) (xy 452.245606 -384.064787)
			(xy 452.254338 -384.121955) (xy 452.254874 -384.15087) (xy 452.254388 -384.178121) (xy 452.246632 -384.232069)
			(xy 452.231277 -384.284364) (xy 452.208635 -384.333941) (xy 452.179169 -384.379791) (xy 452.143478 -384.420982)
			(xy 452.102287 -384.456673) (xy 452.056437 -384.486139) (xy 452.00686 -384.508781) (xy 451.954565 -384.524136)
			(xy 451.900617 -384.531892) (xy 451.846115 -384.531892) (xy 451.792167 -384.524136) (xy 451.739872 -384.508781)
			(xy 451.690295 -384.486139) (xy 451.644445 -384.456673) (xy 451.603254 -384.420982) (xy 451.567563 -384.379791)
			(xy 451.538097 -384.333941) (xy 451.515455 -384.284364) (xy 451.5001 -384.232069) (xy 451.492344 -384.178121)
			(xy 451.491858 -384.15087) (xy 451.492405 -384.121954) (xy 451.501125 -384.064783) (xy 451.518376 -384.009584)
			(xy 451.543762 -383.957622) (xy 451.576702 -383.910087) (xy 451.61644 -383.86807) (xy 451.638924 -383.84988)
			(xy 451.647734 -383.842276) (xy 451.657915 -383.821373) (xy 451.658482 -383.809748) (xy 451.658482 -383.729992)
			(xy 451.65794 -383.71836) (xy 451.647754 -383.69745) (xy 451.638924 -383.68986) (xy 451.618113 -383.673141)
			(xy 451.580985 -383.634782) (xy 451.549567 -383.591623) (xy 451.524471 -383.544505) (xy 451.506188 -383.49435)
			(xy 451.495074 -383.442135) (xy 451.491347 -383.388882) (xy 448.445363 -383.388882) (xy 448.441636 -383.442131)
			(xy 448.430521 -383.494341) (xy 448.412237 -383.544491) (xy 448.387139 -383.591603) (xy 448.355719 -383.634756)
			(xy 448.31859 -383.673107) (xy 448.297808 -383.68986) (xy 448.28903 -383.697496) (xy 448.27883 -383.718375)
			(xy 448.27825 -383.729992) (xy 448.27825 -383.809748) (xy 448.278758 -383.821384) (xy 448.288967 -383.842295)
			(xy 448.297808 -383.84988) (xy 448.320284 -383.86808) (xy 448.360019 -383.910098) (xy 448.392959 -383.957631)
			(xy 448.418348 -384.009591) (xy 448.435606 -384.064787) (xy 448.444338 -384.121955) (xy 448.444874 -384.15087)
			(xy 448.444388 -384.178121) (xy 448.436632 -384.232069) (xy 448.421277 -384.284364) (xy 448.398635 -384.333941)
			(xy 448.369169 -384.379791) (xy 448.333478 -384.420982) (xy 448.292287 -384.456673) (xy 448.246437 -384.486139)
			(xy 448.19686 -384.508781) (xy 448.144565 -384.524136) (xy 448.090617 -384.531892) (xy 448.036115 -384.531892)
			(xy 447.982167 -384.524136) (xy 447.929872 -384.508781) (xy 447.880295 -384.486139) (xy 447.834445 -384.456673)
			(xy 447.793254 -384.420982) (xy 447.757563 -384.379791) (xy 447.728097 -384.333941) (xy 447.705455 -384.284364)
			(xy 447.6901 -384.232069) (xy 447.682344 -384.178121) (xy 447.681858 -384.15087) (xy 447.682405 -384.121954)
			(xy 447.691125 -384.064783) (xy 447.708376 -384.009584) (xy 447.733762 -383.957622) (xy 447.766702 -383.910087)
			(xy 447.80644 -383.86807) (xy 447.828924 -383.84988) (xy 447.837734 -383.842276) (xy 447.847915 -383.821373)
			(xy 447.848482 -383.809748) (xy 447.848482 -383.729992) (xy 447.84794 -383.71836) (xy 447.837754 -383.69745)
			(xy 447.828924 -383.68986) (xy 447.808113 -383.673141) (xy 447.770985 -383.634782) (xy 447.739567 -383.591623)
			(xy 447.714471 -383.544505) (xy 447.696188 -383.49435) (xy 447.685074 -383.442135) (xy 447.681347 -383.388882)
			(xy 446.489563 -383.388882) (xy 446.485836 -383.442131) (xy 446.474721 -383.494341) (xy 446.456437 -383.544491)
			(xy 446.431339 -383.591603) (xy 446.399919 -383.634756) (xy 446.36279 -383.673107) (xy 446.342008 -383.68986)
			(xy 446.33323 -383.697496) (xy 446.32303 -383.718375) (xy 446.32245 -383.729992) (xy 446.32245 -383.809748)
			(xy 446.322958 -383.821384) (xy 446.333167 -383.842295) (xy 446.342008 -383.84988) (xy 446.364484 -383.86808)
			(xy 446.404219 -383.910098) (xy 446.437159 -383.957631) (xy 446.462548 -384.009591) (xy 446.479806 -384.064787)
			(xy 446.488538 -384.121955) (xy 446.489074 -384.15087) (xy 446.488588 -384.178121) (xy 446.480832 -384.232069)
			(xy 446.465477 -384.284364) (xy 446.442835 -384.333941) (xy 446.413369 -384.379791) (xy 446.377678 -384.420982)
			(xy 446.336487 -384.456673) (xy 446.290637 -384.486139) (xy 446.24106 -384.508781) (xy 446.188765 -384.524136)
			(xy 446.134817 -384.531892) (xy 446.080315 -384.531892) (xy 446.026367 -384.524136) (xy 445.974072 -384.508781)
			(xy 445.924495 -384.486139) (xy 445.878645 -384.456673) (xy 445.837454 -384.420982) (xy 445.801763 -384.379791)
			(xy 445.772297 -384.333941) (xy 445.749655 -384.284364) (xy 445.7343 -384.232069) (xy 445.726544 -384.178121)
			(xy 445.726058 -384.15087) (xy 445.726605 -384.121954) (xy 445.735325 -384.064783) (xy 445.752576 -384.009584)
			(xy 445.777962 -383.957622) (xy 445.810902 -383.910087) (xy 445.85064 -383.86807) (xy 445.873124 -383.84988)
			(xy 445.881934 -383.842276) (xy 445.892115 -383.821373) (xy 445.892682 -383.809748) (xy 445.892682 -383.729992)
			(xy 445.89214 -383.71836) (xy 445.881954 -383.69745) (xy 445.873124 -383.68986) (xy 445.852313 -383.673141)
			(xy 445.815185 -383.634782) (xy 445.783767 -383.591623) (xy 445.758671 -383.544505) (xy 445.740388 -383.49435)
			(xy 445.729274 -383.442135) (xy 445.725547 -383.388882) (xy 442.679563 -383.388882) (xy 442.675836 -383.442131)
			(xy 442.664721 -383.494341) (xy 442.646437 -383.544491) (xy 442.621339 -383.591603) (xy 442.589919 -383.634756)
			(xy 442.55279 -383.673107) (xy 442.532008 -383.68986) (xy 442.52323 -383.697496) (xy 442.51303 -383.718375)
			(xy 442.51245 -383.729992) (xy 442.51245 -383.809748) (xy 442.512958 -383.821384) (xy 442.523167 -383.842295)
			(xy 442.532008 -383.84988) (xy 442.554484 -383.86808) (xy 442.594219 -383.910098) (xy 442.627159 -383.957631)
			(xy 442.652548 -384.009591) (xy 442.669806 -384.064787) (xy 442.678538 -384.121955) (xy 442.679074 -384.15087)
			(xy 442.678588 -384.178121) (xy 442.670832 -384.232069) (xy 442.655477 -384.284364) (xy 442.632835 -384.333941)
			(xy 442.603369 -384.379791) (xy 442.567678 -384.420982) (xy 442.526487 -384.456673) (xy 442.480637 -384.486139)
			(xy 442.43106 -384.508781) (xy 442.378765 -384.524136) (xy 442.324817 -384.531892) (xy 442.270315 -384.531892)
			(xy 442.216367 -384.524136) (xy 442.164072 -384.508781) (xy 442.114495 -384.486139) (xy 442.068645 -384.456673)
			(xy 442.027454 -384.420982) (xy 441.991763 -384.379791) (xy 441.962297 -384.333941) (xy 441.939655 -384.284364)
			(xy 441.9243 -384.232069) (xy 441.916544 -384.178121) (xy 441.916058 -384.15087) (xy 441.916605 -384.121954)
			(xy 441.925325 -384.064783) (xy 441.942576 -384.009584) (xy 441.967962 -383.957622) (xy 442.000902 -383.910087)
			(xy 442.04064 -383.86807) (xy 442.063124 -383.84988) (xy 442.071934 -383.842276) (xy 442.082115 -383.821373)
			(xy 442.082682 -383.809748) (xy 442.082682 -383.729992) (xy 442.08214 -383.71836) (xy 442.071954 -383.69745)
			(xy 442.063124 -383.68986) (xy 442.042313 -383.673141) (xy 442.005185 -383.634782) (xy 441.973767 -383.591623)
			(xy 441.948671 -383.544505) (xy 441.930388 -383.49435) (xy 441.919274 -383.442135) (xy 441.915547 -383.388882)
			(xy 441.737496 -383.388882) (xy 441.737496 -385.039108) (xy 447.973196 -385.039108) (xy 447.973663 -385.011855)
			(xy 447.981419 -384.957904) (xy 447.996774 -384.905606) (xy 448.019416 -384.856026) (xy 448.048883 -384.810172)
			(xy 448.084577 -384.76898) (xy 448.125769 -384.733286) (xy 448.171622 -384.703818) (xy 448.221202 -384.681175)
			(xy 448.2735 -384.66582) (xy 448.327451 -384.658063) (xy 448.354704 -384.6576) (xy 448.383621 -384.658116)
			(xy 448.440792 -384.666845) (xy 448.495991 -384.684104) (xy 448.547953 -384.709496) (xy 448.595487 -384.74244)
			(xy 448.637504 -384.782181) (xy 448.655694 -384.804666) (xy 448.663302 -384.813472) (xy 448.684203 -384.823653)
			(xy 448.695826 -384.824224) (xy 448.775582 -384.824224) (xy 448.787215 -384.823687) (xy 448.808126 -384.813499)
			(xy 448.815714 -384.804666) (xy 448.833889 -384.782169) (xy 448.875913 -384.742436) (xy 448.923451 -384.7095)
			(xy 448.975416 -384.684114) (xy 449.030616 -384.66686) (xy 449.087787 -384.658134) (xy 449.116704 -384.6576)
			(xy 449.145443 -384.658121) (xy 449.20227 -384.666744) (xy 449.257161 -384.683795) (xy 449.308873 -384.708887)
			(xy 449.356235 -384.741453) (xy 449.377562 -384.760724) (xy 449.38442 -384.767328) (xy 449.402454 -384.77444)
			(xy 449.491354 -384.77444) (xy 449.509388 -384.767328) (xy 449.516246 -384.760724) (xy 449.537569 -384.741449)
			(xy 449.584933 -384.708884) (xy 449.636645 -384.683792) (xy 449.691537 -384.666743) (xy 449.748365 -384.658121)
			(xy 449.777104 -384.6576) (xy 449.804357 -384.658052) (xy 449.858309 -384.665809) (xy 449.910608 -384.681166)
			(xy 449.960188 -384.70381) (xy 450.006042 -384.733279) (xy 450.047235 -384.768974) (xy 450.082928 -384.810168)
			(xy 450.112396 -384.856022) (xy 450.135038 -384.905604) (xy 450.150393 -384.957903) (xy 450.158149 -385.011855)
			(xy 450.158612 -385.039108) (xy 450.158178 -385.06581) (xy 450.150724 -385.11869) (xy 450.135962 -385.170013)
			(xy 450.114183 -385.218773) (xy 450.085811 -385.264017) (xy 450.06895 -385.284726) (xy 450.068696 -385.28498)
			(xy 450.063042 -385.292441) (xy 450.057056 -385.310162) (xy 450.057012 -385.319524) (xy 450.060314 -385.397756)
			(xy 450.067934 -385.415028) (xy 450.074792 -385.421886) (xy 450.095606 -385.443472) (xy 450.130859 -385.491977)
			(xy 450.158087 -385.545401) (xy 450.176618 -385.602428) (xy 450.185997 -385.661653) (xy 450.186552 -385.691634)
			(xy 450.186008 -385.720693) (xy 450.177172 -385.778134) (xy 450.159725 -385.833571) (xy 450.134071 -385.88572)
			(xy 450.100803 -385.933374) (xy 450.081142 -385.954778) (xy 450.074785 -385.962115) (xy 450.067603 -385.980132)
			(xy 450.067172 -385.98983) (xy 450.067172 -386.06984) (xy 450.074284 -386.087874) (xy 450.081142 -386.094986)
			(xy 450.100804 -386.116391) (xy 450.134085 -386.164037) (xy 450.159743 -386.216185) (xy 450.177186 -386.271625)
			(xy 450.186007 -386.329071) (xy 450.186552 -386.35813) (xy 450.186034 -386.386232) (xy 450.18508 -386.392674)
			(xy 450.3547 -386.392674) (xy 450.355208 -386.363935) (xy 450.363834 -386.307106) (xy 450.380888 -386.252216)
			(xy 450.405983 -386.200504) (xy 450.438552 -386.153142) (xy 450.457824 -386.131816) (xy 450.464428 -386.124958)
			(xy 450.47154 -386.106924) (xy 450.47154 -386.018024) (xy 450.464428 -385.99999) (xy 450.457824 -385.993132)
			(xy 450.438527 -385.971828) (xy 450.405963 -385.924461) (xy 450.380873 -385.872746) (xy 450.363825 -385.817852)
			(xy 450.355205 -385.761021) (xy 450.355207 -385.703541) (xy 450.363833 -385.646711) (xy 450.380887 -385.591819)
			(xy 450.405982 -385.540106) (xy 450.438551 -385.492743) (xy 450.457824 -385.471416) (xy 450.464428 -385.464558)
			(xy 450.47154 -385.446524) (xy 450.47154 -385.357624) (xy 450.464428 -385.33959) (xy 450.457824 -385.332732)
			(xy 450.438539 -385.311418) (xy 450.405975 -385.264052) (xy 450.380885 -385.212337) (xy 450.363838 -385.157444)
			(xy 450.355219 -385.100614) (xy 450.3547 -385.071874) (xy 450.355154 -385.044622) (xy 450.362914 -384.990672)
			(xy 450.378273 -384.938377) (xy 450.400917 -384.888799) (xy 450.430387 -384.842948) (xy 450.466082 -384.801758)
			(xy 450.507275 -384.766067) (xy 450.553129 -384.736601) (xy 450.602709 -384.713961) (xy 450.655006 -384.698607)
			(xy 450.708956 -384.690851) (xy 450.736208 -384.690366) (xy 450.764947 -384.690894) (xy 450.821773 -384.699517)
			(xy 450.876664 -384.716566) (xy 450.928376 -384.741657) (xy 450.975739 -384.77422) (xy 450.997066 -384.79349)
			(xy 451.003924 -384.800094) (xy 451.021958 -384.807206) (xy 451.110858 -384.807206) (xy 451.128892 -384.800094)
			(xy 451.13575 -384.79349) (xy 451.157082 -384.774224) (xy 451.204442 -384.741656) (xy 451.256152 -384.716561)
			(xy 451.311042 -384.69951) (xy 451.367869 -384.690887) (xy 451.396608 -384.690366) (xy 451.423689 -384.690826)
			(xy 451.477306 -384.698483) (xy 451.529302 -384.71364) (xy 451.578635 -384.735995) (xy 451.624313 -384.765098)
			(xy 451.665418 -384.800365) (xy 451.683628 -384.820414) (xy 451.691165 -384.828217) (xy 451.710893 -384.83718)
			(xy 451.721728 -384.837686) (xy 451.797928 -384.837686) (xy 451.808759 -384.83715) (xy 451.828493 -384.828212)
			(xy 451.836028 -384.820414) (xy 451.854219 -384.800347) (xy 451.895329 -384.765083) (xy 451.941011 -384.735985)
			(xy 451.990347 -384.713636) (xy 452.042347 -384.698485) (xy 452.095967 -384.690836) (xy 452.123048 -384.690366)
			(xy 452.150299 -384.690833) (xy 452.204246 -384.698595) (xy 452.25654 -384.713955) (xy 452.306115 -384.7366)
			(xy 452.351964 -384.766069) (xy 452.393153 -384.801762) (xy 452.428844 -384.842953) (xy 452.45831 -384.888804)
			(xy 452.480952 -384.938381) (xy 452.496309 -384.990675) (xy 452.504068 -385.044623) (xy 452.504556 -385.071874)
			(xy 452.504001 -385.100612) (xy 452.495384 -385.157437) (xy 452.47834 -385.212327) (xy 452.453256 -385.264039)
			(xy 452.420699 -385.311403) (xy 452.401432 -385.332732) (xy 452.394828 -385.33959) (xy 452.387716 -385.357624)
			(xy 452.387716 -385.446524) (xy 452.394828 -385.464558) (xy 452.401432 -385.471416) (xy 452.420675 -385.492766)
			(xy 452.453236 -385.540126) (xy 452.478325 -385.591835) (xy 452.495374 -385.646721) (xy 452.503998 -385.703544)
			(xy 452.504001 -385.761018) (xy 452.495383 -385.817842) (xy 452.478339 -385.87273) (xy 452.453255 -385.924441)
			(xy 452.420698 -385.971804) (xy 452.401432 -385.993132) (xy 452.394828 -385.99999) (xy 452.387716 -386.018024)
			(xy 452.387716 -386.106924) (xy 452.394828 -386.124958) (xy 452.401432 -386.131816) (xy 452.420675 -386.153166)
			(xy 452.453236 -386.200526) (xy 452.478325 -386.252235) (xy 452.495374 -386.307121) (xy 452.503998 -386.363944)
			(xy 452.504001 -386.421418) (xy 452.495383 -386.478242) (xy 452.478339 -386.53313) (xy 452.453255 -386.584841)
			(xy 452.420698 -386.632204) (xy 452.401432 -386.653532) (xy 452.394828 -386.660644) (xy 452.387462 -386.678932)
			(xy 452.388478 -386.759196) (xy 452.389038 -386.768789) (xy 452.396333 -386.786547) (xy 452.402702 -386.79374)
			(xy 452.402956 -386.793994) (xy 452.423192 -386.815485) (xy 452.457414 -386.86358) (xy 452.48382 -386.916372)
			(xy 452.50178 -386.972601) (xy 452.510866 -387.030926) (xy 452.511414 -387.06044) (xy 452.510909 -387.087809)
			(xy 452.5031 -387.141986) (xy 452.48762 -387.194489) (xy 452.464787 -387.244236) (xy 452.435071 -387.290205)
			(xy 452.417434 -387.311138) (xy 452.41718 -387.311392) (xy 452.411588 -387.318475) (xy 452.405345 -387.335395)
			(xy 452.404988 -387.344412) (xy 452.404988 -387.411468) (xy 452.405363 -387.420483) (xy 452.411598 -387.4374)
			(xy 452.41718 -387.444488) (xy 452.417434 -387.444488) (xy 452.417434 -387.444742) (xy 452.435065 -387.465681)
			(xy 452.464777 -387.511652) (xy 452.487614 -387.561398) (xy 452.503107 -387.613897) (xy 452.503953 -387.619748)
			(xy 455.361802 -387.619748) (xy 455.362294 -387.591008) (xy 455.370924 -387.534179) (xy 455.387981 -387.479288)
			(xy 455.41308 -387.427577) (xy 455.445652 -387.380216) (xy 455.464926 -387.35889) (xy 455.47153 -387.352032)
			(xy 455.478642 -387.333998) (xy 455.478642 -387.245098) (xy 455.47153 -387.227064) (xy 455.464926 -387.220206)
			(xy 455.445703 -387.198838) (xy 455.413136 -387.151483) (xy 455.388041 -387.099778) (xy 455.370988 -387.044893)
			(xy 455.362361 -386.988071) (xy 455.362355 -386.930599) (xy 455.370972 -386.873775) (xy 455.388016 -386.818888)
			(xy 455.4131 -386.767178) (xy 455.445659 -386.719817) (xy 455.464926 -386.69849) (xy 455.47153 -386.691632)
			(xy 455.478642 -386.673598) (xy 455.478642 -386.584698) (xy 455.47153 -386.566664) (xy 455.464926 -386.559806)
			(xy 455.445703 -386.538438) (xy 455.413136 -386.491083) (xy 455.388041 -386.439378) (xy 455.370988 -386.384493)
			(xy 455.362361 -386.327671) (xy 455.362355 -386.270199) (xy 455.370972 -386.213375) (xy 455.388016 -386.158488)
			(xy 455.4131 -386.106778) (xy 455.445659 -386.059417) (xy 455.464926 -386.03809) (xy 455.47153 -386.031232)
			(xy 455.478642 -386.013198) (xy 455.478642 -385.924298) (xy 455.47153 -385.906264) (xy 455.464926 -385.899406)
			(xy 455.445629 -385.878102) (xy 455.413066 -385.830734) (xy 455.387979 -385.779016) (xy 455.370935 -385.72412)
			(xy 455.362319 -385.667289) (xy 455.361802 -385.638548) (xy 455.3623 -385.611296) (xy 455.370051 -385.557346)
			(xy 455.385401 -385.505048) (xy 455.408039 -385.455467) (xy 455.437503 -385.409613) (xy 455.473193 -385.36842)
			(xy 455.514383 -385.332725) (xy 455.560234 -385.303257) (xy 455.609812 -385.280614) (xy 455.662108 -385.265259)
			(xy 455.716058 -385.257503) (xy 455.74331 -385.25704) (xy 455.769625 -385.257509) (xy 455.821757 -385.264732)
			(xy 455.8724 -385.279054) (xy 455.920594 -385.300203) (xy 455.965422 -385.327778) (xy 456.006034 -385.361253)
			(xy 456.041657 -385.399994) (xy 456.057 -385.421378) (xy 456.063858 -385.431538) (xy 456.085448 -385.442968)
			(xy 456.193144 -385.444492) (xy 456.214988 -385.43357) (xy 456.222354 -385.423664) (xy 456.240463 -385.399945)
			(xy 456.2828 -385.357892) (xy 456.33117 -385.322946) (xy 456.384392 -385.295959) (xy 456.441168 -385.277591)
			(xy 456.500112 -385.26829) (xy 456.529948 -385.267708) (xy 456.557716 -385.26821) (xy 456.612668 -385.276252)
			(xy 456.665873 -385.292172) (xy 456.71621 -385.315634) (xy 456.762615 -385.346145) (xy 456.783694 -385.364228)
			(xy 456.790552 -385.370324) (xy 456.807824 -385.376928) (xy 456.89393 -385.377436) (xy 456.911202 -385.370832)
			(xy 456.918314 -385.364736) (xy 456.939286 -385.346929) (xy 456.985399 -385.316922) (xy 457.035341 -385.293845)
			(xy 457.088079 -385.278176) (xy 457.14252 -385.27024) (xy 457.170028 -385.26974) (xy 457.197284 -385.270129)
			(xy 457.25124 -385.277891) (xy 457.303542 -385.293253) (xy 457.353126 -385.315902) (xy 457.398981 -385.345378)
			(xy 457.440175 -385.381079) (xy 457.475868 -385.42228) (xy 457.505334 -385.468141) (xy 457.527974 -385.517729)
			(xy 457.543325 -385.570034) (xy 457.551076 -385.623992) (xy 457.551536 -385.651248) (xy 457.551032 -385.679988)
			(xy 457.542403 -385.736815) (xy 457.525348 -385.791706) (xy 457.500252 -385.843417) (xy 457.467684 -385.890779)
			(xy 457.448412 -385.912106) (xy 457.441808 -385.918964) (xy 457.434696 -385.936998) (xy 457.434696 -386.025898)
			(xy 457.441808 -386.043932) (xy 457.448412 -386.05079) (xy 457.467729 -386.072076) (xy 457.500289 -386.119447)
			(xy 457.525376 -386.171165) (xy 457.542421 -386.226062) (xy 457.551038 -386.282894) (xy 457.551033 -386.340376)
			(xy 457.542405 -386.397206) (xy 457.52535 -386.4521) (xy 457.500254 -386.503814) (xy 457.467685 -386.551178)
			(xy 457.448412 -386.572506) (xy 457.441808 -386.579364) (xy 457.434696 -386.597398) (xy 457.434696 -386.686298)
			(xy 457.441808 -386.704332) (xy 457.448412 -386.71119) (xy 457.467729 -386.732476) (xy 457.500289 -386.779847)
			(xy 457.525376 -386.831565) (xy 457.542421 -386.886462) (xy 457.551038 -386.943294) (xy 457.551033 -387.000776)
			(xy 457.542405 -387.057606) (xy 457.52535 -387.1125) (xy 457.500254 -387.164214) (xy 457.467685 -387.211578)
			(xy 457.448412 -387.232906) (xy 457.441808 -387.239764) (xy 457.434696 -387.257798) (xy 457.434696 -387.258347)
			(xy 458.670706 -387.258347) (xy 458.670706 -387.203853) (xy 458.678461 -387.149912) (xy 458.693813 -387.097625)
			(xy 458.716449 -387.048054) (xy 458.74591 -387.002209) (xy 458.781594 -386.961023) (xy 458.822777 -386.925334)
			(xy 458.868619 -386.895869) (xy 458.918187 -386.873227) (xy 458.970473 -386.857869) (xy 459.024413 -386.850109)
			(xy 459.05166 -386.84962) (xy 459.080399 -386.850129) (xy 459.137226 -386.858758) (xy 459.192116 -386.875813)
			(xy 459.243828 -386.900907) (xy 459.291191 -386.933473) (xy 459.312518 -386.952744) (xy 459.319376 -386.959348)
			(xy 459.33741 -386.96646) (xy 459.42631 -386.96646) (xy 459.444344 -386.959348) (xy 459.451202 -386.952744)
			(xy 459.472546 -386.933493) (xy 459.519904 -386.900924) (xy 459.571611 -386.875828) (xy 459.626498 -386.858772)
			(xy 459.683322 -386.850144) (xy 459.71206 -386.84962) (xy 459.739317 -386.850024) (xy 459.793276 -386.857777)
			(xy 459.845583 -386.873131) (xy 459.895171 -386.895773) (xy 459.941033 -386.925242) (xy 459.982234 -386.960938)
			(xy 460.017934 -387.002135) (xy 460.047408 -387.047993) (xy 460.070055 -387.09758) (xy 460.085414 -387.149885)
			(xy 460.093173 -387.203843) (xy 460.093173 -387.258357) (xy 460.087696 -387.296447) (xy 460.851306 -387.296447)
			(xy 460.851306 -387.241953) (xy 460.859061 -387.188014) (xy 460.874412 -387.135727) (xy 460.897048 -387.086157)
			(xy 460.926507 -387.040312) (xy 460.962191 -386.999126) (xy 461.003372 -386.963437) (xy 461.049213 -386.933972)
			(xy 461.09878 -386.91133) (xy 461.151065 -386.895971) (xy 461.205003 -386.88821) (xy 461.23225 -386.88772)
			(xy 461.260989 -386.888235) (xy 461.317816 -386.896863) (xy 461.372706 -386.913916) (xy 461.424417 -386.939009)
			(xy 461.47178 -386.971574) (xy 461.493108 -386.990844) (xy 461.499966 -386.997448) (xy 461.518 -387.00456)
			(xy 461.6069 -387.00456) (xy 461.624934 -386.997448) (xy 461.631792 -386.990844) (xy 461.653099 -386.971551)
			(xy 461.700467 -386.938987) (xy 461.752183 -386.913899) (xy 461.807078 -386.896854) (xy 461.86391 -386.888237)
			(xy 461.89265 -386.88772) (xy 461.919907 -386.888124) (xy 461.973868 -386.895875) (xy 462.026175 -386.911228)
			(xy 462.075765 -386.933869) (xy 462.121628 -386.963338) (xy 462.16283 -386.999035) (xy 462.198532 -387.040232)
			(xy 462.228007 -387.086091) (xy 462.250654 -387.135678) (xy 462.266014 -387.187983) (xy 462.273773 -387.241943)
			(xy 462.273773 -387.296457) (xy 462.266014 -387.350416) (xy 462.255395 -387.386576) (xy 462.824828 -387.386576)
			(xy 462.828899 -387.330954) (xy 462.841025 -387.276517) (xy 462.860948 -387.224426) (xy 462.888244 -387.175791)
			(xy 462.92233 -387.131648) (xy 462.962479 -387.092939) (xy 463.007837 -387.060488) (xy 463.057437 -387.034987)
			(xy 463.110221 -387.01698) (xy 463.165064 -387.00685) (xy 463.220798 -387.004813) (xy 463.276235 -387.010913)
			(xy 463.330192 -387.025019) (xy 463.381521 -387.046831) (xy 463.429127 -387.075885) (xy 463.471995 -387.11156)
			(xy 463.509212 -387.153097) (xy 463.539985 -387.19961) (xy 463.563657 -387.250107) (xy 463.579725 -387.303514)
			(xy 463.587845 -387.35869) (xy 463.588354 -387.386576) (xy 463.587845 -387.414462) (xy 463.579725 -387.469638)
			(xy 463.563657 -387.523045) (xy 463.539985 -387.573542) (xy 463.509212 -387.620055) (xy 463.471995 -387.661592)
			(xy 463.429127 -387.697267) (xy 463.381521 -387.726321) (xy 463.330192 -387.748133) (xy 463.276235 -387.762239)
			(xy 463.220798 -387.768339) (xy 463.165064 -387.766302) (xy 463.110221 -387.756172) (xy 463.057437 -387.738165)
			(xy 463.007837 -387.712664) (xy 462.962479 -387.680213) (xy 462.92233 -387.641504) (xy 462.888244 -387.597361)
			(xy 462.860948 -387.548726) (xy 462.841025 -387.496635) (xy 462.828899 -387.442198) (xy 462.824828 -387.386576)
			(xy 462.255395 -387.386576) (xy 462.250654 -387.402722) (xy 462.228007 -387.452309) (xy 462.198532 -387.498168)
			(xy 462.16283 -387.539365) (xy 462.121628 -387.575062) (xy 462.075765 -387.604531) (xy 462.026175 -387.627172)
			(xy 461.973868 -387.642525) (xy 461.919907 -387.650276) (xy 461.89265 -387.650736) (xy 461.86391 -387.650233)
			(xy 461.807083 -387.641604) (xy 461.752192 -387.624548) (xy 461.700481 -387.599453) (xy 461.653119 -387.566884)
			(xy 461.631792 -387.547612) (xy 461.624934 -387.541008) (xy 461.6069 -387.533896) (xy 461.518 -387.533896)
			(xy 461.499966 -387.541008) (xy 461.493108 -387.547612) (xy 461.471794 -387.566898) (xy 461.424429 -387.599464)
			(xy 461.372715 -387.624555) (xy 461.317821 -387.641601) (xy 461.26099 -387.650219) (xy 461.23225 -387.650736)
			(xy 461.205003 -387.65019) (xy 461.151065 -387.642429) (xy 461.09878 -387.62707) (xy 461.049213 -387.604428)
			(xy 461.003372 -387.574963) (xy 460.962191 -387.539274) (xy 460.926507 -387.498088) (xy 460.897048 -387.452243)
			(xy 460.874412 -387.402673) (xy 460.859061 -387.350386) (xy 460.851306 -387.296447) (xy 460.087696 -387.296447)
			(xy 460.085414 -387.312315) (xy 460.070055 -387.36462) (xy 460.047408 -387.414207) (xy 460.017934 -387.460065)
			(xy 459.982234 -387.501262) (xy 459.941033 -387.536958) (xy 459.895171 -387.566427) (xy 459.845583 -387.589069)
			(xy 459.793276 -387.604423) (xy 459.739317 -387.612176) (xy 459.71206 -387.612636) (xy 459.683321 -387.612127)
			(xy 459.626493 -387.603499) (xy 459.571603 -387.586445) (xy 459.519891 -387.561351) (xy 459.472529 -387.528783)
			(xy 459.451202 -387.509512) (xy 459.444344 -387.502908) (xy 459.42631 -387.495796) (xy 459.33741 -387.495796)
			(xy 459.319376 -387.502908) (xy 459.312518 -387.509512) (xy 459.2912 -387.528793) (xy 459.243836 -387.56136)
			(xy 459.192123 -387.586451) (xy 459.137229 -387.603499) (xy 459.0804 -387.612118) (xy 459.05166 -387.612636)
			(xy 459.024413 -387.612091) (xy 458.970473 -387.604331) (xy 458.918187 -387.588973) (xy 458.868619 -387.566331)
			(xy 458.822777 -387.536866) (xy 458.781594 -387.501177) (xy 458.74591 -387.459991) (xy 458.716449 -387.414146)
			(xy 458.693813 -387.364575) (xy 458.678461 -387.312288) (xy 458.670706 -387.258347) (xy 457.434696 -387.258347)
			(xy 457.434696 -387.346698) (xy 457.441808 -387.364732) (xy 457.448412 -387.37159) (xy 457.467697 -387.392905)
			(xy 457.500263 -387.440269) (xy 457.525354 -387.491984) (xy 457.542401 -387.546878) (xy 457.551018 -387.603708)
			(xy 457.551536 -387.632448) (xy 457.551061 -387.659007) (xy 457.543703 -387.711613) (xy 457.529123 -387.762691)
			(xy 457.507601 -387.811254) (xy 457.479554 -387.856364) (xy 457.46289 -387.87705) (xy 457.462636 -387.877304)
			(xy 457.456976 -387.884761) (xy 457.450992 -387.902485) (xy 457.450952 -387.911848) (xy 457.454254 -387.989826)
			(xy 457.461874 -388.007098) (xy 457.468732 -388.013956) (xy 457.489405 -388.035575) (xy 457.524504 -388.084004)
			(xy 457.542741 -388.119874) (xy 457.846428 -388.119874) (xy 457.850499 -388.064252) (xy 457.862625 -388.009815)
			(xy 457.882548 -387.957724) (xy 457.909844 -387.909089) (xy 457.94393 -387.864946) (xy 457.984079 -387.826237)
			(xy 458.029437 -387.793786) (xy 458.079037 -387.768285) (xy 458.131821 -387.750278) (xy 458.186664 -387.740148)
			(xy 458.242398 -387.738111) (xy 458.297835 -387.744211) (xy 458.351792 -387.758317) (xy 458.403121 -387.780129)
			(xy 458.450727 -387.809183) (xy 458.493595 -387.844858) (xy 458.530812 -387.886395) (xy 458.561585 -387.932908)
			(xy 458.585257 -387.983405) (xy 458.601325 -388.036812) (xy 458.609445 -388.091988) (xy 458.609954 -388.119874)
			(xy 458.609445 -388.14776) (xy 458.601325 -388.202936) (xy 458.585257 -388.256343) (xy 458.561585 -388.30684)
			(xy 458.530812 -388.353353) (xy 458.493595 -388.39489) (xy 458.450727 -388.430565) (xy 458.403121 -388.459619)
			(xy 458.351792 -388.481431) (xy 458.297835 -388.495537) (xy 458.242398 -388.501637) (xy 458.186664 -388.4996)
			(xy 458.131821 -388.48947) (xy 458.079037 -388.471463) (xy 458.029437 -388.445962) (xy 457.984079 -388.413511)
			(xy 457.94393 -388.374802) (xy 457.909844 -388.330659) (xy 457.882548 -388.282024) (xy 457.862625 -388.229933)
			(xy 457.850499 -388.175496) (xy 457.846428 -388.119874) (xy 457.542741 -388.119874) (xy 457.551611 -388.137319)
			(xy 457.570061 -388.194213) (xy 457.5794 -388.253291) (xy 457.579984 -388.283196) (xy 457.579541 -388.31045)
			(xy 457.571784 -388.364403) (xy 457.556427 -388.416702) (xy 457.533783 -388.466284) (xy 457.504313 -388.512138)
			(xy 457.468618 -388.553332) (xy 457.427422 -388.589025) (xy 457.381567 -388.618493) (xy 457.331984 -388.641134)
			(xy 457.279683 -388.656488) (xy 457.22573 -388.664242) (xy 457.198476 -388.664704) (xy 457.171906 -388.664233)
			(xy 457.119283 -388.656837) (xy 457.068197 -388.642205) (xy 457.019637 -388.620622) (xy 456.974545 -388.592504)
			(xy 456.953874 -388.575804) (xy 456.946456 -388.570203) (xy 456.928878 -388.564209) (xy 456.919584 -388.56412)
			(xy 456.84186 -388.567168) (xy 456.824842 -388.57428) (xy 456.817984 -388.580884) (xy 456.796502 -388.600972)
			(xy 456.748506 -388.634959) (xy 456.695863 -388.66118) (xy 456.639821 -388.679013) (xy 456.581706 -388.688037)
			(xy 456.5523 -388.68858) (xy 456.524869 -388.688153) (xy 456.470576 -388.680275) (xy 456.417969 -388.66471)
			(xy 456.36813 -388.641778) (xy 456.322085 -388.611952) (xy 456.280781 -388.575844) (xy 456.245068 -388.534198)
			(xy 456.229974 -388.511288) (xy 456.22262 -388.500898) (xy 456.200503 -388.488364) (xy 456.18781 -388.487412)
			(xy 456.102974 -388.486396) (xy 456.090292 -388.486813) (xy 456.067764 -388.49842) (xy 456.060048 -388.508494)
			(xy 456.060048 -388.508748) (xy 456.044731 -388.530502) (xy 456.009069 -388.569982) (xy 455.968269 -388.604127)
			(xy 455.923123 -388.632275) (xy 455.874505 -388.65388) (xy 455.823358 -388.668523) (xy 455.770673 -388.675922)
			(xy 455.744072 -388.676388) (xy 455.716819 -388.675948) (xy 455.662869 -388.668187) (xy 455.610572 -388.652828)
			(xy 455.560993 -388.630182) (xy 455.515142 -388.600711) (xy 455.473952 -388.565014) (xy 455.43826 -388.523819)
			(xy 455.408795 -388.477965) (xy 455.386156 -388.428383) (xy 455.370802 -388.376084) (xy 455.363048 -388.322133)
			(xy 455.362564 -388.29488) (xy 455.363074 -388.265401) (xy 455.372148 -388.207146) (xy 455.390076 -388.15098)
			(xy 455.416433 -388.098241) (xy 455.450589 -388.050185) (xy 455.470768 -388.028688) (xy 455.471022 -388.028434)
			(xy 455.477493 -388.021077) (xy 455.484803 -388.002916) (xy 455.485246 -387.993128) (xy 455.485246 -387.912102)
			(xy 455.47788 -387.893814) (xy 455.470768 -387.886702) (xy 455.450437 -387.865202) (xy 455.416059 -387.817042)
			(xy 455.389529 -387.764151) (xy 455.371483 -387.707798) (xy 455.362355 -387.649334) (xy 455.361802 -387.619748)
			(xy 452.503953 -387.619748) (xy 452.510938 -387.668071) (xy 452.511414 -387.69544) (xy 452.510874 -387.723834)
			(xy 452.502458 -387.779995) (xy 452.485804 -387.834286) (xy 452.46128 -387.885505) (xy 452.429428 -387.932519)
			(xy 452.410576 -387.953758) (xy 452.404731 -387.960834) (xy 452.39795 -387.977874) (xy 452.397368 -387.987032)
			(xy 452.396098 -388.064248) (xy 452.402448 -388.08152) (xy 452.408544 -388.088632) (xy 452.425822 -388.10948)
			(xy 452.454965 -388.155112) (xy 452.477361 -388.204408) (xy 452.492559 -388.256377) (xy 452.500254 -388.309972)
			(xy 452.500746 -388.337044) (xy 452.500746 -388.337552) (xy 452.50026 -388.364803) (xy 452.492504 -388.418751)
			(xy 452.477149 -388.471046) (xy 452.454507 -388.520623) (xy 452.425041 -388.566473) (xy 452.38935 -388.607664)
			(xy 452.348159 -388.643355) (xy 452.302309 -388.672821) (xy 452.252732 -388.695463) (xy 452.200437 -388.710818)
			(xy 452.146489 -388.718574) (xy 452.091987 -388.718574) (xy 452.038039 -388.710818) (xy 451.985744 -388.695463)
			(xy 451.936167 -388.672821) (xy 451.890317 -388.643355) (xy 451.849126 -388.607664) (xy 451.813435 -388.566473)
			(xy 451.783969 -388.520623) (xy 451.761327 -388.471046) (xy 451.745972 -388.418751) (xy 451.738216 -388.364803)
			(xy 451.73773 -388.337552) (xy 451.738128 -388.312092) (xy 451.744897 -388.261624) (xy 451.758321 -388.212505)
			(xy 451.778162 -388.16561) (xy 451.804066 -388.121772) (xy 451.835573 -388.08177) (xy 451.853554 -388.06374)
			(xy 451.860334 -388.056435) (xy 451.86817 -388.038128) (xy 451.868794 -388.02818) (xy 451.869556 -387.99643)
			(xy 451.869256 -387.986442) (xy 451.861922 -387.967875) (xy 451.855332 -387.960362) (xy 451.842886 -387.9469)
			(xy 451.835356 -387.93909) (xy 451.815622 -387.930134) (xy 451.804786 -387.929628) (xy 451.728586 -387.929628)
			(xy 451.717753 -387.930144) (xy 451.698021 -387.939099) (xy 451.690486 -387.9469) (xy 451.672291 -387.966963)
			(xy 451.631182 -388.002226) (xy 451.5855 -388.031325) (xy 451.536165 -388.053675) (xy 451.484166 -388.068827)
			(xy 451.430547 -388.076477) (xy 451.403466 -388.076948) (xy 451.374727 -388.076432) (xy 451.3179 -388.067806)
			(xy 451.263009 -388.050753) (xy 451.211298 -388.02566) (xy 451.163935 -387.993095) (xy 451.142608 -387.973824)
			(xy 451.13575 -387.96722) (xy 451.117716 -387.960108) (xy 451.028816 -387.960108) (xy 451.010782 -387.96722)
			(xy 451.003924 -387.973824) (xy 450.982605 -387.993105) (xy 450.935242 -388.025671) (xy 450.883528 -388.050762)
			(xy 450.828635 -388.06781) (xy 450.771806 -388.076429) (xy 450.743066 -388.076948) (xy 450.715816 -388.076454)
			(xy 450.66187 -388.068694) (xy 450.609578 -388.053336) (xy 450.560004 -388.030694) (xy 450.514155 -388.001228)
			(xy 450.472966 -387.965538) (xy 450.437275 -387.92435) (xy 450.407809 -387.878502) (xy 450.385166 -387.828927)
			(xy 450.369807 -387.776635) (xy 450.362046 -387.72269) (xy 450.361558 -387.69544) (xy 450.362033 -387.66807)
			(xy 450.369847 -387.613891) (xy 450.385333 -387.561387) (xy 450.408173 -387.51164) (xy 450.437897 -387.465673)
			(xy 450.455538 -387.444742) (xy 450.455792 -387.444488) (xy 450.461389 -387.437408) (xy 450.46763 -387.420486)
			(xy 450.467984 -387.411468) (xy 450.467984 -387.344412) (xy 450.467625 -387.335395) (xy 450.461379 -387.318478)
			(xy 450.455792 -387.311392) (xy 450.455538 -387.311392) (xy 450.455538 -387.311138) (xy 450.437909 -387.290198)
			(xy 450.408194 -387.244228) (xy 450.385356 -387.194482) (xy 450.369863 -387.141983) (xy 450.362033 -387.087809)
			(xy 450.361558 -387.06044) (xy 450.362056 -387.0317) (xy 450.370687 -386.974872) (xy 450.387744 -386.919982)
			(xy 450.41284 -386.86827) (xy 450.44541 -386.820909) (xy 450.464682 -386.799582) (xy 450.471286 -386.79247)
			(xy 450.478652 -386.774182) (xy 450.477636 -386.693918) (xy 450.477116 -386.68432) (xy 450.469793 -386.666564)
			(xy 450.463412 -386.659374) (xy 450.463158 -386.65912) (xy 450.442931 -386.637621) (xy 450.408707 -386.589528)
			(xy 450.382299 -386.536738) (xy 450.364337 -386.480511) (xy 450.35525 -386.422187) (xy 450.3547 -386.392674)
			(xy 450.18508 -386.392674) (xy 450.177797 -386.441828) (xy 450.16149 -386.495614) (xy 450.137467 -386.546424)
			(xy 450.106249 -386.59316) (xy 450.06851 -386.634808) (xy 450.047106 -386.653024) (xy 450.038216 -386.66039)
			(xy 450.028564 -386.680202) (xy 450.027548 -386.769356) (xy 450.028024 -386.780409) (xy 450.037095 -386.800557)
			(xy 450.045074 -386.808218) (xy 450.065287 -386.826445) (xy 450.100884 -386.867614) (xy 450.130271 -386.913424)
			(xy 450.152851 -386.962944) (xy 450.168167 -387.015169) (xy 450.175906 -387.069041) (xy 450.176392 -387.096254)
			(xy 450.175903 -387.124994) (xy 450.167272 -387.181823) (xy 450.150214 -387.236714) (xy 450.125115 -387.288426)
			(xy 450.092542 -387.335786) (xy 450.073268 -387.357112) (xy 450.066664 -387.36397) (xy 450.059552 -387.382004)
			(xy 450.059552 -387.470904) (xy 450.066664 -387.488938) (xy 450.073268 -387.495796) (xy 450.092565 -387.5171)
			(xy 450.125128 -387.564468) (xy 450.150215 -387.616186) (xy 450.167259 -387.671082) (xy 450.175875 -387.727913)
			(xy 450.176392 -387.756654) (xy 450.175902 -387.783906) (xy 450.168151 -387.837857) (xy 450.1528 -387.890156)
			(xy 450.130161 -387.939737) (xy 450.100697 -387.985591) (xy 450.065006 -388.026784) (xy 450.023815 -388.062479)
			(xy 449.977963 -388.091947) (xy 449.928384 -388.114589) (xy 449.876087 -388.129944) (xy 449.822136 -388.1377)
			(xy 449.794884 -388.138162) (xy 449.769022 -388.137724) (xy 449.717771 -388.13074) (xy 449.667935 -388.11689)
			(xy 449.620431 -388.096427) (xy 449.57613 -388.069728) (xy 449.535847 -388.037283) (xy 449.51777 -388.018782)
			(xy 449.510297 -388.01159) (xy 449.491296 -388.003327) (xy 449.48094 -388.00278) (xy 449.448682 -388.00278)
			(xy 449.43825 -388.003245) (xy 449.419097 -388.011514) (xy 449.411598 -388.018782) (xy 449.407534 -388.0231)
			(xy 449.400783 -388.030736) (xy 449.393452 -388.049738) (xy 449.39331 -388.05993) (xy 449.39585 -388.14375)
			(xy 449.404486 -388.162292) (xy 449.41236 -388.169404) (xy 449.431897 -388.187576) (xy 449.466161 -388.228477)
			(xy 449.494385 -388.273757) (xy 449.516019 -388.322531) (xy 449.530639 -388.373845) (xy 449.537959 -388.426697)
			(xy 449.538344 -388.453376) (xy 449.538344 -388.45363) (xy 449.538742 -388.463703) (xy 449.546481 -388.482301)
			(xy 449.55333 -388.489698) (xy 451.8787 -390.815068) (xy 451.895981 -390.833141) (xy 451.923787 -390.874694)
			(xy 451.942953 -390.920872) (xy 451.952744 -390.969902) (xy 451.953376 -390.9949) (xy 451.953376 -398.408906)
			(xy 451.952744 -398.433902) (xy 451.942938 -398.482925) (xy 451.923764 -398.529095) (xy 451.895955 -398.570642)
			(xy 451.8787 -398.588738) (xy 451.184038 -399.2834) (xy 454.494221 -399.2834) (xy 454.498203 -399.230259)
			(xy 454.51006 -399.178305) (xy 454.529528 -399.128698) (xy 454.556171 -399.082546) (xy 454.589394 -399.040881)
			(xy 454.628456 -399.004632) (xy 454.672484 -398.974609) (xy 454.720494 -398.951483) (xy 454.771415 -398.93577)
			(xy 454.824109 -398.927821) (xy 454.850754 -398.92732) (xy 454.877114 -398.927802) (xy 454.929257 -398.93559)
			(xy 454.979679 -398.950987) (xy 455.027277 -398.973657) (xy 455.071008 -399.003102) (xy 455.090784 -399.020538)
			(xy 455.091038 -399.020792) (xy 455.098229 -399.026787) (xy 455.115717 -399.033438) (xy 455.125074 -399.033746)
			(xy 455.193654 -399.033746) (xy 455.202992 -399.033352) (xy 455.220445 -399.026698) (xy 455.22769 -399.020792)
			(xy 455.228198 -399.020284) (xy 455.24797 -399.0029) (xy 455.29168 -398.973559) (xy 455.33923 -398.950963)
			(xy 455.389585 -398.935604) (xy 455.441652 -398.927816) (xy 455.467974 -398.92732) (xy 455.494335 -398.92779)
			(xy 455.546478 -398.935581) (xy 455.5969 -398.950981) (xy 455.644498 -398.973653) (xy 455.688228 -399.003101)
			(xy 455.708004 -399.020538) (xy 455.708258 -399.020792) (xy 455.715443 -399.026796) (xy 455.732935 -399.033441)
			(xy 455.742294 -399.033746) (xy 455.810874 -399.033746) (xy 455.820213 -399.033361) (xy 455.837666 -399.026701)
			(xy 455.84491 -399.020792) (xy 455.845418 -399.020284) (xy 455.865182 -399.002891) (xy 455.908894 -398.973551)
			(xy 455.956446 -398.950957) (xy 456.006803 -398.9356) (xy 456.058871 -398.927814) (xy 456.085194 -398.92732)
			(xy 456.11019 -398.927733) (xy 456.159691 -398.93473) (xy 456.207729 -398.948575) (xy 456.253361 -398.968996)
			(xy 456.295692 -398.995591) (xy 456.315064 -399.011394) (xy 456.321922 -399.017236) (xy 456.33894 -399.023586)
			(xy 456.422506 -399.023586) (xy 456.439524 -399.017236) (xy 456.446382 -399.011394) (xy 456.465746 -398.995581)
			(xy 456.508076 -398.96898) (xy 456.55371 -398.94856) (xy 456.601751 -398.934722) (xy 456.651255 -398.927738)
			(xy 456.676252 -398.92732) (xy 456.701833 -398.927781) (xy 456.75247 -398.935097) (xy 456.801538 -398.949585)
			(xy 456.848027 -398.970947) (xy 456.89098 -398.998743) (xy 456.929513 -399.032401) (xy 456.946508 -399.051526)
			(xy 456.952858 -399.059146) (xy 456.97013 -399.068036) (xy 457.059538 -399.076926) (xy 457.078588 -399.071338)
			(xy 457.086208 -399.065242) (xy 457.106427 -399.049888) (xy 457.150186 -399.024146) (xy 457.196972 -399.004433)
			(xy 457.245959 -398.991098) (xy 457.296281 -398.984375) (xy 457.321666 -398.983962) (xy 457.348918 -398.984483)
			(xy 457.402869 -398.992235) (xy 457.455166 -399.007587) (xy 457.504747 -399.030226) (xy 457.550601 -399.059691)
			(xy 457.591794 -399.095382) (xy 457.627489 -399.136572) (xy 457.656958 -399.182423) (xy 457.679601 -399.232002)
			(xy 457.694957 -399.284298) (xy 457.702715 -399.338248) (xy 457.702715 -399.392752) (xy 457.694957 -399.446702)
			(xy 457.679601 -399.498998) (xy 457.656958 -399.548577) (xy 457.627489 -399.594428) (xy 457.591794 -399.635618)
			(xy 457.550601 -399.671309) (xy 457.504747 -399.700774) (xy 457.455166 -399.723413) (xy 457.402869 -399.738765)
			(xy 457.348918 -399.746517) (xy 457.321666 -399.746978) (xy 457.292465 -399.746417) (xy 457.234744 -399.737518)
			(xy 457.179057 -399.719918) (xy 457.126706 -399.694029) (xy 457.078917 -399.660458) (xy 457.036808 -399.619989)
			(xy 457.018644 -399.597118) (xy 457.018644 -399.596864) (xy 457.012399 -399.589565) (xy 456.995815 -399.579903)
			(xy 456.986386 -399.578068) (xy 456.906884 -399.565622) (xy 456.887834 -399.56994) (xy 456.87996 -399.575528)
			(xy 456.857414 -399.59061) (xy 456.808731 -399.61453) (xy 456.756986 -399.630793) (xy 456.703373 -399.639024)
			(xy 456.676252 -399.639536) (xy 456.651257 -399.639084) (xy 456.601759 -399.632094) (xy 456.553722 -399.618257)
			(xy 456.508089 -399.597846) (xy 456.465756 -399.57126) (xy 456.446382 -399.555462) (xy 456.439524 -399.54962)
			(xy 456.422506 -399.54327) (xy 456.33894 -399.54327) (xy 456.321922 -399.54962) (xy 456.315064 -399.555462)
			(xy 456.29569 -399.571262) (xy 456.253362 -399.597863) (xy 456.207731 -399.618285) (xy 456.159692 -399.632126)
			(xy 456.11019 -399.639114) (xy 456.085194 -399.639536) (xy 456.058833 -399.639071) (xy 456.006691 -399.631277)
			(xy 455.956269 -399.615875) (xy 455.908672 -399.593202) (xy 455.86494 -399.563754) (xy 455.845164 -399.546318)
			(xy 455.84491 -399.546064) (xy 455.837709 -399.540084) (xy 455.820229 -399.533425) (xy 455.810874 -399.53311)
			(xy 455.742294 -399.53311) (xy 455.732959 -399.533538) (xy 455.715507 -399.540169) (xy 455.708258 -399.546064)
			(xy 455.70775 -399.546572) (xy 455.687967 -399.563942) (xy 455.644259 -399.593284) (xy 455.596712 -399.615881)
			(xy 455.546359 -399.631244) (xy 455.494295 -399.639037) (xy 455.467974 -399.639536) (xy 455.441615 -399.639023)
			(xy 455.389475 -399.63124) (xy 455.339054 -399.615849) (xy 455.291455 -399.593187) (xy 455.247722 -399.56375)
			(xy 455.227944 -399.546318) (xy 455.22769 -399.546064) (xy 455.220495 -399.540075) (xy 455.20301 -399.533422)
			(xy 455.193654 -399.53311) (xy 455.125074 -399.53311) (xy 455.115738 -399.533528) (xy 455.098286 -399.540166)
			(xy 455.091038 -399.546064) (xy 455.09053 -399.546572) (xy 455.070755 -399.563951) (xy 455.027044 -399.593292)
			(xy 454.979495 -399.615887) (xy 454.929141 -399.631248) (xy 454.877076 -399.639039) (xy 454.850754 -399.639536)
			(xy 454.824109 -399.638979) (xy 454.771415 -399.63103) (xy 454.720494 -399.615317) (xy 454.672484 -399.592191)
			(xy 454.628456 -399.562168) (xy 454.589394 -399.525919) (xy 454.556171 -399.484254) (xy 454.529528 -399.438102)
			(xy 454.51006 -399.388495) (xy 454.498203 -399.336541) (xy 454.494221 -399.2834) (xy 451.184038 -399.2834)
			(xy 450.263768 -400.20367) (xy 456.432158 -400.20367) (xy 456.43265 -400.17642) (xy 456.44041 -400.122474)
			(xy 456.455767 -400.070181) (xy 456.478409 -400.020606) (xy 456.507875 -399.974758) (xy 456.543566 -399.933569)
			(xy 456.584754 -399.897878) (xy 456.630603 -399.868411) (xy 456.680178 -399.845768) (xy 456.73247 -399.83041)
			(xy 456.786416 -399.82265) (xy 456.813666 -399.822162) (xy 456.842583 -399.822681) (xy 456.899755 -399.831407)
			(xy 456.954955 -399.848663) (xy 457.006918 -399.874054) (xy 457.054451 -399.906999) (xy 457.096467 -399.946741)
			(xy 457.114656 -399.969228) (xy 457.122287 -399.97801) (xy 457.14317 -399.988206) (xy 457.154788 -399.988786)
			(xy 457.234544 -399.988786) (xy 457.246178 -399.988263) (xy 457.267087 -399.978063) (xy 457.274676 -399.969228)
			(xy 457.292888 -399.946762) (xy 457.334902 -399.907024) (xy 457.382433 -399.874082) (xy 457.43439 -399.848691)
			(xy 457.489584 -399.831431) (xy 457.546751 -399.822699) (xy 457.575666 -399.822162) (xy 457.602917 -399.822687)
			(xy 457.656864 -399.830438) (xy 457.709159 -399.845789) (xy 457.758737 -399.868425) (xy 457.804589 -399.897887)
			(xy 457.845781 -399.933574) (xy 457.881475 -399.97476) (xy 457.910944 -400.020607) (xy 457.933589 -400.070181)
			(xy 457.948948 -400.122474) (xy 457.956709 -400.176419) (xy 457.957174 -400.20367) (xy 457.956772 -400.22936)
			(xy 457.949869 -400.280274) (xy 457.936196 -400.329801) (xy 457.916 -400.377046) (xy 457.889648 -400.421154)
			(xy 457.857616 -400.461326) (xy 457.820483 -400.496838) (xy 457.799948 -400.51228) (xy 457.788772 -400.520408)
			(xy 457.77785 -400.545808) (xy 457.791566 -400.661378) (xy 457.80833 -400.683476) (xy 457.821284 -400.688556)
			(xy 457.847233 -400.699707) (xy 457.895816 -400.728508) (xy 457.939623 -400.764156) (xy 457.977696 -400.805872)
			(xy 458.009205 -400.852744) (xy 458.03346 -400.903748) (xy 458.049932 -400.95777) (xy 458.058262 -401.013631)
			(xy 458.058774 -401.04187) (xy 458.058317 -401.069124) (xy 458.050563 -401.123077) (xy 458.035209 -401.175377)
			(xy 458.012567 -401.224959) (xy 457.983099 -401.270814) (xy 457.947405 -401.312008) (xy 457.906211 -401.347702)
			(xy 457.860355 -401.377169) (xy 457.810773 -401.39981) (xy 457.758473 -401.415164) (xy 457.70452 -401.422917)
			(xy 457.677266 -401.423378) (xy 457.64835 -401.422821) (xy 457.591181 -401.414101) (xy 457.535982 -401.396851)
			(xy 457.48402 -401.371467) (xy 457.436485 -401.33853) (xy 457.394467 -401.298795) (xy 457.376276 -401.276312)
			(xy 457.368668 -401.267506) (xy 457.347768 -401.257321) (xy 457.336144 -401.256754) (xy 457.256388 -401.256754)
			(xy 457.244754 -401.257282) (xy 457.223844 -401.267477) (xy 457.216256 -401.276312) (xy 457.198093 -401.298819)
			(xy 457.156067 -401.338552) (xy 457.108526 -401.371488) (xy 457.056559 -401.396872) (xy 457.001357 -401.414123)
			(xy 456.944184 -401.422846) (xy 456.915266 -401.423378) (xy 456.888013 -401.422954) (xy 456.834061 -401.415192)
			(xy 456.781763 -401.399831) (xy 456.732184 -401.377184) (xy 456.686332 -401.347711) (xy 456.645142 -401.312013)
			(xy 456.609451 -401.270816) (xy 456.579986 -401.22496) (xy 456.557347 -401.175377) (xy 456.541995 -401.123076)
			(xy 456.534242 -401.069124) (xy 456.533758 -401.04187) (xy 456.534176 -401.01618) (xy 456.541075 -400.965267)
			(xy 456.554745 -400.915739) (xy 456.574937 -400.868494) (xy 456.601286 -400.824386) (xy 456.633317 -400.784213)
			(xy 456.670449 -400.748702) (xy 456.690984 -400.73326) (xy 456.70216 -400.725132) (xy 456.713082 -400.699732)
			(xy 456.699366 -400.584162) (xy 456.682602 -400.562064) (xy 456.669648 -400.556984) (xy 456.643698 -400.545835)
			(xy 456.595119 -400.517029) (xy 456.551316 -400.481379) (xy 456.513245 -400.439663) (xy 456.481737 -400.392791)
			(xy 456.457481 -400.341788) (xy 456.441006 -400.287767) (xy 456.432673 -400.231908) (xy 456.432158 -400.20367)
			(xy 450.263768 -400.20367) (xy 450.153786 -400.313652) (xy 450.135758 -400.330841) (xy 450.094395 -400.35858)
			(xy 450.04843 -400.377752) (xy 449.999615 -400.387626) (xy 449.974716 -400.388328) (xy 449.973192 -400.388328)
			(xy 449.967096 -400.388074) (xy 449.948937 -400.407741) (xy 449.908025 -400.442262) (xy 449.862692 -400.470729)
			(xy 449.813826 -400.492583) (xy 449.762386 -400.507395) (xy 449.709381 -400.514876) (xy 449.682616 -400.515328)
			(xy 449.655364 -400.514826) (xy 449.601414 -400.507071) (xy 449.549117 -400.491717) (xy 449.499537 -400.469077)
			(xy 449.453685 -400.439611) (xy 449.412492 -400.403919) (xy 449.376799 -400.362728) (xy 449.347331 -400.316877)
			(xy 449.324688 -400.267298) (xy 449.309332 -400.215002) (xy 449.301575 -400.161052) (xy 449.301575 -400.106548)
			(xy 449.309332 -400.052598) (xy 449.324688 -400.000302) (xy 449.347331 -399.950723) (xy 449.376799 -399.904872)
			(xy 449.412492 -399.863681) (xy 449.453685 -399.827989) (xy 449.499537 -399.798523) (xy 449.549117 -399.775883)
			(xy 449.601414 -399.760529) (xy 449.655364 -399.752774) (xy 449.682616 -399.752312) (xy 449.709045 -399.752746)
			(xy 449.761394 -399.760067) (xy 449.812229 -399.774551) (xy 449.860574 -399.795922) (xy 449.883276 -399.809462)
			(xy 449.893298 -399.814968) (xy 449.916006 -399.817407) (xy 449.937526 -399.80976) (xy 449.946014 -399.802096)
			(xy 451.429374 -398.318482) (xy 451.436211 -398.311079) (xy 451.443933 -398.292482) (xy 451.44436 -398.282414)
			(xy 451.44436 -391.121392) (xy 451.443949 -391.111321) (xy 451.43622 -391.092723) (xy 451.429374 -391.085324)
			(xy 449.193666 -388.849362) (xy 449.186276 -388.842509) (xy 449.167669 -388.834798) (xy 449.157598 -388.834376)
			(xy 449.157344 -388.834376) (xy 449.128385 -388.833876) (xy 449.071121 -388.825202) (xy 449.015826 -388.807972)
			(xy 448.963771 -388.782581) (xy 448.916152 -388.749613) (xy 448.874065 -388.709826) (xy 448.855846 -388.68731)
			(xy 448.848207 -388.678535) (xy 448.827331 -388.668333) (xy 448.815714 -388.667752) (xy 448.735958 -388.667752)
			(xy 448.724322 -388.668263) (xy 448.703412 -388.67847) (xy 448.695826 -388.68731) (xy 448.677623 -388.709783)
			(xy 448.635605 -388.749519) (xy 448.588073 -388.782458) (xy 448.536114 -388.807848) (xy 448.480919 -388.825107)
			(xy 448.423751 -388.833839) (xy 448.394836 -388.834376) (xy 448.367583 -388.833911) (xy 448.31363 -388.826158)
			(xy 448.26133 -388.810805) (xy 448.211748 -388.788164) (xy 448.165893 -388.758697) (xy 448.124699 -388.723003)
			(xy 448.089005 -388.68181) (xy 448.059537 -388.635955) (xy 448.036896 -388.586374) (xy 448.021543 -388.534074)
			(xy 448.013789 -388.480121) (xy 448.013328 -388.452868) (xy 448.013848 -388.423354) (xy 448.022944 -388.36503)
			(xy 448.040916 -388.308804) (xy 448.067333 -388.256017) (xy 448.101565 -388.207928) (xy 448.121786 -388.186422)
			(xy 448.12853 -388.178781) (xy 448.135864 -388.159783) (xy 448.13601 -388.149592) (xy 448.13347 -388.065772)
			(xy 448.124834 -388.04723) (xy 448.11696 -388.040118) (xy 448.097498 -388.021961) (xy 448.063302 -387.981175)
			(xy 448.035114 -387.936027) (xy 448.013482 -387.887397) (xy 447.998826 -387.836229) (xy 447.991433 -387.783521)
			(xy 447.990976 -387.756908) (xy 447.990976 -387.756654) (xy 447.991478 -387.727914) (xy 448.000107 -387.671086)
			(xy 448.017162 -387.616196) (xy 448.042259 -387.564484) (xy 448.074828 -387.517122) (xy 448.0941 -387.495796)
			(xy 448.100704 -387.488938) (xy 448.107816 -387.470904) (xy 448.107816 -387.382004) (xy 448.100704 -387.36397)
			(xy 448.0941 -387.357112) (xy 448.074818 -387.335794) (xy 448.042251 -387.288431) (xy 448.01716 -387.236717)
			(xy 448.000112 -387.181824) (xy 447.991494 -387.124994) (xy 447.990976 -387.096254) (xy 447.991473 -387.068151)
			(xy 447.999713 -387.012554) (xy 448.016023 -386.958767) (xy 448.04005 -386.907956) (xy 448.071273 -386.861222)
			(xy 448.109016 -386.819575) (xy 448.130422 -386.80136) (xy 448.139312 -386.793994) (xy 448.148964 -386.774182)
			(xy 448.14998 -386.685028) (xy 448.149535 -386.673971) (xy 448.140445 -386.653822) (xy 448.132454 -386.646166)
			(xy 448.112239 -386.627941) (xy 448.076641 -386.586772) (xy 448.047253 -386.540963) (xy 448.024673 -386.491442)
			(xy 448.009359 -386.439215) (xy 448.001621 -386.385343) (xy 448.001136 -386.35813) (xy 448.001696 -386.329072)
			(xy 448.010524 -386.27163) (xy 448.027966 -386.216192) (xy 448.053618 -386.164043) (xy 448.086885 -386.11639)
			(xy 448.106546 -386.094986) (xy 448.112916 -386.08766) (xy 448.12009 -386.069634) (xy 448.120516 -386.059934)
			(xy 448.120516 -385.979924) (xy 448.113404 -385.96189) (xy 448.106546 -385.954778) (xy 448.086865 -385.93339)
			(xy 448.053587 -385.885739) (xy 448.027932 -385.833586) (xy 448.010495 -385.778143) (xy 448.001679 -385.720695)
			(xy 448.001136 -385.691634) (xy 448.001606 -385.664934) (xy 448.009054 -385.612055) (xy 448.023807 -385.560733)
			(xy 448.045578 -385.511973) (xy 448.073941 -385.466727) (xy 448.090798 -385.446016) (xy 448.091052 -385.445762)
			(xy 448.096682 -385.438285) (xy 448.102684 -385.420576) (xy 448.102736 -385.411218) (xy 448.099434 -385.332986)
			(xy 448.091814 -385.315714) (xy 448.084956 -385.308856) (xy 448.064171 -385.287243) (xy 448.028912 -385.238746)
			(xy 448.001679 -385.185329) (xy 447.98314 -385.128308) (xy 447.973755 -385.069088) (xy 447.973196 -385.039108)
			(xy 441.737496 -385.039108) (xy 441.737496 -385.089146) (xy 441.737064 -385.099212) (xy 441.729338 -385.117804)
			(xy 441.72251 -385.125214) (xy 440.63285 -386.21462) (xy 440.626001 -386.222017) (xy 440.618266 -386.240616)
			(xy 440.617864 -386.250688) (xy 440.617864 -386.394706) (xy 442.279024 -386.394706) (xy 442.279461 -386.367452)
			(xy 442.287218 -386.313498) (xy 442.302575 -386.261198) (xy 442.325219 -386.211616) (xy 442.354689 -386.165761)
			(xy 442.390386 -386.124568) (xy 442.431582 -386.088874) (xy 442.477439 -386.059407) (xy 442.527022 -386.036766)
			(xy 442.579324 -386.021412) (xy 442.633278 -386.013659) (xy 442.660532 -386.013198) (xy 442.687776 -386.013668)
			(xy 442.741709 -386.021429) (xy 442.793988 -386.036788) (xy 442.843549 -386.059433) (xy 442.889381 -386.088901)
			(xy 442.930552 -386.124594) (xy 442.966222 -386.165784) (xy 442.981334 -386.188458) (xy 442.986171 -386.195491)
			(xy 442.999584 -386.206035) (xy 443.015727 -386.211557) (xy 443.02426 -386.211826) (xy 443.055756 -386.211826)
			(xy 443.064277 -386.211518) (xy 443.080387 -386.205962) (xy 443.093797 -386.195446) (xy 443.098682 -386.188458)
			(xy 443.118748 -386.16001) (xy 443.124128 -386.152316) (xy 443.129482 -386.13434) (xy 443.129162 -386.124958)
			(xy 443.123066 -386.04698) (xy 443.114938 -386.029962) (xy 443.107826 -386.023358) (xy 443.089012 -386.005256)
			(xy 443.056035 -385.96478) (xy 443.028882 -385.920186) (xy 443.008061 -385.872308) (xy 442.993959 -385.822039)
			(xy 442.986841 -385.770317) (xy 442.986414 -385.744212) (xy 442.986867 -385.716958) (xy 442.994622 -385.663006)
			(xy 443.009978 -385.610707) (xy 443.032621 -385.561125) (xy 443.06209 -385.515271) (xy 443.097785 -385.474077)
			(xy 443.138979 -385.438384) (xy 443.184834 -385.408916) (xy 443.234416 -385.386275) (xy 443.286716 -385.37092)
			(xy 443.340668 -385.363166) (xy 443.367922 -385.362704) (xy 443.394158 -385.363146) (xy 443.446135 -385.370344)
			(xy 443.496634 -385.384602) (xy 443.5447 -385.405649) (xy 443.589427 -385.433089) (xy 443.629968 -385.466403)
			(xy 443.648084 -385.485386) (xy 443.648338 -385.48564) (xy 443.655697 -385.49277) (xy 443.674432 -385.501022)
			(xy 443.68466 -385.501642) (xy 443.758828 -385.502404) (xy 443.769297 -385.502008) (xy 443.788583 -385.493884)
			(xy 443.796166 -385.486656) (xy 443.814239 -385.468464) (xy 443.854381 -385.436556) (xy 443.898434 -385.41031)
			(xy 443.945606 -385.390201) (xy 443.995046 -385.37659) (xy 444.045863 -385.369723) (xy 444.071502 -385.369308)
			(xy 444.097485 -385.369722) (xy 444.148968 -385.376788) (xy 444.199017 -385.390774) (xy 444.246704 -385.411422)
			(xy 444.291149 -385.43835) (xy 444.331529 -385.471061) (xy 444.349632 -385.489704) (xy 444.357159 -385.496931)
			(xy 444.376294 -385.505198) (xy 444.386716 -385.505706) (xy 444.460884 -385.505706) (xy 444.471315 -385.505227)
			(xy 444.490468 -385.496968) (xy 444.497968 -385.489704) (xy 444.516083 -385.471073) (xy 444.556457 -385.438359)
			(xy 444.600899 -385.41143) (xy 444.648585 -385.390784) (xy 444.698633 -385.376803) (xy 444.750116 -385.369748)
			(xy 444.776098 -385.369308) (xy 444.803352 -385.369757) (xy 444.857304 -385.377514) (xy 444.909603 -385.392871)
			(xy 444.959184 -385.415514) (xy 445.005038 -385.444984) (xy 445.046231 -385.480679) (xy 445.081925 -385.521873)
			(xy 445.111392 -385.567728) (xy 445.134034 -385.61731) (xy 445.149389 -385.66961) (xy 445.157144 -385.723562)
			(xy 445.157606 -385.750816) (xy 445.157128 -385.77795) (xy 445.149441 -385.831671) (xy 445.134212 -385.883758)
			(xy 445.111748 -385.933158) (xy 445.082504 -385.978871) (xy 445.06515 -385.999736) (xy 445.059054 -386.006594)
			(xy 445.052704 -386.02412) (xy 445.053974 -386.110226) (xy 445.060578 -386.127498) (xy 445.066928 -386.134356)
			(xy 445.085435 -386.155533) (xy 445.116711 -386.202273) (xy 445.140793 -386.253095) (xy 445.157162 -386.3069)
			(xy 445.165462 -386.362523) (xy 445.165988 -386.390642) (xy 445.165412 -386.419767) (xy 445.156552 -386.477339)
			(xy 445.139044 -386.532895) (xy 445.113296 -386.585145) (xy 445.079906 -386.632874) (xy 445.039649 -386.674974)
			(xy 445.01689 -386.693156) (xy 445.007492 -386.700268) (xy 444.997078 -386.721604) (xy 444.997586 -386.814314)
			(xy 444.998244 -386.826057) (xy 445.008677 -386.847102) (xy 445.017652 -386.8547) (xy 445.040752 -386.872847)
			(xy 445.081617 -386.915042) (xy 445.115533 -386.963003) (xy 445.141697 -387.015595) (xy 445.159491 -387.071575)
			(xy 445.168495 -387.129622) (xy 445.169036 -387.158992) (xy 445.168581 -387.186363) (xy 445.160763 -387.240543)
			(xy 445.145272 -387.293047) (xy 445.122427 -387.342794) (xy 445.092699 -387.388759) (xy 445.075056 -387.40969)
			(xy 445.074802 -387.409944) (xy 445.069233 -387.417043) (xy 445.062976 -387.43395) (xy 445.06261 -387.442964)
			(xy 445.06261 -387.51002) (xy 445.062955 -387.519038) (xy 445.069211 -387.535955) (xy 445.074802 -387.54304)
			(xy 445.075056 -387.54304) (xy 445.075056 -387.543294) (xy 445.09269 -387.564233) (xy 445.122416 -387.610199)
			(xy 445.145263 -387.659944) (xy 445.16076 -387.712446) (xy 445.16859 -387.766624) (xy 445.168591 -387.821364)
			(xy 445.160763 -387.875543) (xy 445.145267 -387.928044) (xy 445.122422 -387.97779) (xy 445.092697 -388.023758)
			(xy 445.075056 -388.04469) (xy 445.074802 -388.044944) (xy 445.069233 -388.052043) (xy 445.062976 -388.06895)
			(xy 445.06261 -388.077964) (xy 445.06261 -388.14502) (xy 445.062955 -388.154038) (xy 445.069211 -388.170955)
			(xy 445.074802 -388.17804) (xy 445.075056 -388.17804) (xy 445.075056 -388.178294) (xy 445.092699 -388.199223)
			(xy 445.122412 -388.245196) (xy 445.145248 -388.294944) (xy 445.160738 -388.347446) (xy 445.168564 -388.401623)
			(xy 445.169036 -388.428992) (xy 445.168515 -388.456242) (xy 445.16076 -388.510187) (xy 445.145407 -388.562479)
			(xy 445.122769 -388.612055) (xy 445.093306 -388.657904) (xy 445.057619 -388.699093) (xy 445.016432 -388.734785)
			(xy 444.970586 -388.764252) (xy 444.921013 -388.786895) (xy 444.868722 -388.802253) (xy 444.814778 -388.810012)
			(xy 444.787528 -388.8105) (xy 444.761546 -388.810064) (xy 444.710064 -388.803002) (xy 444.660016 -388.78902)
			(xy 444.612328 -388.768376) (xy 444.567883 -388.741452) (xy 444.527502 -388.708746) (xy 444.509398 -388.690104)
			(xy 444.501859 -388.682891) (xy 444.482733 -388.674616) (xy 444.472314 -388.674102) (xy 444.398146 -388.674102)
			(xy 444.387711 -388.674541) (xy 444.368558 -388.682828) (xy 444.361062 -388.690104) (xy 444.342982 -388.70877)
			(xy 444.3026 -388.741481) (xy 444.258151 -388.768405) (xy 444.210458 -388.789045) (xy 444.160404 -388.803018)
			(xy 444.108916 -388.810065) (xy 444.082932 -388.8105) (xy 444.05568 -388.810015) (xy 444.001729 -388.802262)
			(xy 443.949431 -388.78691) (xy 443.899851 -388.76427) (xy 443.853997 -388.734805) (xy 443.812804 -388.699113)
			(xy 443.777109 -388.657922) (xy 443.747641 -388.612071) (xy 443.724999 -388.562491) (xy 443.709643 -388.510194)
			(xy 443.701887 -388.456244) (xy 443.701424 -388.428992) (xy 443.70188 -388.401621) (xy 443.709699 -388.347442)
			(xy 443.72519 -388.294938) (xy 443.748034 -388.245191) (xy 443.777762 -388.199225) (xy 443.795404 -388.178294)
			(xy 443.795658 -388.17804) (xy 443.801241 -388.170951) (xy 443.807488 -388.154036) (xy 443.80785 -388.14502)
			(xy 443.80785 -388.077964) (xy 443.807521 -388.068944) (xy 443.801255 -388.052027) (xy 443.795658 -388.044944)
			(xy 443.795404 -388.044944) (xy 443.795404 -388.04469) (xy 443.777747 -388.023772) (xy 443.748038 -387.977795)
			(xy 443.725205 -387.928044) (xy 443.709718 -387.875541) (xy 443.701895 -387.821362) (xy 443.701424 -387.793992)
			(xy 443.701952 -387.764514) (xy 443.711023 -387.70626) (xy 443.728948 -387.650095) (xy 443.7553 -387.597356)
			(xy 443.789452 -387.549299) (xy 443.809628 -387.5278) (xy 443.816159 -387.520463) (xy 443.823606 -387.502304)
			(xy 443.824106 -387.492494) (xy 443.824106 -387.439154) (xy 443.81039 -387.425946) (xy 443.801965 -387.418294)
			(xy 443.780613 -387.410506) (xy 443.769242 -387.41096) (xy 443.690502 -387.41858) (xy 443.67922 -387.420272)
			(xy 443.659697 -387.432016) (xy 443.65291 -387.441186) (xy 443.637716 -387.463474) (xy 443.602042 -387.503932)
			(xy 443.561022 -387.538959) (xy 443.515476 -387.567856) (xy 443.466313 -387.590047) (xy 443.414513 -387.605089)
			(xy 443.36111 -387.612682) (xy 443.33414 -387.613144) (xy 443.3054 -387.612645) (xy 443.248572 -387.604015)
			(xy 443.193682 -387.586958) (xy 443.141971 -387.561861) (xy 443.094609 -387.529292) (xy 443.073282 -387.51002)
			(xy 443.066424 -387.503416) (xy 443.04839 -387.496304) (xy 442.95949 -387.496304) (xy 442.941456 -387.503416)
			(xy 442.934598 -387.51002) (xy 442.913248 -387.529265) (xy 442.865893 -387.561836) (xy 442.814187 -387.586934)
			(xy 442.759301 -387.603991) (xy 442.702478 -387.61262) (xy 442.67374 -387.613144) (xy 442.64649 -387.612608)
			(xy 442.592543 -387.604857) (xy 442.540249 -387.589508) (xy 442.490671 -387.566873) (xy 442.44482 -387.537412)
			(xy 442.403628 -387.501726) (xy 442.367933 -387.460541) (xy 442.338464 -387.414695) (xy 442.315819 -387.365122)
			(xy 442.300459 -387.312831) (xy 442.292698 -387.258886) (xy 442.292232 -387.231636) (xy 442.292795 -387.203509)
			(xy 442.30105 -387.147864) (xy 442.317387 -387.094035) (xy 442.341452 -387.043188) (xy 442.372723 -386.996426)
			(xy 442.410521 -386.954764) (xy 442.454028 -386.919103) (xy 442.477906 -386.90423) (xy 442.48959 -386.897372)
			(xy 442.502798 -386.873496) (xy 442.50102 -386.75818) (xy 442.48705 -386.734812) (xy 442.475112 -386.728208)
			(xy 442.450014 -386.713677) (xy 442.404186 -386.678139) (xy 442.364263 -386.636074) (xy 442.331165 -386.588453)
			(xy 442.305654 -386.536372) (xy 442.288319 -386.481031) (xy 442.279557 -386.423703) (xy 442.279024 -386.394706)
			(xy 440.617864 -386.394706) (xy 440.617864 -388.094982) (xy 440.617425 -388.105045) (xy 440.609686 -388.123624)
			(xy 440.602878 -388.13105) (xy 440.262518 -388.47141) (xy 440.262518 -388.51332) (xy 440.277504 -388.528306)
			(xy 440.284065 -388.53556) (xy 440.291645 -388.553572) (xy 440.291977 -388.573111) (xy 440.288934 -388.582408)
			(xy 440.191398 -388.839964) (xy 440.183698 -388.861706) (xy 440.175398 -388.907074) (xy 440.174888 -388.930134)
			(xy 440.174888 -395.878304) (xy 440.174464 -395.888374) (xy 440.166747 -395.906976) (xy 440.159902 -395.914372)
			(xy 440.001914 -396.07236) (xy 439.996429 -396.07755) (xy 439.983118 -396.084667) (xy 439.975752 -396.08633)
			(xy 439.956448 -396.09014) (xy 439.945045 -396.092965) (xy 439.926378 -396.107184) (xy 439.915926 -396.128193)
			(xy 439.9153 -396.139924) (xy 439.9153 -397.835628) (xy 440.404248 -397.835628) (xy 440.408319 -397.780006)
			(xy 440.420445 -397.725569) (xy 440.440368 -397.673478) (xy 440.467664 -397.624843) (xy 440.50175 -397.5807)
			(xy 440.541899 -397.541991) (xy 440.587257 -397.50954) (xy 440.636857 -397.484039) (xy 440.689641 -397.466032)
			(xy 440.744484 -397.455902) (xy 440.800218 -397.453865) (xy 440.855655 -397.459965) (xy 440.909612 -397.474071)
			(xy 440.960941 -397.495883) (xy 441.008547 -397.524937) (xy 441.051415 -397.560612) (xy 441.088632 -397.602149)
			(xy 441.119405 -397.648662) (xy 441.143077 -397.699159) (xy 441.159145 -397.752566) (xy 441.167265 -397.807742)
			(xy 441.167774 -397.835628) (xy 441.167265 -397.863514) (xy 441.159145 -397.91869) (xy 441.143077 -397.972097)
			(xy 441.119405 -398.022594) (xy 441.088632 -398.069107) (xy 441.051415 -398.110644) (xy 441.008547 -398.146319)
			(xy 440.960941 -398.175373) (xy 440.909612 -398.197185) (xy 440.855655 -398.211291) (xy 440.800218 -398.217391)
			(xy 440.744484 -398.215354) (xy 440.689641 -398.205224) (xy 440.636857 -398.187217) (xy 440.587257 -398.161716)
			(xy 440.541899 -398.129265) (xy 440.50175 -398.090556) (xy 440.467664 -398.046413) (xy 440.440368 -397.997778)
			(xy 440.420445 -397.945687) (xy 440.408319 -397.89125) (xy 440.404248 -397.835628) (xy 439.9153 -397.835628)
			(xy 439.9153 -398.737328) (xy 440.397136 -398.737328) (xy 440.401207 -398.681706) (xy 440.413333 -398.627269)
			(xy 440.433256 -398.575178) (xy 440.460552 -398.526543) (xy 440.494638 -398.4824) (xy 440.534787 -398.443691)
			(xy 440.580145 -398.41124) (xy 440.629745 -398.385739) (xy 440.682529 -398.367732) (xy 440.737372 -398.357602)
			(xy 440.793106 -398.355565) (xy 440.848543 -398.361665) (xy 440.9025 -398.375771) (xy 440.953829 -398.397583)
			(xy 441.001435 -398.426637) (xy 441.044303 -398.462312) (xy 441.08152 -398.503849) (xy 441.112293 -398.550362)
			(xy 441.135965 -398.600859) (xy 441.152033 -398.654266) (xy 441.160153 -398.709442) (xy 441.160662 -398.737328)
			(xy 441.160153 -398.765214) (xy 441.152033 -398.82039) (xy 441.135965 -398.873797) (xy 441.112293 -398.924294)
			(xy 441.08152 -398.970807) (xy 441.044303 -399.012344) (xy 441.001435 -399.048019) (xy 440.953829 -399.077073)
			(xy 440.9025 -399.098885) (xy 440.848543 -399.112991) (xy 440.793106 -399.119091) (xy 440.737372 -399.117054)
			(xy 440.682529 -399.106924) (xy 440.629745 -399.088917) (xy 440.580145 -399.063416) (xy 440.534787 -399.030965)
			(xy 440.494638 -398.992256) (xy 440.460552 -398.948113) (xy 440.433256 -398.899478) (xy 440.413333 -398.847387)
			(xy 440.401207 -398.79295) (xy 440.397136 -398.737328) (xy 439.9153 -398.737328) (xy 439.9153 -401.44192)
			(xy 440.398408 -401.44192) (xy 440.398796 -401.415257) (xy 440.406233 -401.362451) (xy 440.42095 -401.311195)
			(xy 440.44266 -401.262488) (xy 440.470941 -401.217278) (xy 440.505242 -401.176447) (xy 440.544894 -401.14079)
			(xy 440.589125 -401.111001) (xy 440.637073 -401.087661) (xy 440.687804 -401.071226) (xy 440.740329 -401.062014)
			(xy 440.766962 -401.060666) (xy 440.776614 -401.060412) (xy 440.793886 -401.052792) (xy 441.39993 -400.446748)
			(xy 441.406746 -400.439329) (xy 441.414479 -400.420744) (xy 441.414916 -400.41068) (xy 441.414916 -397.008604)
			(xy 441.414511 -396.998532) (xy 441.406778 -396.979933) (xy 441.39993 -396.972536) (xy 440.583066 -396.155418)
			(xy 440.565841 -396.137311) (xy 440.538099 -396.095751) (xy 440.518993 -396.04958) (xy 440.509254 -396.00057)
			(xy 440.508644 -395.975586) (xy 440.508644 -389.225282) (xy 440.509265 -389.200299) (xy 440.519005 -389.151291)
			(xy 440.53811 -389.105122) (xy 440.565846 -389.063561) (xy 440.583066 -389.04545) (xy 441.453016 -388.1755)
			(xy 441.459851 -388.168096) (xy 441.467573 -388.1495) (xy 441.468002 -388.139432) (xy 441.468002 -388.139178)
			(xy 441.468393 -388.1119) (xy 441.476095 -388.057892) (xy 441.491411 -388.005532) (xy 441.514029 -387.955887)
			(xy 441.543487 -387.90997) (xy 441.579185 -387.868717) (xy 441.620395 -387.832968) (xy 441.666276 -387.803454)
			(xy 441.715893 -387.780775) (xy 441.768234 -387.765395) (xy 441.822233 -387.757626) (xy 441.84951 -387.757162)
			(xy 441.876772 -387.757686) (xy 441.93074 -387.765451) (xy 441.983053 -387.780819) (xy 442.032645 -387.803479)
			(xy 442.078505 -387.832969) (xy 442.1197 -387.868687) (xy 442.15539 -387.909907) (xy 442.184848 -387.955787)
			(xy 442.207473 -388.005395) (xy 442.222806 -388.057719) (xy 442.230532 -388.111692) (xy 442.230496 -388.166215)
			(xy 442.222697 -388.220179) (xy 442.207295 -388.272482) (xy 442.184604 -388.322059) (xy 442.155085 -388.367901)
			(xy 442.11934 -388.409073) (xy 442.078098 -388.444736) (xy 442.032198 -388.474165) (xy 441.982576 -388.496758)
			(xy 441.930243 -388.512057) (xy 441.876264 -388.51975) (xy 441.849002 -388.520178) (xy 441.848748 -388.520178)
			(xy 441.838679 -388.520608) (xy 441.82008 -388.528323) (xy 441.81268 -388.535164) (xy 441.032138 -389.315706)
			(xy 441.025308 -389.323114) (xy 441.017581 -389.341707) (xy 441.017152 -389.351774) (xy 441.017152 -395.849094)
			(xy 441.017567 -395.859165) (xy 441.025294 -395.877763) (xy 441.032138 -395.885162) (xy 441.849256 -396.70228)
			(xy 441.866488 -396.720397) (xy 441.894305 -396.761934) (xy 441.913485 -396.808098) (xy 441.923291 -396.857117)
			(xy 441.923932 -396.882112) (xy 441.923932 -397.962628) (xy 449.472048 -397.962628) (xy 449.476119 -397.907006)
			(xy 449.488245 -397.852569) (xy 449.508168 -397.800478) (xy 449.535464 -397.751843) (xy 449.56955 -397.7077)
			(xy 449.609699 -397.668991) (xy 449.655057 -397.63654) (xy 449.704657 -397.611039) (xy 449.757441 -397.593032)
			(xy 449.812284 -397.582902) (xy 449.868018 -397.580865) (xy 449.923455 -397.586965) (xy 449.977412 -397.601071)
			(xy 450.028741 -397.622883) (xy 450.076347 -397.651937) (xy 450.119215 -397.687612) (xy 450.156432 -397.729149)
			(xy 450.187205 -397.775662) (xy 450.210877 -397.826159) (xy 450.226945 -397.879566) (xy 450.235065 -397.934742)
			(xy 450.235574 -397.962628) (xy 450.235065 -397.990514) (xy 450.226945 -398.04569) (xy 450.210877 -398.099097)
			(xy 450.187205 -398.149594) (xy 450.156432 -398.196107) (xy 450.119215 -398.237644) (xy 450.076347 -398.273319)
			(xy 450.028741 -398.302373) (xy 449.977412 -398.324185) (xy 449.923455 -398.338291) (xy 449.868018 -398.344391)
			(xy 449.812284 -398.342354) (xy 449.757441 -398.332224) (xy 449.704657 -398.314217) (xy 449.655057 -398.288716)
			(xy 449.609699 -398.256265) (xy 449.56955 -398.217556) (xy 449.535464 -398.173413) (xy 449.508168 -398.124778)
			(xy 449.488245 -398.072687) (xy 449.476119 -398.01825) (xy 449.472048 -397.962628) (xy 441.923932 -397.962628)
			(xy 441.923932 -398.864328) (xy 449.475858 -398.864328) (xy 449.479929 -398.808706) (xy 449.492055 -398.754269)
			(xy 449.511978 -398.702178) (xy 449.539274 -398.653543) (xy 449.57336 -398.6094) (xy 449.613509 -398.570691)
			(xy 449.658867 -398.53824) (xy 449.708467 -398.512739) (xy 449.761251 -398.494732) (xy 449.816094 -398.484602)
			(xy 449.871828 -398.482565) (xy 449.927265 -398.488665) (xy 449.981222 -398.502771) (xy 450.032551 -398.524583)
			(xy 450.080157 -398.553637) (xy 450.123025 -398.589312) (xy 450.160242 -398.630849) (xy 450.191015 -398.677362)
			(xy 450.214687 -398.727859) (xy 450.230755 -398.781266) (xy 450.238875 -398.836442) (xy 450.239384 -398.864328)
			(xy 450.238875 -398.892214) (xy 450.230755 -398.94739) (xy 450.214687 -399.000797) (xy 450.191015 -399.051294)
			(xy 450.160242 -399.097807) (xy 450.123025 -399.139344) (xy 450.080157 -399.175019) (xy 450.032551 -399.204073)
			(xy 449.981222 -399.225885) (xy 449.927265 -399.239991) (xy 449.871828 -399.246091) (xy 449.816094 -399.244054)
			(xy 449.761251 -399.233924) (xy 449.708467 -399.215917) (xy 449.658867 -399.190416) (xy 449.613509 -399.157965)
			(xy 449.57336 -399.119256) (xy 449.539274 -399.075113) (xy 449.511978 -399.026478) (xy 449.492055 -398.974387)
			(xy 449.479929 -398.91995) (xy 449.475858 -398.864328) (xy 441.923932 -398.864328) (xy 441.923932 -399.2834)
			(xy 445.415396 -399.2834) (xy 445.419379 -399.230248) (xy 445.431241 -399.178283) (xy 445.450715 -399.128667)
			(xy 445.477367 -399.082508) (xy 445.510601 -399.040836) (xy 445.549675 -399.004584) (xy 445.593717 -398.974561)
			(xy 445.641741 -398.951438) (xy 445.692675 -398.935731) (xy 445.745381 -398.927791) (xy 445.772032 -398.92732)
			(xy 445.798392 -398.927815) (xy 445.850533 -398.9356) (xy 445.900956 -398.950994) (xy 445.948554 -398.973661)
			(xy 445.992286 -399.003103) (xy 446.012062 -399.020538) (xy 446.012316 -399.020792) (xy 446.019514 -399.026778)
			(xy 446.036996 -399.033434) (xy 446.046352 -399.033746) (xy 446.114932 -399.033746) (xy 446.124269 -399.033341)
			(xy 446.141722 -399.026695) (xy 446.148968 -399.020792) (xy 446.149476 -399.020284) (xy 446.169256 -399.002911)
			(xy 446.212965 -398.973568) (xy 446.260512 -398.95097) (xy 446.310866 -398.935608) (xy 446.36293 -398.927817)
			(xy 446.389252 -398.92732) (xy 446.415612 -398.927803) (xy 446.467754 -398.935591) (xy 446.518177 -398.950988)
			(xy 446.565775 -398.973657) (xy 446.609506 -399.003102) (xy 446.629282 -399.020538) (xy 446.629536 -399.020792)
			(xy 446.636727 -399.026786) (xy 446.654215 -399.033437) (xy 446.663572 -399.033746) (xy 446.732152 -399.033746)
			(xy 446.74149 -399.033351) (xy 446.758943 -399.026698) (xy 446.766188 -399.020792) (xy 446.766696 -399.020284)
			(xy 446.786468 -399.002901) (xy 446.830179 -398.97356) (xy 446.877728 -398.950963) (xy 446.928084 -398.935604)
			(xy 446.98015 -398.927816) (xy 447.006472 -398.92732) (xy 447.031468 -398.927745) (xy 447.080968 -398.93474)
			(xy 447.129005 -398.948582) (xy 447.174638 -398.968999) (xy 447.21697 -398.995592) (xy 447.236342 -399.011394)
			(xy 447.2432 -399.017236) (xy 447.260218 -399.023586) (xy 447.343784 -399.023586) (xy 447.360802 -399.017236)
			(xy 447.36766 -399.011394) (xy 447.387032 -398.995591) (xy 447.42936 -398.968989) (xy 447.474992 -398.948567)
			(xy 447.523031 -398.934727) (xy 447.572533 -398.92774) (xy 447.59753 -398.92732) (xy 447.624436 -398.927823)
			(xy 447.677639 -398.9359) (xy 447.72902 -398.951895) (xy 447.777406 -398.975444) (xy 447.821695 -399.00601)
			(xy 447.841624 -399.024094) (xy 447.848736 -399.030698) (xy 447.865754 -399.03781) (xy 447.95313 -399.039588)
			(xy 447.97091 -399.033238) (xy 447.978022 -399.026888) (xy 447.998965 -399.009317) (xy 448.044897 -398.979676)
			(xy 448.094591 -398.956895) (xy 448.147027 -398.941443) (xy 448.201133 -398.933634) (xy 448.228466 -398.933162)
			(xy 448.255718 -398.933683) (xy 448.309669 -398.941435) (xy 448.361966 -398.956787) (xy 448.411547 -398.979426)
			(xy 448.457401 -399.008891) (xy 448.498594 -399.044582) (xy 448.534289 -399.085772) (xy 448.563758 -399.131623)
			(xy 448.586401 -399.181202) (xy 448.601757 -399.233498) (xy 448.609515 -399.287448) (xy 448.609515 -399.341952)
			(xy 448.601757 -399.395902) (xy 448.586401 -399.448198) (xy 448.563758 -399.497777) (xy 448.534289 -399.543628)
			(xy 448.498594 -399.584818) (xy 448.457401 -399.620509) (xy 448.411547 -399.649974) (xy 448.361966 -399.672613)
			(xy 448.309669 -399.687965) (xy 448.255718 -399.695717) (xy 448.228466 -399.696178) (xy 448.202545 -399.69574)
			(xy 448.151182 -399.688705) (xy 448.101244 -399.674782) (xy 448.05365 -399.654229) (xy 448.009276 -399.627422)
			(xy 447.968939 -399.594855) (xy 447.950844 -399.57629) (xy 447.944137 -399.569696) (xy 447.927168 -399.561613)
			(xy 447.917824 -399.560542) (xy 447.850006 -399.555208) (xy 447.840622 -399.554868) (xy 447.822639 -399.560223)
			(xy 447.814954 -399.565622) (xy 447.791464 -399.582946) (xy 447.740035 -399.610538) (xy 447.684793 -399.629367)
			(xy 447.627219 -399.63893) (xy 447.598038 -399.639536) (xy 447.59753 -399.639536) (xy 447.572535 -399.639096)
			(xy 447.523036 -399.632103) (xy 447.474999 -399.618264) (xy 447.429367 -399.59785) (xy 447.387033 -399.571261)
			(xy 447.36766 -399.555462) (xy 447.360802 -399.54962) (xy 447.343784 -399.54327) (xy 447.260218 -399.54327)
			(xy 447.2432 -399.54962) (xy 447.236342 -399.555462) (xy 447.216976 -399.571273) (xy 447.174646 -399.597872)
			(xy 447.129012 -399.618291) (xy 447.080972 -399.63213) (xy 447.031469 -399.639116) (xy 447.006472 -399.639536)
			(xy 446.980113 -399.639024) (xy 446.927973 -399.631241) (xy 446.877551 -399.61585) (xy 446.829953 -399.593188)
			(xy 446.78622 -399.56375) (xy 446.766442 -399.546318) (xy 446.766188 -399.546064) (xy 446.758993 -399.540075)
			(xy 446.741508 -399.533422) (xy 446.732152 -399.53311) (xy 446.663572 -399.53311) (xy 446.654236 -399.533527)
			(xy 446.636784 -399.540166) (xy 446.629536 -399.546064) (xy 446.629028 -399.546572) (xy 446.609254 -399.563952)
			(xy 446.565543 -399.593292) (xy 446.517994 -399.615888) (xy 446.467639 -399.631248) (xy 446.415574 -399.639039)
			(xy 446.389252 -399.639536) (xy 446.362893 -399.639036) (xy 446.310752 -399.63125) (xy 446.26033 -399.615856)
			(xy 446.212732 -399.593191) (xy 446.168999 -399.563751) (xy 446.149222 -399.546318) (xy 446.148968 -399.546064)
			(xy 446.14178 -399.540066) (xy 446.12429 -399.533418) (xy 446.114932 -399.53311) (xy 446.046352 -399.53311)
			(xy 446.037015 -399.533517) (xy 446.019563 -399.540163) (xy 446.012316 -399.546064) (xy 446.011808 -399.546572)
			(xy 445.992042 -399.563962) (xy 445.948329 -399.593301) (xy 445.900777 -399.615894) (xy 445.850421 -399.631252)
			(xy 445.798355 -399.63904) (xy 445.772032 -399.639536) (xy 445.745381 -399.639009) (xy 445.692675 -399.631069)
			(xy 445.641741 -399.615362) (xy 445.593716 -399.592239) (xy 445.549675 -399.562216) (xy 445.510601 -399.525964)
			(xy 445.477367 -399.484292) (xy 445.450715 -399.438133) (xy 445.431241 -399.388517) (xy 445.419379 -399.336552)
			(xy 445.415396 -399.2834) (xy 441.923932 -399.2834) (xy 441.923932 -400.15287) (xy 447.338958 -400.15287)
			(xy 447.33945 -400.12562) (xy 447.34721 -400.071674) (xy 447.362567 -400.019381) (xy 447.385209 -399.969806)
			(xy 447.414675 -399.923958) (xy 447.450366 -399.882769) (xy 447.491554 -399.847078) (xy 447.537403 -399.817611)
			(xy 447.586978 -399.794968) (xy 447.63927 -399.77961) (xy 447.693216 -399.77185) (xy 447.720466 -399.771362)
			(xy 447.749383 -399.771881) (xy 447.806555 -399.780607) (xy 447.861755 -399.797863) (xy 447.913718 -399.823254)
			(xy 447.961251 -399.856199) (xy 448.003267 -399.895941) (xy 448.021456 -399.918428) (xy 448.029087 -399.92721)
			(xy 448.04997 -399.937406) (xy 448.061588 -399.937986) (xy 448.141344 -399.937986) (xy 448.152978 -399.937463)
			(xy 448.173887 -399.927263) (xy 448.181476 -399.918428) (xy 448.199688 -399.895962) (xy 448.241702 -399.856224)
			(xy 448.289233 -399.823282) (xy 448.34119 -399.797891) (xy 448.396384 -399.780631) (xy 448.453551 -399.771899)
			(xy 448.482466 -399.771362) (xy 448.509717 -399.771887) (xy 448.563664 -399.779638) (xy 448.615959 -399.794989)
			(xy 448.665537 -399.817625) (xy 448.711389 -399.847087) (xy 448.752581 -399.882774) (xy 448.788275 -399.92396)
			(xy 448.817744 -399.969807) (xy 448.840389 -400.019381) (xy 448.855748 -400.071674) (xy 448.863509 -400.125619)
			(xy 448.863974 -400.15287) (xy 448.863572 -400.17856) (xy 448.856669 -400.229474) (xy 448.842996 -400.279001)
			(xy 448.8228 -400.326246) (xy 448.796448 -400.370354) (xy 448.764416 -400.410526) (xy 448.727283 -400.446038)
			(xy 448.706748 -400.46148) (xy 448.695572 -400.469608) (xy 448.68465 -400.495008) (xy 448.698366 -400.610578)
			(xy 448.71513 -400.632676) (xy 448.728084 -400.637756) (xy 448.754033 -400.648907) (xy 448.802616 -400.677708)
			(xy 448.846423 -400.713356) (xy 448.884496 -400.755072) (xy 448.916005 -400.801944) (xy 448.94026 -400.852948)
			(xy 448.956732 -400.90697) (xy 448.965062 -400.962831) (xy 448.965574 -400.99107) (xy 448.965117 -401.018324)
			(xy 448.957363 -401.072277) (xy 448.953672 -401.084848) (xy 452.907696 -401.084848) (xy 452.907696 -401.030352)
			(xy 452.915451 -400.976411) (xy 452.930803 -400.924123) (xy 452.95344 -400.874551) (xy 452.9829 -400.828705)
			(xy 453.018585 -400.787518) (xy 453.059768 -400.751828) (xy 453.10561 -400.722362) (xy 453.155179 -400.699719)
			(xy 453.207466 -400.684361) (xy 453.261406 -400.676599) (xy 453.288654 -400.67611) (xy 453.314407 -400.676537)
			(xy 453.365442 -400.683484) (xy 453.415079 -400.697231) (xy 453.462417 -400.717528) (xy 453.506596 -400.744006)
			(xy 453.546812 -400.776185) (xy 453.582336 -400.813479) (xy 453.597772 -400.834098) (xy 453.603614 -400.842226)
			(xy 453.620378 -400.85264) (xy 453.71131 -400.867626) (xy 453.73036 -400.863308) (xy 453.738742 -400.857466)
			(xy 453.763002 -400.840983) (xy 453.815524 -400.814883) (xy 453.871423 -400.797134) (xy 453.929381 -400.788154)
			(xy 453.958706 -400.787616) (xy 453.985959 -400.788054) (xy 454.039909 -400.795812) (xy 454.092206 -400.811169)
			(xy 454.141786 -400.833811) (xy 454.187639 -400.86328) (xy 454.228831 -400.898974) (xy 454.264524 -400.940166)
			(xy 454.293991 -400.986019) (xy 454.316634 -401.035599) (xy 454.331989 -401.087897) (xy 454.339746 -401.141847)
			(xy 454.339746 -401.196353) (xy 454.331989 -401.250303) (xy 454.316634 -401.302601) (xy 454.293991 -401.352181)
			(xy 454.264524 -401.398034) (xy 454.228831 -401.439226) (xy 454.187639 -401.47492) (xy 454.141786 -401.504389)
			(xy 454.092206 -401.527031) (xy 454.039909 -401.542388) (xy 453.985959 -401.550146) (xy 453.958706 -401.550632)
			(xy 453.932954 -401.550184) (xy 453.881919 -401.543244) (xy 453.832281 -401.529503) (xy 453.784942 -401.50921)
			(xy 453.740763 -401.482734) (xy 453.700546 -401.450557) (xy 453.665023 -401.413263) (xy 453.649588 -401.392644)
			(xy 453.643746 -401.384516) (xy 453.626982 -401.374102) (xy 453.53605 -401.359116) (xy 453.517 -401.363434)
			(xy 453.508618 -401.369276) (xy 453.484365 -401.385769) (xy 453.431841 -401.411869) (xy 453.375939 -401.429615)
			(xy 453.317979 -401.438591) (xy 453.288654 -401.439126) (xy 453.261406 -401.438601) (xy 453.207466 -401.430839)
			(xy 453.155179 -401.415481) (xy 453.10561 -401.392838) (xy 453.059768 -401.363372) (xy 453.018585 -401.327682)
			(xy 452.9829 -401.286495) (xy 452.95344 -401.240649) (xy 452.930803 -401.191077) (xy 452.915451 -401.138789)
			(xy 452.907696 -401.084848) (xy 448.953672 -401.084848) (xy 448.942009 -401.124577) (xy 448.919367 -401.174159)
			(xy 448.889899 -401.220014) (xy 448.854205 -401.261208) (xy 448.813011 -401.296902) (xy 448.767155 -401.326369)
			(xy 448.717573 -401.34901) (xy 448.665273 -401.364364) (xy 448.61132 -401.372117) (xy 448.584066 -401.372578)
			(xy 448.55515 -401.372021) (xy 448.497981 -401.363301) (xy 448.442782 -401.346051) (xy 448.39082 -401.320667)
			(xy 448.343285 -401.28773) (xy 448.301267 -401.247995) (xy 448.283076 -401.225512) (xy 448.275468 -401.216706)
			(xy 448.254568 -401.206521) (xy 448.242944 -401.205954) (xy 448.163188 -401.205954) (xy 448.151554 -401.206482)
			(xy 448.130644 -401.216677) (xy 448.123056 -401.225512) (xy 448.104893 -401.248019) (xy 448.062867 -401.287752)
			(xy 448.015326 -401.320688) (xy 447.963359 -401.346072) (xy 447.908157 -401.363323) (xy 447.850984 -401.372046)
			(xy 447.822066 -401.372578) (xy 447.794813 -401.372154) (xy 447.740861 -401.364392) (xy 447.688563 -401.349031)
			(xy 447.638984 -401.326384) (xy 447.593132 -401.296911) (xy 447.551942 -401.261213) (xy 447.516251 -401.220016)
			(xy 447.486786 -401.17416) (xy 447.464147 -401.124577) (xy 447.448795 -401.072276) (xy 447.441042 -401.018324)
			(xy 447.440558 -400.99107) (xy 447.440976 -400.96538) (xy 447.447875 -400.914467) (xy 447.461545 -400.864939)
			(xy 447.481737 -400.817694) (xy 447.508086 -400.773586) (xy 447.540117 -400.733413) (xy 447.577249 -400.697902)
			(xy 447.597784 -400.68246) (xy 447.60896 -400.674332) (xy 447.619882 -400.648932) (xy 447.606166 -400.533362)
			(xy 447.589402 -400.511264) (xy 447.576448 -400.506184) (xy 447.550498 -400.495035) (xy 447.501919 -400.466229)
			(xy 447.458116 -400.430579) (xy 447.420045 -400.388863) (xy 447.388537 -400.341991) (xy 447.364281 -400.290988)
			(xy 447.347806 -400.236967) (xy 447.339473 -400.181108) (xy 447.338958 -400.15287) (xy 441.923932 -400.15287)
			(xy 441.923932 -400.537172) (xy 441.923292 -400.562168) (xy 441.913491 -400.611191) (xy 441.894319 -400.657362)
			(xy 441.866511 -400.698908) (xy 441.849256 -400.717004) (xy 441.415932 -401.150328) (xy 444.513714 -401.150328)
			(xy 444.517785 -401.094706) (xy 444.529911 -401.040269) (xy 444.549834 -400.988178) (xy 444.57713 -400.939543)
			(xy 444.611216 -400.8954) (xy 444.651365 -400.856691) (xy 444.696723 -400.82424) (xy 444.746323 -400.798739)
			(xy 444.799107 -400.780732) (xy 444.85395 -400.770602) (xy 444.909684 -400.768565) (xy 444.965121 -400.774665)
			(xy 445.019078 -400.788771) (xy 445.070407 -400.810583) (xy 445.118013 -400.839637) (xy 445.160881 -400.875312)
			(xy 445.198098 -400.916849) (xy 445.228871 -400.963362) (xy 445.252543 -401.013859) (xy 445.268611 -401.067266)
			(xy 445.276731 -401.122442) (xy 445.27724 -401.150328) (xy 445.276731 -401.178214) (xy 445.268611 -401.23339)
			(xy 445.252543 -401.286797) (xy 445.228871 -401.337294) (xy 445.198098 -401.383807) (xy 445.160881 -401.425344)
			(xy 445.118013 -401.461019) (xy 445.070407 -401.490073) (xy 445.019078 -401.511885) (xy 444.965121 -401.525991)
			(xy 444.909684 -401.532091) (xy 444.85395 -401.530054) (xy 444.799107 -401.519924) (xy 444.746323 -401.501917)
			(xy 444.696723 -401.476416) (xy 444.651365 -401.443965) (xy 444.611216 -401.405256) (xy 444.57713 -401.361113)
			(xy 444.549834 -401.312478) (xy 444.529911 -401.260387) (xy 444.517785 -401.20595) (xy 444.513714 -401.150328)
			(xy 441.415932 -401.150328) (xy 441.175902 -401.390358) (xy 441.16892 -401.398112) (xy 441.16131 -401.417517)
			(xy 441.16117 -401.42795) (xy 441.16117 -401.428204) (xy 441.161424 -401.44192) (xy 441.160938 -401.469171)
			(xy 441.153182 -401.523119) (xy 441.137827 -401.575414) (xy 441.115185 -401.624991) (xy 441.085719 -401.670841)
			(xy 441.050028 -401.712032) (xy 441.008837 -401.747723) (xy 440.962987 -401.777189) (xy 440.91341 -401.799831)
			(xy 440.861115 -401.815186) (xy 440.807167 -401.822942) (xy 440.752665 -401.822942) (xy 440.698717 -401.815186)
			(xy 440.646422 -401.799831) (xy 440.596845 -401.777189) (xy 440.550995 -401.747723) (xy 440.509804 -401.712032)
			(xy 440.474113 -401.670841) (xy 440.444647 -401.624991) (xy 440.422005 -401.575414) (xy 440.40665 -401.523119)
			(xy 440.398894 -401.469171) (xy 440.398408 -401.44192) (xy 439.9153 -401.44192) (xy 439.9153 -404.453344)
			(xy 439.914869 -404.463411) (xy 439.907143 -404.482003) (xy 439.900314 -404.489412) (xy 437.810148 -406.579578)
			(xy 437.803308 -406.586978) (xy 437.795595 -406.605577) (xy 437.795162 -406.615646) (xy 437.795162 -417.052506)
			(xy 438.669176 -417.052506) (xy 438.669176 -415.645346) (xy 438.669792 -415.615428) (xy 438.679154 -415.55633)
			(xy 438.69764 -415.499421) (xy 438.724794 -415.446102) (xy 438.75995 -415.397684) (xy 438.780682 -415.376106)
			(xy 439.036714 -415.120074) (xy 439.04356 -415.112679) (xy 439.051276 -415.094076) (xy 439.0517 -415.084006)
			(xy 439.0517 -408.034744) (xy 439.052335 -408.004769) (xy 439.061717 -407.945556) (xy 439.080242 -407.888539)
			(xy 439.107455 -407.83512) (xy 439.142685 -407.786612) (xy 439.16346 -407.764996) (xy 439.450988 -407.477722)
			(xy 439.457221 -407.470953) (xy 439.464778 -407.454187) (xy 439.465977 -407.435836) (xy 439.463688 -407.426922)
			(xy 439.437272 -407.34107) (xy 439.434258 -407.332372) (xy 439.423027 -407.317802) (xy 439.407367 -407.308149)
			(xy 439.39841 -407.306018) (xy 439.372673 -407.300559) (xy 439.322896 -407.283524) (xy 439.275934 -407.259808)
			(xy 439.232678 -407.22986) (xy 439.19395 -407.19425) (xy 439.160485 -407.153654) (xy 439.13292 -407.108842)
			(xy 439.111777 -407.060666) (xy 439.097459 -407.010041) (xy 439.090236 -406.957928) (xy 439.0898 -406.931622)
			(xy 439.090276 -406.904369) (xy 439.09803 -406.850418) (xy 439.113384 -406.79812) (xy 439.136024 -406.74854)
			(xy 439.165491 -406.702686) (xy 439.201183 -406.661493) (xy 439.242375 -406.625799) (xy 439.288227 -406.596331)
			(xy 439.337807 -406.573689) (xy 439.390105 -406.558333) (xy 439.444055 -406.550577) (xy 439.471308 -406.550114)
			(xy 439.497612 -406.550509) (xy 439.549717 -406.557763) (xy 439.600332 -406.572105) (xy 439.648497 -406.593263)
			(xy 439.6933 -406.620836) (xy 439.733892 -406.654301) (xy 439.769502 -406.693025) (xy 439.799456 -406.736272)
			(xy 439.823186 -406.783224) (xy 439.840242 -406.83299) (xy 439.845704 -406.858724) (xy 439.847816 -406.867682)
			(xy 439.857491 -406.883324) (xy 439.87207 -406.894539) (xy 439.880756 -406.897586) (xy 439.966608 -406.924002)
			(xy 439.975524 -406.926325) (xy 439.993894 -406.92518) (xy 440.01065 -406.917562) (xy 440.017408 -406.911302)
			(xy 441.444634 -405.484076) (xy 441.451482 -405.476682) (xy 441.459196 -405.458078) (xy 441.45962 -405.448008)
			(xy 441.45962 -403.374098) (xy 441.459217 -403.364026) (xy 441.451483 -403.345427) (xy 441.444634 -403.33803)
			(xy 440.795918 -402.689568) (xy 440.775198 -402.667981) (xy 440.740058 -402.619554) (xy 440.712907 -402.566237)
			(xy 440.69441 -402.509335) (xy 440.68502 -402.450244) (xy 440.684412 -402.420328) (xy 440.684412 -402.41982)
			(xy 440.684896 -402.39258) (xy 440.692644 -402.338653) (xy 440.707985 -402.286378) (xy 440.730606 -402.236816)
			(xy 440.760049 -402.190977) (xy 440.795713 -402.149793) (xy 440.836873 -402.114101) (xy 440.882693 -402.084628)
			(xy 440.93224 -402.061973) (xy 440.984505 -402.046598) (xy 441.038426 -402.038814) (xy 441.065666 -402.038312)
			(xy 441.095642 -402.038937) (xy 441.154855 -402.048321) (xy 441.211872 -402.066849) (xy 441.265291 -402.094063)
			(xy 441.313798 -402.129296) (xy 441.335414 -402.150072) (xy 441.363354 -402.178012) (xy 443.299848 -402.178012)
			(xy 443.303919 -402.12239) (xy 443.316045 -402.067953) (xy 443.335968 -402.015862) (xy 443.363264 -401.967227)
			(xy 443.39735 -401.923084) (xy 443.437499 -401.884375) (xy 443.482857 -401.851924) (xy 443.532457 -401.826423)
			(xy 443.585241 -401.808416) (xy 443.640084 -401.798286) (xy 443.695818 -401.796249) (xy 443.751255 -401.802349)
			(xy 443.805212 -401.816455) (xy 443.856541 -401.838267) (xy 443.904147 -401.867321) (xy 443.947015 -401.902996)
			(xy 443.984232 -401.944533) (xy 444.015005 -401.991046) (xy 444.038677 -402.041543) (xy 444.054745 -402.09495)
			(xy 444.062865 -402.150126) (xy 444.063374 -402.178012) (xy 444.06291 -402.203412) (xy 445.01003 -402.203412)
			(xy 445.014101 -402.14779) (xy 445.026227 -402.093353) (xy 445.04615 -402.041262) (xy 445.073446 -401.992627)
			(xy 445.107532 -401.948484) (xy 445.147681 -401.909775) (xy 445.193039 -401.877324) (xy 445.242639 -401.851823)
			(xy 445.295423 -401.833816) (xy 445.350266 -401.823686) (xy 445.406 -401.821649) (xy 445.461437 -401.827749)
			(xy 445.515394 -401.841855) (xy 445.566723 -401.863667) (xy 445.582363 -401.873212) (xy 451.885048 -401.873212)
			(xy 451.889119 -401.81759) (xy 451.901245 -401.763153) (xy 451.921168 -401.711062) (xy 451.948464 -401.662427)
			(xy 451.98255 -401.618284) (xy 452.022699 -401.579575) (xy 452.068057 -401.547124) (xy 452.117657 -401.521623)
			(xy 452.170441 -401.503616) (xy 452.225284 -401.493486) (xy 452.281018 -401.491449) (xy 452.336455 -401.497549)
			(xy 452.390412 -401.511655) (xy 452.441741 -401.533467) (xy 452.489347 -401.562521) (xy 452.532215 -401.598196)
			(xy 452.569432 -401.639733) (xy 452.600205 -401.686246) (xy 452.623877 -401.736743) (xy 452.639945 -401.79015)
			(xy 452.648065 -401.845326) (xy 452.648574 -401.873212) (xy 452.648065 -401.901098) (xy 452.639945 -401.956274)
			(xy 452.623877 -402.009681) (xy 452.600205 -402.060178) (xy 452.569432 -402.106691) (xy 452.532215 -402.148228)
			(xy 452.526947 -402.152612) (xy 454.098658 -402.152612) (xy 454.102729 -402.09699) (xy 454.114855 -402.042553)
			(xy 454.134778 -401.990462) (xy 454.162074 -401.941827) (xy 454.19616 -401.897684) (xy 454.236309 -401.858975)
			(xy 454.281667 -401.826524) (xy 454.331267 -401.801023) (xy 454.384051 -401.783016) (xy 454.438894 -401.772886)
			(xy 454.494628 -401.770849) (xy 454.550065 -401.776949) (xy 454.604022 -401.791055) (xy 454.655351 -401.812867)
			(xy 454.702957 -401.841921) (xy 454.745825 -401.877596) (xy 454.783042 -401.919133) (xy 454.813815 -401.965646)
			(xy 454.837487 -402.016143) (xy 454.853555 -402.06955) (xy 454.861675 -402.124726) (xy 454.862184 -402.152612)
			(xy 454.861675 -402.180498) (xy 454.853555 -402.235674) (xy 454.837487 -402.289081) (xy 454.813815 -402.339578)
			(xy 454.783042 -402.386091) (xy 454.745825 -402.427628) (xy 454.702957 -402.463303) (xy 454.655351 -402.492357)
			(xy 454.604022 -402.514169) (xy 454.550065 -402.528275) (xy 454.494628 -402.534375) (xy 454.438894 -402.532338)
			(xy 454.384051 -402.522208) (xy 454.331267 -402.504201) (xy 454.281667 -402.4787) (xy 454.236309 -402.446249)
			(xy 454.19616 -402.40754) (xy 454.162074 -402.363397) (xy 454.134778 -402.314762) (xy 454.114855 -402.262671)
			(xy 454.102729 -402.208234) (xy 454.098658 -402.152612) (xy 452.526947 -402.152612) (xy 452.489347 -402.183903)
			(xy 452.441741 -402.212957) (xy 452.390412 -402.234769) (xy 452.336455 -402.248875) (xy 452.281018 -402.254975)
			(xy 452.225284 -402.252938) (xy 452.170441 -402.242808) (xy 452.117657 -402.224801) (xy 452.068057 -402.1993)
			(xy 452.022699 -402.166849) (xy 451.98255 -402.12814) (xy 451.948464 -402.083997) (xy 451.921168 -402.035362)
			(xy 451.901245 -401.983271) (xy 451.889119 -401.928834) (xy 451.885048 -401.873212) (xy 445.582363 -401.873212)
			(xy 445.614329 -401.892721) (xy 445.657197 -401.928396) (xy 445.694414 -401.969933) (xy 445.725187 -402.016446)
			(xy 445.748859 -402.066943) (xy 445.764927 -402.12035) (xy 445.773047 -402.175526) (xy 445.773556 -402.203412)
			(xy 445.773047 -402.231298) (xy 445.764927 -402.286474) (xy 445.748859 -402.339881) (xy 445.725187 -402.390378)
			(xy 445.694414 -402.436891) (xy 445.657197 -402.478428) (xy 445.614329 -402.514103) (xy 445.566723 -402.543157)
			(xy 445.515394 -402.564969) (xy 445.461437 -402.579075) (xy 445.406 -402.585175) (xy 445.350266 -402.583138)
			(xy 445.295423 -402.573008) (xy 445.242639 -402.555001) (xy 445.193039 -402.5295) (xy 445.147681 -402.497049)
			(xy 445.107532 -402.45834) (xy 445.073446 -402.414197) (xy 445.04615 -402.365562) (xy 445.026227 -402.313471)
			(xy 445.014101 -402.259034) (xy 445.01003 -402.203412) (xy 444.06291 -402.203412) (xy 444.062865 -402.205898)
			(xy 444.054745 -402.261074) (xy 444.038677 -402.314481) (xy 444.015005 -402.364978) (xy 443.984232 -402.411491)
			(xy 443.947015 -402.453028) (xy 443.904147 -402.488703) (xy 443.856541 -402.517757) (xy 443.805212 -402.539569)
			(xy 443.751255 -402.553675) (xy 443.695818 -402.559775) (xy 443.640084 -402.557738) (xy 443.585241 -402.547608)
			(xy 443.532457 -402.529601) (xy 443.482857 -402.5041) (xy 443.437499 -402.471649) (xy 443.39735 -402.43294)
			(xy 443.363264 -402.388797) (xy 443.335968 -402.340162) (xy 443.316045 -402.288071) (xy 443.303919 -402.233634)
			(xy 443.299848 -402.178012) (xy 441.363354 -402.178012) (xy 442.110622 -402.92528) (xy 442.131354 -402.946856)
			(xy 442.166495 -402.995284) (xy 442.193645 -403.048604) (xy 442.212139 -403.105509) (xy 442.221523 -403.164603)
			(xy 442.222128 -403.19452) (xy 442.222128 -404.091902) (xy 442.239146 -404.117556) (xy 442.253624 -404.123398)
			(xy 442.26302 -404.126728) (xy 442.282931 -404.126737) (xy 442.301341 -404.119152) (xy 442.308742 -404.112476)
			(xy 443.107572 -403.3139) (xy 443.1144 -403.306491) (xy 443.122128 -403.287899) (xy 443.122558 -403.277832)
			(xy 443.122558 -403.277578) (xy 443.122992 -403.250302) (xy 443.130694 -403.196298) (xy 443.146008 -403.143942)
			(xy 443.168623 -403.0943) (xy 443.198077 -403.048385) (xy 443.23377 -403.007132) (xy 443.274974 -402.971384)
			(xy 443.32085 -402.941868) (xy 443.370461 -402.919187) (xy 443.422797 -402.903803) (xy 443.476791 -402.896029)
			(xy 443.504066 -402.895562) (xy 443.53133 -402.896083) (xy 443.585303 -402.903842) (xy 443.637621 -402.919207)
			(xy 443.687218 -402.941864) (xy 443.733084 -402.971353) (xy 443.774284 -403.007071) (xy 443.809979 -403.048292)
			(xy 443.839441 -403.094175) (xy 443.86207 -403.143786) (xy 443.877404 -403.196113) (xy 443.885132 -403.25009)
			(xy 443.885096 -403.304618) (xy 443.877296 -403.358584) (xy 443.861892 -403.410891) (xy 443.839197 -403.460471)
			(xy 443.809674 -403.506315) (xy 443.773925 -403.547488) (xy 443.732677 -403.583152) (xy 443.686772 -403.612579)
			(xy 443.637144 -403.63517) (xy 443.584806 -403.650465) (xy 443.530822 -403.658153) (xy 443.503558 -403.658578)
			(xy 443.503304 -403.658578) (xy 443.493232 -403.658985) (xy 443.474633 -403.666716) (xy 443.467236 -403.673564)
			(xy 442.624718 -404.516336) (xy 442.617872 -404.523732) (xy 442.610155 -404.542334) (xy 442.609732 -404.552404)
			(xy 442.609732 -405.892508) (xy 442.609114 -405.917505) (xy 442.599306 -405.966529) (xy 442.580127 -406.0127)
			(xy 442.552314 -406.054245) (xy 442.535056 -406.07234) (xy 442.39815 -406.209246) (xy 448.698112 -406.209246)
			(xy 448.698678 -406.179635) (xy 448.707823 -406.121123) (xy 448.7259 -406.064727) (xy 448.752476 -406.011803)
			(xy 448.786911 -405.963621) (xy 448.828378 -405.92134) (xy 448.875882 -405.885974) (xy 448.90182 -405.87168)
			(xy 448.913621 -405.865041) (xy 448.933432 -405.846593) (xy 448.947695 -405.823585) (xy 448.955406 -405.797636)
			(xy 448.956023 -405.770573) (xy 448.949502 -405.7443) (xy 448.936302 -405.720666) (xy 448.917353 -405.701334)
			(xy 448.905884 -405.694134) (xy 448.881637 -405.679373) (xy 448.837444 -405.643748) (xy 448.799017 -405.601968)
			(xy 448.767207 -405.554953) (xy 448.742716 -405.503744) (xy 448.726084 -405.449471) (xy 448.717679 -405.393332)
			(xy 448.717162 -405.36495) (xy 448.717648 -405.337699) (xy 448.725404 -405.283751) (xy 448.740759 -405.231456)
			(xy 448.763401 -405.181879) (xy 448.792867 -405.136029) (xy 448.828558 -405.094838) (xy 448.869749 -405.059147)
			(xy 448.915599 -405.029681) (xy 448.965176 -405.007039) (xy 449.017471 -404.991684) (xy 449.071419 -404.983928)
			(xy 449.125921 -404.983928) (xy 449.179869 -404.991684) (xy 449.232164 -405.007039) (xy 449.281741 -405.029681)
			(xy 449.327591 -405.059147) (xy 449.368782 -405.094838) (xy 449.404473 -405.136029) (xy 449.433939 -405.181879)
			(xy 449.456581 -405.231456) (xy 449.471936 -405.283751) (xy 449.479692 -405.337699) (xy 449.480178 -405.36495)
			(xy 449.479614 -405.394561) (xy 449.47047 -405.453073) (xy 449.452392 -405.509469) (xy 449.425817 -405.562394)
			(xy 449.391381 -405.610576) (xy 449.349913 -405.652857) (xy 449.302409 -405.688222) (xy 449.27647 -405.702516)
			(xy 449.264673 -405.709161) (xy 449.244864 -405.727609) (xy 449.230603 -405.750616) (xy 449.222893 -405.776563)
			(xy 449.222275 -405.803624) (xy 449.228795 -405.829896) (xy 449.241992 -405.853529) (xy 449.260939 -405.872861)
			(xy 449.272406 -405.880062) (xy 449.296649 -405.894829) (xy 449.340843 -405.930453) (xy 449.37927 -405.972232)
			(xy 449.41108 -406.019245) (xy 449.435572 -406.070453) (xy 449.452205 -406.124726) (xy 449.46061 -406.180864)
			(xy 449.461128 -406.209246) (xy 449.460642 -406.236497) (xy 449.452886 -406.290445) (xy 449.437531 -406.34274)
			(xy 449.414889 -406.392317) (xy 449.385423 -406.438167) (xy 449.349732 -406.479358) (xy 449.308541 -406.515049)
			(xy 449.262691 -406.544515) (xy 449.213114 -406.567157) (xy 449.160819 -406.582512) (xy 449.106871 -406.590268)
			(xy 449.052369 -406.590268) (xy 448.998421 -406.582512) (xy 448.946126 -406.567157) (xy 448.896549 -406.544515)
			(xy 448.850699 -406.515049) (xy 448.809508 -406.479358) (xy 448.773817 -406.438167) (xy 448.744351 -406.392317)
			(xy 448.721709 -406.34274) (xy 448.706354 -406.290445) (xy 448.698598 -406.236497) (xy 448.698112 -406.209246)
			(xy 442.39815 -406.209246) (xy 441.40755 -407.199846) (xy 448.698112 -407.199846) (xy 448.698598 -407.172595)
			(xy 448.706354 -407.118647) (xy 448.721709 -407.066352) (xy 448.744351 -407.016775) (xy 448.773817 -406.970925)
			(xy 448.809508 -406.929734) (xy 448.850699 -406.894043) (xy 448.896549 -406.864577) (xy 448.946126 -406.841935)
			(xy 448.998421 -406.82658) (xy 449.052369 -406.818824) (xy 449.106871 -406.818824) (xy 449.160819 -406.82658)
			(xy 449.213114 -406.841935) (xy 449.262691 -406.864577) (xy 449.308541 -406.894043) (xy 449.349732 -406.929734)
			(xy 449.385423 -406.970925) (xy 449.414889 -407.016775) (xy 449.437531 -407.066352) (xy 449.452886 -407.118647)
			(xy 449.460642 -407.172595) (xy 449.461128 -407.199846) (xy 449.460563 -407.228837) (xy 449.451777 -407.286151)
			(xy 449.434427 -407.341477) (xy 449.408913 -407.393546) (xy 449.375822 -407.441159) (xy 449.335914 -407.483223)
			(xy 449.290106 -407.51877) (xy 449.26504 -407.533348) (xy 449.25296 -407.540612) (xy 449.233005 -407.560503)
			(xy 449.219245 -407.585089) (xy 449.212726 -407.6125) (xy 449.213945 -407.640649) (xy 449.222808 -407.667394)
			(xy 449.238641 -407.690699) (xy 449.260239 -407.708792) (xy 449.272914 -407.714958) (xy 449.29783 -407.726553)
			(xy 449.344309 -407.755877) (xy 449.386098 -407.791567) (xy 449.422332 -407.832886) (xy 449.452262 -407.878977)
			(xy 449.475267 -407.928886) (xy 449.490871 -407.98158) (xy 449.498752 -408.035968) (xy 449.499228 -408.063446)
			(xy 449.498742 -408.090697) (xy 449.490986 -408.144645) (xy 449.475631 -408.19694) (xy 449.452989 -408.246517)
			(xy 449.423523 -408.292367) (xy 449.387832 -408.333558) (xy 449.346641 -408.369249) (xy 449.300791 -408.398715)
			(xy 449.251214 -408.421357) (xy 449.198919 -408.436712) (xy 449.144971 -408.444468) (xy 449.090469 -408.444468)
			(xy 449.036521 -408.436712) (xy 448.984226 -408.421357) (xy 448.934649 -408.398715) (xy 448.888799 -408.369249)
			(xy 448.847608 -408.333558) (xy 448.811917 -408.292367) (xy 448.782451 -408.246517) (xy 448.759809 -408.19694)
			(xy 448.744454 -408.144645) (xy 448.736698 -408.090697) (xy 448.736212 -408.063446) (xy 448.73675 -408.034453)
			(xy 448.745539 -407.977138) (xy 448.762892 -407.92181) (xy 448.788409 -407.869741) (xy 448.821505 -407.822128)
			(xy 448.861418 -407.780065) (xy 448.907232 -407.74452) (xy 448.9323 -407.729944) (xy 448.944382 -407.722687)
			(xy 448.964329 -407.702791) (xy 448.978083 -407.678204) (xy 448.984598 -407.650795) (xy 448.983379 -407.622649)
			(xy 448.974518 -407.595905) (xy 448.95869 -407.5726) (xy 448.937098 -407.554503) (xy 448.924426 -407.548334)
			(xy 448.899516 -407.536726) (xy 448.853036 -407.507406) (xy 448.811245 -407.471718) (xy 448.775009 -407.430402)
			(xy 448.745078 -407.384313) (xy 448.722072 -407.334405) (xy 448.706468 -407.281711) (xy 448.698588 -407.227324)
			(xy 448.698112 -407.199846) (xy 441.40755 -407.199846) (xy 440.216798 -408.390598) (xy 440.209966 -408.398004)
			(xy 440.202242 -408.416599) (xy 440.201812 -408.426666) (xy 440.201812 -415.552636) (xy 440.201215 -415.57762)
			(xy 440.191469 -415.62663) (xy 440.172358 -415.6728) (xy 440.144614 -415.714359) (xy 440.12739 -415.732468)
			(xy 439.843418 -416.016694) (xy 439.83659 -416.024104) (xy 439.828863 -416.042696) (xy 439.828432 -416.052762)
			(xy 439.828432 -416.72256) (xy 439.828788 -416.732607) (xy 439.836386 -416.751203) (xy 439.843164 -416.758628)
			(xy 440.011566 -416.92703) (xy 440.03468 -416.934396) (xy 440.046872 -416.932364) (xy 440.058789 -416.929728)
			(xy 440.07829 -416.915101) (xy 440.08421 -416.904424) (xy 440.111134 -416.849306) (xy 440.11482 -416.842347)
			(xy 440.125696 -416.83097) (xy 440.13247 -416.826954) (xy 440.139074 -416.823398) (xy 440.154822 -416.82035)
			(xy 440.162696 -416.821366) (xy 440.173639 -416.822619) (xy 440.195624 -416.824015) (xy 440.206638 -416.82416)
			(xy 440.216798 -416.82416) (xy 440.225434 -416.827716) (xy 440.229929 -416.829661) (xy 440.238114 -416.835037)
			(xy 440.24169 -416.838384) (xy 440.29249 -416.887914) (xy 440.295969 -416.891535) (xy 440.3016 -416.899847)
			(xy 440.303666 -416.904424) (xy 440.307222 -416.912806) (xy 440.307476 -416.922966) (xy 440.308671 -416.949727)
			(xy 440.317615 -417.002542) (xy 440.333858 -417.053587) (xy 440.357081 -417.101858) (xy 440.386828 -417.146407)
			(xy 440.422512 -417.186358) (xy 440.463434 -417.220924) (xy 440.508788 -417.249427) (xy 440.557683 -417.271307)
			(xy 440.609158 -417.286133) (xy 440.6622 -417.293613) (xy 440.688984 -417.29406) (xy 440.720845 -417.293385)
			(xy 440.783672 -417.282731) (xy 440.843865 -417.261814) (xy 440.872118 -417.24707) (xy 440.884056 -417.24072)
			(xy 440.896756 -417.24072) (xy 440.903452 -417.241048) (xy 440.916325 -417.244778) (xy 440.922156 -417.248086)
			(xy 440.957716 -417.268914) (xy 440.984894 -417.269168) (xy 440.996578 -417.262564) (xy 441.004158 -417.257791)
			(xy 441.015712 -417.244121) (xy 441.021876 -417.227317) (xy 441.022232 -417.218368) (xy 441.022232 -409.466288)
			(xy 441.022822 -409.436311) (xy 441.032214 -409.377096) (xy 441.050749 -409.320078) (xy 441.077972 -409.266659)
			(xy 441.113212 -409.218154) (xy 441.133992 -409.19654) (xy 441.503308 -408.827224) (xy 441.524887 -408.806402)
			(xy 441.573394 -408.77115) (xy 441.62682 -408.743923) (xy 441.683848 -408.725394) (xy 441.743074 -408.716018)
			(xy 441.773056 -408.715464) (xy 449.907152 -408.715464) (xy 449.91722 -408.715023) (xy 449.935818 -408.707314)
			(xy 449.94322 -408.700478) (xy 450.779642 -407.864056) (xy 450.7865 -407.85667) (xy 450.794208 -407.83806)
			(xy 450.794628 -407.827988) (xy 450.794628 -402.977858) (xy 450.794127 -402.967955) (xy 450.786546 -402.949654)
			(xy 450.779896 -402.942298) (xy 450.759443 -402.92073) (xy 450.724789 -402.872442) (xy 450.698051 -402.81936)
			(xy 450.679877 -402.762771) (xy 450.670708 -402.704047) (xy 450.670168 -402.674328) (xy 450.670681 -402.647077)
			(xy 450.678434 -402.593129) (xy 450.693785 -402.540834) (xy 450.716423 -402.491255) (xy 450.745885 -402.445403)
			(xy 450.781574 -402.404211) (xy 450.822761 -402.368517) (xy 450.868609 -402.339048) (xy 450.918185 -402.316403)
			(xy 450.970478 -402.301045) (xy 451.024425 -402.293285) (xy 451.051676 -402.29282) (xy 451.081652 -402.293437)
			(xy 451.140866 -402.302823) (xy 451.197883 -402.321352) (xy 451.251302 -402.348568) (xy 451.299809 -402.383803)
			(xy 451.321424 -402.40458) (xy 451.362826 -402.446236) (xy 451.370795 -402.453625) (xy 451.391075 -402.461383)
			(xy 451.401942 -402.461222) (xy 451.488556 -402.456142) (xy 451.50786 -402.445982) (xy 451.514464 -402.4376)
			(xy 451.532651 -402.415424) (xy 451.574577 -402.376291) (xy 451.621886 -402.343871) (xy 451.673512 -402.318893)
			(xy 451.728295 -402.301922) (xy 451.785 -402.293337) (xy 451.813676 -402.29282) (xy 451.84093 -402.293278)
			(xy 451.894882 -402.301032) (xy 451.947182 -402.316387) (xy 451.996764 -402.339028) (xy 452.042618 -402.368496)
			(xy 452.083812 -402.404191) (xy 452.119506 -402.445385) (xy 452.148974 -402.49124) (xy 452.171615 -402.540822)
			(xy 452.186969 -402.593122) (xy 452.194723 -402.647074) (xy 452.195184 -402.674328) (xy 452.194767 -402.701195)
			(xy 452.187223 -402.754398) (xy 452.172289 -402.806016) (xy 452.15026 -402.855027) (xy 452.121572 -402.900463)
			(xy 452.086793 -402.941424) (xy 452.04661 -402.9771) (xy 452.001819 -403.006785) (xy 451.97776 -403.018752)
			(xy 451.964298 -403.025102) (xy 451.948804 -403.04974) (xy 451.948804 -406.351994) (xy 456.067414 -406.351994)
			(xy 456.067927 -406.323785) (xy 456.076229 -406.267981) (xy 456.092666 -406.214011) (xy 456.116878 -406.163053)
			(xy 456.148338 -406.11622) (xy 456.186356 -406.074536) (xy 456.230104 -406.038912) (xy 456.254104 -406.02408)
			(xy 456.266496 -406.016145) (xy 456.286401 -405.994487) (xy 456.299322 -405.968061) (xy 456.30419 -405.939051)
			(xy 456.300602 -405.909854) (xy 456.288857 -405.882886) (xy 456.269923 -405.860373) (xy 456.257914 -405.851868)
			(xy 456.235704 -405.836632) (xy 456.195365 -405.800945) (xy 456.160445 -405.759942) (xy 456.131636 -405.714436)
			(xy 456.109511 -405.665331) (xy 456.09451 -405.613604) (xy 456.08693 -405.560281) (xy 456.086464 -405.533352)
			(xy 456.08695 -405.506101) (xy 456.094706 -405.452153) (xy 456.110061 -405.399858) (xy 456.132703 -405.350281)
			(xy 456.162169 -405.304431) (xy 456.19786 -405.26324) (xy 456.239051 -405.227549) (xy 456.284901 -405.198083)
			(xy 456.334478 -405.175441) (xy 456.386773 -405.160086) (xy 456.440721 -405.15233) (xy 456.495223 -405.15233)
			(xy 456.549171 -405.160086) (xy 456.601466 -405.175441) (xy 456.651043 -405.198083) (xy 456.696893 -405.227549)
			(xy 456.738084 -405.26324) (xy 456.773775 -405.304431) (xy 456.803241 -405.350281) (xy 456.825883 -405.399858)
			(xy 456.841238 -405.452153) (xy 456.848994 -405.506101) (xy 456.84948 -405.533352) (xy 456.848927 -405.56156)
			(xy 456.840633 -405.617362) (xy 456.824203 -405.671331) (xy 456.799998 -405.722289) (xy 456.768544 -405.769122)
			(xy 456.730531 -405.810808) (xy 456.686788 -405.846434) (xy 456.66279 -405.861266) (xy 456.650449 -405.869273)
			(xy 456.630548 -405.890916) (xy 456.617626 -405.917326) (xy 456.612753 -405.946321) (xy 456.61633 -405.975505)
			(xy 456.628062 -406.002465) (xy 456.646979 -406.024973) (xy 456.65898 -406.033478) (xy 456.68121 -406.048686)
			(xy 456.721549 -406.084377) (xy 456.756468 -406.125386) (xy 456.785275 -406.170896) (xy 456.807396 -406.220005)
			(xy 456.822393 -406.271737) (xy 456.829967 -406.325063) (xy 456.83043 -406.351994) (xy 456.829944 -406.379245)
			(xy 456.822188 -406.433193) (xy 456.806833 -406.485488) (xy 456.784191 -406.535065) (xy 456.754725 -406.580915)
			(xy 456.719034 -406.622106) (xy 456.677843 -406.657797) (xy 456.631993 -406.687263) (xy 456.582416 -406.709905)
			(xy 456.530121 -406.72526) (xy 456.476173 -406.733016) (xy 456.421671 -406.733016) (xy 456.367723 -406.72526)
			(xy 456.315428 -406.709905) (xy 456.265851 -406.687263) (xy 456.220001 -406.657797) (xy 456.17881 -406.622106)
			(xy 456.143119 -406.580915) (xy 456.113653 -406.535065) (xy 456.091011 -406.485488) (xy 456.075656 -406.433193)
			(xy 456.0679 -406.379245) (xy 456.067414 -406.351994) (xy 451.948804 -406.351994) (xy 451.948804 -407.330148)
			(xy 456.075796 -407.330148) (xy 456.076282 -407.302897) (xy 456.084038 -407.248949) (xy 456.099393 -407.196654)
			(xy 456.122035 -407.147077) (xy 456.151501 -407.101227) (xy 456.187192 -407.060036) (xy 456.228383 -407.024345)
			(xy 456.274233 -406.994879) (xy 456.32381 -406.972237) (xy 456.376105 -406.956882) (xy 456.430053 -406.949126)
			(xy 456.484555 -406.949126) (xy 456.538503 -406.956882) (xy 456.590798 -406.972237) (xy 456.640375 -406.994879)
			(xy 456.686225 -407.024345) (xy 456.727416 -407.060036) (xy 456.763107 -407.101227) (xy 456.792573 -407.147077)
			(xy 456.815215 -407.196654) (xy 456.83057 -407.248949) (xy 456.838326 -407.302897) (xy 456.838812 -407.330148)
			(xy 456.838291 -407.35901) (xy 456.829609 -407.416078) (xy 456.812419 -407.471184) (xy 456.787116 -407.523067)
			(xy 456.754278 -407.570541) (xy 456.714656 -407.612519) (xy 456.669156 -407.648043) (xy 456.644248 -407.662634)
			(xy 456.632498 -407.669733) (xy 456.61303 -407.689076) (xy 456.599416 -407.712904) (xy 456.592637 -407.739497)
			(xy 456.593184 -407.766935) (xy 456.601016 -407.793237) (xy 456.615569 -407.816504) (xy 456.635792 -407.835056)
			(xy 456.647804 -407.841704) (xy 456.670957 -407.854001) (xy 456.713937 -407.884023) (xy 456.752403 -407.919644)
			(xy 456.785633 -407.960193) (xy 456.813001 -408.004909) (xy 456.833993 -408.05295) (xy 456.848213 -408.103411)
			(xy 456.855393 -408.155343) (xy 456.85583 -408.181556) (xy 456.855344 -408.208807) (xy 456.847588 -408.262755)
			(xy 456.832233 -408.31505) (xy 456.809591 -408.364627) (xy 456.780125 -408.410477) (xy 456.744434 -408.451668)
			(xy 456.703243 -408.487359) (xy 456.657393 -408.516825) (xy 456.607816 -408.539467) (xy 456.555521 -408.554822)
			(xy 456.501573 -408.562578) (xy 456.447071 -408.562578) (xy 456.393123 -408.554822) (xy 456.340828 -408.539467)
			(xy 456.291251 -408.516825) (xy 456.245401 -408.487359) (xy 456.20421 -408.451668) (xy 456.168519 -408.410477)
			(xy 456.139053 -408.364627) (xy 456.116411 -408.31505) (xy 456.101056 -408.262755) (xy 456.0933 -408.208807)
			(xy 456.092814 -408.181556) (xy 456.093325 -408.152693) (xy 456.102008 -408.095624) (xy 456.119198 -408.040518)
			(xy 456.144503 -407.988634) (xy 456.177343 -407.94116) (xy 456.216967 -407.899183) (xy 456.262469 -407.863661)
			(xy 456.287378 -407.84907) (xy 456.299122 -407.841963) (xy 456.318584 -407.822619) (xy 456.332195 -407.798793)
			(xy 456.338971 -407.772203) (xy 456.338425 -407.744769) (xy 456.330596 -407.718469) (xy 456.316048 -407.695203)
			(xy 456.295831 -407.67665) (xy 456.283822 -407.67) (xy 456.260676 -407.657689) (xy 456.217696 -407.62767)
			(xy 456.179228 -407.592052) (xy 456.145997 -407.551504) (xy 456.118628 -407.50679) (xy 456.097635 -407.458752)
			(xy 456.083415 -407.408292) (xy 456.076233 -407.356361) (xy 456.075796 -407.330148) (xy 451.948804 -407.330148)
			(xy 451.948804 -408.26944) (xy 451.948212 -408.294425) (xy 451.938465 -408.343434) (xy 451.919352 -408.389604)
			(xy 451.891607 -408.431164) (xy 451.874382 -408.449272) (xy 450.527674 -409.79598) (xy 450.50958 -409.813238)
			(xy 450.468035 -409.841049) (xy 450.421863 -409.860222) (xy 450.372839 -409.87002) (xy 450.347842 -409.870656)
			(xy 442.245496 -409.870656) (xy 442.236107 -409.871145) (xy 442.218591 -409.877913) (xy 442.204692 -409.890539)
			(xy 442.196276 -409.907325) (xy 442.19495 -409.91663) (xy 442.19495 -409.916884) (xy 442.194696 -409.921456)
			(xy 442.194696 -410.578554) (xy 446.710306 -410.578554) (xy 446.714377 -410.522932) (xy 446.726503 -410.468495)
			(xy 446.746426 -410.416404) (xy 446.773722 -410.367769) (xy 446.807808 -410.323626) (xy 446.847957 -410.284917)
			(xy 446.893315 -410.252466) (xy 446.942915 -410.226965) (xy 446.995699 -410.208958) (xy 447.050542 -410.198828)
			(xy 447.106276 -410.196791) (xy 447.161713 -410.202891) (xy 447.21567 -410.216997) (xy 447.266999 -410.238809)
			(xy 447.314605 -410.267863) (xy 447.357473 -410.303538) (xy 447.39469 -410.345075) (xy 447.425463 -410.391588)
			(xy 447.449135 -410.442085) (xy 447.465203 -410.495492) (xy 447.473323 -410.550668) (xy 447.473832 -410.578554)
			(xy 447.599306 -410.578554) (xy 447.603377 -410.522932) (xy 447.615503 -410.468495) (xy 447.635426 -410.416404)
			(xy 447.662722 -410.367769) (xy 447.696808 -410.323626) (xy 447.736957 -410.284917) (xy 447.782315 -410.252466)
			(xy 447.831915 -410.226965) (xy 447.884699 -410.208958) (xy 447.939542 -410.198828) (xy 447.995276 -410.196791)
			(xy 448.050713 -410.202891) (xy 448.10467 -410.216997) (xy 448.155999 -410.238809) (xy 448.203605 -410.267863)
			(xy 448.246473 -410.303538) (xy 448.28369 -410.345075) (xy 448.314463 -410.391588) (xy 448.338135 -410.442085)
			(xy 448.354203 -410.495492) (xy 448.362323 -410.550668) (xy 448.362832 -410.578554) (xy 448.488306 -410.578554)
			(xy 448.492377 -410.522932) (xy 448.504503 -410.468495) (xy 448.524426 -410.416404) (xy 448.551722 -410.367769)
			(xy 448.585808 -410.323626) (xy 448.625957 -410.284917) (xy 448.671315 -410.252466) (xy 448.720915 -410.226965)
			(xy 448.773699 -410.208958) (xy 448.828542 -410.198828) (xy 448.884276 -410.196791) (xy 448.939713 -410.202891)
			(xy 448.99367 -410.216997) (xy 449.044999 -410.238809) (xy 449.092605 -410.267863) (xy 449.135473 -410.303538)
			(xy 449.17269 -410.345075) (xy 449.203463 -410.391588) (xy 449.227135 -410.442085) (xy 449.243203 -410.495492)
			(xy 449.251323 -410.550668) (xy 449.251832 -410.578554) (xy 449.251323 -410.60644) (xy 449.243203 -410.661616)
			(xy 449.227135 -410.715023) (xy 449.203463 -410.76552) (xy 449.17269 -410.812033) (xy 449.135473 -410.85357)
			(xy 449.092605 -410.889245) (xy 449.071044 -410.902404) (xy 451.091808 -410.902404) (xy 451.092365 -410.87228)
			(xy 451.101847 -410.812782) (xy 451.12056 -410.755513) (xy 451.14804 -410.701897) (xy 451.183603 -410.653264)
			(xy 451.204584 -410.63164) (xy 451.211397 -410.624218) (xy 451.219133 -410.605636) (xy 451.21957 -410.595572)
			(xy 451.21957 -410.523436) (xy 451.219133 -410.513368) (xy 451.211421 -410.49477) (xy 451.204584 -410.487368)
			(xy 451.183608 -410.465739) (xy 451.14804 -410.417111) (xy 451.12056 -410.363495) (xy 451.10185 -410.306226)
			(xy 451.092377 -410.246728) (xy 451.091808 -410.216604) (xy 451.092259 -410.189351) (xy 451.100016 -410.135398)
			(xy 451.115372 -410.083099) (xy 451.138015 -410.033518) (xy 451.167485 -409.987664) (xy 451.20318 -409.946471)
			(xy 451.244374 -409.910777) (xy 451.290229 -409.88131) (xy 451.339811 -409.858668) (xy 451.39211 -409.843313)
			(xy 451.446063 -409.835558) (xy 451.473316 -409.835096) (xy 451.503441 -409.835643) (xy 451.562939 -409.845128)
			(xy 451.620207 -409.863844) (xy 451.673824 -409.891325) (xy 451.722457 -409.92689) (xy 451.74408 -409.947872)
			(xy 451.751496 -409.954692) (xy 451.770083 -409.962424) (xy 451.780148 -409.962858) (xy 451.852284 -409.962858)
			(xy 451.862354 -409.962435) (xy 451.880952 -409.954714) (xy 451.888352 -409.947872) (xy 451.909987 -409.926903)
			(xy 451.958612 -409.89133) (xy 452.012225 -409.863847) (xy 452.069494 -409.845136) (xy 452.128992 -409.835665)
			(xy 452.159116 -409.835096) (xy 452.186487 -409.835554) (xy 452.240666 -409.843374) (xy 452.293169 -409.858865)
			(xy 452.342916 -409.881708) (xy 452.388882 -409.911434) (xy 452.409814 -409.929076) (xy 452.410068 -409.92933)
			(xy 452.417157 -409.934913) (xy 452.434072 -409.941161) (xy 452.443088 -409.941522) (xy 452.510144 -409.941522)
			(xy 452.519158 -409.941134) (xy 452.536075 -409.934907) (xy 452.543164 -409.92933) (xy 452.543164 -409.929076)
			(xy 452.543418 -409.929076) (xy 452.564367 -409.911458) (xy 452.610336 -409.881744) (xy 452.660079 -409.858904)
			(xy 452.712576 -409.843408) (xy 452.766748 -409.835574) (xy 452.794116 -409.835096) (xy 452.821368 -409.835563)
			(xy 452.875316 -409.843322) (xy 452.927612 -409.858679) (xy 452.977189 -409.881322) (xy 453.02304 -409.910791)
			(xy 453.06423 -409.946484) (xy 453.099921 -409.987676) (xy 453.129387 -410.033528) (xy 453.152028 -410.083107)
			(xy 453.167383 -410.135403) (xy 453.175139 -410.189352) (xy 453.175624 -410.216604) (xy 453.175063 -410.246728)
			(xy 453.165581 -410.306225) (xy 453.146868 -410.363493) (xy 453.11939 -410.41711) (xy 453.083828 -410.465744)
			(xy 453.062848 -410.487368) (xy 453.056036 -410.494791) (xy 453.048298 -410.513372) (xy 453.047862 -410.523436)
			(xy 453.047862 -410.595572) (xy 453.048204 -410.6037) (xy 454.780648 -410.6037) (xy 454.784719 -410.548078)
			(xy 454.796845 -410.493641) (xy 454.816768 -410.44155) (xy 454.844064 -410.392915) (xy 454.87815 -410.348772)
			(xy 454.918299 -410.310063) (xy 454.963657 -410.277612) (xy 455.013257 -410.252111) (xy 455.066041 -410.234104)
			(xy 455.120884 -410.223974) (xy 455.176618 -410.221937) (xy 455.232055 -410.228037) (xy 455.286012 -410.242143)
			(xy 455.337341 -410.263955) (xy 455.384947 -410.293009) (xy 455.427815 -410.328684) (xy 455.465032 -410.370221)
			(xy 455.495805 -410.416734) (xy 455.519477 -410.467231) (xy 455.535545 -410.520638) (xy 455.543665 -410.575814)
			(xy 455.544174 -410.6037) (xy 455.669648 -410.6037) (xy 455.673719 -410.548078) (xy 455.685845 -410.493641)
			(xy 455.705768 -410.44155) (xy 455.733064 -410.392915) (xy 455.76715 -410.348772) (xy 455.807299 -410.310063)
			(xy 455.852657 -410.277612) (xy 455.902257 -410.252111) (xy 455.955041 -410.234104) (xy 456.009884 -410.223974)
			(xy 456.065618 -410.221937) (xy 456.121055 -410.228037) (xy 456.175012 -410.242143) (xy 456.226341 -410.263955)
			(xy 456.273947 -410.293009) (xy 456.316815 -410.328684) (xy 456.354032 -410.370221) (xy 456.384805 -410.416734)
			(xy 456.408477 -410.467231) (xy 456.424545 -410.520638) (xy 456.432665 -410.575814) (xy 456.433174 -410.6037)
			(xy 456.558648 -410.6037) (xy 456.562719 -410.548078) (xy 456.574845 -410.493641) (xy 456.594768 -410.44155)
			(xy 456.622064 -410.392915) (xy 456.65615 -410.348772) (xy 456.696299 -410.310063) (xy 456.741657 -410.277612)
			(xy 456.791257 -410.252111) (xy 456.844041 -410.234104) (xy 456.898884 -410.223974) (xy 456.954618 -410.221937)
			(xy 457.010055 -410.228037) (xy 457.064012 -410.242143) (xy 457.115341 -410.263955) (xy 457.162947 -410.293009)
			(xy 457.205815 -410.328684) (xy 457.243032 -410.370221) (xy 457.273805 -410.416734) (xy 457.297477 -410.467231)
			(xy 457.313545 -410.520638) (xy 457.321665 -410.575814) (xy 457.322174 -410.6037) (xy 457.321665 -410.631586)
			(xy 457.313545 -410.686762) (xy 457.297477 -410.740169) (xy 457.273805 -410.790666) (xy 457.243032 -410.837179)
			(xy 457.205815 -410.878716) (xy 457.162947 -410.914391) (xy 457.115341 -410.943445) (xy 457.064012 -410.965257)
			(xy 457.010055 -410.979363) (xy 456.954618 -410.985463) (xy 456.898884 -410.983426) (xy 456.844041 -410.973296)
			(xy 456.791257 -410.955289) (xy 456.741657 -410.929788) (xy 456.696299 -410.897337) (xy 456.65615 -410.858628)
			(xy 456.622064 -410.814485) (xy 456.594768 -410.76585) (xy 456.574845 -410.713759) (xy 456.562719 -410.659322)
			(xy 456.558648 -410.6037) (xy 456.433174 -410.6037) (xy 456.432665 -410.631586) (xy 456.424545 -410.686762)
			(xy 456.408477 -410.740169) (xy 456.384805 -410.790666) (xy 456.354032 -410.837179) (xy 456.316815 -410.878716)
			(xy 456.273947 -410.914391) (xy 456.226341 -410.943445) (xy 456.175012 -410.965257) (xy 456.121055 -410.979363)
			(xy 456.065618 -410.985463) (xy 456.009884 -410.983426) (xy 455.955041 -410.973296) (xy 455.902257 -410.955289)
			(xy 455.852657 -410.929788) (xy 455.807299 -410.897337) (xy 455.76715 -410.858628) (xy 455.733064 -410.814485)
			(xy 455.705768 -410.76585) (xy 455.685845 -410.713759) (xy 455.673719 -410.659322) (xy 455.669648 -410.6037)
			(xy 455.544174 -410.6037) (xy 455.543665 -410.631586) (xy 455.535545 -410.686762) (xy 455.519477 -410.740169)
			(xy 455.495805 -410.790666) (xy 455.465032 -410.837179) (xy 455.427815 -410.878716) (xy 455.384947 -410.914391)
			(xy 455.337341 -410.943445) (xy 455.286012 -410.965257) (xy 455.232055 -410.979363) (xy 455.176618 -410.985463)
			(xy 455.120884 -410.983426) (xy 455.066041 -410.973296) (xy 455.013257 -410.955289) (xy 454.963657 -410.929788)
			(xy 454.918299 -410.897337) (xy 454.87815 -410.858628) (xy 454.844064 -410.814485) (xy 454.816768 -410.76585)
			(xy 454.796845 -410.713759) (xy 454.784719 -410.659322) (xy 454.780648 -410.6037) (xy 453.048204 -410.6037)
			(xy 453.048286 -410.605642) (xy 453.056006 -410.624241) (xy 453.062848 -410.63164) (xy 453.083816 -410.653277)
			(xy 453.119388 -410.701901) (xy 453.146871 -410.755515) (xy 453.165582 -410.812783) (xy 453.175055 -410.87228)
			(xy 453.175624 -410.902404) (xy 453.175126 -410.929655) (xy 453.167369 -410.983601) (xy 453.152015 -411.035895)
			(xy 453.129374 -411.085471) (xy 453.099909 -411.13132) (xy 453.064219 -411.17251) (xy 453.02303 -411.208202)
			(xy 452.977181 -411.237668) (xy 452.927606 -411.26031) (xy 452.875313 -411.275667) (xy 452.821367 -411.283425)
			(xy 452.794116 -411.283912) (xy 452.766746 -411.283434) (xy 452.712568 -411.275618) (xy 452.660065 -411.260132)
			(xy 452.610318 -411.237293) (xy 452.56435 -411.207572) (xy 452.543418 -411.189932) (xy 452.543164 -411.189678)
			(xy 452.536065 -411.18411) (xy 452.519158 -411.177853) (xy 452.510144 -411.177486) (xy 452.443088 -411.177486)
			(xy 452.434071 -411.17784) (xy 452.417154 -411.18409) (xy 452.410068 -411.189678) (xy 452.410068 -411.189932)
			(xy 452.409814 -411.189932) (xy 452.388892 -411.207583) (xy 452.342916 -411.237292) (xy 452.293166 -411.260125)
			(xy 452.240663 -411.275613) (xy 452.186486 -411.283439) (xy 452.159116 -411.283912) (xy 452.128992 -411.283342)
			(xy 452.069496 -411.273862) (xy 452.012227 -411.255152) (xy 451.95861 -411.227675) (xy 451.909976 -411.192116)
			(xy 451.888352 -411.171136) (xy 451.880924 -411.164331) (xy 451.862346 -411.15659) (xy 451.852284 -411.15615)
			(xy 451.780148 -411.15615) (xy 451.77008 -411.156587) (xy 451.751481 -411.164298) (xy 451.74408 -411.171136)
			(xy 451.722432 -411.192091) (xy 451.673811 -411.227665) (xy 451.6202 -411.255151) (xy 451.562935 -411.273865)
			(xy 451.503439 -411.283341) (xy 451.473316 -411.283912) (xy 451.446064 -411.28343) (xy 451.392114 -411.275675)
			(xy 451.339816 -411.260321) (xy 451.290237 -411.237681) (xy 451.244384 -411.208215) (xy 451.203191 -411.172523)
			(xy 451.167497 -411.131332) (xy 451.138029 -411.085481) (xy 451.115386 -411.035902) (xy 451.100029 -410.983606)
			(xy 451.092272 -410.929656) (xy 451.091808 -410.902404) (xy 449.071044 -410.902404) (xy 449.044999 -410.918299)
			(xy 448.99367 -410.940111) (xy 448.939713 -410.954217) (xy 448.884276 -410.960317) (xy 448.828542 -410.95828)
			(xy 448.773699 -410.94815) (xy 448.720915 -410.930143) (xy 448.671315 -410.904642) (xy 448.625957 -410.872191)
			(xy 448.585808 -410.833482) (xy 448.551722 -410.789339) (xy 448.524426 -410.740704) (xy 448.504503 -410.688613)
			(xy 448.492377 -410.634176) (xy 448.488306 -410.578554) (xy 448.362832 -410.578554) (xy 448.362323 -410.60644)
			(xy 448.354203 -410.661616) (xy 448.338135 -410.715023) (xy 448.314463 -410.76552) (xy 448.28369 -410.812033)
			(xy 448.246473 -410.85357) (xy 448.203605 -410.889245) (xy 448.155999 -410.918299) (xy 448.10467 -410.940111)
			(xy 448.050713 -410.954217) (xy 447.995276 -410.960317) (xy 447.939542 -410.95828) (xy 447.884699 -410.94815)
			(xy 447.831915 -410.930143) (xy 447.782315 -410.904642) (xy 447.736957 -410.872191) (xy 447.696808 -410.833482)
			(xy 447.662722 -410.789339) (xy 447.635426 -410.740704) (xy 447.615503 -410.688613) (xy 447.603377 -410.634176)
			(xy 447.599306 -410.578554) (xy 447.473832 -410.578554) (xy 447.473323 -410.60644) (xy 447.465203 -410.661616)
			(xy 447.449135 -410.715023) (xy 447.425463 -410.76552) (xy 447.39469 -410.812033) (xy 447.357473 -410.85357)
			(xy 447.314605 -410.889245) (xy 447.266999 -410.918299) (xy 447.21567 -410.940111) (xy 447.161713 -410.954217)
			(xy 447.106276 -410.960317) (xy 447.050542 -410.95828) (xy 446.995699 -410.94815) (xy 446.942915 -410.930143)
			(xy 446.893315 -410.904642) (xy 446.847957 -410.872191) (xy 446.807808 -410.833482) (xy 446.773722 -410.789339)
			(xy 446.746426 -410.740704) (xy 446.726503 -410.688613) (xy 446.714377 -410.634176) (xy 446.710306 -410.578554)
			(xy 442.194696 -410.578554) (xy 442.194696 -415.147252) (xy 449.363338 -415.147252) (xy 449.363825 -415.119882)
			(xy 449.371637 -415.065704) (xy 449.38712 -415.013201) (xy 449.409957 -414.963453) (xy 449.439678 -414.917486)
			(xy 449.457318 -414.896554) (xy 449.457572 -414.8963) (xy 449.463173 -414.889224) (xy 449.469409 -414.872299)
			(xy 449.469764 -414.86328) (xy 449.469764 -414.796224) (xy 449.469403 -414.787207) (xy 449.463159 -414.77029)
			(xy 449.457572 -414.763204) (xy 449.457318 -414.763204) (xy 449.457318 -414.76295) (xy 449.439692 -414.742008)
			(xy 449.409977 -414.696038) (xy 449.387139 -414.646293) (xy 449.371645 -414.593795) (xy 449.363813 -414.539621)
			(xy 449.363338 -414.512252) (xy 449.363733 -414.484997) (xy 449.371498 -414.431044) (xy 449.386861 -414.378745)
			(xy 449.409511 -414.329164) (xy 449.438987 -414.283312) (xy 449.474688 -414.242121) (xy 449.515887 -414.20643)
			(xy 449.561747 -414.176966) (xy 449.611333 -414.154328) (xy 449.663636 -414.138978) (xy 449.717591 -414.131227)
			(xy 449.744846 -414.130744) (xy 449.774968 -414.13135) (xy 449.834463 -414.140823) (xy 449.89173 -414.159526)
			(xy 449.945348 -414.186993) (xy 449.993984 -414.222544) (xy 450.01561 -414.24352) (xy 450.02301 -414.25036)
			(xy 450.041609 -414.258079) (xy 450.051678 -414.258506) (xy 450.123814 -414.258506) (xy 450.133887 -414.258113)
			(xy 450.152486 -414.250372) (xy 450.159882 -414.24352) (xy 450.181495 -414.222527) (xy 450.230127 -414.186959)
			(xy 450.283746 -414.159481) (xy 450.341019 -414.140776) (xy 450.400521 -414.13131) (xy 450.430646 -414.130744)
			(xy 450.457896 -414.131235) (xy 450.511841 -414.138996) (xy 450.564133 -414.154355) (xy 450.613707 -414.176998)
			(xy 450.659555 -414.206465) (xy 450.700743 -414.242155) (xy 450.736434 -414.283343) (xy 450.765901 -414.329191)
			(xy 450.788544 -414.378765) (xy 450.803903 -414.431057) (xy 450.811665 -414.485002) (xy 450.812154 -414.512252)
			(xy 450.811597 -414.541729) (xy 450.802533 -414.599982) (xy 450.784616 -414.656147) (xy 450.75827 -414.708887)
			(xy 450.724123 -414.756945) (xy 450.70395 -414.778444) (xy 450.697396 -414.785764) (xy 450.689964 -414.803936)
			(xy 450.689472 -414.81375) (xy 450.689472 -414.86709) (xy 450.702426 -414.87979) (xy 450.710381 -414.887091)
			(xy 450.730494 -414.894873) (xy 450.741288 -414.894776) (xy 450.7738 -414.892998) (xy 450.784529 -414.891856)
			(xy 450.803696 -414.881997) (xy 450.810884 -414.873948) (xy 450.829058 -414.851788) (xy 450.870946 -414.812677)
			(xy 450.918212 -414.780268) (xy 450.969793 -414.755292) (xy 451.024528 -414.738309) (xy 451.081188 -414.729702)
			(xy 451.109842 -414.729168) (xy 451.139964 -414.72977) (xy 451.199459 -414.739243) (xy 451.256727 -414.757946)
			(xy 451.310345 -414.785415) (xy 451.35898 -414.820968) (xy 451.380606 -414.841944) (xy 451.388005 -414.848785)
			(xy 451.406605 -414.856503) (xy 451.416674 -414.85693) (xy 451.48881 -414.85693) (xy 451.498882 -414.856528)
			(xy 451.517481 -414.848793) (xy 451.524878 -414.841944) (xy 451.546497 -414.820957) (xy 451.595126 -414.785388)
			(xy 451.648744 -414.757908) (xy 451.706016 -414.739202) (xy 451.765517 -414.729734) (xy 451.795642 -414.729168)
			(xy 451.821941 -414.729585) (xy 451.87404 -414.73681) (xy 451.92465 -414.751129) (xy 451.972811 -414.772271)
			(xy 452.017608 -414.799834) (xy 452.058189 -414.833295) (xy 452.076312 -414.852358) (xy 452.076566 -414.852612)
			(xy 452.083703 -414.859507) (xy 452.101733 -414.867745) (xy 452.111618 -414.868614) (xy 452.184008 -414.871408)
			(xy 452.194086 -414.871318) (xy 452.212945 -414.864263) (xy 452.220584 -414.857692) (xy 452.241902 -414.838411)
			(xy 452.289266 -414.805844) (xy 452.340979 -414.780753) (xy 452.395873 -414.763705) (xy 452.452702 -414.755087)
			(xy 452.481442 -414.754568) (xy 452.48195 -414.754568) (xy 452.510699 -414.7551) (xy 452.567538 -414.763778)
			(xy 452.622433 -414.780883) (xy 452.674141 -414.80603) (xy 452.721491 -414.83865) (xy 452.742808 -414.857946)
			(xy 452.74992 -414.864804) (xy 452.767954 -414.871916) (xy 452.858124 -414.871154) (xy 452.87565 -414.864042)
			(xy 452.882762 -414.857438) (xy 452.88327 -414.85693) (xy 452.904733 -414.836966) (xy 452.952616 -414.803157)
			(xy 453.005105 -414.777067) (xy 453.060966 -414.759309) (xy 453.118885 -414.750301) (xy 453.148192 -414.749742)
			(xy 453.174522 -414.750156) (xy 453.226681 -414.757391) (xy 453.277348 -414.77174) (xy 453.325556 -414.792927)
			(xy 453.370388 -414.820551) (xy 453.41099 -414.854084) (xy 453.429116 -414.873186) (xy 453.436284 -414.880283)
			(xy 453.454619 -414.88866) (xy 453.464676 -414.889442) (xy 453.51827 -414.891474) (xy 453.52462 -414.885124)
			(xy 453.531317 -414.877781) (xy 453.53903 -414.859486) (xy 453.539606 -414.849564) (xy 453.540114 -414.77819)
			(xy 453.539782 -414.768266) (xy 453.532447 -414.749834) (xy 453.52589 -414.742376) (xy 453.505877 -414.720922)
			(xy 453.472052 -414.672985) (xy 453.44596 -414.620436) (xy 453.428217 -414.564514) (xy 453.419239 -414.506535)
			(xy 453.418702 -414.4772) (xy 453.419188 -414.449949) (xy 453.426944 -414.396001) (xy 453.442299 -414.343706)
			(xy 453.464941 -414.294129) (xy 453.494407 -414.248279) (xy 453.530098 -414.207088) (xy 453.571289 -414.171397)
			(xy 453.617139 -414.141931) (xy 453.666716 -414.119289) (xy 453.719011 -414.103934) (xy 453.772959 -414.096178)
			(xy 453.827461 -414.096178) (xy 453.881409 -414.103934) (xy 453.933704 -414.119289) (xy 453.983281 -414.141931)
			(xy 454.029131 -414.171397) (xy 454.070322 -414.207088) (xy 454.106013 -414.248279) (xy 454.135479 -414.294129)
			(xy 454.158121 -414.343706) (xy 454.173476 -414.396001) (xy 454.181232 -414.449949) (xy 454.181718 -414.4772)
			(xy 454.181157 -414.507324) (xy 454.171675 -414.566821) (xy 454.152962 -414.62409) (xy 454.125484 -414.677707)
			(xy 454.089923 -414.72634) (xy 454.068942 -414.747964) (xy 454.062258 -414.755318) (xy 454.054536 -414.773605)
			(xy 454.053956 -414.783524) (xy 454.053448 -414.854898) (xy 454.053795 -414.86482) (xy 454.06112 -414.883252)
			(xy 454.067672 -414.890712) (xy 454.087673 -414.912177) (xy 454.121501 -414.960111) (xy 454.147596 -415.012656)
			(xy 454.165342 -415.068577) (xy 454.174322 -415.126554) (xy 454.17486 -415.155888) (xy 454.174371 -415.183386)
			(xy 454.166481 -415.237812) (xy 454.150863 -415.290544) (xy 454.12784 -415.340488) (xy 454.097888 -415.386612)
			(xy 454.080118 -415.407602) (xy 454.074187 -415.414893) (xy 454.067651 -415.432498) (xy 454.067418 -415.441892)
			(xy 454.068434 -415.509964) (xy 454.068915 -415.519203) (xy 454.075699 -415.5364) (xy 454.081642 -415.543492)
			(xy 454.08215 -415.544) (xy 454.101142 -415.565301) (xy 454.133286 -415.612451) (xy 454.158056 -415.663859)
			(xy 454.174901 -415.718381) (xy 454.183446 -415.774802) (xy 454.184004 -415.803334) (xy 454.183554 -415.830586)
			(xy 454.175793 -415.884535) (xy 454.160433 -415.936831) (xy 454.137788 -415.986409) (xy 454.108317 -416.032259)
			(xy 454.072622 -416.073449) (xy 454.031429 -416.10914) (xy 453.985575 -416.138606) (xy 453.935995 -416.161246)
			(xy 453.883698 -416.176601) (xy 453.829748 -416.184357) (xy 453.802496 -416.184842) (xy 453.776975 -416.18445)
			(xy 453.726387 -416.177654) (xy 453.677158 -416.164171) (xy 453.630167 -416.144242) (xy 453.586254 -416.118222)
			(xy 453.546205 -416.086578) (xy 453.528176 -416.06851) (xy 453.521572 -416.061652) (xy 453.5043 -416.053778)
			(xy 453.416162 -416.048698) (xy 453.398128 -416.054794) (xy 453.390762 -416.06089) (xy 453.3702 -416.077244)
			(xy 453.325433 -416.104742) (xy 453.277315 -416.125832) (xy 453.226756 -416.140116) (xy 453.174715 -416.147322)
			(xy 453.148446 -416.147758) (xy 453.147938 -416.147758) (xy 453.119165 -416.147216) (xy 453.062272 -416.138566)
			(xy 453.007322 -416.121474) (xy 452.955562 -416.096324) (xy 452.908164 -416.063689) (xy 452.886826 -416.04438)
			(xy 452.879714 -416.037522) (xy 452.86168 -416.03041) (xy 452.77151 -416.031172) (xy 452.753984 -416.038284)
			(xy 452.746872 -416.044888) (xy 452.746364 -416.045396) (xy 452.72489 -416.065348) (xy 452.67701 -416.099157)
			(xy 452.624523 -416.125249) (xy 452.568665 -416.14301) (xy 452.510748 -416.152023) (xy 452.481442 -416.152584)
			(xy 452.45132 -416.151977) (xy 452.391826 -416.142503) (xy 452.334559 -416.1238) (xy 452.280941 -416.096333)
			(xy 452.232305 -416.060783) (xy 452.210678 -416.039808) (xy 452.203279 -416.032967) (xy 452.184679 -416.025247)
			(xy 452.17461 -416.024822) (xy 452.102474 -416.024822) (xy 452.092403 -416.025228) (xy 452.073805 -416.032962)
			(xy 452.066406 -416.039808) (xy 452.046782 -416.05891) (xy 452.003043 -416.091863) (xy 451.955042 -416.118223)
			(xy 451.903764 -416.137449) (xy 451.850264 -416.149145) (xy 451.795642 -416.15307) (xy 451.74102 -416.149145)
			(xy 451.68752 -416.137449) (xy 451.636242 -416.118223) (xy 451.588241 -416.091863) (xy 451.544502 -416.05891)
			(xy 451.524878 -416.039808) (xy 451.517479 -416.032967) (xy 451.498879 -416.025247) (xy 451.48881 -416.024822)
			(xy 451.416674 -416.024822) (xy 451.406603 -416.025228) (xy 451.388005 -416.032962) (xy 451.380606 -416.039808)
			(xy 451.359003 -416.060812) (xy 451.310368 -416.096377) (xy 451.256746 -416.123852) (xy 451.199471 -416.142555)
			(xy 451.139968 -416.152019) (xy 451.109842 -416.152584) (xy 451.080711 -416.152045) (xy 451.023129 -416.14317)
			(xy 450.967568 -416.125637) (xy 450.915322 -416.099853) (xy 450.867607 -416.06642) (xy 450.84619 -416.046666)
			(xy 450.845936 -416.046412) (xy 450.838471 -416.040047) (xy 450.820182 -416.032996) (xy 450.810376 -416.032696)
			(xy 450.738748 -416.033966) (xy 450.728887 -416.034563) (xy 450.71072 -416.042272) (xy 450.703442 -416.048952)
			(xy 450.703188 -416.049206) (xy 450.681532 -416.070516) (xy 450.632677 -416.106631) (xy 450.578715 -416.134546)
			(xy 450.521011 -416.153554) (xy 450.461023 -416.163175) (xy 450.430646 -416.16376) (xy 450.403392 -416.163302)
			(xy 450.349438 -416.15555) (xy 450.297138 -416.140197) (xy 450.247554 -416.117557) (xy 450.201699 -416.088089)
			(xy 450.160504 -416.052394) (xy 450.12481 -416.0112) (xy 450.095343 -415.965344) (xy 450.072702 -415.915761)
			(xy 450.05735 -415.86346) (xy 450.049598 -415.809506) (xy 450.049138 -415.782252) (xy 450.0497 -415.752775)
			(xy 450.058762 -415.694522) (xy 450.076679 -415.638357) (xy 450.103024 -415.585618) (xy 450.137169 -415.537559)
			(xy 450.157342 -415.51606) (xy 450.163893 -415.508738) (xy 450.171327 -415.490568) (xy 450.17182 -415.480754)
			(xy 450.17182 -415.427414) (xy 450.159882 -415.415984) (xy 450.152484 -415.409142) (xy 450.133883 -415.401424)
			(xy 450.123814 -415.400998) (xy 450.051678 -415.400998) (xy 450.041604 -415.401386) (xy 450.023005 -415.40913)
			(xy 450.01561 -415.415984) (xy 449.994001 -415.436982) (xy 449.945368 -415.472548) (xy 449.891748 -415.500026)
			(xy 449.834474 -415.51873) (xy 449.774971 -415.528195) (xy 449.744846 -415.52876) (xy 449.717592 -415.528302)
			(xy 449.663638 -415.52055) (xy 449.611338 -415.505197) (xy 449.561754 -415.482557) (xy 449.515899 -415.453089)
			(xy 449.474704 -415.417394) (xy 449.43901 -415.3762) (xy 449.409543 -415.330344) (xy 449.386902 -415.280761)
			(xy 449.37155 -415.22846) (xy 449.363798 -415.174506) (xy 449.363338 -415.147252) (xy 442.194696 -415.147252)
			(xy 442.194696 -417.278312) (xy 442.19509 -417.288385) (xy 442.20283 -417.306984) (xy 442.209682 -417.31438)
			(xy 443.095126 -418.199824) (xy 448.144898 -418.199824) (xy 448.148969 -418.144202) (xy 448.161095 -418.089765)
			(xy 448.181018 -418.037674) (xy 448.208314 -417.989039) (xy 448.2424 -417.944896) (xy 448.282549 -417.906187)
			(xy 448.327907 -417.873736) (xy 448.377507 -417.848235) (xy 448.430291 -417.830228) (xy 448.485134 -417.820098)
			(xy 448.540868 -417.818061) (xy 448.596305 -417.824161) (xy 448.650262 -417.838267) (xy 448.701591 -417.860079)
			(xy 448.749197 -417.889133) (xy 448.792065 -417.924808) (xy 448.829282 -417.966345) (xy 448.860055 -418.012858)
			(xy 448.883727 -418.063355) (xy 448.899795 -418.116762) (xy 448.907915 -418.171938) (xy 448.908424 -418.199824)
			(xy 448.907915 -418.22771) (xy 448.899795 -418.282886) (xy 448.883727 -418.336293) (xy 448.860055 -418.38679)
			(xy 448.829282 -418.433303) (xy 448.792065 -418.47484) (xy 448.749197 -418.510515) (xy 448.701591 -418.539569)
			(xy 448.650262 -418.561381) (xy 448.596305 -418.575487) (xy 448.540868 -418.581587) (xy 448.485134 -418.57955)
			(xy 448.430291 -418.56942) (xy 448.377507 -418.551413) (xy 448.327907 -418.525912) (xy 448.282549 -418.493461)
			(xy 448.2424 -418.454752) (xy 448.208314 -418.410609) (xy 448.181018 -418.361974) (xy 448.161095 -418.309883)
			(xy 448.148969 -418.255446) (xy 448.144898 -418.199824) (xy 443.095126 -418.199824) (xy 443.273434 -418.378132)
			(xy 443.290635 -418.39626) (xy 443.318381 -418.437813) (xy 443.337494 -418.483977) (xy 443.347242 -418.532982)
			(xy 443.347856 -418.557964) (xy 443.347856 -418.783516) (xy 443.348374 -418.793519) (xy 443.35603 -418.812003)
			(xy 443.370173 -418.826154) (xy 443.388653 -418.833821) (xy 443.398656 -418.834316) (xy 446.852294 -418.834316)
			(xy 446.862363 -418.83474) (xy 446.880961 -418.842461) (xy 446.888362 -418.849302) (xy 447.635835 -419.596824)
			(xy 448.925948 -419.596824) (xy 448.930019 -419.541202) (xy 448.942145 -419.486765) (xy 448.962068 -419.434674)
			(xy 448.989364 -419.386039) (xy 449.02345 -419.341896) (xy 449.063599 -419.303187) (xy 449.108957 -419.270736)
			(xy 449.158557 -419.245235) (xy 449.211341 -419.227228) (xy 449.266184 -419.217098) (xy 449.321918 -419.215061)
			(xy 449.377355 -419.221161) (xy 449.431312 -419.235267) (xy 449.482641 -419.257079) (xy 449.530247 -419.286133)
			(xy 449.573115 -419.321808) (xy 449.610332 -419.363345) (xy 449.641105 -419.409858) (xy 449.664777 -419.460355)
			(xy 449.680845 -419.513762) (xy 449.688965 -419.568938) (xy 449.689474 -419.596824) (xy 449.688965 -419.62471)
			(xy 449.680845 -419.679886) (xy 449.664777 -419.733293) (xy 449.641105 -419.78379) (xy 449.610332 -419.830303)
			(xy 449.573115 -419.87184) (xy 449.530247 -419.907515) (xy 449.482641 -419.936569) (xy 449.431312 -419.958381)
			(xy 449.377355 -419.972487) (xy 449.321918 -419.978587) (xy 449.266184 -419.97655) (xy 449.211341 -419.96642)
			(xy 449.158557 -419.948413) (xy 449.108957 -419.922912) (xy 449.063599 -419.890461) (xy 449.02345 -419.851752)
			(xy 448.989364 -419.807609) (xy 448.962068 -419.758974) (xy 448.942145 -419.706883) (xy 448.930019 -419.652446)
			(xy 448.925948 -419.596824) (xy 447.635835 -419.596824) (xy 449.035029 -420.99611) (xy 450.196458 -420.99611)
			(xy 450.196941 -420.968612) (xy 450.204832 -420.914185) (xy 450.220451 -420.861453) (xy 450.243476 -420.811509)
			(xy 450.27343 -420.765386) (xy 450.2912 -420.744396) (xy 450.297296 -420.737538) (xy 450.3039 -420.720266)
			(xy 450.3039 -420.634668) (xy 450.297296 -420.617396) (xy 450.2912 -420.610538) (xy 450.273442 -420.589537)
			(xy 450.243486 -420.543417) (xy 450.220458 -420.493476) (xy 450.204835 -420.440747) (xy 450.19694 -420.386321)
			(xy 450.196458 -420.358824) (xy 450.196944 -420.331573) (xy 450.2047 -420.277625) (xy 450.220055 -420.22533)
			(xy 450.242697 -420.175753) (xy 450.272163 -420.129903) (xy 450.307854 -420.088712) (xy 450.349045 -420.053021)
			(xy 450.394895 -420.023555) (xy 450.444472 -420.000913) (xy 450.496767 -419.985558) (xy 450.550715 -419.977802)
			(xy 450.605217 -419.977802) (xy 450.659165 -419.985558) (xy 450.71146 -420.000913) (xy 450.761037 -420.023555)
			(xy 450.806887 -420.053021) (xy 450.848078 -420.088712) (xy 450.883769 -420.129903) (xy 450.913235 -420.175753)
			(xy 450.935877 -420.22533) (xy 450.951232 -420.277625) (xy 450.958988 -420.331573) (xy 450.959474 -420.358824)
			(xy 450.959003 -420.386322) (xy 450.951108 -420.44075) (xy 450.935486 -420.493481) (xy 450.912458 -420.543425)
			(xy 450.882503 -420.589548) (xy 450.864732 -420.610538) (xy 450.858636 -420.617396) (xy 450.852032 -420.634668)
			(xy 450.852032 -420.720266) (xy 450.858636 -420.737538) (xy 450.864732 -420.744396) (xy 450.882511 -420.76538)
			(xy 450.912463 -420.811505) (xy 450.935486 -420.861451) (xy 450.951105 -420.914183) (xy 450.958995 -420.968611)
			(xy 450.959474 -420.99611) (xy 450.958988 -421.023361) (xy 450.951232 -421.077309) (xy 450.935877 -421.129604)
			(xy 450.913235 -421.179181) (xy 450.883769 -421.225031) (xy 450.848078 -421.266222) (xy 450.806887 -421.301913)
			(xy 450.761037 -421.331379) (xy 450.71146 -421.354021) (xy 450.659165 -421.369376) (xy 450.605217 -421.377132)
			(xy 450.550715 -421.377132) (xy 450.496767 -421.369376) (xy 450.444472 -421.354021) (xy 450.394895 -421.331379)
			(xy 450.349045 -421.301913) (xy 450.307854 -421.266222) (xy 450.272163 -421.225031) (xy 450.242697 -421.179181)
			(xy 450.220055 -421.129604) (xy 450.2047 -421.077309) (xy 450.196944 -421.023361) (xy 450.196458 -420.99611)
			(xy 449.035029 -420.99611) (xy 450.759322 -422.720516) (xy 450.766165 -422.727914) (xy 450.773882 -422.746515)
			(xy 450.774308 -422.756584) (xy 450.774308 -423.556738) (xy 456.285335 -423.556738) (xy 456.285335 -423.427598)
			(xy 456.293285 -423.298703) (xy 456.309155 -423.170543) (xy 456.332884 -423.043602) (xy 456.364383 -422.918363)
			(xy 456.403532 -422.7953) (xy 456.450183 -422.674881) (xy 456.504158 -422.557562) (xy 456.565253 -422.443788)
			(xy 456.633236 -422.333991) (xy 456.70785 -422.228588) (xy 456.788811 -422.127978) (xy 456.875811 -422.032543)
			(xy 456.968522 -421.942644) (xy 457.066592 -421.858623) (xy 457.169647 -421.780799) (xy 457.277298 -421.709467)
			(xy 457.389137 -421.644897) (xy 457.504738 -421.587335) (xy 457.623663 -421.536998) (xy 457.745462 -421.494078)
			(xy 457.869672 -421.458737) (xy 457.995821 -421.43111) (xy 458.123433 -421.411301) (xy 458.252022 -421.399385)
			(xy 458.3811 -421.395409) (xy 458.510178 -421.399385) (xy 458.638767 -421.411301) (xy 458.766379 -421.43111)
			(xy 458.892528 -421.458737) (xy 459.016738 -421.494078) (xy 459.138537 -421.536998) (xy 459.257462 -421.587335)
			(xy 459.373063 -421.644897) (xy 459.484902 -421.709467) (xy 459.592553 -421.780799) (xy 459.695608 -421.858623)
			(xy 459.793678 -421.942644) (xy 459.886389 -422.032543) (xy 459.973389 -422.127978) (xy 460.05435 -422.228588)
			(xy 460.128964 -422.333991) (xy 460.196947 -422.443788) (xy 460.258042 -422.557562) (xy 460.312017 -422.674881)
			(xy 460.358668 -422.7953) (xy 460.397817 -422.918363) (xy 460.429316 -423.043602) (xy 460.453045 -423.170543)
			(xy 460.468915 -423.298703) (xy 460.476865 -423.427598) (xy 460.477362 -423.492168) (xy 460.476865 -423.556738)
			(xy 460.468915 -423.685633) (xy 460.453045 -423.813793) (xy 460.429316 -423.940734) (xy 460.397817 -424.065973)
			(xy 460.358668 -424.189036) (xy 460.312017 -424.309455) (xy 460.258042 -424.426774) (xy 460.196947 -424.540548)
			(xy 460.128964 -424.650345) (xy 460.05435 -424.755748) (xy 459.973389 -424.856358) (xy 459.886389 -424.951793)
			(xy 459.793678 -425.041692) (xy 459.695608 -425.125713) (xy 459.592553 -425.203537) (xy 459.484902 -425.274869)
			(xy 459.373063 -425.339439) (xy 459.257462 -425.397001) (xy 459.138537 -425.447338) (xy 459.016738 -425.490258)
			(xy 458.892528 -425.525599) (xy 458.766379 -425.553226) (xy 458.638767 -425.573035) (xy 458.510178 -425.584951)
			(xy 458.3811 -425.588928) (xy 458.252022 -425.584951) (xy 458.123433 -425.573035) (xy 457.995821 -425.553226)
			(xy 457.869672 -425.525599) (xy 457.745462 -425.490258) (xy 457.623663 -425.447338) (xy 457.504738 -425.397001)
			(xy 457.389137 -425.339439) (xy 457.277298 -425.274869) (xy 457.169647 -425.203537) (xy 457.066592 -425.125713)
			(xy 456.968522 -425.041692) (xy 456.875811 -424.951793) (xy 456.788811 -424.856358) (xy 456.70785 -424.755748)
			(xy 456.633236 -424.650345) (xy 456.565253 -424.540548) (xy 456.504158 -424.426774) (xy 456.450183 -424.309455)
			(xy 456.403532 -424.189036) (xy 456.364383 -424.065973) (xy 456.332884 -423.940734) (xy 456.309155 -423.813793)
			(xy 456.293285 -423.685633) (xy 456.285335 -423.556738) (xy 450.774308 -423.556738) (xy 450.774308 -424.617642)
			(xy 450.774752 -424.628077) (xy 450.783035 -424.64723) (xy 450.79031 -424.654726) (xy 450.810675 -424.6745)
			(xy 450.84589 -424.719018) (xy 450.874119 -424.768262) (xy 450.894739 -424.821146) (xy 450.907296 -424.876502)
			(xy 450.911512 -424.933107) (xy 450.907294 -424.989712) (xy 450.894735 -425.045067) (xy 450.874113 -425.09795)
			(xy 450.845882 -425.147194) (xy 450.810666 -425.19171) (xy 450.79031 -425.211494) (xy 450.783058 -425.219)
			(xy 450.774805 -425.238151) (xy 450.774308 -425.248578) (xy 450.774308 -425.515786) (xy 450.774792 -425.526294)
			(xy 450.783179 -425.545562) (xy 450.798591 -425.559848) (xy 450.808344 -425.563792) (xy 450.834303 -425.573416)
			(xy 450.883334 -425.599123) (xy 450.928134 -425.631648) (xy 450.967763 -425.670307) (xy 451.001388 -425.714289)
			(xy 451.028302 -425.762668) (xy 451.047941 -425.81443) (xy 451.059891 -425.868487) (xy 451.063902 -425.923703)
			(xy 451.05989 -425.97892) (xy 451.047939 -426.032976) (xy 451.028299 -426.084738) (xy 451.001384 -426.133117)
			(xy 450.967759 -426.177098) (xy 450.928129 -426.215756) (xy 450.883328 -426.24828) (xy 450.834297 -426.273987)
			(xy 450.808344 -426.283628) (xy 450.798627 -426.287631) (xy 450.78324 -426.301908) (xy 450.774835 -426.32114)
			(xy 450.774308 -426.331634) (xy 450.774308 -426.60443) (xy 450.774968 -426.617075) (xy 450.786975 -426.639334)
			(xy 450.797168 -426.646848) (xy 450.81934 -426.66207) (xy 450.859562 -426.697774) (xy 450.894374 -426.73877)
			(xy 450.923088 -426.784245) (xy 450.945137 -426.8333) (xy 450.960082 -426.884964) (xy 450.967629 -426.938214)
			(xy 450.967629 -426.991997) (xy 450.96008 -427.045247) (xy 450.945133 -427.09691) (xy 450.923083 -427.145965)
			(xy 450.894367 -427.191439) (xy 450.859554 -427.232434) (xy 450.819332 -427.268137) (xy 450.797168 -427.283372)
			(xy 450.786982 -427.290891) (xy 450.774984 -427.313148) (xy 450.774308 -427.32579) (xy 450.774308 -427.848268)
			(xy 450.77389 -427.858339) (xy 450.766167 -427.876938) (xy 450.759322 -427.884336) (xy 450.254116 -428.389542)
			(xy 450.246709 -428.396373) (xy 450.228115 -428.404097) (xy 450.218048 -428.404528) (xy 446.982088 -428.404528)
			(xy 446.972016 -428.404128) (xy 446.953417 -428.396391) (xy 446.94602 -428.389542) (xy 446.528698 -427.97222)
			(xy 446.521874 -427.964807) (xy 446.514145 -427.946218) (xy 446.513712 -427.936152) (xy 446.513712 -422.136316)
			(xy 446.513302 -422.126245) (xy 446.505573 -422.107645) (xy 446.498726 -422.100248) (xy 446.423542 -422.025064)
			(xy 446.416071 -422.018358) (xy 446.397504 -422.010774) (xy 446.387474 -422.010332) (xy 443.000638 -422.010332)
			(xy 442.990569 -422.009905) (xy 442.97197 -422.002187) (xy 442.96457 -421.995346) (xy 442.801502 -421.832278)
			(xy 442.794098 -421.825443) (xy 442.775502 -421.817721) (xy 442.765434 -421.817292) (xy 442.399166 -421.817292)
			(xy 442.369189 -421.816708) (xy 442.309974 -421.807314) (xy 442.252956 -421.788777) (xy 442.199538 -421.761553)
			(xy 442.151033 -421.726312) (xy 442.129418 -421.705532) (xy 441.099702 -420.675816) (xy 441.078954 -420.654254)
			(xy 441.043819 -420.605821) (xy 441.016673 -420.552497) (xy 440.998182 -420.495589) (xy 440.9888 -420.436494)
			(xy 440.988196 -420.406576) (xy 440.988196 -420.075868) (xy 440.987663 -420.064754) (xy 440.9783 -420.044596)
			(xy 440.970162 -420.037006) (xy 440.91098 -419.986968) (xy 440.902243 -419.980246) (xy 440.88104 -419.974311)
			(xy 440.870086 -419.975538) (xy 440.869832 -419.975538) (xy 440.854448 -419.977917) (xy 440.823422 -419.980463)
			(xy 440.807856 -419.980618) (xy 440.807602 -419.980618) (xy 440.780351 -419.98012) (xy 440.726404 -419.972364)
			(xy 440.674111 -419.95701) (xy 440.624534 -419.93437) (xy 440.578684 -419.904905) (xy 440.537494 -419.869214)
			(xy 440.501802 -419.828026) (xy 440.472336 -419.782177) (xy 440.449694 -419.732601) (xy 440.434338 -419.680307)
			(xy 440.42658 -419.626361) (xy 440.426094 -419.59911) (xy 440.426528 -419.573421) (xy 440.433422 -419.522507)
			(xy 440.447088 -419.472979) (xy 440.467277 -419.425734) (xy 440.493625 -419.381625) (xy 440.525654 -419.341453)
			(xy 440.562786 -419.305942) (xy 440.58332 -419.2905) (xy 440.592464 -419.283896) (xy 440.603386 -419.264592)
			(xy 440.610244 -419.176454) (xy 440.610563 -419.165426) (xy 440.602918 -419.144754) (xy 440.595512 -419.136576)
			(xy 440.026806 -418.56787) (xy 440.017585 -418.559668) (xy 439.994104 -418.552221) (xy 439.981848 -418.553646)
			(xy 439.90006 -418.568124) (xy 439.888076 -418.570988) (xy 439.868569 -418.58598) (xy 439.862722 -418.596826)
			(xy 439.850888 -418.621202) (xy 439.821332 -418.666617) (xy 439.785646 -418.707392) (xy 439.744549 -418.742707)
			(xy 439.698869 -418.77185) (xy 439.649524 -418.794237) (xy 439.597508 -418.809414) (xy 439.543867 -418.817079)
			(xy 439.516774 -418.817552) (xy 439.489524 -418.817047) (xy 439.435579 -418.809288) (xy 439.383288 -418.793931)
			(xy 439.333713 -418.77129) (xy 439.287865 -418.741826) (xy 439.246676 -418.706136) (xy 439.210985 -418.664949)
			(xy 439.181518 -418.619103) (xy 439.158875 -418.569529) (xy 439.143516 -418.517238) (xy 439.135755 -418.463294)
			(xy 439.135266 -418.436044) (xy 439.135731 -418.408952) (xy 439.143405 -418.355314) (xy 439.158589 -418.303302)
			(xy 439.18098 -418.25396) (xy 439.210125 -418.208283) (xy 439.245439 -418.167188) (xy 439.286212 -418.131503)
			(xy 439.331624 -418.101944) (xy 439.355992 -418.090096) (xy 439.366972 -418.084416) (xy 439.382012 -418.064827)
			(xy 439.384694 -418.052758) (xy 439.399172 -417.97097) (xy 439.400645 -417.958711) (xy 439.393189 -417.93521)
			(xy 439.384948 -417.926012) (xy 438.780682 -417.321746) (xy 438.759963 -417.300158) (xy 438.72482 -417.251733)
			(xy 438.697667 -417.198416) (xy 438.67917 -417.141514) (xy 438.669783 -417.082422) (xy 438.669176 -417.052506)
			(xy 437.795162 -417.052506) (xy 437.795162 -418.436044) (xy 438.118756 -418.436044) (xy 438.122827 -418.380422)
			(xy 438.134953 -418.325985) (xy 438.154876 -418.273894) (xy 438.182172 -418.225259) (xy 438.216258 -418.181116)
			(xy 438.256407 -418.142407) (xy 438.301765 -418.109956) (xy 438.351365 -418.084455) (xy 438.404149 -418.066448)
			(xy 438.458992 -418.056318) (xy 438.514726 -418.054281) (xy 438.570163 -418.060381) (xy 438.62412 -418.074487)
			(xy 438.675449 -418.096299) (xy 438.723055 -418.125353) (xy 438.765923 -418.161028) (xy 438.80314 -418.202565)
			(xy 438.833913 -418.249078) (xy 438.857585 -418.299575) (xy 438.873653 -418.352982) (xy 438.881773 -418.408158)
			(xy 438.882282 -418.436044) (xy 438.881773 -418.46393) (xy 438.873653 -418.519106) (xy 438.857585 -418.572513)
			(xy 438.833913 -418.62301) (xy 438.80314 -418.669523) (xy 438.765923 -418.71106) (xy 438.723055 -418.746735)
			(xy 438.675449 -418.775789) (xy 438.62412 -418.797601) (xy 438.570163 -418.811707) (xy 438.514726 -418.817807)
			(xy 438.458992 -418.81577) (xy 438.404149 -418.80564) (xy 438.351365 -418.787633) (xy 438.301765 -418.762132)
			(xy 438.256407 -418.729681) (xy 438.216258 -418.690972) (xy 438.182172 -418.646829) (xy 438.154876 -418.598194)
			(xy 438.134953 -418.546103) (xy 438.122827 -418.491666) (xy 438.118756 -418.436044) (xy 437.795162 -418.436044)
			(xy 437.795162 -420.86911) (xy 440.180982 -420.86911) (xy 440.185053 -420.813488) (xy 440.197179 -420.759051)
			(xy 440.217102 -420.70696) (xy 440.244398 -420.658325) (xy 440.278484 -420.614182) (xy 440.318633 -420.575473)
			(xy 440.363991 -420.543022) (xy 440.413591 -420.517521) (xy 440.466375 -420.499514) (xy 440.521218 -420.489384)
			(xy 440.576952 -420.487347) (xy 440.632389 -420.493447) (xy 440.686346 -420.507553) (xy 440.737675 -420.529365)
			(xy 440.785281 -420.558419) (xy 440.828149 -420.594094) (xy 440.865366 -420.635631) (xy 440.896139 -420.682144)
			(xy 440.919811 -420.732641) (xy 440.935879 -420.786048) (xy 440.943999 -420.841224) (xy 440.944508 -420.86911)
			(xy 440.943999 -420.896996) (xy 440.935879 -420.952172) (xy 440.919811 -421.005579) (xy 440.896139 -421.056076)
			(xy 440.865366 -421.102589) (xy 440.828149 -421.144126) (xy 440.785281 -421.179801) (xy 440.737675 -421.208855)
			(xy 440.686346 -421.230667) (xy 440.632389 -421.244773) (xy 440.576952 -421.250873) (xy 440.521218 -421.248836)
			(xy 440.466375 -421.238706) (xy 440.413591 -421.220699) (xy 440.363991 -421.195198) (xy 440.318633 -421.162747)
			(xy 440.278484 -421.124038) (xy 440.244398 -421.079895) (xy 440.217102 -421.03126) (xy 440.197179 -420.979169)
			(xy 440.185053 -420.924732) (xy 440.180982 -420.86911) (xy 437.795162 -420.86911) (xy 437.795162 -423.215562)
			(xy 440.204098 -423.215562) (xy 440.204539 -423.188278) (xy 440.212331 -423.134267) (xy 440.227736 -423.081918)
			(xy 440.25044 -423.032296) (xy 440.279981 -422.986414) (xy 440.315756 -422.945208) (xy 440.357035 -422.909517)
			(xy 440.402977 -422.880069) (xy 440.427618 -422.868344) (xy 440.44102 -422.861668) (xy 440.463477 -422.841883)
			(xy 440.479241 -422.816442) (xy 440.486961 -422.787526) (xy 440.485975 -422.757613) (xy 440.476368 -422.729268)
			(xy 440.458964 -422.70492) (xy 440.44743 -422.69537) (xy 440.424753 -422.677154) (xy 440.384614 -422.63506)
			(xy 440.351326 -422.587363) (xy 440.325662 -422.535167) (xy 440.308214 -422.479682) (xy 440.299387 -422.422192)
			(xy 440.29884 -422.39311) (xy 440.299326 -422.365859) (xy 440.307082 -422.311911) (xy 440.322437 -422.259616)
			(xy 440.345079 -422.210039) (xy 440.374545 -422.164189) (xy 440.410236 -422.122998) (xy 440.451427 -422.087307)
			(xy 440.497277 -422.057841) (xy 440.546854 -422.035199) (xy 440.599149 -422.019844) (xy 440.653097 -422.012088)
			(xy 440.707599 -422.012088) (xy 440.761547 -422.019844) (xy 440.813842 -422.035199) (xy 440.863419 -422.057841)
			(xy 440.909269 -422.087307) (xy 440.95046 -422.122998) (xy 440.986151 -422.164189) (xy 441.015617 -422.210039)
			(xy 441.038259 -422.259616) (xy 441.053614 -422.311911) (xy 441.06137 -422.365859) (xy 441.061856 -422.39311)
			(xy 441.061419 -422.420395) (xy 441.05363 -422.474406) (xy 441.038226 -422.526757) (xy 441.015522 -422.57638)
			(xy 440.98598 -422.622263) (xy 440.950204 -422.663469) (xy 440.908923 -422.699159) (xy 440.862979 -422.728605)
			(xy 440.838336 -422.740328) (xy 440.824956 -422.747048) (xy 440.802492 -422.76682) (xy 440.786721 -422.792252)
			(xy 440.778996 -422.821163) (xy 440.779978 -422.851072) (xy 440.789584 -422.879414) (xy 440.80699 -422.903756)
			(xy 440.818524 -422.913302) (xy 440.841247 -422.931463) (xy 440.881381 -422.97357) (xy 440.914661 -423.021279)
			(xy 440.940317 -423.073485) (xy 440.957756 -423.128979) (xy 440.966572 -423.186477) (xy 440.967114 -423.215562)
			(xy 440.966628 -423.242813) (xy 440.958872 -423.296761) (xy 440.943517 -423.349056) (xy 440.920875 -423.398633)
			(xy 440.891409 -423.444483) (xy 440.855718 -423.485674) (xy 440.814527 -423.521365) (xy 440.768677 -423.550831)
			(xy 440.7191 -423.573473) (xy 440.666805 -423.588828) (xy 440.612857 -423.596584) (xy 440.558355 -423.596584)
			(xy 440.504407 -423.588828) (xy 440.452112 -423.573473) (xy 440.402535 -423.550831) (xy 440.356685 -423.521365)
			(xy 440.315494 -423.485674) (xy 440.279803 -423.444483) (xy 440.250337 -423.398633) (xy 440.227695 -423.349056)
			(xy 440.21234 -423.296761) (xy 440.204584 -423.242813) (xy 440.204098 -423.215562) (xy 437.795162 -423.215562)
			(xy 437.795162 -424.18635) (xy 437.795596 -424.196415) (xy 437.80333 -424.215) (xy 437.810148 -424.222418)
			(xy 438.004204 -424.416474) (xy 438.009908 -424.421811) (xy 438.023747 -424.429043) (xy 438.031382 -424.430698)
			(xy 438.059678 -424.436406) (xy 438.114251 -424.455213) (xy 438.165369 -424.482024) (xy 438.211865 -424.516229)
			(xy 438.252681 -424.557045) (xy 438.286883 -424.603543) (xy 438.313693 -424.654662) (xy 438.332498 -424.709235)
			(xy 438.338214 -424.73753) (xy 438.339862 -424.745166) (xy 438.347108 -424.758996) (xy 438.352438 -424.764708)
			(xy 438.64784 -425.06011) (xy 440.298584 -425.06011) (xy 440.302655 -425.004488) (xy 440.314781 -424.950051)
			(xy 440.334704 -424.89796) (xy 440.362 -424.849325) (xy 440.396086 -424.805182) (xy 440.436235 -424.766473)
			(xy 440.481593 -424.734022) (xy 440.531193 -424.708521) (xy 440.583977 -424.690514) (xy 440.63882 -424.680384)
			(xy 440.694554 -424.678347) (xy 440.749991 -424.684447) (xy 440.803948 -424.698553) (xy 440.855277 -424.720365)
			(xy 440.902883 -424.749419) (xy 440.945751 -424.785094) (xy 440.982968 -424.826631) (xy 441.013741 -424.873144)
			(xy 441.037413 -424.923641) (xy 441.053481 -424.977048) (xy 441.061601 -425.032224) (xy 441.06211 -425.06011)
			(xy 441.061601 -425.087996) (xy 441.053481 -425.143172) (xy 441.037413 -425.196579) (xy 441.013741 -425.247076)
			(xy 440.982968 -425.293589) (xy 440.945751 -425.335126) (xy 440.902883 -425.370801) (xy 440.855277 -425.399855)
			(xy 440.803948 -425.421667) (xy 440.749991 -425.435773) (xy 440.694554 -425.441873) (xy 440.63882 -425.439836)
			(xy 440.583977 -425.429706) (xy 440.531193 -425.411699) (xy 440.481593 -425.386198) (xy 440.436235 -425.353747)
			(xy 440.396086 -425.315038) (xy 440.362 -425.270895) (xy 440.334704 -425.22226) (xy 440.314781 -425.170169)
			(xy 440.302655 -425.115732) (xy 440.298584 -425.06011) (xy 438.64784 -425.06011) (xy 440.187588 -426.599858)
			(xy 440.195444 -426.606923) (xy 440.215124 -426.614545) (xy 440.225688 -426.61459) (xy 440.311286 -426.61078)
			(xy 440.33059 -426.601382) (xy 440.337194 -426.593254) (xy 440.35542 -426.572255) (xy 440.396915 -426.535244)
			(xy 440.443344 -426.504651) (xy 440.493724 -426.481124) (xy 440.546986 -426.465162) (xy 440.602001 -426.457103)
			(xy 440.629802 -426.456602) (xy 440.657054 -426.457065) (xy 440.711005 -426.464823) (xy 440.763302 -426.480179)
			(xy 440.812881 -426.502822) (xy 440.858733 -426.53229) (xy 440.899925 -426.567984) (xy 440.935617 -426.609177)
			(xy 440.965084 -426.65503) (xy 440.987725 -426.70461) (xy 441.00308 -426.756907) (xy 441.010835 -426.810857)
			(xy 441.01131 -426.83811) (xy 441.010807 -426.865911) (xy 441.002739 -426.920924) (xy 440.986774 -426.974185)
			(xy 440.963251 -427.024566) (xy 440.932667 -427.071001) (xy 440.89567 -427.112507) (xy 440.874658 -427.130718)
			(xy 440.86653 -427.137322) (xy 440.857132 -427.156626) (xy 440.853322 -427.242224) (xy 440.853378 -427.252787)
			(xy 440.860997 -427.272463) (xy 440.868054 -427.280324) (xy 441.913584 -428.325854) (xy 443.607365 -428.325854)
			(xy 443.607365 -428.271346) (xy 443.615123 -428.217392) (xy 443.630481 -428.165093) (xy 443.653126 -428.115511)
			(xy 443.682598 -428.069657) (xy 443.718295 -428.028464) (xy 443.759492 -427.992771) (xy 443.805349 -427.963305)
			(xy 443.854934 -427.940666) (xy 443.907236 -427.925314) (xy 443.96119 -427.917562) (xy 443.988444 -427.917102)
			(xy 444.017293 -427.917646) (xy 444.074335 -427.926313) (xy 444.129421 -427.943475) (xy 444.181293 -427.968738)
			(xy 444.228767 -428.001527) (xy 444.270761 -428.041093) (xy 444.306316 -428.086533) (xy 444.32093 -428.111412)
			(xy 444.3281 -428.123128) (xy 444.347478 -428.142576) (xy 444.371341 -428.156153) (xy 444.39796 -428.162874)
			(xy 444.425407 -428.162254) (xy 444.451695 -428.154337) (xy 444.47492 -428.139697) (xy 444.4934 -428.119393)
			(xy 444.5 -428.107348) (xy 444.512235 -428.084067) (xy 444.54219 -428.040838) (xy 444.577801 -428.002135)
			(xy 444.618393 -427.968693) (xy 444.663195 -427.941146) (xy 444.711358 -427.920018) (xy 444.761968 -427.905708)
			(xy 444.814063 -427.898489) (xy 444.84036 -427.898052) (xy 444.867612 -427.898593) (xy 444.921561 -427.906344)
			(xy 444.973859 -427.921695) (xy 445.023439 -427.944333) (xy 445.069292 -427.973797) (xy 445.110485 -428.009487)
			(xy 445.146179 -428.050676) (xy 445.175648 -428.096526) (xy 445.198291 -428.146104) (xy 445.213647 -428.198399)
			(xy 445.221405 -428.252348) (xy 445.221405 -428.306852) (xy 445.213647 -428.360801) (xy 445.198291 -428.413096)
			(xy 445.175648 -428.462674) (xy 445.146179 -428.508524) (xy 445.110485 -428.549713) (xy 445.069292 -428.585403)
			(xy 445.023439 -428.614867) (xy 444.973859 -428.637505) (xy 444.921561 -428.652856) (xy 444.867612 -428.660607)
			(xy 444.84036 -428.661068) (xy 444.811511 -428.660536) (xy 444.754467 -428.651868) (xy 444.69938 -428.634706)
			(xy 444.647508 -428.609441) (xy 444.600033 -428.57665) (xy 444.55804 -428.537081) (xy 444.522487 -428.491638)
			(xy 444.507874 -428.466758) (xy 444.500695 -428.45505) (xy 444.481316 -428.435607) (xy 444.457456 -428.422035)
			(xy 444.43084 -428.415316) (xy 444.403397 -428.415935) (xy 444.377112 -428.423849) (xy 444.353888 -428.438484)
			(xy 444.335406 -428.458781) (xy 444.328804 -428.470822) (xy 444.316553 -428.494094) (xy 444.286602 -428.537325)
			(xy 444.250993 -428.576029) (xy 444.210404 -428.609472) (xy 444.165604 -428.63702) (xy 444.117443 -428.65815)
			(xy 444.066835 -428.672461) (xy 444.01474 -428.679681) (xy 443.988444 -428.680118) (xy 443.96119 -428.679638)
			(xy 443.907236 -428.671886) (xy 443.854934 -428.656534) (xy 443.805349 -428.633895) (xy 443.759492 -428.604429)
			(xy 443.718295 -428.568736) (xy 443.682598 -428.527543) (xy 443.653126 -428.481689) (xy 443.630481 -428.432107)
			(xy 443.615123 -428.379808) (xy 443.607365 -428.325854) (xy 441.913584 -428.325854) (xy 443.598554 -430.010824)
			(xy 449.461634 -430.010824) (xy 449.465705 -429.955202) (xy 449.477831 -429.900765) (xy 449.497754 -429.848674)
			(xy 449.52505 -429.800039) (xy 449.559136 -429.755896) (xy 449.599285 -429.717187) (xy 449.644643 -429.684736)
			(xy 449.694243 -429.659235) (xy 449.747027 -429.641228) (xy 449.80187 -429.631098) (xy 449.857604 -429.629061)
			(xy 449.913041 -429.635161) (xy 449.966998 -429.649267) (xy 450.018327 -429.671079) (xy 450.065933 -429.700133)
			(xy 450.108801 -429.735808) (xy 450.146018 -429.777345) (xy 450.176791 -429.823858) (xy 450.200463 -429.874355)
			(xy 450.216531 -429.927762) (xy 450.224651 -429.982938) (xy 450.22516 -430.010824) (xy 450.224651 -430.03871)
			(xy 450.216531 -430.093886) (xy 450.200463 -430.147293) (xy 450.176791 -430.19779) (xy 450.146018 -430.244303)
			(xy 450.108801 -430.28584) (xy 450.065933 -430.321515) (xy 450.018327 -430.350569) (xy 449.966998 -430.372381)
			(xy 449.913041 -430.386487) (xy 449.857604 -430.392587) (xy 449.80187 -430.39055) (xy 449.747027 -430.38042)
			(xy 449.694243 -430.362413) (xy 449.644643 -430.336912) (xy 449.599285 -430.304461) (xy 449.559136 -430.265752)
			(xy 449.52505 -430.221609) (xy 449.497754 -430.172974) (xy 449.477831 -430.120883) (xy 449.465705 -430.066446)
			(xy 449.461634 -430.010824) (xy 443.598554 -430.010824) (xy 444.033148 -430.445418) (xy 444.043816 -430.445418)
			(xy 445.126618 -431.52822) (xy 445.13347 -431.535616) (xy 445.14121 -431.554215) (xy 445.141604 -431.564288)
			(xy 445.141604 -435.677116) (xy 445.799708 -435.677116) (xy 445.799708 -435.522564) (xy 445.807664 -435.368217)
			(xy 445.823555 -435.214484) (xy 445.847339 -435.061773) (xy 445.878953 -434.910489) (xy 445.918313 -434.761033)
			(xy 445.965314 -434.613801) (xy 446.019833 -434.469184) (xy 446.081724 -434.327565) (xy 446.150823 -434.189321)
			(xy 446.226947 -434.054816) (xy 446.309895 -433.924409) (xy 446.399446 -433.798445) (xy 446.495362 -433.677257)
			(xy 446.59739 -433.561169) (xy 446.705259 -433.450486) (xy 446.818682 -433.345503) (xy 446.93736 -433.246498)
			(xy 447.060976 -433.153733) (xy 447.189205 -433.067456) (xy 447.321704 -432.987893) (xy 447.458124 -432.915258)
			(xy 447.598102 -432.849741) (xy 447.741268 -432.791517) (xy 447.88724 -432.74074) (xy 448.035633 -432.697545)
			(xy 448.186053 -432.662046) (xy 448.338101 -432.634338) (xy 448.491374 -432.614494) (xy 448.645465 -432.602566)
			(xy 448.799966 -432.598587) (xy 448.954467 -432.602566) (xy 449.108558 -432.614494) (xy 449.261831 -432.634338)
			(xy 449.413879 -432.662046) (xy 449.564299 -432.697545) (xy 449.712692 -432.74074) (xy 449.858664 -432.791517)
			(xy 450.00183 -432.849741) (xy 450.141808 -432.915258) (xy 450.278228 -432.987893) (xy 450.410727 -433.067456)
			(xy 450.538956 -433.153733) (xy 450.662572 -433.246498) (xy 450.78125 -433.345503) (xy 450.894673 -433.450486)
			(xy 451.002542 -433.561169) (xy 451.10457 -433.677257) (xy 451.200486 -433.798445) (xy 451.290037 -433.924409)
			(xy 451.372985 -434.054816) (xy 451.449109 -434.189321) (xy 451.518208 -434.327565) (xy 451.580099 -434.469184)
			(xy 451.634618 -434.613801) (xy 451.681619 -434.761033) (xy 451.720979 -434.910489) (xy 451.752593 -435.061773)
			(xy 451.776377 -435.214484) (xy 451.792268 -435.368217) (xy 451.800224 -435.522564) (xy 451.800722 -435.59984)
			(xy 451.800224 -435.677116) (xy 451.792268 -435.831463) (xy 451.776377 -435.985196) (xy 451.752593 -436.137907)
			(xy 451.720979 -436.289191) (xy 451.681619 -436.438647) (xy 451.634618 -436.585879) (xy 451.580099 -436.730496)
			(xy 451.518208 -436.872115) (xy 451.449109 -437.010359) (xy 451.372985 -437.144864) (xy 451.290037 -437.275271)
			(xy 451.200486 -437.401235) (xy 451.10457 -437.522423) (xy 451.002542 -437.638511) (xy 450.894673 -437.749194)
			(xy 450.78125 -437.854177) (xy 450.662572 -437.953182) (xy 450.538956 -438.045947) (xy 450.410727 -438.132224)
			(xy 450.278228 -438.211787) (xy 450.141808 -438.284422) (xy 450.00183 -438.349939) (xy 449.858664 -438.408163)
			(xy 449.712692 -438.45894) (xy 449.564299 -438.502135) (xy 449.413879 -438.537634) (xy 449.261831 -438.565342)
			(xy 449.108558 -438.585186) (xy 448.954467 -438.597114) (xy 448.799966 -438.601094) (xy 448.645465 -438.597114)
			(xy 448.491374 -438.585186) (xy 448.338101 -438.565342) (xy 448.186053 -438.537634) (xy 448.035633 -438.502135)
			(xy 447.88724 -438.45894) (xy 447.741268 -438.408163) (xy 447.598102 -438.349939) (xy 447.458124 -438.284422)
			(xy 447.321704 -438.211787) (xy 447.189205 -438.132224) (xy 447.060976 -438.045947) (xy 446.93736 -437.953182)
			(xy 446.818682 -437.854177) (xy 446.705259 -437.749194) (xy 446.59739 -437.638511) (xy 446.495362 -437.522423)
			(xy 446.399446 -437.401235) (xy 446.309895 -437.275271) (xy 446.226947 -437.144864) (xy 446.150823 -437.010359)
			(xy 446.081724 -436.872115) (xy 446.019833 -436.730496) (xy 445.965314 -436.585879) (xy 445.918313 -436.438647)
			(xy 445.878953 -436.289191) (xy 445.847339 -436.137907) (xy 445.823555 -435.985196) (xy 445.807664 -435.831463)
			(xy 445.799708 -435.677116) (xy 445.141604 -435.677116) (xy 445.141604 -439.978546) (xy 445.142036 -439.988612)
			(xy 445.149762 -440.007204) (xy 445.15659 -440.014614) (xy 445.748664 -440.606688) (xy 445.756066 -440.613525)
			(xy 445.774664 -440.621238) (xy 445.784732 -440.621674)
		)
		(stroke
			(width 0)
			(type solid)
		)
		(fill yes)
		(layer "In15.Cu")
		(net "GND")
	)
	(gr_poly
		(pts
			(xy 418.162232 -440.719972) (xy 418.170764 -440.719703) (xy 418.186905 -440.71418) (xy 418.200311 -440.70363)
			(xy 418.205158 -440.696604) (xy 418.258244 -440.613038) (xy 418.259768 -440.58713) (xy 418.25418 -440.575192)
			(xy 418.242708 -440.54969) (xy 418.226527 -440.496163) (xy 418.21835 -440.440845) (xy 418.217858 -440.412886)
			(xy 418.218344 -440.385635) (xy 418.2261 -440.331687) (xy 418.241455 -440.279392) (xy 418.264097 -440.229815)
			(xy 418.293563 -440.183965) (xy 418.329254 -440.142774) (xy 418.370445 -440.107083) (xy 418.416295 -440.077617)
			(xy 418.465872 -440.054975) (xy 418.518167 -440.03962) (xy 418.572115 -440.031864) (xy 418.626617 -440.031864)
			(xy 418.680565 -440.03962) (xy 418.73286 -440.054975) (xy 418.782437 -440.077617) (xy 418.828287 -440.107083)
			(xy 418.869478 -440.142774) (xy 418.905169 -440.183965) (xy 418.934635 -440.229815) (xy 418.957277 -440.279392)
			(xy 418.972632 -440.331687) (xy 418.980388 -440.385635) (xy 418.980874 -440.412886) (xy 418.98036 -440.440843)
			(xy 418.972161 -440.496153) (xy 418.955994 -440.549679) (xy 418.944552 -440.575192) (xy 418.938964 -440.58713)
			(xy 418.940488 -440.613038) (xy 418.993574 -440.696604) (xy 418.998453 -440.703603) (xy 419.011859 -440.714142)
			(xy 419.027974 -440.719717) (xy 419.0365 -440.719972) (xy 444.656464 -440.719972) (xy 444.666426 -440.719486)
			(xy 444.684848 -440.711895) (xy 444.692278 -440.70524) (xy 444.853314 -440.544204) (xy 444.86017 -440.53681)
			(xy 444.86792 -440.518211) (xy 444.8683 -440.508136) (xy 444.8683 -436.090314) (xy 444.86576 -436.08244)
			(xy 444.856504 -436.05301) (xy 444.846545 -435.992128) (xy 444.845948 -435.961282) (xy 444.846563 -435.930438)
			(xy 444.856517 -435.869557) (xy 444.86576 -435.840124) (xy 444.8683 -435.83225) (xy 444.8683 -432.242214)
			(xy 444.867861 -432.232151) (xy 444.860125 -432.213569) (xy 444.853314 -432.206146) (xy 444.49111 -431.843688)
			(xy 438.533032 -425.88561) (xy 438.525709 -425.878798) (xy 438.507284 -425.871058) (xy 438.487299 -425.870981)
			(xy 438.477914 -425.874434) (xy 438.377076 -425.915074) (xy 438.359804 -425.94022) (xy 438.35955 -425.955714)
			(xy 438.358625 -425.98266) (xy 438.350124 -426.035902) (xy 438.334211 -426.087416) (xy 438.311204 -426.136177)
			(xy 438.281561 -426.181213) (xy 438.245873 -426.221627) (xy 438.204851 -426.256613) (xy 438.159311 -426.285476)
			(xy 438.110161 -426.307639) (xy 438.05838 -426.322662) (xy 438.005 -426.330245) (xy 437.978042 -426.330618)
			(xy 437.950787 -426.330158) (xy 437.896831 -426.322406) (xy 437.844527 -426.307054) (xy 437.794941 -426.284414)
			(xy 437.749082 -426.254947) (xy 437.707883 -426.219253) (xy 437.672184 -426.17806) (xy 437.642711 -426.132205)
			(xy 437.620065 -426.082621) (xy 437.604705 -426.03032) (xy 437.596946 -425.976365) (xy 437.596534 -425.94911)
			(xy 437.597004 -425.922161) (xy 437.604602 -425.868801) (xy 437.619632 -425.817042) (xy 437.641797 -425.767912)
			(xy 437.670655 -425.722391) (xy 437.705631 -425.681383) (xy 437.746031 -425.645706) (xy 437.791048 -425.616069)
			(xy 437.839789 -425.593061) (xy 437.891282 -425.577142) (xy 437.944503 -425.568627) (xy 437.971438 -425.567602)
			(xy 437.986932 -425.567348) (xy 438.012078 -425.550076) (xy 438.052718 -425.449238) (xy 438.055992 -425.439825)
			(xy 438.055862 -425.419915) (xy 438.048203 -425.401536) (xy 438.041542 -425.39412) (xy 437.797448 -425.150026)
			(xy 437.790336 -425.14647) (xy 437.763658 -425.132308) (xy 437.714755 -425.096863) (xy 437.672047 -425.054157)
			(xy 437.6366 -425.005256) (xy 437.622442 -424.978576) (xy 437.618886 -424.971464) (xy 437.046878 -424.399456)
			(xy 437.04003 -424.392059) (xy 437.032299 -424.37346) (xy 437.031892 -424.363388) (xy 437.031892 -424.327828)
			(xy 437.009286 -424.300142) (xy 436.991506 -424.296332) (xy 436.960668 -424.289457) (xy 436.900862 -424.269076)
			(xy 436.844043 -424.241442) (xy 436.791086 -424.20698) (xy 436.742808 -424.166221) (xy 436.699953 -424.119794)
			(xy 436.663181 -424.068414) (xy 436.633059 -424.012873) (xy 436.610052 -423.954028) (xy 436.594514 -423.892786)
			(xy 436.586684 -423.83009) (xy 436.586685 -423.766907) (xy 436.594514 -423.704211) (xy 436.610053 -423.642969)
			(xy 436.63306 -423.584124) (xy 436.663182 -423.528583) (xy 436.699955 -423.477204) (xy 436.74281 -423.430777)
			(xy 436.791089 -423.390018) (xy 436.844046 -423.355556) (xy 436.900865 -423.327923) (xy 436.960671 -423.307542)
			(xy 436.991506 -423.300652) (xy 437.009286 -423.296842) (xy 437.031892 -423.269156) (xy 437.031892 -410.163518)
			(xy 437.031355 -410.152498) (xy 437.022139 -410.132478) (xy 437.014112 -410.12491) (xy 436.946548 -410.067506)
			(xy 436.925212 -410.06141) (xy 436.914036 -410.063442) (xy 436.898836 -410.065723) (xy 436.868192 -410.068135)
			(xy 436.852822 -410.068268) (xy 436.825569 -410.067806) (xy 436.771618 -410.060051) (xy 436.71932 -410.044697)
			(xy 436.669739 -410.022055) (xy 436.623886 -409.992587) (xy 436.582694 -409.956893) (xy 436.547002 -409.915699)
			(xy 436.517536 -409.869845) (xy 436.494897 -409.820263) (xy 436.479545 -409.767964) (xy 436.471793 -409.714013)
			(xy 436.471314 -409.68676) (xy 436.471823 -409.658123) (xy 436.480376 -409.601491) (xy 436.497299 -409.546775)
			(xy 436.522211 -409.495203) (xy 436.554553 -409.447934) (xy 436.593598 -409.406032) (xy 436.638468 -409.370438)
			(xy 436.663084 -409.355798) (xy 436.670648 -409.351032) (xy 436.68212 -409.337335) (xy 436.688207 -409.320536)
			(xy 436.688484 -409.311602) (xy 436.688484 -409.223718) (xy 436.68819 -409.214782) (xy 436.682135 -409.197971)
			(xy 436.670655 -409.184279) (xy 436.663084 -409.179522) (xy 436.640126 -409.165843) (xy 436.597926 -409.133051)
			(xy 436.560717 -409.094691) (xy 436.529226 -409.051512) (xy 436.504071 -409.004361) (xy 436.485743 -408.954159)
			(xy 436.474603 -408.901891) (xy 436.470866 -408.84858) (xy 436.474608 -408.795269) (xy 436.485754 -408.743002)
			(xy 436.504087 -408.692803) (xy 436.529247 -408.645654) (xy 436.560742 -408.602479) (xy 436.597956 -408.564122)
			(xy 436.640159 -408.531335) (xy 436.663084 -408.517598) (xy 436.670648 -408.512832) (xy 436.68212 -408.499135)
			(xy 436.688207 -408.482336) (xy 436.688484 -408.473402) (xy 436.688484 -408.385518) (xy 436.68819 -408.376582)
			(xy 436.682135 -408.359771) (xy 436.670655 -408.346079) (xy 436.663084 -408.341322) (xy 436.640126 -408.327643)
			(xy 436.597926 -408.294851) (xy 436.560717 -408.256491) (xy 436.529226 -408.213312) (xy 436.504071 -408.166161)
			(xy 436.485743 -408.115959) (xy 436.474603 -408.063691) (xy 436.470866 -408.01038) (xy 436.474608 -407.957069)
			(xy 436.485754 -407.904802) (xy 436.504087 -407.854603) (xy 436.529247 -407.807454) (xy 436.560742 -407.764279)
			(xy 436.597956 -407.725922) (xy 436.640159 -407.693135) (xy 436.663084 -407.679398) (xy 436.670648 -407.674632)
			(xy 436.68212 -407.660935) (xy 436.688207 -407.644136) (xy 436.688484 -407.635202) (xy 436.688484 -407.547318)
			(xy 436.68819 -407.538382) (xy 436.682135 -407.521571) (xy 436.670655 -407.507879) (xy 436.663084 -407.503122)
			(xy 436.640126 -407.489443) (xy 436.597926 -407.456651) (xy 436.560717 -407.418291) (xy 436.529226 -407.375112)
			(xy 436.504071 -407.327961) (xy 436.485743 -407.277759) (xy 436.474603 -407.225491) (xy 436.470866 -407.17218)
			(xy 436.474608 -407.118869) (xy 436.485754 -407.066602) (xy 436.504087 -407.016403) (xy 436.529247 -406.969254)
			(xy 436.560742 -406.926079) (xy 436.597956 -406.887722) (xy 436.640159 -406.854935) (xy 436.663084 -406.841198)
			(xy 436.670648 -406.836432) (xy 436.68212 -406.822735) (xy 436.688207 -406.805936) (xy 436.688484 -406.797002)
			(xy 436.688484 -406.709118) (xy 436.68819 -406.700182) (xy 436.682135 -406.683371) (xy 436.670655 -406.669679)
			(xy 436.663084 -406.664922) (xy 436.638499 -406.650234) (xy 436.593635 -406.614642) (xy 436.554593 -406.572746)
			(xy 436.52225 -406.525486) (xy 436.497333 -406.473924) (xy 436.480401 -406.419217) (xy 436.471834 -406.362594)
			(xy 436.471314 -406.33396) (xy 436.471803 -406.306711) (xy 436.479564 -406.252769) (xy 436.494923 -406.20048)
			(xy 436.517567 -406.15091) (xy 436.547034 -406.105066) (xy 436.582726 -406.063882) (xy 436.623916 -406.028197)
			(xy 436.669764 -405.998737) (xy 436.719339 -405.976101) (xy 436.77163 -405.960751) (xy 436.825573 -405.952999)
			(xy 436.852822 -405.952452) (xy 436.881074 -405.952965) (xy 436.93696 -405.961301) (xy 436.991006 -405.977789)
			(xy 437.042029 -406.002067) (xy 437.088913 -406.033604) (xy 437.110124 -406.052274) (xy 437.117296 -406.058329)
			(xy 437.134781 -406.065118) (xy 437.14416 -406.065482) (xy 437.17464 -406.065482) (xy 437.184673 -406.065046)
			(xy 437.20325 -406.057473) (xy 437.210708 -406.05075) (xy 439.640218 -403.62124) (xy 439.647064 -403.613842)
			(xy 439.654789 -403.595243) (xy 439.655204 -403.585172) (xy 439.655204 -392.001502) (xy 439.654571 -391.990085)
			(xy 439.644673 -391.969507) (xy 439.636154 -391.961878) (xy 439.565288 -391.904982) (xy 439.542936 -391.899648)
			(xy 439.531506 -391.902188) (xy 439.50424 -391.90789) (xy 439.448869 -391.914005) (xy 439.421016 -391.91438)
			(xy 439.387708 -391.913853) (xy 439.321664 -391.905143) (xy 439.257323 -391.887883) (xy 439.195786 -391.86237)
			(xy 439.138109 -391.829039) (xy 439.085277 -391.788462) (xy 439.061352 -391.765282) (xy 439.05424 -391.75817)
			(xy 439.035444 -391.75055) (xy 438.943242 -391.75055) (xy 438.9247 -391.75817) (xy 438.917588 -391.765282)
			(xy 438.893671 -391.788559) (xy 438.840796 -391.829286) (xy 438.783045 -391.862739) (xy 438.72141 -391.888343)
			(xy 438.656955 -391.905658) (xy 438.590787 -391.914385) (xy 438.557416 -391.914888) (xy 438.525454 -391.914408)
			(xy 438.462035 -391.906398) (xy 438.400119 -391.890503) (xy 438.340684 -391.866972) (xy 438.284667 -391.836178)
			(xy 438.232951 -391.798606) (xy 438.186352 -391.754848) (xy 438.145605 -391.705595) (xy 438.111352 -391.651623)
			(xy 438.084134 -391.593783) (xy 438.064381 -391.532988) (xy 438.052402 -391.470197) (xy 438.048388 -391.4064)
			(xy 438.052402 -391.342603) (xy 438.064381 -391.279812) (xy 438.084134 -391.219017) (xy 438.111352 -391.161177)
			(xy 438.145605 -391.107205) (xy 438.186352 -391.057952) (xy 438.232951 -391.014194) (xy 438.284667 -390.976622)
			(xy 438.340684 -390.945828) (xy 438.400119 -390.922297) (xy 438.462035 -390.906402) (xy 438.525454 -390.898392)
			(xy 438.557416 -390.897872) (xy 438.590725 -390.898395) (xy 438.656773 -390.907098) (xy 438.721118 -390.924352)
			(xy 438.782659 -390.949861) (xy 438.840341 -390.98319) (xy 438.893177 -391.023766) (xy 438.91708 -391.04697)
			(xy 438.924192 -391.054082) (xy 438.942988 -391.061702) (xy 439.03519 -391.061702) (xy 439.053732 -391.054082)
			(xy 439.060844 -391.04697) (xy 439.084763 -391.023696) (xy 439.13764 -390.982977) (xy 439.195392 -390.94953)
			(xy 439.257026 -390.923932) (xy 439.321481 -390.906623) (xy 439.387647 -390.897901) (xy 439.421016 -390.897364)
			(xy 439.448869 -390.897755) (xy 439.504238 -390.903866) (xy 439.531506 -390.909556) (xy 439.542936 -390.912096)
			(xy 439.565288 -390.906762) (xy 439.636154 -390.849866) (xy 439.644661 -390.842232) (xy 439.654538 -390.821654)
			(xy 439.655204 -390.810242) (xy 439.655204 -388.740142) (xy 439.655638 -388.730077) (xy 439.663368 -388.711488)
			(xy 439.67019 -388.704074) (xy 440.348624 -388.02564) (xy 440.355469 -388.018242) (xy 440.363194 -387.999643)
			(xy 440.36361 -387.989572) (xy 440.36361 -386.145278) (xy 440.364037 -386.13521) (xy 440.371759 -386.116612)
			(xy 440.378596 -386.10921) (xy 441.468002 -385.019804) (xy 441.474849 -385.012406) (xy 441.482585 -384.993808)
			(xy 441.482988 -384.983736) (xy 441.482988 -376.289062) (xy 441.483418 -376.278995) (xy 441.49114 -376.260399)
			(xy 441.497974 -376.252994) (xy 442.483494 -375.267474) (xy 442.490888 -375.260618) (xy 442.509487 -375.25287)
			(xy 442.519562 -375.252488) (xy 449.620894 -375.252488) (xy 449.630964 -375.252066) (xy 449.649569 -375.244351)
			(xy 449.656962 -375.237502) (xy 454.104502 -370.789962) (xy 454.111342 -370.782561) (xy 454.119062 -370.763963)
			(xy 454.119488 -370.753894) (xy 454.119488 -366.403636) (xy 454.119053 -366.393571) (xy 454.111321 -366.374985)
			(xy 454.104502 -366.367568) (xy 453.680068 -365.943134) (xy 453.672669 -365.936289) (xy 453.654071 -365.928561)
			(xy 453.644 -365.928148) (xy 446.58788 -365.928148) (xy 446.577984 -365.928672) (xy 446.559699 -365.936263)
			(xy 446.55232 -365.94288) (xy 446.550288 -365.944658) (xy 436.153052 -365.944658) (xy 436.142987 -365.945091)
			(xy 436.124401 -365.952825) (xy 436.116984 -365.959644) (xy 433.56657 -368.510058) (xy 433.560728 -368.540284)
			(xy 433.56657 -368.554508) (xy 433.579015 -368.585685) (xy 433.596534 -368.650488) (xy 433.605391 -368.717031)
			(xy 433.60594 -368.750596) (xy 433.605476 -368.781328) (xy 433.598068 -368.842344) (xy 433.58336 -368.902021)
			(xy 433.561566 -368.959491) (xy 433.533004 -369.013916) (xy 433.49809 -369.0645) (xy 433.457333 -369.110508)
			(xy 433.411329 -369.151267) (xy 433.360746 -369.186185) (xy 433.306324 -369.214751) (xy 433.248856 -369.236549)
			(xy 433.189179 -369.251262) (xy 433.128164 -369.258674) (xy 433.097432 -369.259104) (xy 433.063865 -369.258571)
			(xy 432.997316 -369.249737) (xy 432.932512 -369.232206) (xy 432.901344 -369.219734) (xy 432.88712 -369.213892)
			(xy 432.856894 -369.219734) (xy 431.779426 -370.297202) (xy 431.772579 -370.304711) (xy 431.764938 -370.323523)
			(xy 431.76517 -370.343827) (xy 431.768758 -370.353336) (xy 431.812192 -370.454428) (xy 431.838608 -370.471192)
			(xy 431.854102 -370.470684) (xy 431.869088 -370.47043) (xy 431.900626 -370.470905) (xy 431.963219 -370.478705)
			(xy 432.024366 -370.494188) (xy 432.083128 -370.517115) (xy 432.138603 -370.547135) (xy 432.189939 -370.583786)
			(xy 432.236348 -370.626505) (xy 432.277116 -370.674637) (xy 432.311617 -370.727441) (xy 432.339322 -370.784108)
			(xy 432.359805 -370.843766) (xy 432.36998 -370.892281) (xy 447.615812 -370.892281) (xy 447.615812 -370.828359)
			(xy 447.623823 -370.764941) (xy 447.63972 -370.703027) (xy 447.663252 -370.643594) (xy 447.694046 -370.587579)
			(xy 447.731619 -370.535864) (xy 447.775376 -370.489267) (xy 447.824629 -370.448522) (xy 447.8786 -370.414271)
			(xy 447.936439 -370.387054) (xy 447.997232 -370.367301) (xy 448.060022 -370.355323) (xy 448.123818 -370.35131)
			(xy 448.187614 -370.355323) (xy 448.250404 -370.367301) (xy 448.311197 -370.387054) (xy 448.369036 -370.414271)
			(xy 448.423007 -370.448522) (xy 448.47226 -370.489267) (xy 448.516017 -370.535864) (xy 448.55359 -370.587579)
			(xy 448.584384 -370.643594) (xy 448.607916 -370.703027) (xy 448.623813 -370.764941) (xy 448.631824 -370.828359)
			(xy 448.632326 -370.86032) (xy 448.631824 -370.892281) (xy 448.623813 -370.955699) (xy 448.607916 -371.017613)
			(xy 448.584384 -371.077046) (xy 448.55359 -371.133061) (xy 448.516017 -371.184776) (xy 448.47226 -371.231373)
			(xy 448.423007 -371.272118) (xy 448.369036 -371.306369) (xy 448.311197 -371.333586) (xy 448.250404 -371.353339)
			(xy 448.187614 -371.365317) (xy 448.123818 -371.369331) (xy 448.060022 -371.365317) (xy 447.997232 -371.353339)
			(xy 447.936439 -371.333586) (xy 447.8786 -371.306369) (xy 447.824629 -371.272118) (xy 447.775376 -371.231373)
			(xy 447.731619 -371.184776) (xy 447.694046 -371.133061) (xy 447.663252 -371.077046) (xy 447.63972 -371.017613)
			(xy 447.623823 -370.955699) (xy 447.615812 -370.892281) (xy 432.36998 -370.892281) (xy 432.372752 -370.9055)
			(xy 432.377963 -370.968361) (xy 432.375359 -371.031383) (xy 432.36498 -371.0936) (xy 432.346984 -371.154056)
			(xy 432.321649 -371.211821) (xy 432.289364 -371.266008) (xy 432.250624 -371.315787) (xy 432.206024 -371.360391)
			(xy 432.15625 -371.399136) (xy 432.102065 -371.431427) (xy 432.044302 -371.456767) (xy 431.983849 -371.474769)
			(xy 431.921633 -371.485154) (xy 431.858611 -371.487764) (xy 431.795749 -371.482559) (xy 431.734014 -371.469619)
			(xy 431.674354 -371.449141) (xy 431.617685 -371.421442) (xy 431.564877 -371.386946) (xy 431.516741 -371.346182)
			(xy 431.474017 -371.299778) (xy 431.437362 -371.248446) (xy 431.407336 -371.192974) (xy 431.384403 -371.134213)
			(xy 431.368915 -371.073068) (xy 431.361108 -371.010476) (xy 431.36058 -370.978938) (xy 431.360834 -370.963952)
			(xy 431.361342 -370.948458) (xy 431.344578 -370.922042) (xy 431.243486 -370.878608) (xy 431.233991 -370.874946)
			(xy 431.213661 -370.874692) (xy 431.19484 -370.882385) (xy 431.187352 -370.889276) (xy 429.562728 -372.5139)
			(xy 430.894749 -372.5139) (xy 430.898763 -372.450102) (xy 430.910741 -372.38731) (xy 430.930493 -372.326515)
			(xy 430.957709 -372.268674) (xy 430.99196 -372.214701) (xy 431.032705 -372.165445) (xy 431.079302 -372.121684)
			(xy 431.131015 -372.084108) (xy 431.187031 -372.05331) (xy 431.246464 -372.029774) (xy 431.308379 -372.013873)
			(xy 431.371798 -372.005856) (xy 431.40376 -372.005352) (xy 431.438096 -372.00595) (xy 431.506143 -372.015187)
			(xy 431.572328 -372.033497) (xy 431.635447 -372.060548) (xy 431.694352 -372.095847) (xy 431.721514 -372.116858)
			(xy 431.728537 -372.122057) (xy 431.745038 -372.127769) (xy 431.753772 -372.128034) (xy 431.783744 -372.12778)
			(xy 431.792474 -372.127308) (xy 431.808841 -372.121201) (xy 431.815748 -372.115842) (xy 431.838681 -372.097168)
			(xy 431.888097 -372.064671) (xy 431.940951 -372.038131) (xy 431.996528 -372.017905) (xy 432.054077 -372.004266)
			(xy 432.11282 -371.9974) (xy 432.142392 -371.99697) (xy 432.17257 -371.997388) (xy 432.232502 -372.004528)
			(xy 432.291169 -372.01871) (xy 432.347745 -372.039733) (xy 432.401436 -372.067303) (xy 432.451488 -372.101032)
			(xy 432.474624 -372.120414) (xy 432.48453 -372.12905) (xy 432.510184 -372.134384) (xy 432.618134 -372.100348)
			(xy 432.636168 -372.081298) (xy 432.63947 -372.068344) (xy 432.647397 -372.038773) (xy 432.669352 -371.981623)
			(xy 432.698013 -371.927523) (xy 432.732966 -371.877259) (xy 432.773703 -371.831557) (xy 432.819636 -371.79108)
			(xy 432.870098 -371.756414) (xy 432.92436 -371.728061) (xy 432.981634 -371.706431) (xy 433.041092 -371.691839)
			(xy 433.101873 -371.684494) (xy 433.132484 -371.684042) (xy 433.16445 -371.684422) (xy 433.227879 -371.692433)
			(xy 433.289803 -371.708331) (xy 433.349246 -371.731864) (xy 433.405271 -371.762663) (xy 433.456994 -371.80024)
			(xy 433.503599 -371.844004) (xy 433.544352 -371.893264) (xy 433.578609 -371.947244) (xy 433.605831 -372.005091)
			(xy 433.625587 -372.065894) (xy 433.637567 -372.128694) (xy 433.641582 -372.1925) (xy 433.637567 -372.256306)
			(xy 433.625587 -372.319106) (xy 433.605831 -372.379909) (xy 433.578609 -372.437756) (xy 433.544352 -372.491736)
			(xy 433.503599 -372.540996) (xy 433.456994 -372.58476) (xy 433.405271 -372.622337) (xy 433.349246 -372.653136)
			(xy 433.289803 -372.676669) (xy 433.227879 -372.692567) (xy 433.16445 -372.700578) (xy 433.132484 -372.701058)
			(xy 433.102307 -372.700612) (xy 433.042375 -372.69348) (xy 432.983708 -372.679305) (xy 432.927132 -372.658287)
			(xy 432.87344 -372.630721) (xy 432.823388 -372.596994) (xy 432.800252 -372.577614) (xy 432.790346 -372.568978)
			(xy 432.764692 -372.563644) (xy 432.656742 -372.59768) (xy 432.638708 -372.61673) (xy 432.635406 -372.629684)
			(xy 432.62752 -372.659267) (xy 432.60556 -372.716418) (xy 432.576895 -372.770518) (xy 432.541938 -372.820782)
			(xy 432.501196 -372.866483) (xy 432.455259 -372.906959) (xy 432.4156 -372.9342) (xy 435.971019 -372.9342)
			(xy 435.975032 -372.870412) (xy 435.987008 -372.807629) (xy 436.006757 -372.746843) (xy 436.033969 -372.689011)
			(xy 436.068214 -372.635045) (xy 436.108953 -372.585796) (xy 436.155542 -372.542042) (xy 436.207248 -372.504471)
			(xy 436.263254 -372.473676) (xy 436.322678 -372.450143) (xy 436.384583 -372.434243) (xy 436.447993 -372.426227)
			(xy 436.47995 -372.425722) (xy 436.513587 -372.426307) (xy 436.580276 -372.435167) (xy 436.645214 -372.45274)
			(xy 436.70727 -372.478718) (xy 436.765361 -372.512649) (xy 436.818473 -372.553941) (xy 436.865678 -372.601873)
			(xy 436.88635 -372.628414) (xy 436.893716 -372.63832) (xy 436.91556 -372.648988) (xy 437.023256 -372.646194)
			(xy 437.044592 -372.63451) (xy 437.051704 -372.62435) (xy 437.069447 -372.598882) (xy 437.11019 -372.552055)
			(xy 437.156335 -372.51054) (xy 437.207193 -372.474956) (xy 437.262007 -372.445831) (xy 437.319961 -372.423601)
			(xy 437.380191 -372.408595) (xy 437.4418 -372.401039) (xy 437.472836 -372.400576) (xy 437.503567 -372.401022)
			(xy 437.564581 -372.408434) (xy 437.624257 -372.423146) (xy 437.681724 -372.444944) (xy 437.736145 -372.473509)
			(xy 437.786726 -372.508425) (xy 437.822629 -372.540233) (xy 450.515222 -372.540233) (xy 450.515222 -372.476311)
			(xy 450.523233 -372.412893) (xy 450.53913 -372.350979) (xy 450.562662 -372.291546) (xy 450.593456 -372.235531)
			(xy 450.631029 -372.183816) (xy 450.674786 -372.137219) (xy 450.724039 -372.096474) (xy 450.77801 -372.062223)
			(xy 450.835849 -372.035006) (xy 450.896642 -372.015253) (xy 450.959432 -372.003275) (xy 451.023228 -371.999262)
			(xy 451.087024 -372.003275) (xy 451.149814 -372.015253) (xy 451.210607 -372.035006) (xy 451.268446 -372.062223)
			(xy 451.322417 -372.096474) (xy 451.37167 -372.137219) (xy 451.415427 -372.183816) (xy 451.453 -372.235531)
			(xy 451.483794 -372.291546) (xy 451.507326 -372.350979) (xy 451.523223 -372.412893) (xy 451.531234 -372.476311)
			(xy 451.531736 -372.508272) (xy 451.531234 -372.540233) (xy 451.523223 -372.603651) (xy 451.507326 -372.665565)
			(xy 451.483794 -372.724998) (xy 451.453 -372.781013) (xy 451.415427 -372.832728) (xy 451.37167 -372.879325)
			(xy 451.322417 -372.92007) (xy 451.268446 -372.954321) (xy 451.210607 -372.981538) (xy 451.149814 -373.001291)
			(xy 451.087024 -373.013269) (xy 451.023228 -373.017283) (xy 450.959432 -373.013269) (xy 450.896642 -373.001291)
			(xy 450.835849 -372.981538) (xy 450.77801 -372.954321) (xy 450.724039 -372.92007) (xy 450.674786 -372.879325)
			(xy 450.631029 -372.832728) (xy 450.593456 -372.781013) (xy 450.562662 -372.724998) (xy 450.53913 -372.665565)
			(xy 450.523233 -372.603651) (xy 450.515222 -372.540233) (xy 437.822629 -372.540233) (xy 437.832731 -372.549183)
			(xy 437.873487 -372.595189) (xy 437.908401 -372.645772) (xy 437.936964 -372.700194) (xy 437.95876 -372.757663)
			(xy 437.97347 -372.817339) (xy 437.980879 -372.878353) (xy 437.981344 -372.909084) (xy 437.980822 -372.940396)
			(xy 437.973124 -373.002546) (xy 437.957855 -373.063281) (xy 437.935246 -373.121683) (xy 437.905639 -373.176867)
			(xy 437.869481 -373.227999) (xy 437.848756 -373.251476) (xy 437.842764 -373.25876) (xy 437.83599 -373.276345)
			(xy 437.835548 -373.285766) (xy 437.835802 -373.316754) (xy 437.836218 -373.326216) (xy 437.84312 -373.343837)
			(xy 437.849264 -373.351044) (xy 437.870452 -373.374575) (xy 437.907372 -373.426022) (xy 437.937615 -373.481656)
			(xy 437.960715 -373.540616) (xy 437.976313 -373.601988) (xy 437.984168 -373.664822) (xy 437.984646 -373.696484)
			(xy 437.984144 -373.728445) (xy 437.976133 -373.791863) (xy 437.960236 -373.853777) (xy 437.936704 -373.91321)
			(xy 437.90591 -373.969225) (xy 437.868337 -374.02094) (xy 437.82458 -374.067537) (xy 437.775327 -374.108282)
			(xy 437.721356 -374.142533) (xy 437.663517 -374.16975) (xy 437.602724 -374.189503) (xy 437.539934 -374.201481)
			(xy 437.476138 -374.205495) (xy 437.412342 -374.201481) (xy 437.349552 -374.189503) (xy 437.288759 -374.16975)
			(xy 437.23092 -374.142533) (xy 437.176949 -374.108282) (xy 437.127696 -374.067537) (xy 437.083939 -374.02094)
			(xy 437.046366 -373.969225) (xy 437.015572 -373.91321) (xy 436.99204 -373.853777) (xy 436.976143 -373.791863)
			(xy 436.968132 -373.728445) (xy 436.96763 -373.696484) (xy 436.968113 -373.66517) (xy 436.975816 -373.603018)
			(xy 436.991091 -373.542282) (xy 437.013708 -373.48388) (xy 437.043323 -373.428697) (xy 437.079488 -373.377567)
			(xy 437.100218 -373.354092) (xy 437.10622 -373.346815) (xy 437.11299 -373.329225) (xy 437.113426 -373.319802)
			(xy 437.113172 -373.288814) (xy 437.112778 -373.279349) (xy 437.105861 -373.261728) (xy 437.09971 -373.254524)
			(xy 437.09095 -373.244997) (xy 437.074307 -373.225173) (xy 437.066436 -373.2149) (xy 437.05907 -373.204994)
			(xy 437.037226 -373.194326) (xy 436.92953 -373.19712) (xy 436.908194 -373.208804) (xy 436.901082 -373.218964)
			(xy 436.883321 -373.244419) (xy 436.842582 -373.291249) (xy 436.796442 -373.332767) (xy 436.745587 -373.368355)
			(xy 436.690775 -373.397482) (xy 436.632823 -373.419714) (xy 436.572594 -373.43472) (xy 436.510985 -373.442276)
			(xy 436.47995 -373.442738) (xy 436.447993 -373.442173) (xy 436.384583 -373.434157) (xy 436.322678 -373.418257)
			(xy 436.263254 -373.394724) (xy 436.207248 -373.363929) (xy 436.155542 -373.326358) (xy 436.108953 -373.282604)
			(xy 436.068214 -373.233355) (xy 436.033969 -373.179389) (xy 436.006757 -373.121557) (xy 435.987008 -373.060771)
			(xy 435.975032 -372.997988) (xy 435.971019 -372.9342) (xy 432.4156 -372.9342) (xy 432.404792 -372.941624)
			(xy 432.350527 -372.969976) (xy 432.293249 -372.991603) (xy 432.233788 -373.006193) (xy 432.173005 -373.013535)
			(xy 432.142392 -373.013986) (xy 432.108055 -373.013428) (xy 432.040005 -373.004184) (xy 431.973819 -372.985865)
			(xy 431.910701 -372.958805) (xy 431.851798 -372.923496) (xy 431.824638 -372.90248) (xy 431.817606 -372.897296)
			(xy 431.801112 -372.891576) (xy 431.79238 -372.891304) (xy 431.762408 -372.891558) (xy 431.753678 -372.89202)
			(xy 431.737311 -372.898135) (xy 431.730404 -372.903496) (xy 431.707481 -372.922183) (xy 431.658064 -372.95468)
			(xy 431.605208 -372.98122) (xy 431.549629 -373.001444) (xy 431.492077 -373.015079) (xy 431.433332 -373.02194)
			(xy 431.40376 -373.022368) (xy 431.371798 -373.021944) (xy 431.308379 -373.013927) (xy 431.246464 -372.998026)
			(xy 431.187031 -372.97449) (xy 431.131015 -372.943692) (xy 431.079302 -372.906116) (xy 431.032705 -372.862355)
			(xy 430.99196 -372.813099) (xy 430.957709 -372.759126) (xy 430.930493 -372.701285) (xy 430.910741 -372.64049)
			(xy 430.898763 -372.577698) (xy 430.894749 -372.5139) (xy 429.562728 -372.5139) (xy 428.821088 -373.25554)
			(xy 428.815205 -373.261862) (xy 428.807694 -373.2774) (xy 428.805772 -373.294551) (xy 428.807372 -373.303038)
			(xy 428.829978 -373.400066) (xy 428.847758 -373.41937) (xy 428.860204 -373.423688) (xy 428.890009 -373.434305)
			(xy 428.946943 -373.461904) (xy 429.000013 -373.496353) (xy 429.048399 -373.537122) (xy 429.091353 -373.583578)
			(xy 429.12821 -373.635006) (xy 429.158402 -373.690609) (xy 429.181461 -373.749528) (xy 429.197032 -373.810853)
			(xy 429.204873 -373.873636) (xy 429.20539 -373.905272) (xy 429.205042 -373.929359) (xy 435.373774 -373.929359)
			(xy 435.373774 -373.865437) (xy 435.381785 -373.802019) (xy 435.397682 -373.740105) (xy 435.421214 -373.680672)
			(xy 435.452008 -373.624657) (xy 435.489581 -373.572942) (xy 435.533338 -373.526345) (xy 435.582591 -373.4856)
			(xy 435.636562 -373.451349) (xy 435.694401 -373.424132) (xy 435.755194 -373.404379) (xy 435.817984 -373.392401)
			(xy 435.88178 -373.388388) (xy 435.945576 -373.392401) (xy 436.008366 -373.404379) (xy 436.069159 -373.424132)
			(xy 436.126998 -373.451349) (xy 436.180969 -373.4856) (xy 436.230222 -373.526345) (xy 436.273979 -373.572942)
			(xy 436.311552 -373.624657) (xy 436.342346 -373.680672) (xy 436.365878 -373.740105) (xy 436.381775 -373.802019)
			(xy 436.389786 -373.865437) (xy 436.390288 -373.897398) (xy 436.389786 -373.929359) (xy 436.381775 -373.992777)
			(xy 436.365878 -374.054691) (xy 436.342346 -374.114124) (xy 436.311552 -374.170139) (xy 436.273979 -374.221854)
			(xy 436.230222 -374.268451) (xy 436.180969 -374.309196) (xy 436.126998 -374.343447) (xy 436.069159 -374.370664)
			(xy 436.008366 -374.390417) (xy 435.945576 -374.402395) (xy 435.88178 -374.406409) (xy 435.817984 -374.402395)
			(xy 435.755194 -374.390417) (xy 435.694401 -374.370664) (xy 435.636562 -374.343447) (xy 435.582591 -374.309196)
			(xy 435.533338 -374.268451) (xy 435.489581 -374.221854) (xy 435.452008 -374.170139) (xy 435.421214 -374.114124)
			(xy 435.397682 -374.054691) (xy 435.381785 -373.992777) (xy 435.373774 -373.929359) (xy 429.205042 -373.929359)
			(xy 429.204946 -373.936005) (xy 429.19754 -373.997023) (xy 429.182833 -374.056703) (xy 429.161039 -374.114175)
			(xy 429.132476 -374.168601) (xy 429.09756 -374.219187) (xy 429.056802 -374.265195) (xy 429.010794 -374.305954)
			(xy 428.960209 -374.340871) (xy 428.905784 -374.369435) (xy 428.848312 -374.39123) (xy 428.788632 -374.405938)
			(xy 428.727615 -374.413345) (xy 428.696882 -374.41378) (xy 428.665246 -374.413298) (xy 428.602462 -374.405447)
			(xy 428.541137 -374.389868) (xy 428.482219 -374.366803) (xy 428.426616 -374.336607) (xy 428.375189 -374.299747)
			(xy 428.328731 -374.256792) (xy 428.287961 -374.208407) (xy 428.253507 -374.155337) (xy 428.225903 -374.098403)
			(xy 428.215298 -374.068594) (xy 428.21098 -374.056148) (xy 428.191676 -374.038368) (xy 428.094648 -374.015762)
			(xy 428.086161 -374.01415) (xy 428.069005 -374.01607) (xy 428.05346 -374.023579) (xy 428.04715 -374.029478)
			(xy 427.871382 -374.205246) (xy 427.864534 -374.212643) (xy 427.856803 -374.231242) (xy 427.856396 -374.241314)
			(xy 427.856396 -384.87858) (xy 429.226987 -384.87858) (xy 429.230994 -384.693676) (xy 429.243007 -384.509118)
			(xy 429.263003 -384.325254) (xy 429.290945 -384.14243) (xy 429.326781 -383.960987) (xy 429.370443 -383.781266)
			(xy 429.42185 -383.603606) (xy 429.480904 -383.42834) (xy 429.547495 -383.255796) (xy 429.621498 -383.086299)
			(xy 429.702774 -382.920167) (xy 429.79117 -382.757711) (xy 429.886521 -382.599237) (xy 429.988647 -382.445042)
			(xy 430.097356 -382.295416) (xy 430.212445 -382.15064) (xy 430.333698 -382.010985) (xy 430.460887 -381.876714)
			(xy 430.593772 -381.748078) (xy 430.732106 -381.625319) (xy 430.875627 -381.508669) (xy 431.024066 -381.398345)
			(xy 431.177146 -381.294554) (xy 431.334577 -381.197492) (xy 431.496066 -381.107342) (xy 431.661308 -381.024271)
			(xy 431.829994 -380.948436) (xy 432.001806 -380.87998) (xy 432.176422 -380.81903) (xy 432.353515 -380.765703)
			(xy 432.532752 -380.720096) (xy 432.713796 -380.682297) (xy 432.896307 -380.652376) (xy 433.079944 -380.630389)
			(xy 433.26436 -380.616377) (xy 433.44921 -380.610367) (xy 433.634147 -380.612371) (xy 433.818824 -380.622384)
			(xy 434.002894 -380.640387) (xy 434.18601 -380.666348) (xy 434.367831 -380.700216) (xy 434.548014 -380.741928)
			(xy 434.72622 -380.791407) (xy 434.902116 -380.848559) (xy 435.075371 -380.913277) (xy 435.24566 -380.98544)
			(xy 435.412663 -381.064911) (xy 435.576067 -381.151542) (xy 435.735564 -381.245171) (xy 435.890856 -381.34562)
			(xy 436.041651 -381.452703) (xy 436.187666 -381.566217) (xy 436.328626 -381.685949) (xy 436.464267 -381.811676)
			(xy 436.594335 -381.94316) (xy 436.718585 -382.080156) (xy 436.836783 -382.222405) (xy 436.948709 -382.36964)
			(xy 437.054152 -382.521586) (xy 437.152913 -382.677957) (xy 437.244808 -382.83846) (xy 437.329664 -383.002792)
			(xy 437.407322 -383.170647) (xy 437.477635 -383.341707) (xy 437.540472 -383.515653) (xy 437.595716 -383.692158)
			(xy 437.643261 -383.87089) (xy 437.683019 -384.051514) (xy 437.714916 -384.233691) (xy 437.738891 -384.417078)
			(xy 437.754899 -384.601332) (xy 437.762911 -384.786106) (xy 437.763412 -384.87858) (xy 437.762911 -384.971054)
			(xy 437.754899 -385.155828) (xy 437.738891 -385.340082) (xy 437.714916 -385.523469) (xy 437.683019 -385.705646)
			(xy 437.643261 -385.88627) (xy 437.595716 -386.065002) (xy 437.540472 -386.241507) (xy 437.477635 -386.415453)
			(xy 437.407322 -386.586513) (xy 437.329664 -386.754368) (xy 437.244808 -386.9187) (xy 437.152913 -387.079203)
			(xy 437.054152 -387.235574) (xy 436.948709 -387.38752) (xy 436.836783 -387.534755) (xy 436.718585 -387.677004)
			(xy 436.594335 -387.814) (xy 436.464267 -387.945484) (xy 436.328626 -388.071211) (xy 436.187666 -388.190943)
			(xy 436.041651 -388.304457) (xy 435.890856 -388.41154) (xy 435.735564 -388.511989) (xy 435.576067 -388.605618)
			(xy 435.412663 -388.692249) (xy 435.24566 -388.77172) (xy 435.075371 -388.843883) (xy 434.902116 -388.908601)
			(xy 434.72622 -388.965753) (xy 434.548014 -389.015232) (xy 434.367831 -389.056944) (xy 434.18601 -389.090812)
			(xy 434.002894 -389.116773) (xy 433.818824 -389.134776) (xy 433.634147 -389.144789) (xy 433.44921 -389.146793)
			(xy 433.26436 -389.140783) (xy 433.079944 -389.126771) (xy 432.896307 -389.104784) (xy 432.713796 -389.074863)
			(xy 432.532752 -389.037064) (xy 432.353515 -388.991457) (xy 432.176422 -388.93813) (xy 432.001806 -388.87718)
			(xy 431.829994 -388.808724) (xy 431.661308 -388.732889) (xy 431.496066 -388.649818) (xy 431.334577 -388.559668)
			(xy 431.177146 -388.462606) (xy 431.024066 -388.358815) (xy 430.875627 -388.248491) (xy 430.732106 -388.131841)
			(xy 430.593772 -388.009082) (xy 430.460887 -387.880446) (xy 430.333698 -387.746175) (xy 430.212445 -387.60652)
			(xy 430.097356 -387.461744) (xy 429.988647 -387.312118) (xy 429.886521 -387.157923) (xy 429.79117 -386.999449)
			(xy 429.702774 -386.836993) (xy 429.621498 -386.670861) (xy 429.547495 -386.501364) (xy 429.480904 -386.32882)
			(xy 429.42185 -386.153554) (xy 429.370443 -385.975894) (xy 429.326781 -385.796173) (xy 429.290945 -385.61473)
			(xy 429.263003 -385.431906) (xy 429.243007 -385.248042) (xy 429.230994 -385.063484) (xy 429.226987 -384.87858)
			(xy 427.856396 -384.87858) (xy 427.856396 -385.248912) (xy 427.856773 -385.257271) (xy 427.862211 -385.273084)
			(xy 427.867064 -385.2799) (xy 427.883869 -385.302337) (xy 427.911416 -385.351158) (xy 427.931527 -385.403482)
			(xy 427.94377 -385.458185) (xy 427.947881 -385.514091) (xy 427.943773 -385.569996) (xy 427.931533 -385.6247)
			(xy 427.911424 -385.677025) (xy 427.88388 -385.725847) (xy 427.867064 -385.748276) (xy 427.862145 -385.75506)
			(xy 427.85668 -385.77089) (xy 427.856396 -385.779264) (xy 427.856396 -387.438392) (xy 427.856786 -387.446746)
			(xy 427.862243 -387.462544) (xy 427.867064 -387.46938) (xy 427.883871 -387.491817) (xy 427.91142 -387.540638)
			(xy 427.931534 -387.592963) (xy 427.94378 -387.647668) (xy 427.947893 -387.703575) (xy 427.943787 -387.759482)
			(xy 427.931549 -387.814188) (xy 427.911442 -387.866516) (xy 427.883899 -387.915341) (xy 427.867064 -387.937756)
			(xy 427.862156 -387.944543) (xy 427.856716 -387.960374) (xy 427.856396 -387.968744) (xy 427.856396 -388.652512)
			(xy 427.856773 -388.660871) (xy 427.862211 -388.676684) (xy 427.867064 -388.6835) (xy 427.883869 -388.705937)
			(xy 427.911416 -388.754758) (xy 427.931527 -388.807082) (xy 427.94377 -388.861785) (xy 427.947881 -388.917691)
			(xy 427.943773 -388.973596) (xy 427.931533 -389.0283) (xy 427.911424 -389.080625) (xy 427.88388 -389.129447)
			(xy 427.867064 -389.151876) (xy 427.862145 -389.15866) (xy 427.85668 -389.17449) (xy 427.856396 -389.182864)
			(xy 427.856396 -390.29005) (xy 427.875954 -390.31672) (xy 427.89221 -390.3218) (xy 427.91783 -390.330195)
			(xy 427.966592 -390.353191) (xy 428.011632 -390.382823) (xy 428.05205 -390.418501) (xy 428.087042 -390.459515)
			(xy 428.115911 -390.505047) (xy 428.138082 -390.55419) (xy 428.153112 -390.605965) (xy 428.160704 -390.659341)
			(xy 428.160704 -390.713253) (xy 428.153114 -390.766629) (xy 428.138084 -390.818404) (xy 428.115914 -390.867548)
			(xy 428.087046 -390.91308) (xy 428.052054 -390.954094) (xy 428.011636 -390.989773) (xy 427.966598 -391.019406)
			(xy 427.917835 -391.042403) (xy 427.89221 -391.05078) (xy 427.875954 -391.05586) (xy 427.856396 -391.08253)
			(xy 427.856396 -392.479022) (xy 430.282348 -392.479022) (xy 430.286419 -392.4234) (xy 430.298545 -392.368963)
			(xy 430.318468 -392.316872) (xy 430.345764 -392.268237) (xy 430.37985 -392.224094) (xy 430.419999 -392.185385)
			(xy 430.465357 -392.152934) (xy 430.514957 -392.127433) (xy 430.567741 -392.109426) (xy 430.622584 -392.099296)
			(xy 430.678318 -392.097259) (xy 430.733755 -392.103359) (xy 430.787712 -392.117465) (xy 430.839041 -392.139277)
			(xy 430.886647 -392.168331) (xy 430.929515 -392.204006) (xy 430.966732 -392.245543) (xy 430.997505 -392.292056)
			(xy 431.021177 -392.342553) (xy 431.037245 -392.39596) (xy 431.045365 -392.451136) (xy 431.045874 -392.479022)
			(xy 431.045365 -392.506908) (xy 431.037245 -392.562084) (xy 431.021177 -392.615491) (xy 430.997505 -392.665988)
			(xy 430.966732 -392.712501) (xy 430.929515 -392.754038) (xy 430.886647 -392.789713) (xy 430.839041 -392.818767)
			(xy 430.787712 -392.840579) (xy 430.733755 -392.854685) (xy 430.678318 -392.860785) (xy 430.622584 -392.858748)
			(xy 430.567741 -392.848618) (xy 430.514957 -392.830611) (xy 430.465357 -392.80511) (xy 430.419999 -392.772659)
			(xy 430.37985 -392.73395) (xy 430.345764 -392.689807) (xy 430.318468 -392.641172) (xy 430.298545 -392.589081)
			(xy 430.286419 -392.534644) (xy 430.282348 -392.479022) (xy 427.856396 -392.479022) (xy 427.856396 -393.193016)
			(xy 427.856799 -393.202214) (xy 427.863288 -393.219431) (xy 427.875399 -393.233281) (xy 427.88332 -393.237974)
			(xy 427.975268 -393.286742) (xy 428.002954 -393.285218) (xy 428.014892 -393.27709) (xy 428.040185 -393.260529)
			(xy 428.093944 -393.232866) (xy 428.150603 -393.211771) (xy 428.209364 -393.197541) (xy 428.269397 -393.190377)
			(xy 428.299626 -393.189968) (xy 428.330356 -393.190434) (xy 428.391369 -393.197845) (xy 428.451044 -393.212555)
			(xy 428.50851 -393.234351) (xy 428.562931 -393.262915) (xy 428.613512 -393.297829) (xy 428.659516 -393.338586)
			(xy 428.700272 -393.38459) (xy 428.735186 -393.435171) (xy 428.76375 -393.489592) (xy 428.785545 -393.547058)
			(xy 428.800256 -393.606733) (xy 428.807667 -393.667745) (xy 428.808134 -393.698476) (xy 428.807709 -393.728298)
			(xy 428.800739 -393.787533) (xy 428.786891 -393.845547) (xy 428.766355 -393.901544) (xy 428.739414 -393.954757)
			(xy 428.706436 -394.004454) (xy 428.667874 -394.049955) (xy 428.646336 -394.070586) (xy 428.638723 -394.078393)
			(xy 428.630363 -394.098509) (xy 428.631053 -394.120283) (xy 428.635414 -394.130276) (xy 428.644558 -394.150088)
			(xy 428.64906 -394.159249) (xy 428.663866 -394.173273) (xy 428.67326 -394.177266) (xy 428.702978 -394.188442)
			(xy 428.712521 -394.191491) (xy 428.732524 -394.190853) (xy 428.74184 -394.187172) (xy 428.766817 -394.176245)
			(xy 428.819116 -394.160847) (xy 428.873077 -394.153071) (xy 428.900336 -394.152628) (xy 428.927583 -394.153117)
			(xy 428.981522 -394.160877) (xy 429.033807 -394.176233) (xy 429.083375 -394.198874) (xy 429.129217 -394.228339)
			(xy 429.170399 -394.264027) (xy 429.206083 -394.305212) (xy 429.235543 -394.351057) (xy 429.258179 -394.400627)
			(xy 429.273531 -394.452914) (xy 429.281286 -394.506853) (xy 429.281286 -394.561347) (xy 429.273531 -394.615286)
			(xy 429.258179 -394.667573) (xy 429.235543 -394.717143) (xy 429.206083 -394.762988) (xy 429.170399 -394.804173)
			(xy 429.129217 -394.839861) (xy 429.083375 -394.869326) (xy 429.033807 -394.891967) (xy 428.981522 -394.907323)
			(xy 428.927583 -394.915083) (xy 428.900336 -394.915644) (xy 428.878161 -394.915369) (xy 428.834104 -394.91028)
			(xy 428.812452 -394.905484) (xy 428.801276 -394.90269) (xy 428.778924 -394.907516) (xy 428.698152 -394.97)
			(xy 428.687992 -394.99032) (xy 428.687484 -395.002004) (xy 428.686363 -395.031482) (xy 428.684759 -395.042898)
			(xy 429.271174 -395.042898) (xy 429.275245 -394.987276) (xy 429.287371 -394.932839) (xy 429.307294 -394.880748)
			(xy 429.33459 -394.832113) (xy 429.368676 -394.78797) (xy 429.408825 -394.749261) (xy 429.454183 -394.71681)
			(xy 429.503783 -394.691309) (xy 429.556567 -394.673302) (xy 429.61141 -394.663172) (xy 429.667144 -394.661135)
			(xy 429.722581 -394.667235) (xy 429.776538 -394.681341) (xy 429.827867 -394.703153) (xy 429.875473 -394.732207)
			(xy 429.918341 -394.767882) (xy 429.955558 -394.809419) (xy 429.986331 -394.855932) (xy 430.010003 -394.906429)
			(xy 430.026071 -394.959836) (xy 430.034191 -395.015012) (xy 430.0347 -395.042898) (xy 430.034191 -395.070784)
			(xy 430.026071 -395.12596) (xy 430.010003 -395.179367) (xy 429.986331 -395.229864) (xy 429.955558 -395.276377)
			(xy 429.918341 -395.317914) (xy 429.875473 -395.353589) (xy 429.827867 -395.382643) (xy 429.776538 -395.404455)
			(xy 429.722581 -395.418561) (xy 429.667144 -395.424661) (xy 429.61141 -395.422624) (xy 429.556567 -395.412494)
			(xy 429.503783 -395.394487) (xy 429.454183 -395.368986) (xy 429.408825 -395.336535) (xy 429.368676 -395.297826)
			(xy 429.33459 -395.253683) (xy 429.307294 -395.205048) (xy 429.287371 -395.152957) (xy 429.275245 -395.09852)
			(xy 429.271174 -395.042898) (xy 428.684759 -395.042898) (xy 428.678156 -395.089902) (xy 428.663243 -395.146979)
			(xy 428.641826 -395.201948) (xy 428.614192 -395.254068) (xy 428.597822 -395.27861) (xy 428.592341 -395.287361)
			(xy 428.588198 -395.307572) (xy 428.592319 -395.327786) (xy 428.597822 -395.336522) (xy 428.614874 -395.36205)
			(xy 428.643398 -395.416413) (xy 428.665164 -395.473817) (xy 428.679855 -395.533426) (xy 428.687256 -395.59437)
			(xy 428.687738 -395.625066) (xy 428.687233 -395.65777) (xy 428.678844 -395.722639) (xy 428.662201 -395.785894)
			(xy 428.637579 -395.846491) (xy 428.605384 -395.903428) (xy 428.56615 -395.955763) (xy 428.520524 -396.00263)
			(xy 428.495206 -396.023338) (xy 428.485554 -396.031212) (xy 428.475394 -396.053818) (xy 428.479554 -396.119604)
			(xy 429.189386 -396.119604) (xy 429.193457 -396.063982) (xy 429.205583 -396.009545) (xy 429.225506 -395.957454)
			(xy 429.252802 -395.908819) (xy 429.286888 -395.864676) (xy 429.327037 -395.825967) (xy 429.372395 -395.793516)
			(xy 429.421995 -395.768015) (xy 429.474779 -395.750008) (xy 429.529622 -395.739878) (xy 429.585356 -395.737841)
			(xy 429.640793 -395.743941) (xy 429.69475 -395.758047) (xy 429.746079 -395.779859) (xy 429.793685 -395.808913)
			(xy 429.836553 -395.844588) (xy 429.87377 -395.886125) (xy 429.904543 -395.932638) (xy 429.928215 -395.983135)
			(xy 429.944283 -396.036542) (xy 429.952403 -396.091718) (xy 429.952912 -396.119604) (xy 429.952403 -396.14749)
			(xy 429.944283 -396.202666) (xy 429.928215 -396.256073) (xy 429.904543 -396.30657) (xy 429.87377 -396.353083)
			(xy 429.836553 -396.39462) (xy 429.793685 -396.430295) (xy 429.746079 -396.459349) (xy 429.69475 -396.481161)
			(xy 429.640793 -396.495267) (xy 429.585356 -396.501367) (xy 429.529622 -396.49933) (xy 429.474779 -396.4892)
			(xy 429.421995 -396.471193) (xy 429.372395 -396.445692) (xy 429.327037 -396.413241) (xy 429.286888 -396.374532)
			(xy 429.252802 -396.330389) (xy 429.225506 -396.281754) (xy 429.205583 -396.229663) (xy 429.193457 -396.175226)
			(xy 429.189386 -396.119604) (xy 428.479554 -396.119604) (xy 428.482252 -396.162276) (xy 428.495206 -396.183358)
			(xy 428.505874 -396.189962) (xy 428.533549 -396.207287) (xy 428.584635 -396.247951) (xy 428.630096 -396.294819)
			(xy 428.669184 -396.347121) (xy 428.701256 -396.403995) (xy 428.725785 -396.464507) (xy 428.742366 -396.527661)
			(xy 428.750728 -396.592417) (xy 428.751238 -396.625064) (xy 428.750794 -396.655798) (xy 428.74339 -396.716819)
			(xy 428.728683 -396.776502) (xy 428.70689 -396.833977) (xy 428.678328 -396.888407) (xy 428.643414 -396.938996)
			(xy 428.602656 -396.985009) (xy 428.556648 -397.025773) (xy 428.506063 -397.060694) (xy 428.451638 -397.089263)
			(xy 428.394165 -397.111064) (xy 428.334484 -397.125778) (xy 428.273464 -397.13319) (xy 428.24273 -397.133572)
			(xy 428.21187 -397.133117) (xy 428.150604 -397.125651) (xy 428.090689 -397.110837) (xy 428.033002 -397.088891)
			(xy 428.005494 -397.074898) (xy 427.993556 -397.068548) (xy 427.966886 -397.06931) (xy 427.881034 -397.121126)
			(xy 427.87376 -397.125943) (xy 427.865858 -397.135604) (xy 429.189386 -397.135604) (xy 429.193457 -397.079982)
			(xy 429.205583 -397.025545) (xy 429.225506 -396.973454) (xy 429.252802 -396.924819) (xy 429.286888 -396.880676)
			(xy 429.327037 -396.841967) (xy 429.372395 -396.809516) (xy 429.421995 -396.784015) (xy 429.474779 -396.766008)
			(xy 429.529622 -396.755878) (xy 429.585356 -396.753841) (xy 429.640793 -396.759941) (xy 429.69475 -396.774047)
			(xy 429.746079 -396.795859) (xy 429.793685 -396.824913) (xy 429.836553 -396.860588) (xy 429.87377 -396.902125)
			(xy 429.904543 -396.948638) (xy 429.928215 -396.999135) (xy 429.944283 -397.052542) (xy 429.952403 -397.107718)
			(xy 429.952912 -397.135604) (xy 429.952403 -397.16349) (xy 429.944283 -397.218666) (xy 429.928215 -397.272073)
			(xy 429.904543 -397.32257) (xy 429.87377 -397.369083) (xy 429.836553 -397.41062) (xy 429.793685 -397.446295)
			(xy 429.746079 -397.475349) (xy 429.69475 -397.497161) (xy 429.640793 -397.511267) (xy 429.585356 -397.517367)
			(xy 429.529622 -397.51533) (xy 429.474779 -397.5052) (xy 429.421995 -397.487193) (xy 429.372395 -397.461692)
			(xy 429.327037 -397.429241) (xy 429.286888 -397.390532) (xy 429.252802 -397.346389) (xy 429.225506 -397.297754)
			(xy 429.205583 -397.245663) (xy 429.193457 -397.191226) (xy 429.189386 -397.135604) (xy 427.865858 -397.135604)
			(xy 427.862722 -397.139438) (xy 427.856824 -397.155845) (xy 427.856396 -397.16456) (xy 427.856396 -397.247364)
			(xy 427.855961 -397.257429) (xy 427.84823 -397.276016) (xy 427.84141 -397.283432) (xy 427.33595 -397.788892)
			(xy 427.329442 -397.795918) (xy 427.321737 -397.813437) (xy 427.320978 -397.832559) (xy 427.323758 -397.841724)
			(xy 427.35881 -397.9418) (xy 427.38167 -397.960088) (xy 427.396402 -397.961866) (xy 427.423994 -397.965479)
			(xy 427.477799 -397.979674) (xy 427.528967 -398.001543) (xy 427.576411 -398.030621) (xy 427.619123 -398.066288)
			(xy 427.656193 -398.107788) (xy 427.686835 -398.154238) (xy 427.710396 -398.204649) (xy 427.726375 -398.257952)
			(xy 427.734433 -398.313011) (xy 427.734984 -398.340834) (xy 427.734495 -398.368083) (xy 427.726735 -398.422026)
			(xy 427.711377 -398.474315) (xy 427.688733 -398.523886) (xy 427.659266 -398.569731) (xy 427.623574 -398.610915)
			(xy 427.582384 -398.6466) (xy 427.536535 -398.676061) (xy 427.486961 -398.698697) (xy 427.434669 -398.714047)
			(xy 427.380725 -398.7218) (xy 427.353476 -398.722342) (xy 427.325659 -398.721829) (xy 427.270616 -398.713728)
			(xy 427.217335 -398.697718) (xy 427.166944 -398.674137) (xy 427.120514 -398.643486) (xy 427.079029 -398.606415)
			(xy 427.04337 -398.56371) (xy 427.014292 -398.516279) (xy 426.992414 -398.465126) (xy 426.978199 -398.411337)
			(xy 426.974508 -398.38376) (xy 426.97273 -398.369028) (xy 426.954442 -398.346168) (xy 426.854366 -398.311116)
			(xy 426.845198 -398.308339) (xy 426.826072 -398.309085) (xy 426.808549 -398.316786) (xy 426.801534 -398.323308)
			(xy 426.031152 -399.09369) (xy 426.462696 -399.09369) (xy 426.466767 -399.038068) (xy 426.478893 -398.983631)
			(xy 426.498816 -398.93154) (xy 426.526112 -398.882905) (xy 426.560198 -398.838762) (xy 426.600347 -398.800053)
			(xy 426.645705 -398.767602) (xy 426.695305 -398.742101) (xy 426.748089 -398.724094) (xy 426.802932 -398.713964)
			(xy 426.858666 -398.711927) (xy 426.914103 -398.718027) (xy 426.96806 -398.732133) (xy 427.019389 -398.753945)
			(xy 427.066995 -398.782999) (xy 427.109863 -398.818674) (xy 427.14708 -398.860211) (xy 427.177853 -398.906724)
			(xy 427.201525 -398.957221) (xy 427.217593 -399.010628) (xy 427.225713 -399.065804) (xy 427.226222 -399.09369)
			(xy 427.225713 -399.121576) (xy 427.217593 -399.176752) (xy 427.201525 -399.230159) (xy 427.177853 -399.280656)
			(xy 427.161735 -399.305018) (xy 428.847502 -399.305018) (xy 428.851573 -399.249396) (xy 428.863699 -399.194959)
			(xy 428.883622 -399.142868) (xy 428.910918 -399.094233) (xy 428.945004 -399.05009) (xy 428.985153 -399.011381)
			(xy 429.030511 -398.97893) (xy 429.080111 -398.953429) (xy 429.132895 -398.935422) (xy 429.187738 -398.925292)
			(xy 429.243472 -398.923255) (xy 429.298909 -398.929355) (xy 429.352866 -398.943461) (xy 429.404195 -398.965273)
			(xy 429.451801 -398.994327) (xy 429.494669 -399.030002) (xy 429.531886 -399.071539) (xy 429.554527 -399.10576)
			(xy 432.544208 -399.10576) (xy 432.544208 -398.954112) (xy 432.552145 -398.802671) (xy 432.567996 -398.651853)
			(xy 432.591719 -398.502072) (xy 432.623249 -398.353737) (xy 432.662498 -398.207256) (xy 432.70936 -398.06303)
			(xy 432.763706 -397.921453) (xy 432.825387 -397.782916) (xy 432.894234 -397.647796) (xy 432.970059 -397.516464)
			(xy 433.052652 -397.389281) (xy 433.141789 -397.266595) (xy 433.237225 -397.148742) (xy 433.338697 -397.036045)
			(xy 433.445929 -396.928813) (xy 433.558626 -396.827341) (xy 433.676479 -396.731905) (xy 433.799165 -396.642768)
			(xy 433.926348 -396.560175) (xy 434.05768 -396.48435) (xy 434.1928 -396.415503) (xy 434.331337 -396.353822)
			(xy 434.472914 -396.299476) (xy 434.61714 -396.252614) (xy 434.763621 -396.213365) (xy 434.911956 -396.181835)
			(xy 435.061737 -396.158112) (xy 435.212555 -396.142261) (xy 435.363996 -396.134324) (xy 435.515644 -396.134324)
			(xy 435.667085 -396.142261) (xy 435.817903 -396.158112) (xy 435.967684 -396.181835) (xy 436.116019 -396.213365)
			(xy 436.2625 -396.252614) (xy 436.406726 -396.299476) (xy 436.548303 -396.353822) (xy 436.68684 -396.415503)
			(xy 436.82196 -396.48435) (xy 436.953292 -396.560175) (xy 437.080475 -396.642768) (xy 437.203161 -396.731905)
			(xy 437.321014 -396.827341) (xy 437.433711 -396.928813) (xy 437.540943 -397.036045) (xy 437.642415 -397.148742)
			(xy 437.737851 -397.266595) (xy 437.826988 -397.389281) (xy 437.909581 -397.516464) (xy 437.985406 -397.647796)
			(xy 438.054253 -397.782916) (xy 438.115934 -397.921453) (xy 438.17028 -398.06303) (xy 438.217142 -398.207256)
			(xy 438.256391 -398.353737) (xy 438.287921 -398.502072) (xy 438.311644 -398.651853) (xy 438.327495 -398.802671)
			(xy 438.335432 -398.954112) (xy 438.335928 -399.029936) (xy 438.335432 -399.10576) (xy 438.327495 -399.257201)
			(xy 438.311644 -399.408019) (xy 438.287921 -399.5578) (xy 438.256391 -399.706135) (xy 438.217142 -399.852616)
			(xy 438.17028 -399.996842) (xy 438.115934 -400.138419) (xy 438.054253 -400.276956) (xy 437.985406 -400.412076)
			(xy 437.909581 -400.543408) (xy 437.826988 -400.670591) (xy 437.737851 -400.793277) (xy 437.642415 -400.91113)
			(xy 437.540943 -401.023827) (xy 437.433711 -401.131059) (xy 437.321014 -401.232531) (xy 437.203161 -401.327967)
			(xy 437.080475 -401.417104) (xy 436.953292 -401.499697) (xy 436.82196 -401.575522) (xy 436.68684 -401.644369)
			(xy 436.548303 -401.70605) (xy 436.406726 -401.760396) (xy 436.2625 -401.807258) (xy 436.116019 -401.846507)
			(xy 435.967684 -401.878037) (xy 435.817903 -401.90176) (xy 435.667085 -401.917611) (xy 435.515644 -401.925548)
			(xy 435.363996 -401.925548) (xy 435.212555 -401.917611) (xy 435.061737 -401.90176) (xy 434.911956 -401.878037)
			(xy 434.763621 -401.846507) (xy 434.61714 -401.807258) (xy 434.472914 -401.760396) (xy 434.331337 -401.70605)
			(xy 434.1928 -401.644369) (xy 434.05768 -401.575522) (xy 433.926348 -401.499697) (xy 433.799165 -401.417104)
			(xy 433.676479 -401.327967) (xy 433.558626 -401.232531) (xy 433.445929 -401.131059) (xy 433.338697 -401.023827)
			(xy 433.237225 -400.91113) (xy 433.141789 -400.793277) (xy 433.052652 -400.670591) (xy 432.970059 -400.543408)
			(xy 432.894234 -400.412076) (xy 432.825387 -400.276956) (xy 432.763706 -400.138419) (xy 432.70936 -399.996842)
			(xy 432.662498 -399.852616) (xy 432.623249 -399.706135) (xy 432.591719 -399.5578) (xy 432.567996 -399.408019)
			(xy 432.552145 -399.257201) (xy 432.544208 -399.10576) (xy 429.554527 -399.10576) (xy 429.562659 -399.118052)
			(xy 429.586331 -399.168549) (xy 429.602399 -399.221956) (xy 429.610519 -399.277132) (xy 429.611028 -399.305018)
			(xy 429.610519 -399.332904) (xy 429.602399 -399.38808) (xy 429.586331 -399.441487) (xy 429.562659 -399.491984)
			(xy 429.531886 -399.538497) (xy 429.494669 -399.580034) (xy 429.451801 -399.615709) (xy 429.404195 -399.644763)
			(xy 429.352866 -399.666575) (xy 429.298909 -399.680681) (xy 429.243472 -399.686781) (xy 429.187738 -399.684744)
			(xy 429.132895 -399.674614) (xy 429.080111 -399.656607) (xy 429.030511 -399.631106) (xy 428.985153 -399.598655)
			(xy 428.945004 -399.559946) (xy 428.910918 -399.515803) (xy 428.883622 -399.467168) (xy 428.863699 -399.415077)
			(xy 428.851573 -399.36064) (xy 428.847502 -399.305018) (xy 427.161735 -399.305018) (xy 427.14708 -399.327169)
			(xy 427.109863 -399.368706) (xy 427.066995 -399.404381) (xy 427.019389 -399.433435) (xy 426.96806 -399.455247)
			(xy 426.914103 -399.469353) (xy 426.858666 -399.475453) (xy 426.802932 -399.473416) (xy 426.748089 -399.463286)
			(xy 426.695305 -399.445279) (xy 426.645705 -399.419778) (xy 426.600347 -399.387327) (xy 426.560198 -399.348618)
			(xy 426.526112 -399.304475) (xy 426.498816 -399.25584) (xy 426.478893 -399.203749) (xy 426.466767 -399.149312)
			(xy 426.462696 -399.09369) (xy 426.031152 -399.09369) (xy 425.043092 -400.08175) (xy 426.971458 -400.08175)
			(xy 426.975529 -400.026128) (xy 426.987655 -399.971691) (xy 427.007578 -399.9196) (xy 427.034874 -399.870965)
			(xy 427.06896 -399.826822) (xy 427.109109 -399.788113) (xy 427.154467 -399.755662) (xy 427.204067 -399.730161)
			(xy 427.256851 -399.712154) (xy 427.311694 -399.702024) (xy 427.367428 -399.699987) (xy 427.422865 -399.706087)
			(xy 427.476822 -399.720193) (xy 427.528151 -399.742005) (xy 427.575757 -399.771059) (xy 427.618625 -399.806734)
			(xy 427.655842 -399.848271) (xy 427.686615 -399.894784) (xy 427.710287 -399.945281) (xy 427.726355 -399.998688)
			(xy 427.734475 -400.053864) (xy 427.734984 -400.08175) (xy 427.734475 -400.109636) (xy 427.726355 -400.164812)
			(xy 427.710287 -400.218219) (xy 427.686615 -400.268716) (xy 427.655842 -400.315229) (xy 427.618625 -400.356766)
			(xy 427.575757 -400.392441) (xy 427.528151 -400.421495) (xy 427.476822 -400.443307) (xy 427.422865 -400.457413)
			(xy 427.367428 -400.463513) (xy 427.311694 -400.461476) (xy 427.256851 -400.451346) (xy 427.204067 -400.433339)
			(xy 427.154467 -400.407838) (xy 427.109109 -400.375387) (xy 427.06896 -400.336678) (xy 427.034874 -400.292535)
			(xy 427.007578 -400.2439) (xy 426.987655 -400.191809) (xy 426.975529 -400.137372) (xy 426.971458 -400.08175)
			(xy 425.043092 -400.08175) (xy 424.894248 -400.230594) (xy 424.888914 -400.26209) (xy 424.895772 -400.276568)
			(xy 424.907303 -400.302027) (xy 424.925367 -400.35492) (xy 424.93753 -400.409473) (xy 424.943644 -400.46503)
			(xy 424.944032 -400.492976) (xy 424.943569 -400.523708) (xy 424.936163 -400.584726) (xy 424.921457 -400.644405)
			(xy 424.899664 -400.701877) (xy 424.871102 -400.756303) (xy 424.836188 -400.806889) (xy 424.811636 -400.834606)
			(xy 426.462696 -400.834606) (xy 426.466767 -400.778984) (xy 426.478893 -400.724547) (xy 426.498816 -400.672456)
			(xy 426.526112 -400.623821) (xy 426.560198 -400.579678) (xy 426.600347 -400.540969) (xy 426.645705 -400.508518)
			(xy 426.695305 -400.483017) (xy 426.748089 -400.46501) (xy 426.802932 -400.45488) (xy 426.858666 -400.452843)
			(xy 426.914103 -400.458943) (xy 426.96806 -400.473049) (xy 427.019389 -400.494861) (xy 427.066995 -400.523915)
			(xy 427.109863 -400.55959) (xy 427.14708 -400.601127) (xy 427.177853 -400.64764) (xy 427.201525 -400.698137)
			(xy 427.217593 -400.751544) (xy 427.225713 -400.80672) (xy 427.226222 -400.834606) (xy 427.225713 -400.862492)
			(xy 427.217593 -400.917668) (xy 427.201525 -400.971075) (xy 427.177853 -401.021572) (xy 427.14708 -401.068085)
			(xy 427.109863 -401.109622) (xy 427.066995 -401.145297) (xy 427.019389 -401.174351) (xy 426.96806 -401.196163)
			(xy 426.914103 -401.210269) (xy 426.858666 -401.216369) (xy 426.802932 -401.214332) (xy 426.748089 -401.204202)
			(xy 426.695305 -401.186195) (xy 426.645705 -401.160694) (xy 426.600347 -401.128243) (xy 426.560198 -401.089534)
			(xy 426.526112 -401.045391) (xy 426.498816 -400.996756) (xy 426.478893 -400.944665) (xy 426.466767 -400.890228)
			(xy 426.462696 -400.834606) (xy 424.811636 -400.834606) (xy 424.795432 -400.852898) (xy 424.749427 -400.893659)
			(xy 424.698844 -400.928577) (xy 424.644421 -400.957144) (xy 424.586951 -400.978942) (xy 424.527273 -400.993655)
			(xy 424.466256 -401.001066) (xy 424.435524 -401.001484) (xy 424.407576 -401.001119) (xy 424.352015 -400.995017)
			(xy 424.29746 -400.982851) (xy 424.244571 -400.964768) (xy 424.219116 -400.953224) (xy 424.204638 -400.946366)
			(xy 424.173142 -400.9517) (xy 423.40784 -401.717002) (xy 423.860974 -401.717002) (xy 423.865045 -401.66138)
			(xy 423.877171 -401.606943) (xy 423.897094 -401.554852) (xy 423.92439 -401.506217) (xy 423.958476 -401.462074)
			(xy 423.998625 -401.423365) (xy 424.043983 -401.390914) (xy 424.093583 -401.365413) (xy 424.146367 -401.347406)
			(xy 424.20121 -401.337276) (xy 424.256944 -401.335239) (xy 424.312381 -401.341339) (xy 424.366338 -401.355445)
			(xy 424.417667 -401.377257) (xy 424.465273 -401.406311) (xy 424.508141 -401.441986) (xy 424.545358 -401.483523)
			(xy 424.576131 -401.530036) (xy 424.599803 -401.580533) (xy 424.615871 -401.63394) (xy 424.623991 -401.689116)
			(xy 424.6245 -401.717002) (xy 424.623991 -401.744888) (xy 424.615871 -401.800064) (xy 424.599803 -401.853471)
			(xy 424.576131 -401.903968) (xy 424.545358 -401.950481) (xy 424.508141 -401.992018) (xy 424.465273 -402.027693)
			(xy 424.417667 -402.056747) (xy 424.374379 -402.075142) (xy 424.921934 -402.075142) (xy 424.922416 -402.042998)
			(xy 424.930503 -401.979221) (xy 424.946567 -401.916972) (xy 424.970351 -401.857245) (xy 425.001475 -401.800994)
			(xy 425.039443 -401.749115) (xy 425.083648 -401.702437) (xy 425.133386 -401.661705) (xy 425.187862 -401.627569)
			(xy 425.216828 -401.613624) (xy 425.226539 -401.608563) (xy 425.240773 -401.591947) (xy 425.246854 -401.570929)
			(xy 425.245784 -401.56003) (xy 425.243166 -401.541408) (xy 425.240373 -401.503904) (xy 425.240196 -401.4851)
			(xy 425.240698 -401.453139) (xy 425.248709 -401.389721) (xy 425.264606 -401.327807) (xy 425.288138 -401.268374)
			(xy 425.318932 -401.212359) (xy 425.356505 -401.160644) (xy 425.400262 -401.114047) (xy 425.449515 -401.073302)
			(xy 425.503486 -401.039051) (xy 425.561325 -401.011834) (xy 425.622118 -400.992081) (xy 425.684908 -400.980103)
			(xy 425.748704 -400.97609) (xy 425.8125 -400.980103) (xy 425.87529 -400.992081) (xy 425.936083 -401.011834)
			(xy 425.993922 -401.039051) (xy 426.047893 -401.073302) (xy 426.097146 -401.114047) (xy 426.140903 -401.160644)
			(xy 426.178476 -401.212359) (xy 426.20927 -401.268374) (xy 426.232802 -401.327807) (xy 426.248699 -401.389721)
			(xy 426.25671 -401.453139) (xy 426.257212 -401.4851) (xy 426.256739 -401.517244) (xy 426.248647 -401.581021)
			(xy 426.23258 -401.643268) (xy 426.208794 -401.702994) (xy 426.177669 -401.759245) (xy 426.139701 -401.811123)
			(xy 426.095495 -401.857801) (xy 426.045758 -401.898534) (xy 425.991283 -401.932672) (xy 425.962318 -401.946618)
			(xy 425.952626 -401.951706) (xy 425.938397 -401.968313) (xy 425.932304 -401.989317) (xy 425.933362 -402.000212)
			(xy 425.935973 -402.018835) (xy 425.938771 -402.056338) (xy 425.93895 -402.075142) (xy 425.938448 -402.107103)
			(xy 425.930437 -402.170521) (xy 425.91454 -402.232435) (xy 425.891008 -402.291868) (xy 425.860214 -402.347883)
			(xy 425.822641 -402.399598) (xy 425.778884 -402.446195) (xy 425.729631 -402.48694) (xy 425.67566 -402.521191)
			(xy 425.617821 -402.548408) (xy 425.557028 -402.568161) (xy 425.494238 -402.580139) (xy 425.430442 -402.584153)
			(xy 425.366646 -402.580139) (xy 425.303856 -402.568161) (xy 425.243063 -402.548408) (xy 425.185224 -402.521191)
			(xy 425.131253 -402.48694) (xy 425.082 -402.446195) (xy 425.038243 -402.399598) (xy 425.00067 -402.347883)
			(xy 424.969876 -402.291868) (xy 424.946344 -402.232435) (xy 424.930447 -402.170521) (xy 424.922436 -402.107103)
			(xy 424.921934 -402.075142) (xy 424.374379 -402.075142) (xy 424.366338 -402.078559) (xy 424.312381 -402.092665)
			(xy 424.256944 -402.098765) (xy 424.20121 -402.096728) (xy 424.146367 -402.086598) (xy 424.093583 -402.068591)
			(xy 424.043983 -402.04309) (xy 423.998625 -402.010639) (xy 423.958476 -401.97193) (xy 423.92439 -401.927787)
			(xy 423.897094 -401.879152) (xy 423.877171 -401.827061) (xy 423.865045 -401.772624) (xy 423.860974 -401.717002)
			(xy 423.40784 -401.717002) (xy 421.579548 -403.545294) (xy 421.572868 -403.552706) (xy 421.565292 -403.571141)
			(xy 421.564816 -403.581108) (xy 421.564816 -403.99462) (xy 421.565194 -404.004294) (xy 421.572244 -404.02231)
			(xy 421.578532 -404.029672) (xy 421.633396 -404.087584) (xy 421.650922 -404.095712) (xy 421.660828 -404.09622)
			(xy 421.692918 -404.098429) (xy 421.756205 -404.109934) (xy 421.817536 -404.129328) (xy 421.875932 -404.156303)
			(xy 421.930459 -404.190426) (xy 421.980247 -404.231154) (xy 422.018436 -404.271437) (xy 428.841656 -404.271437)
			(xy 428.841656 -404.207515) (xy 428.849667 -404.144097) (xy 428.865564 -404.082183) (xy 428.889096 -404.02275)
			(xy 428.91989 -403.966735) (xy 428.957463 -403.91502) (xy 429.00122 -403.868423) (xy 429.050473 -403.827678)
			(xy 429.104444 -403.793427) (xy 429.162283 -403.76621) (xy 429.223076 -403.746457) (xy 429.285866 -403.734479)
			(xy 429.349662 -403.730466) (xy 429.413458 -403.734479) (xy 429.476248 -403.746457) (xy 429.537041 -403.76621)
			(xy 429.59488 -403.793427) (xy 429.648851 -403.827678) (xy 429.698104 -403.868423) (xy 429.741861 -403.91502)
			(xy 429.779434 -403.966735) (xy 429.810228 -404.02275) (xy 429.83376 -404.082183) (xy 429.849657 -404.144097)
			(xy 429.857668 -404.207515) (xy 429.85817 -404.239476) (xy 429.857668 -404.271437) (xy 429.849657 -404.334855)
			(xy 429.83376 -404.396769) (xy 429.810228 -404.456202) (xy 429.779434 -404.512217) (xy 429.741861 -404.563932)
			(xy 429.698104 -404.610529) (xy 429.648851 -404.651274) (xy 429.59488 -404.685525) (xy 429.537041 -404.712742)
			(xy 429.476248 -404.732495) (xy 429.413458 -404.744473) (xy 429.349662 -404.748487) (xy 429.285866 -404.744473)
			(xy 429.223076 -404.732495) (xy 429.162283 -404.712742) (xy 429.104444 -404.685525) (xy 429.050473 -404.651274)
			(xy 429.00122 -404.610529) (xy 428.957463 -404.563932) (xy 428.91989 -404.512217) (xy 428.889096 -404.456202)
			(xy 428.865564 -404.396769) (xy 428.849667 -404.334855) (xy 428.841656 -404.271437) (xy 422.018436 -404.271437)
			(xy 422.024502 -404.277836) (xy 422.062516 -404.329726) (xy 422.093682 -404.385996) (xy 422.117503 -404.445747)
			(xy 422.133598 -404.508025) (xy 422.14171 -404.571836) (xy 422.141711 -404.63616) (xy 422.133599 -404.699971)
			(xy 422.117504 -404.76225) (xy 422.093683 -404.822001) (xy 422.062518 -404.878271) (xy 422.024504 -404.930162)
			(xy 421.98025 -404.976844) (xy 421.930462 -405.017572) (xy 421.875935 -405.051696) (xy 421.81754 -405.078671)
			(xy 421.756209 -405.098065) (xy 421.692922 -405.109571) (xy 421.660828 -405.111712) (xy 421.650922 -405.11222)
			(xy 421.645445 -405.11476) (xy 436.470804 -405.11476) (xy 436.474875 -405.059138) (xy 436.487001 -405.004701)
			(xy 436.506924 -404.95261) (xy 436.53422 -404.903975) (xy 436.568306 -404.859832) (xy 436.608455 -404.821123)
			(xy 436.653813 -404.788672) (xy 436.703413 -404.763171) (xy 436.756197 -404.745164) (xy 436.81104 -404.735034)
			(xy 436.866774 -404.732997) (xy 436.922211 -404.739097) (xy 436.976168 -404.753203) (xy 437.027497 -404.775015)
			(xy 437.075103 -404.804069) (xy 437.117971 -404.839744) (xy 437.155188 -404.881281) (xy 437.185961 -404.927794)
			(xy 437.209633 -404.978291) (xy 437.225701 -405.031698) (xy 437.233821 -405.086874) (xy 437.23433 -405.11476)
			(xy 437.233821 -405.142646) (xy 437.225701 -405.197822) (xy 437.209633 -405.251229) (xy 437.185961 -405.301726)
			(xy 437.155188 -405.348239) (xy 437.117971 -405.389776) (xy 437.075103 -405.425451) (xy 437.027497 -405.454505)
			(xy 436.976168 -405.476317) (xy 436.922211 -405.490423) (xy 436.866774 -405.496523) (xy 436.81104 -405.494486)
			(xy 436.756197 -405.484356) (xy 436.703413 -405.466349) (xy 436.653813 -405.440848) (xy 436.608455 -405.408397)
			(xy 436.568306 -405.369688) (xy 436.53422 -405.325545) (xy 436.506924 -405.27691) (xy 436.487001 -405.224819)
			(xy 436.474875 -405.170382) (xy 436.470804 -405.11476) (xy 421.645445 -405.11476) (xy 421.633396 -405.120348)
			(xy 421.578532 -405.17826) (xy 421.572208 -405.185603) (xy 421.565139 -405.203628) (xy 421.564816 -405.213312)
			(xy 421.564816 -405.794421) (xy 433.82285 -405.794421) (xy 433.82285 -405.730499) (xy 433.830861 -405.667081)
			(xy 433.846758 -405.605167) (xy 433.87029 -405.545734) (xy 433.901084 -405.489719) (xy 433.938657 -405.438004)
			(xy 433.982414 -405.391407) (xy 434.031667 -405.350662) (xy 434.085638 -405.316411) (xy 434.143477 -405.289194)
			(xy 434.20427 -405.269441) (xy 434.26706 -405.257463) (xy 434.330856 -405.25345) (xy 434.394652 -405.257463)
			(xy 434.457442 -405.269441) (xy 434.518235 -405.289194) (xy 434.576074 -405.316411) (xy 434.630045 -405.350662)
			(xy 434.679298 -405.391407) (xy 434.723055 -405.438004) (xy 434.760628 -405.489719) (xy 434.791422 -405.545734)
			(xy 434.814954 -405.605167) (xy 434.830851 -405.667081) (xy 434.837311 -405.718221) (xy 435.278016 -405.718221)
			(xy 435.278016 -405.654299) (xy 435.286027 -405.590881) (xy 435.301924 -405.528967) (xy 435.325456 -405.469534)
			(xy 435.35625 -405.413519) (xy 435.393823 -405.361804) (xy 435.43758 -405.315207) (xy 435.486833 -405.274462)
			(xy 435.540804 -405.240211) (xy 435.598643 -405.212994) (xy 435.659436 -405.193241) (xy 435.722226 -405.181263)
			(xy 435.786022 -405.17725) (xy 435.849818 -405.181263) (xy 435.912608 -405.193241) (xy 435.973401 -405.212994)
			(xy 436.03124 -405.240211) (xy 436.085211 -405.274462) (xy 436.134464 -405.315207) (xy 436.178221 -405.361804)
			(xy 436.215794 -405.413519) (xy 436.246588 -405.469534) (xy 436.27012 -405.528967) (xy 436.286017 -405.590881)
			(xy 436.294028 -405.654299) (xy 436.29453 -405.68626) (xy 436.294028 -405.718221) (xy 436.286017 -405.781639)
			(xy 436.27012 -405.843553) (xy 436.246588 -405.902986) (xy 436.215794 -405.959001) (xy 436.178221 -406.010716)
			(xy 436.134464 -406.057313) (xy 436.085211 -406.098058) (xy 436.03124 -406.132309) (xy 435.973401 -406.159526)
			(xy 435.912608 -406.179279) (xy 435.849818 -406.191257) (xy 435.786022 -406.195271) (xy 435.722226 -406.191257)
			(xy 435.659436 -406.179279) (xy 435.598643 -406.159526) (xy 435.540804 -406.132309) (xy 435.486833 -406.098058)
			(xy 435.43758 -406.057313) (xy 435.393823 -406.010716) (xy 435.35625 -405.959001) (xy 435.325456 -405.902986)
			(xy 435.301924 -405.843553) (xy 435.286027 -405.781639) (xy 435.278016 -405.718221) (xy 434.837311 -405.718221)
			(xy 434.838862 -405.730499) (xy 434.839364 -405.76246) (xy 434.838862 -405.794421) (xy 434.830851 -405.857839)
			(xy 434.814954 -405.919753) (xy 434.791422 -405.979186) (xy 434.760628 -406.035201) (xy 434.723055 -406.086916)
			(xy 434.679298 -406.133513) (xy 434.630045 -406.174258) (xy 434.576074 -406.208509) (xy 434.518235 -406.235726)
			(xy 434.457442 -406.255479) (xy 434.394652 -406.267457) (xy 434.330856 -406.271471) (xy 434.26706 -406.267457)
			(xy 434.20427 -406.255479) (xy 434.143477 -406.235726) (xy 434.085638 -406.208509) (xy 434.031667 -406.174258)
			(xy 433.982414 -406.133513) (xy 433.938657 -406.086916) (xy 433.901084 -406.035201) (xy 433.87029 -405.979186)
			(xy 433.846758 -405.919753) (xy 433.830861 -405.857839) (xy 433.82285 -405.794421) (xy 421.564816 -405.794421)
			(xy 421.564816 -407.204121) (xy 434.744616 -407.204121) (xy 434.744616 -407.140199) (xy 434.752627 -407.076781)
			(xy 434.768524 -407.014867) (xy 434.792056 -406.955434) (xy 434.82285 -406.899419) (xy 434.860423 -406.847704)
			(xy 434.90418 -406.801107) (xy 434.953433 -406.760362) (xy 435.007404 -406.726111) (xy 435.065243 -406.698894)
			(xy 435.126036 -406.679141) (xy 435.188826 -406.667163) (xy 435.252622 -406.66315) (xy 435.316418 -406.667163)
			(xy 435.379208 -406.679141) (xy 435.440001 -406.698894) (xy 435.49784 -406.726111) (xy 435.551811 -406.760362)
			(xy 435.601064 -406.801107) (xy 435.644821 -406.847704) (xy 435.682394 -406.899419) (xy 435.713188 -406.955434)
			(xy 435.73672 -407.014867) (xy 435.752617 -407.076781) (xy 435.760628 -407.140199) (xy 435.76113 -407.17216)
			(xy 435.760628 -407.204121) (xy 435.752617 -407.267539) (xy 435.73672 -407.329453) (xy 435.713188 -407.388886)
			(xy 435.682394 -407.444901) (xy 435.644821 -407.496616) (xy 435.601064 -407.543213) (xy 435.551811 -407.583958)
			(xy 435.49784 -407.618209) (xy 435.440001 -407.645426) (xy 435.379208 -407.665179) (xy 435.316418 -407.677157)
			(xy 435.252622 -407.681171) (xy 435.188826 -407.677157) (xy 435.126036 -407.665179) (xy 435.065243 -407.645426)
			(xy 435.007404 -407.618209) (xy 434.953433 -407.583958) (xy 434.90418 -407.543213) (xy 434.860423 -407.496616)
			(xy 434.82285 -407.444901) (xy 434.792056 -407.388886) (xy 434.768524 -407.329453) (xy 434.752627 -407.267539)
			(xy 434.744616 -407.204121) (xy 421.564816 -407.204121) (xy 421.564816 -408.042321) (xy 433.789576 -408.042321)
			(xy 433.789576 -407.978399) (xy 433.797587 -407.914981) (xy 433.813484 -407.853067) (xy 433.837016 -407.793634)
			(xy 433.86781 -407.737619) (xy 433.905383 -407.685904) (xy 433.94914 -407.639307) (xy 433.998393 -407.598562)
			(xy 434.052364 -407.564311) (xy 434.110203 -407.537094) (xy 434.170996 -407.517341) (xy 434.233786 -407.505363)
			(xy 434.297582 -407.50135) (xy 434.361378 -407.505363) (xy 434.424168 -407.517341) (xy 434.484961 -407.537094)
			(xy 434.5428 -407.564311) (xy 434.596771 -407.598562) (xy 434.646024 -407.639307) (xy 434.689781 -407.685904)
			(xy 434.727354 -407.737619) (xy 434.758148 -407.793634) (xy 434.78168 -407.853067) (xy 434.797577 -407.914981)
			(xy 434.805588 -407.978399) (xy 434.80609 -408.01036) (xy 434.805588 -408.042321) (xy 434.797577 -408.105739)
			(xy 434.78168 -408.167653) (xy 434.758148 -408.227086) (xy 434.727354 -408.283101) (xy 434.689781 -408.334816)
			(xy 434.646024 -408.381413) (xy 434.596771 -408.422158) (xy 434.5428 -408.456409) (xy 434.484961 -408.483626)
			(xy 434.424168 -408.503379) (xy 434.361378 -408.515357) (xy 434.297582 -408.519371) (xy 434.233786 -408.515357)
			(xy 434.170996 -408.503379) (xy 434.110203 -408.483626) (xy 434.052364 -408.456409) (xy 433.998393 -408.422158)
			(xy 433.94914 -408.381413) (xy 433.905383 -408.334816) (xy 433.86781 -408.283101) (xy 433.837016 -408.227086)
			(xy 433.813484 -408.167653) (xy 433.797587 -408.105739) (xy 433.789576 -408.042321) (xy 421.564816 -408.042321)
			(xy 421.564816 -408.880521) (xy 434.744616 -408.880521) (xy 434.744616 -408.816599) (xy 434.752627 -408.753181)
			(xy 434.768524 -408.691267) (xy 434.792056 -408.631834) (xy 434.82285 -408.575819) (xy 434.860423 -408.524104)
			(xy 434.90418 -408.477507) (xy 434.953433 -408.436762) (xy 435.007404 -408.402511) (xy 435.065243 -408.375294)
			(xy 435.126036 -408.355541) (xy 435.188826 -408.343563) (xy 435.252622 -408.33955) (xy 435.316418 -408.343563)
			(xy 435.379208 -408.355541) (xy 435.440001 -408.375294) (xy 435.49784 -408.402511) (xy 435.551811 -408.436762)
			(xy 435.601064 -408.477507) (xy 435.644821 -408.524104) (xy 435.682394 -408.575819) (xy 435.713188 -408.631834)
			(xy 435.73672 -408.691267) (xy 435.752617 -408.753181) (xy 435.760628 -408.816599) (xy 435.76113 -408.84856)
			(xy 435.760628 -408.880521) (xy 435.752617 -408.943939) (xy 435.73672 -409.005853) (xy 435.713188 -409.065286)
			(xy 435.682394 -409.121301) (xy 435.644821 -409.173016) (xy 435.601064 -409.219613) (xy 435.551811 -409.260358)
			(xy 435.49784 -409.294609) (xy 435.440001 -409.321826) (xy 435.379208 -409.341579) (xy 435.316418 -409.353557)
			(xy 435.252622 -409.357571) (xy 435.188826 -409.353557) (xy 435.126036 -409.341579) (xy 435.065243 -409.321826)
			(xy 435.007404 -409.294609) (xy 434.953433 -409.260358) (xy 434.90418 -409.219613) (xy 434.860423 -409.173016)
			(xy 434.82285 -409.121301) (xy 434.792056 -409.065286) (xy 434.768524 -409.005853) (xy 434.752627 -408.943939)
			(xy 434.744616 -408.880521) (xy 421.564816 -408.880521) (xy 421.564816 -412.853124) (xy 421.565137 -412.861641)
			(xy 421.570714 -412.877736) (xy 421.575738 -412.88462) (xy 421.595624 -412.910307) (xy 421.630169 -412.965324)
			(xy 421.658341 -413.023861) (xy 421.679786 -413.085182) (xy 421.694237 -413.148518) (xy 421.697185 -413.174688)
			(xy 422.727127 -413.174688) (xy 422.731134 -412.989784) (xy 422.743147 -412.805226) (xy 422.763143 -412.621362)
			(xy 422.791085 -412.438538) (xy 422.826921 -412.257095) (xy 422.870583 -412.077374) (xy 422.92199 -411.899714)
			(xy 422.981044 -411.724448) (xy 423.047635 -411.551904) (xy 423.121638 -411.382407) (xy 423.202914 -411.216275)
			(xy 423.29131 -411.053819) (xy 423.386661 -410.895345) (xy 423.488787 -410.74115) (xy 423.597496 -410.591524)
			(xy 423.712585 -410.446748) (xy 423.833838 -410.307093) (xy 423.961027 -410.172822) (xy 424.093912 -410.044186)
			(xy 424.232246 -409.921427) (xy 424.375767 -409.804777) (xy 424.524206 -409.694453) (xy 424.677286 -409.590662)
			(xy 424.834717 -409.4936) (xy 424.996206 -409.40345) (xy 425.161448 -409.320379) (xy 425.330134 -409.244544)
			(xy 425.501946 -409.176088) (xy 425.676562 -409.115138) (xy 425.853655 -409.061811) (xy 426.032892 -409.016204)
			(xy 426.213936 -408.978405) (xy 426.396447 -408.948484) (xy 426.580084 -408.926497) (xy 426.7645 -408.912485)
			(xy 426.94935 -408.906475) (xy 427.134287 -408.908479) (xy 427.318964 -408.918492) (xy 427.503034 -408.936495)
			(xy 427.68615 -408.962456) (xy 427.867971 -408.996324) (xy 428.048154 -409.038036) (xy 428.22636 -409.087515)
			(xy 428.402256 -409.144667) (xy 428.575511 -409.209385) (xy 428.7458 -409.281548) (xy 428.912803 -409.361019)
			(xy 429.076207 -409.44765) (xy 429.235704 -409.541279) (xy 429.390996 -409.641728) (xy 429.499418 -409.718721)
			(xy 433.789576 -409.718721) (xy 433.789576 -409.654799) (xy 433.797587 -409.591381) (xy 433.813484 -409.529467)
			(xy 433.837016 -409.470034) (xy 433.86781 -409.414019) (xy 433.905383 -409.362304) (xy 433.94914 -409.315707)
			(xy 433.998393 -409.274962) (xy 434.052364 -409.240711) (xy 434.110203 -409.213494) (xy 434.170996 -409.193741)
			(xy 434.233786 -409.181763) (xy 434.297582 -409.17775) (xy 434.361378 -409.181763) (xy 434.424168 -409.193741)
			(xy 434.484961 -409.213494) (xy 434.5428 -409.240711) (xy 434.596771 -409.274962) (xy 434.646024 -409.315707)
			(xy 434.689781 -409.362304) (xy 434.727354 -409.414019) (xy 434.758148 -409.470034) (xy 434.78168 -409.529467)
			(xy 434.797577 -409.591381) (xy 434.805588 -409.654799) (xy 434.80609 -409.68676) (xy 434.805588 -409.718721)
			(xy 434.797577 -409.782139) (xy 434.78168 -409.844053) (xy 434.758148 -409.903486) (xy 434.727354 -409.959501)
			(xy 434.689781 -410.011216) (xy 434.646024 -410.057813) (xy 434.596771 -410.098558) (xy 434.5428 -410.132809)
			(xy 434.484961 -410.160026) (xy 434.424168 -410.179779) (xy 434.361378 -410.191757) (xy 434.297582 -410.195771)
			(xy 434.233786 -410.191757) (xy 434.170996 -410.179779) (xy 434.110203 -410.160026) (xy 434.052364 -410.132809)
			(xy 433.998393 -410.098558) (xy 433.94914 -410.057813) (xy 433.905383 -410.011216) (xy 433.86781 -409.959501)
			(xy 433.837016 -409.903486) (xy 433.813484 -409.844053) (xy 433.797587 -409.782139) (xy 433.789576 -409.718721)
			(xy 429.499418 -409.718721) (xy 429.541791 -409.748811) (xy 429.687806 -409.862325) (xy 429.828766 -409.982057)
			(xy 429.964407 -410.107784) (xy 430.094475 -410.239268) (xy 430.218725 -410.376264) (xy 430.336923 -410.518513)
			(xy 430.448849 -410.665748) (xy 430.554292 -410.817694) (xy 430.653053 -410.974065) (xy 430.744948 -411.134568)
			(xy 430.829804 -411.2989) (xy 430.907462 -411.466755) (xy 430.977775 -411.637815) (xy 431.040612 -411.811761)
			(xy 431.095856 -411.988266) (xy 431.143401 -412.166998) (xy 431.183159 -412.347622) (xy 431.215056 -412.529799)
			(xy 431.239031 -412.713186) (xy 431.255039 -412.89744) (xy 431.263051 -413.082214) (xy 431.263552 -413.174688)
			(xy 431.263051 -413.267162) (xy 431.255039 -413.451936) (xy 431.239031 -413.63619) (xy 431.215056 -413.819577)
			(xy 431.183159 -414.001754) (xy 431.143401 -414.182378) (xy 431.095856 -414.36111) (xy 431.040612 -414.537615)
			(xy 430.977775 -414.711561) (xy 430.907462 -414.882621) (xy 430.829804 -415.050476) (xy 430.744948 -415.214808)
			(xy 430.653053 -415.375311) (xy 430.554292 -415.531682) (xy 430.448849 -415.683628) (xy 430.336923 -415.830863)
			(xy 430.218725 -415.973112) (xy 430.094475 -416.110108) (xy 429.964407 -416.241592) (xy 429.828766 -416.367319)
			(xy 429.687806 -416.487051) (xy 429.541791 -416.600565) (xy 429.390996 -416.707648) (xy 429.235704 -416.808097)
			(xy 429.076207 -416.901726) (xy 428.912803 -416.988357) (xy 428.7458 -417.067828) (xy 428.575511 -417.139991)
			(xy 428.402256 -417.204709) (xy 428.22636 -417.261861) (xy 428.048154 -417.31134) (xy 427.867971 -417.353052)
			(xy 427.68615 -417.38692) (xy 427.503034 -417.412881) (xy 427.318964 -417.430884) (xy 427.134287 -417.440897)
			(xy 426.94935 -417.442901) (xy 426.7645 -417.436891) (xy 426.580084 -417.422879) (xy 426.396447 -417.400892)
			(xy 426.213936 -417.370971) (xy 426.032892 -417.333172) (xy 425.853655 -417.287565) (xy 425.676562 -417.234238)
			(xy 425.501946 -417.173288) (xy 425.330134 -417.104832) (xy 425.161448 -417.028997) (xy 424.996206 -416.945926)
			(xy 424.834717 -416.855776) (xy 424.677286 -416.758714) (xy 424.524206 -416.654923) (xy 424.375767 -416.544599)
			(xy 424.232246 -416.427949) (xy 424.093912 -416.30519) (xy 423.961027 -416.176554) (xy 423.833838 -416.042283)
			(xy 423.712585 -415.902628) (xy 423.597496 -415.757852) (xy 423.488787 -415.608226) (xy 423.386661 -415.454031)
			(xy 423.29131 -415.295557) (xy 423.202914 -415.133101) (xy 423.121638 -414.966969) (xy 423.047635 -414.797472)
			(xy 422.981044 -414.624928) (xy 422.92199 -414.449662) (xy 422.870583 -414.272002) (xy 422.826921 -414.092281)
			(xy 422.791085 -413.910838) (xy 422.763143 -413.728014) (xy 422.743147 -413.54415) (xy 422.731134 -413.359592)
			(xy 422.727127 -413.174688) (xy 421.697185 -413.174688) (xy 421.70151 -413.213072) (xy 421.701976 -413.245554)
			(xy 421.701976 -413.672274) (xy 421.701461 -413.706468) (xy 421.693384 -413.774377) (xy 421.677373 -413.840865)
			(xy 421.653651 -413.905007) (xy 421.622547 -413.965913) (xy 421.603932 -413.9946) (xy 421.598715 -414.003156)
			(xy 421.594805 -414.022795) (xy 421.598712 -414.042435) (xy 421.603932 -414.050988) (xy 421.622549 -414.079675)
			(xy 421.653659 -414.140578) (xy 421.677383 -414.20472) (xy 421.693393 -414.271209) (xy 421.701465 -414.33912)
			(xy 421.701976 -414.373314) (xy 421.701976 -414.800034) (xy 421.701464 -414.834229) (xy 421.69339 -414.90214)
			(xy 421.677383 -414.96863) (xy 421.653665 -415.032775) (xy 421.622564 -415.093683) (xy 421.603932 -415.12236)
			(xy 421.598707 -415.130916) (xy 421.594782 -415.150561) (xy 421.598678 -415.170212) (xy 421.603932 -415.178748)
			(xy 421.622551 -415.207434) (xy 421.653665 -415.268337) (xy 421.677394 -415.332479) (xy 421.693408 -415.398967)
			(xy 421.701485 -415.466879) (xy 421.701976 -415.501074) (xy 421.701976 -415.927794) (xy 421.70146 -415.961987)
			(xy 421.69338 -416.029896) (xy 421.677367 -416.096382) (xy 421.653643 -416.160523) (xy 421.622539 -416.221427)
			(xy 421.603932 -416.25012) (xy 421.598719 -416.258676) (xy 421.594816 -416.278312) (xy 421.598728 -416.297946)
			(xy 421.603932 -416.306508) (xy 421.622547 -416.335195) (xy 421.653655 -416.396099) (xy 421.677377 -416.460241)
			(xy 421.693385 -416.52673) (xy 421.701454 -416.59464) (xy 421.701976 -416.628834) (xy 421.701976 -417.055554)
			(xy 421.701504 -417.088033) (xy 421.694206 -417.152581) (xy 421.679741 -417.215909) (xy 421.658291 -417.277224)
			(xy 421.630124 -417.335758) (xy 421.595592 -417.390779) (xy 421.575738 -417.416488) (xy 421.57015 -417.423346)
			(xy 421.564816 -417.439348) (xy 421.564816 -417.619434) (xy 421.564395 -417.649698) (xy 421.558027 -417.709892)
			(xy 421.552116 -417.739576) (xy 421.449246 -418.225224) (xy 421.442616 -418.254653) (xy 421.424037 -418.312048)
			(xy 421.412162 -418.339778) (xy 421.033448 -419.194234) (xy 421.032178 -419.210998) (xy 421.034464 -419.219634)
			(xy 421.043231 -419.255574) (xy 421.052651 -419.328949) (xy 421.05326 -419.365938) (xy 421.052848 -419.396122)
			(xy 421.046521 -419.456157) (xy 421.033981 -419.515208) (xy 421.015365 -419.572633) (xy 421.003476 -419.60038)
			(xy 420.830756 -419.990778) (xy 420.817196 -420.020352) (xy 420.784381 -420.076535) (xy 420.745482 -420.12869)
			(xy 420.700988 -420.176161) (xy 420.651459 -420.218353) (xy 420.597517 -420.254733) (xy 420.568882 -420.270178)
			(xy 420.561262 -420.274242) (xy 420.549324 -420.286688) (xy 420.47668 -420.450772) (xy 420.464067 -420.478324)
			(xy 420.433911 -420.530886) (xy 420.416482 -420.555674) (xy 420.292606 -420.7269) (xy 423.964538 -420.7269)
			(xy 423.968553 -420.663096) (xy 423.980533 -420.600298) (xy 424.000289 -420.539497) (xy 424.02751 -420.481651)
			(xy 424.061766 -420.427673) (xy 424.102518 -420.378415) (xy 424.149122 -420.334653) (xy 424.200844 -420.297077)
			(xy 424.256868 -420.26628) (xy 424.31631 -420.242748) (xy 424.378232 -420.226851) (xy 424.441659 -420.218842)
			(xy 424.473624 -420.218362) (xy 424.504535 -420.218813) (xy 424.565902 -420.226317) (xy 424.625907 -420.241199)
			(xy 424.683668 -420.26324) (xy 424.738333 -420.292116) (xy 424.789098 -420.3274) (xy 424.81246 -420.347648)
			(xy 424.819318 -420.353998) (xy 424.83659 -420.360602) (xy 424.923458 -420.360602) (xy 424.94073 -420.353998)
			(xy 424.947588 -420.347648) (xy 424.970949 -420.3274) (xy 425.021713 -420.292116) (xy 425.076378 -420.263243)
			(xy 425.13414 -420.241208) (xy 425.194147 -420.226335) (xy 425.255513 -420.218843) (xy 425.317335 -420.218843)
			(xy 425.378701 -420.226335) (xy 425.438708 -420.241208) (xy 425.49647 -420.263243) (xy 425.551135 -420.292116)
			(xy 425.601899 -420.3274) (xy 425.62526 -420.347648) (xy 425.632118 -420.353998) (xy 425.64939 -420.360602)
			(xy 425.736258 -420.360602) (xy 425.75353 -420.353998) (xy 425.760388 -420.347648) (xy 425.783754 -420.327405)
			(xy 425.834513 -420.292109) (xy 425.889176 -420.263228) (xy 425.946937 -420.241186) (xy 426.006944 -420.226309)
			(xy 426.068312 -420.218817) (xy 426.099224 -420.218362) (xy 426.129911 -420.21881) (xy 426.190839 -420.22619)
			(xy 426.250435 -420.240852) (xy 426.307832 -420.262583) (xy 426.362195 -420.291067) (xy 426.412733 -420.325889)
			(xy 426.436028 -420.34587) (xy 426.443527 -420.351954) (xy 426.461678 -420.35849) (xy 426.471334 -420.35857)
			(xy 426.502322 -420.357554) (xy 426.511898 -420.356877) (xy 426.529522 -420.349296) (xy 426.536612 -420.342822)
			(xy 426.560546 -420.319608) (xy 426.613399 -420.278961) (xy 426.671112 -420.245572) (xy 426.732695 -420.220013)
			(xy 426.79709 -420.202723) (xy 426.863192 -420.193999) (xy 426.89653 -420.19347) (xy 426.928488 -420.194018)
			(xy 426.991901 -420.202032) (xy 427.053809 -420.217931) (xy 427.113236 -420.241463) (xy 427.169246 -420.272257)
			(xy 427.220954 -420.309828) (xy 427.267547 -420.353584) (xy 427.308287 -420.402834) (xy 427.342535 -420.456801)
			(xy 427.369748 -420.514636) (xy 427.389499 -420.575424) (xy 427.401475 -420.638209) (xy 427.405489 -420.702)
			(xy 427.401475 -420.765791) (xy 427.389499 -420.828576) (xy 427.369748 -420.889364) (xy 427.342535 -420.947199)
			(xy 427.308287 -421.001166) (xy 427.267547 -421.050416) (xy 427.220954 -421.094172) (xy 427.169246 -421.131743)
			(xy 427.113236 -421.162537) (xy 427.053809 -421.186069) (xy 426.991901 -421.201968) (xy 426.928488 -421.209982)
			(xy 426.89653 -421.210486) (xy 426.865843 -421.210054) (xy 426.804915 -421.202669) (xy 426.745319 -421.188003)
			(xy 426.687922 -421.166269) (xy 426.633559 -421.137783) (xy 426.583021 -421.102959) (xy 426.559726 -421.082978)
			(xy 426.552237 -421.076879) (xy 426.534078 -421.07035) (xy 426.52442 -421.070278) (xy 426.493432 -421.071294)
			(xy 426.483861 -421.072011) (xy 426.466237 -421.079565) (xy 426.459142 -421.086026) (xy 426.435237 -421.109271)
			(xy 426.382376 -421.149913) (xy 426.324657 -421.183297) (xy 426.263069 -421.20885) (xy 426.198669 -421.226134)
			(xy 426.132563 -421.234852) (xy 426.099224 -421.235378) (xy 426.068314 -421.234888) (xy 426.00695 -421.22739)
			(xy 425.946945 -421.212515) (xy 425.889185 -421.190481) (xy 425.834518 -421.161613) (xy 425.783751 -421.126336)
			(xy 425.760388 -421.106092) (xy 425.75353 -421.099742) (xy 425.736258 -421.093138) (xy 425.64939 -421.093138)
			(xy 425.632118 -421.099742) (xy 425.62526 -421.106092) (xy 425.601899 -421.12634) (xy 425.551135 -421.161624)
			(xy 425.49647 -421.190497) (xy 425.438708 -421.212532) (xy 425.378701 -421.227405) (xy 425.317335 -421.234897)
			(xy 425.255513 -421.234897) (xy 425.194147 -421.227405) (xy 425.13414 -421.212532) (xy 425.076378 -421.190497)
			(xy 425.021713 -421.161624) (xy 424.970949 -421.12634) (xy 424.947588 -421.106092) (xy 424.94073 -421.099742)
			(xy 424.923458 -421.093138) (xy 424.83659 -421.093138) (xy 424.819318 -421.099742) (xy 424.81246 -421.106092)
			(xy 424.78912 -421.126366) (xy 424.738355 -421.161657) (xy 424.683686 -421.190534) (xy 424.62592 -421.21257)
			(xy 424.565909 -421.22744) (xy 424.504537 -421.234926) (xy 424.473624 -421.235378) (xy 424.441659 -421.234958)
			(xy 424.378232 -421.226949) (xy 424.31631 -421.211052) (xy 424.256868 -421.18752) (xy 424.200844 -421.156723)
			(xy 424.149122 -421.119147) (xy 424.102518 -421.075385) (xy 424.061766 -421.026127) (xy 424.02751 -420.972149)
			(xy 424.000289 -420.914303) (xy 423.980533 -420.853502) (xy 423.968553 -420.790704) (xy 423.964538 -420.7269)
			(xy 420.292606 -420.7269) (xy 420.021766 -421.101266) (xy 420.01694 -421.117522) (xy 420.017448 -421.126412)
			(xy 420.017956 -421.153082) (xy 420.017194 -421.186864) (xy 420.016432 -421.197278) (xy 420.02329 -421.216328)
			(xy 420.086282 -421.28567) (xy 420.10457 -421.294052) (xy 420.115238 -421.294306) (xy 420.141654 -421.29583)
			(xy 420.152725 -421.296269) (xy 420.173551 -421.288783) (xy 420.189285 -421.273219) (xy 420.193724 -421.263064)
			(xy 420.20498 -421.234379) (xy 420.233462 -421.179733) (xy 420.268338 -421.12893) (xy 420.309097 -421.082713)
			(xy 420.355142 -421.041759) (xy 420.405798 -421.00667) (xy 420.460323 -420.977958) (xy 420.517918 -420.956046)
			(xy 420.577739 -420.941253) (xy 420.638909 -420.933798) (xy 420.66972 -420.933372) (xy 420.701681 -420.933875)
			(xy 420.7651 -420.941889) (xy 420.827014 -420.957788) (xy 420.886448 -420.981322) (xy 420.942463 -421.012118)
			(xy 420.994177 -421.049692) (xy 421.040774 -421.093452) (xy 421.081519 -421.142706) (xy 421.11577 -421.196678)
			(xy 421.142986 -421.254518) (xy 421.162739 -421.315312) (xy 421.174717 -421.378103) (xy 421.178731 -421.4419)
			(xy 421.175651 -421.490859) (xy 427.907444 -421.490859) (xy 427.907444 -421.426937) (xy 427.915455 -421.363519)
			(xy 427.931352 -421.301605) (xy 427.954884 -421.242172) (xy 427.985678 -421.186157) (xy 428.023251 -421.134442)
			(xy 428.067008 -421.087845) (xy 428.116261 -421.0471) (xy 428.170232 -421.012849) (xy 428.228071 -420.985632)
			(xy 428.288864 -420.965879) (xy 428.351654 -420.953901) (xy 428.41545 -420.949888) (xy 428.479246 -420.953901)
			(xy 428.542036 -420.965879) (xy 428.602829 -420.985632) (xy 428.660668 -421.012849) (xy 428.714639 -421.0471)
			(xy 428.763892 -421.087845) (xy 428.807649 -421.134442) (xy 428.845222 -421.186157) (xy 428.876016 -421.242172)
			(xy 428.899548 -421.301605) (xy 428.915445 -421.363519) (xy 428.923456 -421.426937) (xy 428.923958 -421.458898)
			(xy 428.923456 -421.490859) (xy 428.915445 -421.554277) (xy 428.899548 -421.616191) (xy 428.876016 -421.675624)
			(xy 428.845222 -421.731639) (xy 428.807649 -421.783354) (xy 428.763892 -421.829951) (xy 428.714639 -421.870696)
			(xy 428.660668 -421.904947) (xy 428.602829 -421.932164) (xy 428.542036 -421.951917) (xy 428.479246 -421.963895)
			(xy 428.41545 -421.967909) (xy 428.351654 -421.963895) (xy 428.288864 -421.951917) (xy 428.228071 -421.932164)
			(xy 428.170232 -421.904947) (xy 428.116261 -421.870696) (xy 428.067008 -421.829951) (xy 428.023251 -421.783354)
			(xy 427.985678 -421.731639) (xy 427.954884 -421.675624) (xy 427.931352 -421.616191) (xy 427.915455 -421.554277)
			(xy 427.907444 -421.490859) (xy 421.175651 -421.490859) (xy 421.174717 -421.505697) (xy 421.162739 -421.568488)
			(xy 421.142986 -421.629282) (xy 421.11577 -421.687122) (xy 421.081519 -421.741094) (xy 421.040774 -421.790348)
			(xy 420.994177 -421.834108) (xy 420.942463 -421.871682) (xy 420.886448 -421.902478) (xy 420.827014 -421.926012)
			(xy 420.7651 -421.941911) (xy 420.701681 -421.949925) (xy 420.66972 -421.950388) (xy 420.626286 -421.94861)
			(xy 420.615208 -421.948162) (xy 420.594359 -421.955634) (xy 420.578596 -421.971191) (xy 420.574216 -421.981376)
			(xy 420.562958 -422.01006) (xy 420.534475 -422.064705) (xy 420.499598 -422.115508) (xy 420.458839 -422.161724)
			(xy 420.412794 -422.202678) (xy 420.362138 -422.237768) (xy 420.307614 -422.266481) (xy 420.25002 -422.288396)
			(xy 420.1902 -422.303192) (xy 420.129031 -422.310651) (xy 420.09822 -422.311068) (xy 420.066895 -422.310582)
			(xy 420.004721 -422.302878) (xy 419.943964 -422.287597) (xy 419.885544 -422.264969) (xy 419.830345 -422.235338)
			(xy 419.779203 -422.199152) (xy 419.732892 -422.156959) (xy 419.692113 -422.109398) (xy 419.657485 -422.057188)
			(xy 419.643052 -422.029382) (xy 419.638226 -422.01973) (xy 419.621716 -422.006014) (xy 419.528244 -421.980106)
			(xy 419.507162 -421.983154) (xy 419.498018 -421.988996) (xy 419.46193 -422.010857) (xy 419.384788 -422.045032)
			(xy 419.344348 -422.057068) (xy 419.335712 -422.059608) (xy 419.321996 -422.06926) (xy 419.216586 -422.215056)
			(xy 419.194264 -422.244904) (xy 419.143178 -422.299177) (xy 419.114732 -422.32326) (xy 418.634672 -422.717468)
			(xy 418.587174 -422.755784) (xy 418.488208 -422.827206) (xy 418.385056 -422.892439) (xy 418.313272 -422.931904)
			(xy 419.022406 -422.931904) (xy 419.025015 -422.868877) (xy 419.0354 -422.806656) (xy 419.053401 -422.746197)
			(xy 419.078743 -422.688429) (xy 419.111035 -422.63424) (xy 419.149782 -422.584461) (xy 419.19439 -422.539857)
			(xy 419.244171 -422.501114) (xy 419.298363 -422.468825) (xy 419.356133 -422.443488) (xy 419.416593 -422.425491)
			(xy 419.478814 -422.415111) (xy 419.541842 -422.412507) (xy 419.604708 -422.417719) (xy 419.666447 -422.430667)
			(xy 419.726109 -422.451152) (xy 419.78278 -422.47886) (xy 419.835588 -422.513365) (xy 419.883723 -422.554138)
			(xy 419.926444 -422.60055) (xy 419.963097 -422.651891) (xy 419.993117 -422.707372) (xy 420.016045 -422.766139)
			(xy 420.031527 -422.827291) (xy 420.039326 -422.889889) (xy 420.0398 -422.92143) (xy 420.039687 -422.929007)
			(xy 420.33164 -422.929007) (xy 420.33164 -422.865085) (xy 420.339651 -422.801667) (xy 420.355548 -422.739753)
			(xy 420.37908 -422.68032) (xy 420.409874 -422.624305) (xy 420.447447 -422.57259) (xy 420.491204 -422.525993)
			(xy 420.540457 -422.485248) (xy 420.594428 -422.450997) (xy 420.652267 -422.42378) (xy 420.71306 -422.404027)
			(xy 420.77585 -422.392049) (xy 420.839646 -422.388036) (xy 420.903442 -422.392049) (xy 420.966232 -422.404027)
			(xy 421.027025 -422.42378) (xy 421.084864 -422.450997) (xy 421.118056 -422.472061) (xy 423.723302 -422.472061)
			(xy 423.723302 -422.408139) (xy 423.731313 -422.344721) (xy 423.74721 -422.282807) (xy 423.770742 -422.223374)
			(xy 423.801536 -422.167359) (xy 423.839109 -422.115644) (xy 423.882866 -422.069047) (xy 423.932119 -422.028302)
			(xy 423.98609 -421.994051) (xy 424.043929 -421.966834) (xy 424.104722 -421.947081) (xy 424.167512 -421.935103)
			(xy 424.231308 -421.93109) (xy 424.295104 -421.935103) (xy 424.357894 -421.947081) (xy 424.418687 -421.966834)
			(xy 424.476526 -421.994051) (xy 424.530497 -422.028302) (xy 424.57975 -422.069047) (xy 424.623507 -422.115644)
			(xy 424.66108 -422.167359) (xy 424.691874 -422.223374) (xy 424.715406 -422.282807) (xy 424.731303 -422.344721)
			(xy 424.739314 -422.408139) (xy 424.739816 -422.4401) (xy 424.739314 -422.472061) (xy 424.739089 -422.473839)
			(xy 425.015654 -422.473839) (xy 425.015654 -422.409917) (xy 425.023665 -422.346499) (xy 425.039562 -422.284585)
			(xy 425.063094 -422.225152) (xy 425.093888 -422.169137) (xy 425.131461 -422.117422) (xy 425.175218 -422.070825)
			(xy 425.224471 -422.03008) (xy 425.278442 -421.995829) (xy 425.336281 -421.968612) (xy 425.397074 -421.948859)
			(xy 425.459864 -421.936881) (xy 425.52366 -421.932868) (xy 425.587456 -421.936881) (xy 425.650246 -421.948859)
			(xy 425.711039 -421.968612) (xy 425.768878 -421.995829) (xy 425.822849 -422.03008) (xy 425.872102 -422.070825)
			(xy 425.915859 -422.117422) (xy 425.953432 -422.169137) (xy 425.984226 -422.225152) (xy 426.007758 -422.284585)
			(xy 426.023655 -422.346499) (xy 426.031666 -422.409917) (xy 426.032168 -422.441878) (xy 426.031666 -422.473839)
			(xy 426.024928 -422.527179) (xy 426.305212 -422.527179) (xy 426.305212 -422.463257) (xy 426.313223 -422.399839)
			(xy 426.32912 -422.337925) (xy 426.352652 -422.278492) (xy 426.383446 -422.222477) (xy 426.421019 -422.170762)
			(xy 426.464776 -422.124165) (xy 426.514029 -422.08342) (xy 426.568 -422.049169) (xy 426.625839 -422.021952)
			(xy 426.686632 -422.002199) (xy 426.749422 -421.990221) (xy 426.813218 -421.986208) (xy 426.877014 -421.990221)
			(xy 426.939804 -422.002199) (xy 427.000597 -422.021952) (xy 427.058436 -422.049169) (xy 427.112407 -422.08342)
			(xy 427.16166 -422.124165) (xy 427.205417 -422.170762) (xy 427.24299 -422.222477) (xy 427.273784 -422.278492)
			(xy 427.297316 -422.337925) (xy 427.313213 -422.399839) (xy 427.321224 -422.463257) (xy 427.321726 -422.495218)
			(xy 427.321224 -422.527179) (xy 427.317823 -422.5541) (xy 427.608036 -422.5541) (xy 427.612049 -422.49031)
			(xy 427.624026 -422.427526) (xy 427.643777 -422.366738) (xy 427.670991 -422.308904) (xy 427.705239 -422.254938)
			(xy 427.745981 -422.20569) (xy 427.792574 -422.161936) (xy 427.844283 -422.124367) (xy 427.900293 -422.093575)
			(xy 427.959721 -422.070046) (xy 428.02163 -422.054151) (xy 428.085042 -422.04614) (xy 428.117 -422.045638)
			(xy 428.151158 -422.046203) (xy 428.218859 -422.055345) (xy 428.284728 -422.073465) (xy 428.347579 -422.100236)
			(xy 428.406282 -422.135178) (xy 428.459782 -422.177661) (xy 428.507115 -422.226922) (xy 428.527718 -422.254172)
			(xy 428.533604 -422.261482) (xy 428.549363 -422.271646) (xy 428.558452 -422.273984) (xy 428.588678 -422.280334)
			(xy 428.597794 -422.281812) (xy 428.616022 -422.278959) (xy 428.624238 -422.274746) (xy 428.645939 -422.262731)
			(xy 428.691807 -422.243844) (xy 428.739737 -422.231065) (xy 428.78892 -422.224609) (xy 428.813722 -422.2242)
			(xy 428.840973 -422.224671) (xy 428.894919 -422.232431) (xy 428.947212 -422.247788) (xy 428.996788 -422.270431)
			(xy 429.042637 -422.299898) (xy 429.083825 -422.335591) (xy 429.119515 -422.376781) (xy 429.14898 -422.422631)
			(xy 429.17162 -422.472208) (xy 429.186974 -422.524502) (xy 429.19473 -422.578449) (xy 429.19473 -422.632951)
			(xy 429.186974 -422.686898) (xy 429.17162 -422.739192) (xy 429.14898 -422.788769) (xy 429.119515 -422.834619)
			(xy 429.083825 -422.875809) (xy 429.042637 -422.911502) (xy 428.996788 -422.940969) (xy 428.947212 -422.963612)
			(xy 428.894919 -422.978969) (xy 428.840973 -422.986729) (xy 428.813722 -422.987216) (xy 428.788233 -422.986812)
			(xy 428.73771 -422.980018) (xy 428.688544 -422.966547) (xy 428.641613 -422.946641) (xy 428.597755 -422.920655)
			(xy 428.577502 -422.905174) (xy 428.570006 -422.899815) (xy 428.552425 -422.894343) (xy 428.543212 -422.894506)
			(xy 428.512224 -422.896284) (xy 428.50291 -422.89726) (xy 428.485845 -422.904934) (xy 428.47895 -422.91127)
			(xy 428.454961 -422.934772) (xy 428.401925 -422.975967) (xy 428.343926 -423.009818) (xy 428.281974 -423.035736)
			(xy 428.217148 -423.05327) (xy 428.150578 -423.062114) (xy 428.117 -423.062654) (xy 428.085042 -423.06206)
			(xy 428.02163 -423.054049) (xy 427.959721 -423.038154) (xy 427.900293 -423.014625) (xy 427.844283 -422.983833)
			(xy 427.792574 -422.946264) (xy 427.745981 -422.90251) (xy 427.705239 -422.853262) (xy 427.670991 -422.799296)
			(xy 427.643777 -422.741462) (xy 427.624026 -422.680674) (xy 427.612049 -422.61789) (xy 427.608036 -422.5541)
			(xy 427.317823 -422.5541) (xy 427.313213 -422.590597) (xy 427.297316 -422.652511) (xy 427.273784 -422.711944)
			(xy 427.24299 -422.767959) (xy 427.205417 -422.819674) (xy 427.16166 -422.866271) (xy 427.112407 -422.907016)
			(xy 427.058436 -422.941267) (xy 427.000597 -422.968484) (xy 426.939804 -422.988237) (xy 426.877014 -423.000215)
			(xy 426.813218 -423.004229) (xy 426.749422 -423.000215) (xy 426.686632 -422.988237) (xy 426.625839 -422.968484)
			(xy 426.568 -422.941267) (xy 426.514029 -422.907016) (xy 426.464776 -422.866271) (xy 426.421019 -422.819674)
			(xy 426.383446 -422.767959) (xy 426.352652 -422.711944) (xy 426.32912 -422.652511) (xy 426.313223 -422.590597)
			(xy 426.305212 -422.527179) (xy 426.024928 -422.527179) (xy 426.023655 -422.537257) (xy 426.007758 -422.599171)
			(xy 425.984226 -422.658604) (xy 425.953432 -422.714619) (xy 425.915859 -422.766334) (xy 425.872102 -422.812931)
			(xy 425.822849 -422.853676) (xy 425.768878 -422.887927) (xy 425.711039 -422.915144) (xy 425.650246 -422.934897)
			(xy 425.587456 -422.946875) (xy 425.52366 -422.950889) (xy 425.459864 -422.946875) (xy 425.397074 -422.934897)
			(xy 425.336281 -422.915144) (xy 425.278442 -422.887927) (xy 425.224471 -422.853676) (xy 425.175218 -422.812931)
			(xy 425.131461 -422.766334) (xy 425.093888 -422.714619) (xy 425.063094 -422.658604) (xy 425.039562 -422.599171)
			(xy 425.023665 -422.537257) (xy 425.015654 -422.473839) (xy 424.739089 -422.473839) (xy 424.731303 -422.535479)
			(xy 424.715406 -422.597393) (xy 424.691874 -422.656826) (xy 424.66108 -422.712841) (xy 424.623507 -422.764556)
			(xy 424.57975 -422.811153) (xy 424.530497 -422.851898) (xy 424.476526 -422.886149) (xy 424.418687 -422.913366)
			(xy 424.357894 -422.933119) (xy 424.295104 -422.945097) (xy 424.231308 -422.949111) (xy 424.167512 -422.945097)
			(xy 424.104722 -422.933119) (xy 424.043929 -422.913366) (xy 423.98609 -422.886149) (xy 423.932119 -422.851898)
			(xy 423.882866 -422.811153) (xy 423.839109 -422.764556) (xy 423.801536 -422.712841) (xy 423.770742 -422.656826)
			(xy 423.74721 -422.597393) (xy 423.731313 -422.535479) (xy 423.723302 -422.472061) (xy 421.118056 -422.472061)
			(xy 421.138835 -422.485248) (xy 421.188088 -422.525993) (xy 421.231845 -422.57259) (xy 421.269418 -422.624305)
			(xy 421.300212 -422.68032) (xy 421.323744 -422.739753) (xy 421.339641 -422.801667) (xy 421.347652 -422.865085)
			(xy 421.348154 -422.897046) (xy 421.347652 -422.929007) (xy 421.339641 -422.992425) (xy 421.323744 -423.054339)
			(xy 421.300212 -423.113772) (xy 421.269418 -423.169787) (xy 421.231845 -423.221502) (xy 421.188088 -423.268099)
			(xy 421.138835 -423.308844) (xy 421.084864 -423.343095) (xy 421.027025 -423.370312) (xy 420.966232 -423.390065)
			(xy 420.903442 -423.402043) (xy 420.839646 -423.406057) (xy 420.77585 -423.402043) (xy 420.71306 -423.390065)
			(xy 420.652267 -423.370312) (xy 420.594428 -423.343095) (xy 420.540457 -423.308844) (xy 420.491204 -423.268099)
			(xy 420.447447 -423.221502) (xy 420.409874 -423.169787) (xy 420.37908 -423.113772) (xy 420.355548 -423.054339)
			(xy 420.339651 -422.992425) (xy 420.33164 -422.929007) (xy 420.039687 -422.929007) (xy 420.039297 -422.955026)
			(xy 420.030449 -423.021632) (xy 420.012898 -423.08649) (xy 419.986951 -423.148469) (xy 419.95306 -423.206487)
			(xy 419.932866 -423.233342) (xy 419.924764 -423.244468) (xy 419.914302 -423.269916) (xy 419.911008 -423.297232)
			(xy 419.915119 -423.324437) (xy 419.926339 -423.349559) (xy 419.943854 -423.370778) (xy 419.966395 -423.386556)
			(xy 419.992327 -423.39575) (xy 420.006018 -423.397172) (xy 420.034579 -423.399682) (xy 420.090551 -423.412099)
			(xy 420.144032 -423.432757) (xy 420.193817 -423.46119) (xy 420.238783 -423.496756) (xy 420.277918 -423.538654)
			(xy 420.310337 -423.58594) (xy 420.329101 -423.624713) (xy 422.698666 -423.624713) (xy 422.698666 -423.560791)
			(xy 422.706677 -423.497373) (xy 422.722574 -423.435459) (xy 422.746106 -423.376026) (xy 422.7769 -423.320011)
			(xy 422.814473 -423.268296) (xy 422.85823 -423.221699) (xy 422.907483 -423.180954) (xy 422.961454 -423.146703)
			(xy 423.019293 -423.119486) (xy 423.080086 -423.099733) (xy 423.142876 -423.087755) (xy 423.206672 -423.083742)
			(xy 423.270468 -423.087755) (xy 423.333258 -423.099733) (xy 423.394051 -423.119486) (xy 423.45189 -423.146703)
			(xy 423.505861 -423.180954) (xy 423.555114 -423.221699) (xy 423.598871 -423.268296) (xy 423.636444 -423.320011)
			(xy 423.667238 -423.376026) (xy 423.69077 -423.435459) (xy 423.706667 -423.497373) (xy 423.714678 -423.560791)
			(xy 423.71518 -423.592752) (xy 423.714678 -423.624713) (xy 423.706667 -423.688131) (xy 423.69077 -423.750045)
			(xy 423.667238 -423.809478) (xy 423.661548 -423.819828) (xy 425.568616 -423.819828) (xy 425.572687 -423.764206)
			(xy 425.584813 -423.709769) (xy 425.604736 -423.657678) (xy 425.632032 -423.609043) (xy 425.666118 -423.5649)
			(xy 425.706267 -423.526191) (xy 425.751625 -423.49374) (xy 425.801225 -423.468239) (xy 425.854009 -423.450232)
			(xy 425.908852 -423.440102) (xy 425.964586 -423.438065) (xy 426.020023 -423.444165) (xy 426.07398 -423.458271)
			(xy 426.125309 -423.480083) (xy 426.172915 -423.509137) (xy 426.215783 -423.544812) (xy 426.253 -423.586349)
			(xy 426.283773 -423.632862) (xy 426.307445 -423.683359) (xy 426.323513 -423.736766) (xy 426.331633 -423.791942)
			(xy 426.332142 -423.819828) (xy 426.331633 -423.847714) (xy 426.323513 -423.90289) (xy 426.307445 -423.956297)
			(xy 426.283773 -424.006794) (xy 426.253 -424.053307) (xy 426.215783 -424.094844) (xy 426.172915 -424.130519)
			(xy 426.125309 -424.159573) (xy 426.07398 -424.181385) (xy 426.020023 -424.195491) (xy 425.964586 -424.201591)
			(xy 425.908852 -424.199554) (xy 425.854009 -424.189424) (xy 425.801225 -424.171417) (xy 425.751625 -424.145916)
			(xy 425.706267 -424.113465) (xy 425.666118 -424.074756) (xy 425.632032 -424.030613) (xy 425.604736 -423.981978)
			(xy 425.584813 -423.929887) (xy 425.572687 -423.87545) (xy 425.568616 -423.819828) (xy 423.661548 -423.819828)
			(xy 423.636444 -423.865493) (xy 423.598871 -423.917208) (xy 423.555114 -423.963805) (xy 423.505861 -424.00455)
			(xy 423.45189 -424.038801) (xy 423.394051 -424.066018) (xy 423.333258 -424.085771) (xy 423.270468 -424.097749)
			(xy 423.206672 -424.101763) (xy 423.142876 -424.097749) (xy 423.080086 -424.085771) (xy 423.019293 -424.066018)
			(xy 422.961454 -424.038801) (xy 422.907483 -424.00455) (xy 422.85823 -423.963805) (xy 422.814473 -423.917208)
			(xy 422.7769 -423.865493) (xy 422.746106 -423.809478) (xy 422.722574 -423.750045) (xy 422.706677 -423.688131)
			(xy 422.698666 -423.624713) (xy 420.329101 -423.624713) (xy 420.335312 -423.637546) (xy 420.352277 -423.692311)
			(xy 420.360852 -423.748998) (xy 420.361364 -423.777664) (xy 420.360878 -423.804915) (xy 420.353122 -423.858863)
			(xy 420.337767 -423.911158) (xy 420.315125 -423.960735) (xy 420.285659 -424.006585) (xy 420.249968 -424.047776)
			(xy 420.208777 -424.083467) (xy 420.162927 -424.112933) (xy 420.11335 -424.135575) (xy 420.061055 -424.15093)
			(xy 420.007107 -424.158686) (xy 419.952605 -424.158686) (xy 419.898657 -424.15093) (xy 419.846362 -424.135575)
			(xy 419.796785 -424.112933) (xy 419.750935 -424.083467) (xy 419.709744 -424.047776) (xy 419.674053 -424.006585)
			(xy 419.644587 -423.960735) (xy 419.621945 -423.911158) (xy 419.60659 -423.858863) (xy 419.598834 -423.804915)
			(xy 419.598348 -423.777664) (xy 419.598767 -423.75206) (xy 419.605606 -423.701312) (xy 419.61917 -423.651933)
			(xy 419.639214 -423.604812) (xy 419.651942 -423.582592) (xy 419.65846 -423.5705) (xy 419.665662 -423.54401)
			(xy 419.66555 -423.516559) (xy 419.65813 -423.49013) (xy 419.643939 -423.466632) (xy 419.624002 -423.447761)
			(xy 419.59976 -423.434883) (xy 419.572963 -423.428926) (xy 419.559232 -423.429176) (xy 419.531292 -423.429938)
			(xy 419.499751 -423.429424) (xy 419.437154 -423.42162) (xy 419.376003 -423.406133) (xy 419.317237 -423.383201)
			(xy 419.261759 -423.353177) (xy 419.210421 -423.31652) (xy 419.164011 -423.273795) (xy 419.123243 -423.225658)
			(xy 419.088742 -423.172847) (xy 419.061038 -423.116174) (xy 419.040557 -423.05651) (xy 419.027613 -422.994771)
			(xy 419.022406 -422.931904) (xy 418.313272 -422.931904) (xy 418.278106 -422.951237) (xy 418.167759 -423.003381)
			(xy 418.054427 -423.048674) (xy 417.996624 -423.068242) (xy 417.497006 -423.233342) (xy 417.491404 -423.235305)
			(xy 417.481259 -423.241463) (xy 417.47694 -423.245534) (xy 417.15309 -423.569384) (xy 417.146247 -423.576783)
			(xy 417.138529 -423.595382) (xy 417.138104 -423.605452) (xy 417.138104 -424.677543) (xy 418.871648 -424.677543)
			(xy 418.871648 -424.613621) (xy 418.879659 -424.550203) (xy 418.895556 -424.488289) (xy 418.919088 -424.428856)
			(xy 418.949882 -424.372841) (xy 418.987455 -424.321126) (xy 419.031212 -424.274529) (xy 419.080465 -424.233784)
			(xy 419.134436 -424.199533) (xy 419.192275 -424.172316) (xy 419.253068 -424.152563) (xy 419.315858 -424.140585)
			(xy 419.379654 -424.136572) (xy 419.44345 -424.140585) (xy 419.50624 -424.152563) (xy 419.567033 -424.172316)
			(xy 419.624872 -424.199533) (xy 419.678843 -424.233784) (xy 419.728096 -424.274529) (xy 419.771853 -424.321126)
			(xy 419.809426 -424.372841) (xy 419.84022 -424.428856) (xy 419.863752 -424.488289) (xy 419.879649 -424.550203)
			(xy 419.88766 -424.613621) (xy 419.888162 -424.645582) (xy 419.888111 -424.648841) (xy 420.141648 -424.648841)
			(xy 420.141648 -424.584919) (xy 420.149659 -424.521501) (xy 420.165556 -424.459587) (xy 420.189088 -424.400154)
			(xy 420.219882 -424.344139) (xy 420.257455 -424.292424) (xy 420.301212 -424.245827) (xy 420.350465 -424.205082)
			(xy 420.404436 -424.170831) (xy 420.462275 -424.143614) (xy 420.523068 -424.123861) (xy 420.585858 -424.111883)
			(xy 420.649654 -424.10787) (xy 420.71345 -424.111883) (xy 420.77624 -424.123861) (xy 420.837033 -424.143614)
			(xy 420.894872 -424.170831) (xy 420.948843 -424.205082) (xy 420.998096 -424.245827) (xy 421.041853 -424.292424)
			(xy 421.079426 -424.344139) (xy 421.11022 -424.400154) (xy 421.133752 -424.459587) (xy 421.149649 -424.521501)
			(xy 421.15766 -424.584919) (xy 421.157807 -424.594274) (xy 421.537636 -424.594274) (xy 421.541707 -424.538652)
			(xy 421.553833 -424.484215) (xy 421.573756 -424.432124) (xy 421.601052 -424.383489) (xy 421.635138 -424.339346)
			(xy 421.675287 -424.300637) (xy 421.720645 -424.268186) (xy 421.770245 -424.242685) (xy 421.823029 -424.224678)
			(xy 421.877872 -424.214548) (xy 421.933606 -424.212511) (xy 421.982091 -424.217846) (xy 423.933618 -424.217846)
			(xy 423.937689 -424.162224) (xy 423.949815 -424.107787) (xy 423.969738 -424.055696) (xy 423.997034 -424.007061)
			(xy 424.03112 -423.962918) (xy 424.071269 -423.924209) (xy 424.116627 -423.891758) (xy 424.166227 -423.866257)
			(xy 424.219011 -423.84825) (xy 424.273854 -423.83812) (xy 424.329588 -423.836083) (xy 424.385025 -423.842183)
			(xy 424.438982 -423.856289) (xy 424.490311 -423.878101) (xy 424.537917 -423.907155) (xy 424.580785 -423.94283)
			(xy 424.618002 -423.984367) (xy 424.648775 -424.03088) (xy 424.672447 -424.081377) (xy 424.688515 -424.134784)
			(xy 424.696635 -424.18996) (xy 424.697144 -424.217846) (xy 424.696635 -424.245732) (xy 424.688515 -424.300908)
			(xy 424.672447 -424.354315) (xy 424.648775 -424.404812) (xy 424.618002 -424.451325) (xy 424.580785 -424.492862)
			(xy 424.537917 -424.528537) (xy 424.490311 -424.557591) (xy 424.438982 -424.579403) (xy 424.385025 -424.593509)
			(xy 424.329588 -424.599609) (xy 424.273854 -424.597572) (xy 424.219011 -424.587442) (xy 424.166227 -424.569435)
			(xy 424.116627 -424.543934) (xy 424.071269 -424.511483) (xy 424.03112 -424.472774) (xy 423.997034 -424.428631)
			(xy 423.969738 -424.379996) (xy 423.949815 -424.327905) (xy 423.937689 -424.273468) (xy 423.933618 -424.217846)
			(xy 421.982091 -424.217846) (xy 421.989043 -424.218611) (xy 422.043 -424.232717) (xy 422.094329 -424.254529)
			(xy 422.141935 -424.283583) (xy 422.184803 -424.319258) (xy 422.22202 -424.360795) (xy 422.252793 -424.407308)
			(xy 422.276465 -424.457805) (xy 422.292533 -424.511212) (xy 422.300653 -424.566388) (xy 422.301162 -424.594274)
			(xy 422.300653 -424.62216) (xy 422.300539 -424.622933) (xy 430.272692 -424.622933) (xy 430.272692 -424.559011)
			(xy 430.280703 -424.495593) (xy 430.2966 -424.433679) (xy 430.320132 -424.374246) (xy 430.350926 -424.318231)
			(xy 430.388499 -424.266516) (xy 430.432256 -424.219919) (xy 430.481509 -424.179174) (xy 430.53548 -424.144923)
			(xy 430.593319 -424.117706) (xy 430.654112 -424.097953) (xy 430.716902 -424.085975) (xy 430.780698 -424.081962)
			(xy 430.844494 -424.085975) (xy 430.907284 -424.097953) (xy 430.968077 -424.117706) (xy 431.025916 -424.144923)
			(xy 431.079887 -424.179174) (xy 431.12914 -424.219919) (xy 431.172897 -424.266516) (xy 431.21047 -424.318231)
			(xy 431.241264 -424.374246) (xy 431.264796 -424.433679) (xy 431.280693 -424.495593) (xy 431.288704 -424.559011)
			(xy 431.289206 -424.590972) (xy 431.288704 -424.622933) (xy 431.79593 -424.622933) (xy 431.79593 -424.559011)
			(xy 431.803941 -424.495593) (xy 431.819838 -424.433679) (xy 431.84337 -424.374246) (xy 431.874164 -424.318231)
			(xy 431.911737 -424.266516) (xy 431.955494 -424.219919) (xy 432.004747 -424.179174) (xy 432.058718 -424.144923)
			(xy 432.116557 -424.117706) (xy 432.17735 -424.097953) (xy 432.24014 -424.085975) (xy 432.303936 -424.081962)
			(xy 432.367732 -424.085975) (xy 432.430522 -424.097953) (xy 432.491315 -424.117706) (xy 432.549154 -424.144923)
			(xy 432.603125 -424.179174) (xy 432.652378 -424.219919) (xy 432.696135 -424.266516) (xy 432.733708 -424.318231)
			(xy 432.764502 -424.374246) (xy 432.788034 -424.433679) (xy 432.803931 -424.495593) (xy 432.811942 -424.559011)
			(xy 432.812444 -424.590972) (xy 432.811942 -424.622933) (xy 432.803931 -424.686351) (xy 432.788034 -424.748265)
			(xy 432.764502 -424.807698) (xy 432.733708 -424.863713) (xy 432.696135 -424.915428) (xy 432.652378 -424.962025)
			(xy 432.603125 -425.00277) (xy 432.549154 -425.037021) (xy 432.491315 -425.064238) (xy 432.430522 -425.083991)
			(xy 432.367732 -425.095969) (xy 432.303936 -425.099983) (xy 432.24014 -425.095969) (xy 432.17735 -425.083991)
			(xy 432.116557 -425.064238) (xy 432.058718 -425.037021) (xy 432.004747 -425.00277) (xy 431.955494 -424.962025)
			(xy 431.911737 -424.915428) (xy 431.874164 -424.863713) (xy 431.84337 -424.807698) (xy 431.819838 -424.748265)
			(xy 431.803941 -424.686351) (xy 431.79593 -424.622933) (xy 431.288704 -424.622933) (xy 431.280693 -424.686351)
			(xy 431.264796 -424.748265) (xy 431.241264 -424.807698) (xy 431.21047 -424.863713) (xy 431.172897 -424.915428)
			(xy 431.12914 -424.962025) (xy 431.079887 -425.00277) (xy 431.025916 -425.037021) (xy 430.968077 -425.064238)
			(xy 430.907284 -425.083991) (xy 430.844494 -425.095969) (xy 430.780698 -425.099983) (xy 430.716902 -425.095969)
			(xy 430.654112 -425.083991) (xy 430.593319 -425.064238) (xy 430.53548 -425.037021) (xy 430.481509 -425.00277)
			(xy 430.432256 -424.962025) (xy 430.388499 -424.915428) (xy 430.350926 -424.863713) (xy 430.320132 -424.807698)
			(xy 430.2966 -424.748265) (xy 430.280703 -424.686351) (xy 430.272692 -424.622933) (xy 422.300539 -424.622933)
			(xy 422.292533 -424.677336) (xy 422.276465 -424.730743) (xy 422.252793 -424.78124) (xy 422.22202 -424.827753)
			(xy 422.184803 -424.86929) (xy 422.141935 -424.904965) (xy 422.094329 -424.934019) (xy 422.043 -424.955831)
			(xy 421.989043 -424.969937) (xy 421.933606 -424.976037) (xy 421.877872 -424.974) (xy 421.823029 -424.96387)
			(xy 421.770245 -424.945863) (xy 421.720645 -424.920362) (xy 421.675287 -424.887911) (xy 421.635138 -424.849202)
			(xy 421.601052 -424.805059) (xy 421.573756 -424.756424) (xy 421.553833 -424.704333) (xy 421.541707 -424.649896)
			(xy 421.537636 -424.594274) (xy 421.157807 -424.594274) (xy 421.158162 -424.61688) (xy 421.15766 -424.648841)
			(xy 421.149649 -424.712259) (xy 421.133752 -424.774173) (xy 421.11022 -424.833606) (xy 421.079426 -424.889621)
			(xy 421.041853 -424.941336) (xy 420.998096 -424.987933) (xy 420.948843 -425.028678) (xy 420.894872 -425.062929)
			(xy 420.837033 -425.090146) (xy 420.77624 -425.109899) (xy 420.71345 -425.121877) (xy 420.649654 -425.125891)
			(xy 420.585858 -425.121877) (xy 420.523068 -425.109899) (xy 420.462275 -425.090146) (xy 420.404436 -425.062929)
			(xy 420.350465 -425.028678) (xy 420.301212 -424.987933) (xy 420.257455 -424.941336) (xy 420.219882 -424.889621)
			(xy 420.189088 -424.833606) (xy 420.165556 -424.774173) (xy 420.149659 -424.712259) (xy 420.141648 -424.648841)
			(xy 419.888111 -424.648841) (xy 419.88766 -424.677543) (xy 419.879649 -424.740961) (xy 419.863752 -424.802875)
			(xy 419.84022 -424.862308) (xy 419.809426 -424.918323) (xy 419.771853 -424.970038) (xy 419.728096 -425.016635)
			(xy 419.678843 -425.05738) (xy 419.624872 -425.091631) (xy 419.567033 -425.118848) (xy 419.50624 -425.138601)
			(xy 419.44345 -425.150579) (xy 419.379654 -425.154593) (xy 419.315858 -425.150579) (xy 419.253068 -425.138601)
			(xy 419.192275 -425.118848) (xy 419.134436 -425.091631) (xy 419.080465 -425.05738) (xy 419.031212 -425.016635)
			(xy 418.987455 -424.970038) (xy 418.949882 -424.918323) (xy 418.919088 -424.862308) (xy 418.895556 -424.802875)
			(xy 418.879659 -424.740961) (xy 418.871648 -424.677543) (xy 417.138104 -424.677543) (xy 417.138104 -425.253912)
			(xy 418.133782 -425.253912) (xy 418.137853 -425.19829) (xy 418.149979 -425.143853) (xy 418.169902 -425.091762)
			(xy 418.197198 -425.043127) (xy 418.231284 -424.998984) (xy 418.271433 -424.960275) (xy 418.316791 -424.927824)
			(xy 418.366391 -424.902323) (xy 418.419175 -424.884316) (xy 418.474018 -424.874186) (xy 418.529752 -424.872149)
			(xy 418.585189 -424.878249) (xy 418.639146 -424.892355) (xy 418.690475 -424.914167) (xy 418.738081 -424.943221)
			(xy 418.780949 -424.978896) (xy 418.818166 -425.020433) (xy 418.848939 -425.066946) (xy 418.872611 -425.117443)
			(xy 418.888679 -425.17085) (xy 418.896799 -425.226026) (xy 418.897308 -425.253912) (xy 418.896799 -425.281798)
			(xy 418.888679 -425.336974) (xy 418.872611 -425.390381) (xy 418.848939 -425.440878) (xy 418.818166 -425.487391)
			(xy 418.796833 -425.5112) (xy 423.512803 -425.5112) (xy 423.516817 -425.447409) (xy 423.528793 -425.384624)
			(xy 423.548543 -425.323835) (xy 423.575756 -425.266001) (xy 423.610003 -425.212033) (xy 423.650744 -425.162783)
			(xy 423.697335 -425.119026) (xy 423.749043 -425.081454) (xy 423.805052 -425.050659) (xy 423.864479 -425.027126)
			(xy 423.926387 -425.011226) (xy 423.9898 -425.00321) (xy 424.021758 -425.002706) (xy 424.055252 -425.003256)
			(xy 424.121659 -425.012058) (xy 424.186336 -425.029502) (xy 424.248163 -425.055286) (xy 424.30607 -425.088963)
			(xy 424.359054 -425.129952) (xy 424.406199 -425.177541) (xy 424.446688 -425.230908) (xy 424.463718 -425.259754)
			(xy 424.469859 -425.269289) (xy 424.488476 -425.282197) (xy 424.510826 -425.285903) (xy 424.521884 -425.283376)
			(xy 424.55592 -425.27474) (xy 424.56608 -425.272454) (xy 424.58259 -425.261024) (xy 424.632374 -425.181776)
			(xy 424.635676 -425.161964) (xy 424.63339 -425.151804) (xy 424.628425 -425.12985) (xy 424.62308 -425.085156)
			(xy 424.622722 -425.06265) (xy 424.623208 -425.035399) (xy 424.630964 -424.981451) (xy 424.646319 -424.929156)
			(xy 424.668961 -424.879579) (xy 424.698427 -424.833729) (xy 424.734118 -424.792538) (xy 424.775309 -424.756847)
			(xy 424.821159 -424.727381) (xy 424.870736 -424.704739) (xy 424.923031 -424.689384) (xy 424.976979 -424.681628)
			(xy 425.031481 -424.681628) (xy 425.085429 -424.689384) (xy 425.137724 -424.704739) (xy 425.187301 -424.727381)
			(xy 425.233151 -424.756847) (xy 425.274342 -424.792538) (xy 425.310033 -424.833729) (xy 425.339499 -424.879579)
			(xy 425.362141 -424.929156) (xy 425.377496 -424.981451) (xy 425.385252 -425.035399) (xy 425.385738 -425.06265)
			(xy 425.385238 -425.089659) (xy 425.377637 -425.143139) (xy 425.362567 -425.195012) (xy 425.340328 -425.24424)
			(xy 425.311366 -425.289837) (xy 425.27626 -425.330891) (xy 425.235712 -425.366582) (xy 425.190535 -425.396194)
			(xy 425.166282 -425.40809) (xy 425.15663 -425.412408) (xy 425.143168 -425.427394) (xy 425.112434 -425.515786)
			(xy 425.113704 -425.535852) (xy 425.118276 -425.54525) (xy 425.126339 -425.561806) (xy 425.140321 -425.595876)
			(xy 425.146216 -425.613322) (xy 425.149259 -425.621482) (xy 425.159915 -425.635243) (xy 425.167044 -425.640246)
			(xy 425.19219 -425.656248) (xy 425.199665 -425.660648) (xy 425.21656 -425.66453) (xy 425.22521 -425.663868)
			(xy 425.239325 -425.662418) (xy 425.267663 -425.660891) (xy 425.281852 -425.66082) (xy 425.313818 -425.661242)
			(xy 425.377247 -425.669249) (xy 425.439171 -425.685144) (xy 425.498616 -425.708674) (xy 425.554642 -425.73947)
			(xy 425.606366 -425.777046) (xy 425.652973 -425.820808) (xy 425.693726 -425.870067) (xy 425.727985 -425.924045)
			(xy 425.755207 -425.981892) (xy 425.774965 -426.042695) (xy 425.786945 -426.105494) (xy 425.79096 -426.1693)
			(xy 425.786945 -426.233106) (xy 425.774965 -426.295905) (xy 425.755207 -426.356708) (xy 425.727985 -426.414555)
			(xy 425.693726 -426.468533) (xy 425.652973 -426.517792) (xy 425.606366 -426.561554) (xy 425.554642 -426.59913)
			(xy 425.498616 -426.629926) (xy 425.439171 -426.653456) (xy 425.377247 -426.669351) (xy 425.313818 -426.677358)
			(xy 425.281852 -426.677836) (xy 425.249967 -426.677318) (xy 425.186701 -426.669328) (xy 425.124929 -426.653492)
			(xy 425.065621 -426.630058) (xy 425.009708 -426.599394) (xy 424.958067 -426.561981) (xy 424.911508 -426.518407)
			(xy 424.870761 -426.469353) (xy 424.836465 -426.415591) (xy 424.809159 -426.357964) (xy 424.798744 -426.327824)
			(xy 424.795697 -426.319666) (xy 424.785044 -426.305903) (xy 424.777916 -426.3009) (xy 424.75277 -426.284898)
			(xy 424.74528 -426.280528) (xy 424.728397 -426.276626) (xy 424.71975 -426.277278) (xy 424.705635 -426.278731)
			(xy 424.677297 -426.280256) (xy 424.663108 -426.280326) (xy 424.629612 -426.279837) (xy 424.563201 -426.27103)
			(xy 424.498521 -426.253579) (xy 424.436692 -426.227787) (xy 424.378785 -426.194101) (xy 424.325802 -426.153104)
			(xy 424.27866 -426.105505) (xy 424.238175 -426.052129) (xy 424.221148 -426.023278) (xy 424.214946 -426.013789)
			(xy 424.196359 -426.000871) (xy 424.174033 -425.997144) (xy 424.162982 -425.999656) (xy 424.128431 -426.009029)
			(xy 424.057553 -426.019095) (xy 424.021758 -426.019722) (xy 423.9898 -426.01919) (xy 423.926387 -426.011174)
			(xy 423.864479 -425.995274) (xy 423.805052 -425.971741) (xy 423.749043 -425.940946) (xy 423.697335 -425.903374)
			(xy 423.650744 -425.859617) (xy 423.610003 -425.810367) (xy 423.575756 -425.756399) (xy 423.548543 -425.698565)
			(xy 423.528793 -425.637776) (xy 423.516817 -425.574991) (xy 423.512803 -425.5112) (xy 418.796833 -425.5112)
			(xy 418.780949 -425.528928) (xy 418.738081 -425.564603) (xy 418.690475 -425.593657) (xy 418.639146 -425.615469)
			(xy 418.585189 -425.629575) (xy 418.529752 -425.635675) (xy 418.474018 -425.633638) (xy 418.419175 -425.623508)
			(xy 418.366391 -425.605501) (xy 418.316791 -425.58) (xy 418.271433 -425.547549) (xy 418.231284 -425.50884)
			(xy 418.197198 -425.464697) (xy 418.169902 -425.416062) (xy 418.149979 -425.363971) (xy 418.137853 -425.309534)
			(xy 418.133782 -425.253912) (xy 417.138104 -425.253912) (xy 417.138104 -427.193413) (xy 417.79926 -427.193413)
			(xy 417.79926 -427.129491) (xy 417.807271 -427.066073) (xy 417.823168 -427.004159) (xy 417.8467 -426.944726)
			(xy 417.877494 -426.888711) (xy 417.915067 -426.836996) (xy 417.958824 -426.790399) (xy 418.008077 -426.749654)
			(xy 418.062048 -426.715403) (xy 418.119887 -426.688186) (xy 418.18068 -426.668433) (xy 418.24347 -426.656455)
			(xy 418.307266 -426.652442) (xy 418.371062 -426.656455) (xy 418.433852 -426.668433) (xy 418.494645 -426.688186)
			(xy 418.552484 -426.715403) (xy 418.606455 -426.749654) (xy 418.655708 -426.790399) (xy 418.699465 -426.836996)
			(xy 418.737038 -426.888711) (xy 418.767832 -426.944726) (xy 418.791364 -427.004159) (xy 418.807261 -427.066073)
			(xy 418.81055 -427.09211) (xy 437.580784 -427.09211) (xy 437.584855 -427.036488) (xy 437.596981 -426.982051)
			(xy 437.616904 -426.92996) (xy 437.6442 -426.881325) (xy 437.678286 -426.837182) (xy 437.718435 -426.798473)
			(xy 437.763793 -426.766022) (xy 437.813393 -426.740521) (xy 437.866177 -426.722514) (xy 437.92102 -426.712384)
			(xy 437.976754 -426.710347) (xy 438.032191 -426.716447) (xy 438.086148 -426.730553) (xy 438.137477 -426.752365)
			(xy 438.185083 -426.781419) (xy 438.227951 -426.817094) (xy 438.265168 -426.858631) (xy 438.295941 -426.905144)
			(xy 438.319613 -426.955641) (xy 438.335681 -427.009048) (xy 438.343801 -427.064224) (xy 438.34431 -427.09211)
			(xy 438.343801 -427.119996) (xy 438.335681 -427.175172) (xy 438.319613 -427.228579) (xy 438.295941 -427.279076)
			(xy 438.265168 -427.325589) (xy 438.227951 -427.367126) (xy 438.185083 -427.402801) (xy 438.137477 -427.431855)
			(xy 438.086148 -427.453667) (xy 438.032191 -427.467773) (xy 437.976754 -427.473873) (xy 437.92102 -427.471836)
			(xy 437.866177 -427.461706) (xy 437.813393 -427.443699) (xy 437.763793 -427.418198) (xy 437.718435 -427.385747)
			(xy 437.678286 -427.347038) (xy 437.6442 -427.302895) (xy 437.616904 -427.25426) (xy 437.596981 -427.202169)
			(xy 437.584855 -427.147732) (xy 437.580784 -427.09211) (xy 418.81055 -427.09211) (xy 418.815272 -427.129491)
			(xy 418.815774 -427.161452) (xy 418.815272 -427.193413) (xy 418.807261 -427.256831) (xy 418.791364 -427.318745)
			(xy 418.767832 -427.378178) (xy 418.737038 -427.434193) (xy 418.699465 -427.485908) (xy 418.655708 -427.532505)
			(xy 418.606455 -427.57325) (xy 418.552484 -427.607501) (xy 418.49694 -427.633638) (xy 426.190662 -427.633638)
			(xy 426.194733 -427.578016) (xy 426.206859 -427.523579) (xy 426.226782 -427.471488) (xy 426.254078 -427.422853)
			(xy 426.288164 -427.37871) (xy 426.328313 -427.340001) (xy 426.373671 -427.30755) (xy 426.423271 -427.282049)
			(xy 426.476055 -427.264042) (xy 426.530898 -427.253912) (xy 426.586632 -427.251875) (xy 426.642069 -427.257975)
			(xy 426.696026 -427.272081) (xy 426.747355 -427.293893) (xy 426.794961 -427.322947) (xy 426.837829 -427.358622)
			(xy 426.875046 -427.400159) (xy 426.905819 -427.446672) (xy 426.929491 -427.497169) (xy 426.945559 -427.550576)
			(xy 426.953679 -427.605752) (xy 426.954188 -427.633638) (xy 426.953679 -427.661524) (xy 426.945784 -427.715172)
			(xy 428.07966 -427.715172) (xy 428.083731 -427.65955) (xy 428.095857 -427.605113) (xy 428.11578 -427.553022)
			(xy 428.143076 -427.504387) (xy 428.177162 -427.460244) (xy 428.217311 -427.421535) (xy 428.262669 -427.389084)
			(xy 428.312269 -427.363583) (xy 428.365053 -427.345576) (xy 428.419896 -427.335446) (xy 428.47563 -427.333409)
			(xy 428.531067 -427.339509) (xy 428.585024 -427.353615) (xy 428.636353 -427.375427) (xy 428.683959 -427.404481)
			(xy 428.726827 -427.440156) (xy 428.764044 -427.481693) (xy 428.794817 -427.528206) (xy 428.818489 -427.578703)
			(xy 428.834557 -427.63211) (xy 428.842677 -427.687286) (xy 428.843186 -427.715172) (xy 428.842677 -427.743058)
			(xy 428.834557 -427.798234) (xy 428.818489 -427.851641) (xy 428.794817 -427.902138) (xy 428.764044 -427.948651)
			(xy 428.726827 -427.990188) (xy 428.683959 -428.025863) (xy 428.636353 -428.054917) (xy 428.585024 -428.076729)
			(xy 428.531067 -428.090835) (xy 428.47563 -428.096935) (xy 428.419896 -428.094898) (xy 428.365053 -428.084768)
			(xy 428.312269 -428.066761) (xy 428.262669 -428.04126) (xy 428.217311 -428.008809) (xy 428.177162 -427.9701)
			(xy 428.143076 -427.925957) (xy 428.11578 -427.877322) (xy 428.095857 -427.825231) (xy 428.083731 -427.770794)
			(xy 428.07966 -427.715172) (xy 426.945784 -427.715172) (xy 426.945559 -427.7167) (xy 426.929491 -427.770107)
			(xy 426.905819 -427.820604) (xy 426.875046 -427.867117) (xy 426.837829 -427.908654) (xy 426.794961 -427.944329)
			(xy 426.747355 -427.973383) (xy 426.696026 -427.995195) (xy 426.642069 -428.009301) (xy 426.586632 -428.015401)
			(xy 426.530898 -428.013364) (xy 426.476055 -428.003234) (xy 426.423271 -427.985227) (xy 426.373671 -427.959726)
			(xy 426.328313 -427.927275) (xy 426.288164 -427.888566) (xy 426.254078 -427.844423) (xy 426.226782 -427.795788)
			(xy 426.206859 -427.743697) (xy 426.194733 -427.68926) (xy 426.190662 -427.633638) (xy 418.49694 -427.633638)
			(xy 418.494645 -427.634718) (xy 418.433852 -427.654471) (xy 418.371062 -427.666449) (xy 418.307266 -427.670463)
			(xy 418.24347 -427.666449) (xy 418.18068 -427.654471) (xy 418.119887 -427.634718) (xy 418.062048 -427.607501)
			(xy 418.008077 -427.57325) (xy 417.958824 -427.532505) (xy 417.915067 -427.485908) (xy 417.877494 -427.434193)
			(xy 417.8467 -427.378178) (xy 417.823168 -427.318745) (xy 417.807271 -427.256831) (xy 417.79926 -427.193413)
			(xy 417.138104 -427.193413) (xy 417.138104 -428.972663) (xy 423.867357 -428.972663) (xy 423.869959 -428.909629)
			(xy 423.880338 -428.847401) (xy 423.898334 -428.786935) (xy 423.923671 -428.729159) (xy 423.95596 -428.674961)
			(xy 423.994705 -428.625173) (xy 424.03931 -428.58056) (xy 424.089092 -428.541807) (xy 424.143285 -428.509509)
			(xy 424.201056 -428.484163) (xy 424.261519 -428.466157) (xy 424.323745 -428.455768) (xy 424.386779 -428.453155)
			(xy 424.449651 -428.45836) (xy 424.511396 -428.471301) (xy 424.571067 -428.491781) (xy 424.627746 -428.519484)
			(xy 424.680564 -428.553985) (xy 424.728708 -428.594754) (xy 424.77144 -428.641165) (xy 424.808103 -428.692506)
			(xy 424.838133 -428.747987) (xy 424.861071 -428.806757) (xy 424.874096 -428.858172) (xy 429.22266 -428.858172)
			(xy 429.226731 -428.80255) (xy 429.238857 -428.748113) (xy 429.25878 -428.696022) (xy 429.286076 -428.647387)
			(xy 429.320162 -428.603244) (xy 429.360311 -428.564535) (xy 429.405669 -428.532084) (xy 429.455269 -428.506583)
			(xy 429.508053 -428.488576) (xy 429.562896 -428.478446) (xy 429.61863 -428.476409) (xy 429.674067 -428.482509)
			(xy 429.728024 -428.496615) (xy 429.779353 -428.518427) (xy 429.826959 -428.547481) (xy 429.869827 -428.583156)
			(xy 429.907044 -428.624693) (xy 429.937817 -428.671206) (xy 429.961489 -428.721703) (xy 429.977557 -428.77511)
			(xy 429.985677 -428.830286) (xy 429.986186 -428.858172) (xy 429.985677 -428.886058) (xy 429.977557 -428.941234)
			(xy 429.961489 -428.994641) (xy 429.937817 -429.045138) (xy 429.907044 -429.091651) (xy 429.869827 -429.133188)
			(xy 429.826959 -429.168863) (xy 429.779353 -429.197917) (xy 429.728024 -429.219729) (xy 429.674067 -429.233835)
			(xy 429.61863 -429.239935) (xy 429.562896 -429.237898) (xy 429.508053 -429.227768) (xy 429.455269 -429.209761)
			(xy 429.405669 -429.18426) (xy 429.360311 -429.151809) (xy 429.320162 -429.1131) (xy 429.286076 -429.068957)
			(xy 429.25878 -429.020322) (xy 429.238857 -428.968231) (xy 429.226731 -428.913794) (xy 429.22266 -428.858172)
			(xy 424.874096 -428.858172) (xy 424.876563 -428.867912) (xy 424.884372 -428.930514) (xy 424.88485 -428.962058)
			(xy 424.88485 -428.964598) (xy 424.88485 -428.974758) (xy 424.892216 -428.993046) (xy 424.95597 -429.058578)
			(xy 424.974004 -429.066452) (xy 424.984164 -429.066706) (xy 425.011004 -429.067839) (xy 425.064003 -429.076591)
			(xy 425.115252 -429.092688) (xy 425.163737 -429.115813) (xy 425.2085 -429.145508) (xy 425.248656 -429.181187)
			(xy 425.283413 -429.222145) (xy 425.312083 -429.267571) (xy 425.3341 -429.316569) (xy 425.349028 -429.368171)
			(xy 425.356572 -429.421355) (xy 425.357036 -429.448214) (xy 425.356535 -429.475464) (xy 425.348778 -429.52941)
			(xy 425.333422 -429.581703) (xy 425.310781 -429.631278) (xy 425.281316 -429.677127) (xy 425.245626 -429.718317)
			(xy 425.204438 -429.754008) (xy 425.158591 -429.783475) (xy 425.109016 -429.806117) (xy 425.056724 -429.821475)
			(xy 425.002778 -429.829234) (xy 424.975528 -429.829722) (xy 424.947111 -429.829189) (xy 424.890909 -429.820734)
			(xy 424.836582 -429.804038) (xy 424.785332 -429.779469) (xy 424.738292 -429.747572) (xy 424.696503 -429.70905)
			(xy 424.66089 -429.664757) (xy 424.632239 -429.615673) (xy 424.611185 -429.562881) (xy 424.60418 -429.535336)
			(xy 424.601894 -429.52543) (xy 424.59021 -429.509174) (xy 424.512994 -429.460406) (xy 424.49369 -429.45685)
			(xy 424.483784 -429.459136) (xy 424.457249 -429.464502) (xy 424.403412 -429.470232) (xy 424.376342 -429.470566)
			(xy 424.344798 -429.470177) (xy 424.282195 -429.462379) (xy 424.221037 -429.446897) (xy 424.162263 -429.423969)
			(xy 424.106777 -429.393947) (xy 424.055431 -429.357293) (xy 424.009012 -429.314569) (xy 423.968235 -429.266431)
			(xy 423.933725 -429.21362) (xy 423.906013 -429.156945) (xy 423.885524 -429.097277) (xy 423.872572 -429.035534)
			(xy 423.867357 -428.972663) (xy 417.138104 -428.972663) (xy 417.138104 -429.461676) (xy 422.339006 -429.461676)
			(xy 422.343077 -429.406054) (xy 422.355203 -429.351617) (xy 422.375126 -429.299526) (xy 422.402422 -429.250891)
			(xy 422.436508 -429.206748) (xy 422.476657 -429.168039) (xy 422.522015 -429.135588) (xy 422.571615 -429.110087)
			(xy 422.624399 -429.09208) (xy 422.679242 -429.08195) (xy 422.734976 -429.079913) (xy 422.790413 -429.086013)
			(xy 422.84437 -429.100119) (xy 422.895699 -429.121931) (xy 422.943305 -429.150985) (xy 422.986173 -429.18666)
			(xy 423.02339 -429.228197) (xy 423.054163 -429.27471) (xy 423.077835 -429.325207) (xy 423.093903 -429.378614)
			(xy 423.102023 -429.43379) (xy 423.102532 -429.461676) (xy 423.102023 -429.489562) (xy 423.093903 -429.544738)
			(xy 423.077835 -429.598145) (xy 423.054163 -429.648642) (xy 423.02339 -429.695155) (xy 422.986173 -429.736692)
			(xy 422.943305 -429.772367) (xy 422.895699 -429.801421) (xy 422.84437 -429.823233) (xy 422.790413 -429.837339)
			(xy 422.734976 -429.843439) (xy 422.679242 -429.841402) (xy 422.624399 -429.831272) (xy 422.571615 -429.813265)
			(xy 422.522015 -429.787764) (xy 422.476657 -429.755313) (xy 422.436508 -429.716604) (xy 422.402422 -429.672461)
			(xy 422.375126 -429.623826) (xy 422.355203 -429.571735) (xy 422.343077 -429.517298) (xy 422.339006 -429.461676)
			(xy 417.138104 -429.461676) (xy 417.138104 -431.533808) (xy 427.540164 -431.533808) (xy 427.544235 -431.478186)
			(xy 427.556361 -431.423749) (xy 427.576284 -431.371658) (xy 427.60358 -431.323023) (xy 427.637666 -431.27888)
			(xy 427.677815 -431.240171) (xy 427.723173 -431.20772) (xy 427.772773 -431.182219) (xy 427.825557 -431.164212)
			(xy 427.8804 -431.154082) (xy 427.936134 -431.152045) (xy 427.991571 -431.158145) (xy 428.045528 -431.172251)
			(xy 428.096857 -431.194063) (xy 428.144463 -431.223117) (xy 428.187331 -431.258792) (xy 428.224548 -431.300329)
			(xy 428.255321 -431.346842) (xy 428.278993 -431.397339) (xy 428.295061 -431.450746) (xy 428.303181 -431.505922)
			(xy 428.303667 -431.532538) (xy 430.17389 -431.532538) (xy 430.177961 -431.476916) (xy 430.190087 -431.422479)
			(xy 430.21001 -431.370388) (xy 430.237306 -431.321753) (xy 430.271392 -431.27761) (xy 430.311541 -431.238901)
			(xy 430.356899 -431.20645) (xy 430.406499 -431.180949) (xy 430.459283 -431.162942) (xy 430.514126 -431.152812)
			(xy 430.56986 -431.150775) (xy 430.625297 -431.156875) (xy 430.679254 -431.170981) (xy 430.730583 -431.192793)
			(xy 430.778189 -431.221847) (xy 430.821057 -431.257522) (xy 430.858274 -431.299059) (xy 430.889047 -431.345572)
			(xy 430.912719 -431.396069) (xy 430.928787 -431.449476) (xy 430.936634 -431.5028) (xy 431.330588 -431.5028)
			(xy 431.334602 -431.439002) (xy 431.346581 -431.37621) (xy 431.366335 -431.315415) (xy 431.393554 -431.257575)
			(xy 431.427807 -431.203603) (xy 431.468554 -431.154349) (xy 431.515154 -431.110591) (xy 431.566871 -431.073019)
			(xy 431.622889 -431.042225) (xy 431.682325 -431.018695) (xy 431.744242 -431.002801) (xy 431.807662 -430.994791)
			(xy 431.839624 -430.994312) (xy 431.883058 -430.99609) (xy 431.894488 -430.997106) (xy 431.91557 -430.989232)
			(xy 431.98669 -430.917096) (xy 431.994056 -430.89576) (xy 431.992786 -430.88433) (xy 431.991477 -430.871034)
			(xy 431.99008 -430.84435) (xy 431.989992 -430.83099) (xy 431.990447 -430.800259) (xy 431.997856 -430.739245)
			(xy 432.012566 -430.679568) (xy 432.034362 -430.6221) (xy 432.062926 -430.567679) (xy 432.097841 -430.517096)
			(xy 432.138599 -430.471091) (xy 432.184604 -430.430335) (xy 432.235187 -430.395421) (xy 432.28961 -430.366858)
			(xy 432.347078 -430.345063) (xy 432.406754 -430.330354) (xy 432.467769 -430.322946) (xy 432.4985 -430.322482)
			(xy 432.510393 -430.322561) (xy 432.534152 -430.323706) (xy 432.545998 -430.324768) (xy 432.555142 -430.32553)
			(xy 432.572668 -430.320958) (xy 432.641756 -430.271428) (xy 432.651916 -430.256442) (xy 432.654202 -430.247552)
			(xy 432.660846 -430.222015) (xy 432.680278 -430.172957) (xy 432.706287 -430.127044) (xy 432.738375 -430.085155)
			(xy 432.775931 -430.048089) (xy 432.818237 -430.016552) (xy 432.841146 -430.003458) (xy 432.849782 -429.998632)
			(xy 432.86172 -429.984154) (xy 432.889406 -429.899572) (xy 432.88839 -429.880776) (xy 432.884326 -429.871632)
			(xy 432.869509 -429.838034) (xy 432.848597 -429.767646) (xy 432.838004 -429.694986) (xy 432.837336 -429.658272)
			(xy 432.837838 -429.626311) (xy 432.845849 -429.562893) (xy 432.861746 -429.500979) (xy 432.885278 -429.441546)
			(xy 432.916072 -429.385531) (xy 432.953645 -429.333816) (xy 432.997402 -429.287219) (xy 433.046655 -429.246474)
			(xy 433.100626 -429.212223) (xy 433.158465 -429.185006) (xy 433.219258 -429.165253) (xy 433.282048 -429.153275)
			(xy 433.345844 -429.149262) (xy 433.40964 -429.153275) (xy 433.47243 -429.165253) (xy 433.533223 -429.185006)
			(xy 433.591062 -429.212223) (xy 433.645033 -429.246474) (xy 433.694286 -429.287219) (xy 433.738043 -429.333816)
			(xy 433.738083 -429.333871) (xy 439.403738 -429.333871) (xy 439.403738 -429.269949) (xy 439.411749 -429.206531)
			(xy 439.427646 -429.144617) (xy 439.451178 -429.085184) (xy 439.481972 -429.029169) (xy 439.519545 -428.977454)
			(xy 439.563302 -428.930857) (xy 439.612555 -428.890112) (xy 439.666526 -428.855861) (xy 439.724365 -428.828644)
			(xy 439.785158 -428.808891) (xy 439.847948 -428.796913) (xy 439.911744 -428.7929) (xy 439.97554 -428.796913)
			(xy 440.03833 -428.808891) (xy 440.099123 -428.828644) (xy 440.156962 -428.855861) (xy 440.210933 -428.890112)
			(xy 440.260186 -428.930857) (xy 440.303943 -428.977454) (xy 440.341516 -429.029169) (xy 440.37231 -429.085184)
			(xy 440.395842 -429.144617) (xy 440.411739 -429.206531) (xy 440.41975 -429.269949) (xy 440.420252 -429.30191)
			(xy 440.41975 -429.333871) (xy 440.411739 -429.397289) (xy 440.395842 -429.459203) (xy 440.37231 -429.518636)
			(xy 440.341516 -429.574651) (xy 440.303943 -429.626366) (xy 440.260186 -429.672963) (xy 440.210933 -429.713708)
			(xy 440.156962 -429.747959) (xy 440.099123 -429.775176) (xy 440.03833 -429.794929) (xy 439.97554 -429.806907)
			(xy 439.911744 -429.810921) (xy 439.847948 -429.806907) (xy 439.785158 -429.794929) (xy 439.724365 -429.775176)
			(xy 439.666526 -429.747959) (xy 439.612555 -429.713708) (xy 439.563302 -429.672963) (xy 439.519545 -429.626366)
			(xy 439.481972 -429.574651) (xy 439.451178 -429.518636) (xy 439.427646 -429.459203) (xy 439.411749 -429.397289)
			(xy 439.403738 -429.333871) (xy 433.738083 -429.333871) (xy 433.775616 -429.385531) (xy 433.80641 -429.441546)
			(xy 433.829942 -429.500979) (xy 433.845839 -429.562893) (xy 433.85385 -429.626311) (xy 433.854352 -429.658272)
			(xy 433.853878 -429.691738) (xy 433.845077 -429.758088) (xy 433.827649 -429.822711) (xy 433.801895 -429.88449)
			(xy 433.76826 -429.942357) (xy 433.749532 -429.966585) (xy 437.749436 -429.966585) (xy 437.749436 -429.902663)
			(xy 437.757447 -429.839245) (xy 437.773344 -429.777331) (xy 437.796876 -429.717898) (xy 437.82767 -429.661883)
			(xy 437.865243 -429.610168) (xy 437.909 -429.563571) (xy 437.958253 -429.522826) (xy 438.012224 -429.488575)
			(xy 438.070063 -429.461358) (xy 438.130856 -429.441605) (xy 438.193646 -429.429627) (xy 438.257442 -429.425614)
			(xy 438.321238 -429.429627) (xy 438.384028 -429.441605) (xy 438.444821 -429.461358) (xy 438.50266 -429.488575)
			(xy 438.556631 -429.522826) (xy 438.605884 -429.563571) (xy 438.649641 -429.610168) (xy 438.687214 -429.661883)
			(xy 438.718008 -429.717898) (xy 438.74154 -429.777331) (xy 438.757437 -429.839245) (xy 438.765448 -429.902663)
			(xy 438.76595 -429.934624) (xy 438.765448 -429.966585) (xy 438.757437 -430.030003) (xy 438.74154 -430.091917)
			(xy 438.718008 -430.15135) (xy 438.687214 -430.207365) (xy 438.649641 -430.25908) (xy 438.605884 -430.305677)
			(xy 438.556631 -430.346422) (xy 438.50266 -430.380673) (xy 438.444821 -430.40789) (xy 438.384028 -430.427643)
			(xy 438.321238 -430.439621) (xy 438.257442 -430.443635) (xy 438.193646 -430.439621) (xy 438.130856 -430.427643)
			(xy 438.070063 -430.40789) (xy 438.012224 -430.380673) (xy 437.958253 -430.346422) (xy 437.909 -430.305677)
			(xy 437.865243 -430.25908) (xy 437.82767 -430.207365) (xy 437.796876 -430.15135) (xy 437.773344 -430.091917)
			(xy 437.757447 -430.030003) (xy 437.749436 -429.966585) (xy 433.749532 -429.966585) (xy 433.727326 -429.995313)
			(xy 433.6798 -430.042442) (xy 433.626503 -430.08293) (xy 433.568356 -430.116078) (xy 433.506363 -430.141313)
			(xy 433.474114 -430.15027) (xy 433.464462 -430.15281) (xy 433.449222 -430.163986) (xy 433.40147 -430.23917)
			(xy 433.397914 -430.257712) (xy 433.399692 -430.267364) (xy 433.402777 -430.28479) (xy 433.406085 -430.320026)
			(xy 433.406296 -430.337722) (xy 433.40581 -430.364373) (xy 433.398375 -430.417153) (xy 433.383666 -430.468386)
			(xy 433.361971 -430.517072) (xy 433.33371 -430.562265) (xy 433.299435 -430.603085) (xy 433.259812 -430.638738)
			(xy 433.215613 -430.668529) (xy 433.167697 -430.691879) (xy 433.116999 -430.708333) (xy 433.090828 -430.713388)
			(xy 433.081684 -430.715166) (xy 433.065936 -430.72431) (xy 433.012342 -430.790096) (xy 433.0065 -430.807114)
			(xy 433.006754 -430.816512) (xy 433.007008 -430.83099) (xy 433.006553 -430.861722) (xy 432.999145 -430.922738)
			(xy 432.984437 -430.982416) (xy 432.962643 -431.039886) (xy 432.93408 -431.09431) (xy 432.899165 -431.144894)
			(xy 432.858407 -431.1909) (xy 432.812402 -431.231659) (xy 432.761818 -431.266575) (xy 432.707395 -431.295139)
			(xy 432.649925 -431.316934) (xy 432.590248 -431.331644) (xy 432.529232 -431.339052) (xy 432.4985 -431.339498)
			(xy 432.478924 -431.339295) (xy 432.439892 -431.336241) (xy 432.420522 -431.333402) (xy 432.408399 -431.332267)
			(xy 432.385332 -431.339942) (xy 432.376326 -431.348134) (xy 432.354228 -431.37074) (xy 432.346227 -431.379902)
			(xy 432.339067 -431.403112) (xy 432.340512 -431.41519) (xy 432.342798 -431.428906) (xy 432.344322 -431.439574)
			(xy 432.355752 -431.457608) (xy 432.436016 -431.511456) (xy 432.456844 -431.515266) (xy 432.467512 -431.512726)
			(xy 432.489831 -431.507612) (xy 432.535294 -431.502141) (xy 432.55819 -431.501804) (xy 432.585444 -431.502242)
			(xy 432.639398 -431.509998) (xy 432.691699 -431.525354) (xy 432.741282 -431.547997) (xy 432.787138 -431.577465)
			(xy 432.828333 -431.61316) (xy 432.864029 -431.654354) (xy 432.893499 -431.700209) (xy 432.916143 -431.749792)
			(xy 432.9315 -431.802092) (xy 432.939257 -431.856046) (xy 432.939257 -431.910554) (xy 432.9315 -431.964508)
			(xy 432.916143 -432.016808) (xy 432.893499 -432.066391) (xy 432.864029 -432.112246) (xy 432.828333 -432.15344)
			(xy 432.787138 -432.189135) (xy 432.741282 -432.218603) (xy 432.691699 -432.241246) (xy 432.639398 -432.256602)
			(xy 432.585444 -432.264358) (xy 432.55819 -432.26482) (xy 432.529216 -432.264283) (xy 432.471938 -432.255498)
			(xy 432.416645 -432.238161) (xy 432.364605 -432.21267) (xy 432.317012 -432.17961) (xy 432.274961 -432.13974)
			(xy 432.239414 -432.093976) (xy 432.211189 -432.043366) (xy 432.200558 -432.016408) (xy 432.197002 -432.006502)
			(xy 432.182016 -431.991008) (xy 432.092354 -431.955194) (xy 432.071018 -431.955702) (xy 432.061112 -431.960528)
			(xy 432.035146 -431.972653) (xy 431.981083 -431.99167) (xy 431.925224 -432.004484) (xy 431.868279 -432.010934)
			(xy 431.839624 -432.011328) (xy 431.807662 -432.010809) (xy 431.744242 -432.002799) (xy 431.682325 -431.986905)
			(xy 431.622889 -431.963375) (xy 431.566871 -431.932581) (xy 431.515154 -431.895009) (xy 431.468554 -431.851251)
			(xy 431.427807 -431.801997) (xy 431.393554 -431.748025) (xy 431.366335 -431.690185) (xy 431.346581 -431.62939)
			(xy 431.334602 -431.566598) (xy 431.330588 -431.5028) (xy 430.936634 -431.5028) (xy 430.936907 -431.504652)
			(xy 430.937416 -431.532538) (xy 430.936907 -431.560424) (xy 430.928787 -431.6156) (xy 430.912719 -431.669007)
			(xy 430.889047 -431.719504) (xy 430.858274 -431.766017) (xy 430.821057 -431.807554) (xy 430.778189 -431.843229)
			(xy 430.730583 -431.872283) (xy 430.679254 -431.894095) (xy 430.625297 -431.908201) (xy 430.56986 -431.914301)
			(xy 430.514126 -431.912264) (xy 430.459283 -431.902134) (xy 430.406499 -431.884127) (xy 430.356899 -431.858626)
			(xy 430.311541 -431.826175) (xy 430.271392 -431.787466) (xy 430.237306 -431.743323) (xy 430.21001 -431.694688)
			(xy 430.190087 -431.642597) (xy 430.177961 -431.58816) (xy 430.17389 -431.532538) (xy 428.303667 -431.532538)
			(xy 428.30369 -431.533808) (xy 428.303181 -431.561694) (xy 428.295061 -431.61687) (xy 428.278993 -431.670277)
			(xy 428.255321 -431.720774) (xy 428.224548 -431.767287) (xy 428.187331 -431.808824) (xy 428.144463 -431.844499)
			(xy 428.096857 -431.873553) (xy 428.045528 -431.895365) (xy 427.991571 -431.909471) (xy 427.936134 -431.915571)
			(xy 427.8804 -431.913534) (xy 427.825557 -431.903404) (xy 427.772773 -431.885397) (xy 427.723173 -431.859896)
			(xy 427.677815 -431.827445) (xy 427.637666 -431.788736) (xy 427.60358 -431.744593) (xy 427.576284 -431.695958)
			(xy 427.556361 -431.643867) (xy 427.544235 -431.58943) (xy 427.540164 -431.533808) (xy 417.138104 -431.533808)
			(xy 417.138104 -431.921412) (xy 418.997636 -431.921412) (xy 419.001707 -431.86579) (xy 419.013833 -431.811353)
			(xy 419.033756 -431.759262) (xy 419.061052 -431.710627) (xy 419.095138 -431.666484) (xy 419.135287 -431.627775)
			(xy 419.180645 -431.595324) (xy 419.230245 -431.569823) (xy 419.283029 -431.551816) (xy 419.337872 -431.541686)
			(xy 419.393606 -431.539649) (xy 419.449043 -431.545749) (xy 419.503 -431.559855) (xy 419.554329 -431.581667)
			(xy 419.601935 -431.610721) (xy 419.644803 -431.646396) (xy 419.68202 -431.687933) (xy 419.712793 -431.734446)
			(xy 419.736465 -431.784943) (xy 419.752533 -431.83835) (xy 419.760653 -431.893526) (xy 419.761162 -431.921412)
			(xy 419.760653 -431.949298) (xy 419.752533 -432.004474) (xy 419.736465 -432.057881) (xy 419.712793 -432.108378)
			(xy 419.711828 -432.109837) (xy 420.141648 -432.109837) (xy 420.141648 -432.045915) (xy 420.149659 -431.982497)
			(xy 420.165556 -431.920583) (xy 420.189088 -431.86115) (xy 420.219882 -431.805135) (xy 420.257455 -431.75342)
			(xy 420.301212 -431.706823) (xy 420.350465 -431.666078) (xy 420.404436 -431.631827) (xy 420.462275 -431.60461)
			(xy 420.523068 -431.584857) (xy 420.585858 -431.572879) (xy 420.649654 -431.568866) (xy 420.71345 -431.572879)
			(xy 420.77624 -431.584857) (xy 420.837033 -431.60461) (xy 420.894872 -431.631827) (xy 420.948843 -431.666078)
			(xy 420.998096 -431.706823) (xy 421.041853 -431.75342) (xy 421.079426 -431.805135) (xy 421.11022 -431.86115)
			(xy 421.133752 -431.920583) (xy 421.149649 -431.982497) (xy 421.15766 -432.045915) (xy 421.158162 -432.077876)
			(xy 421.15766 -432.109837) (xy 421.149649 -432.173255) (xy 421.133752 -432.235169) (xy 421.11022 -432.294602)
			(xy 421.079426 -432.350617) (xy 421.069637 -432.364091) (xy 428.54473 -432.364091) (xy 428.54473 -432.300169)
			(xy 428.552741 -432.236751) (xy 428.568638 -432.174837) (xy 428.59217 -432.115404) (xy 428.622964 -432.059389)
			(xy 428.660537 -432.007674) (xy 428.704294 -431.961077) (xy 428.753547 -431.920332) (xy 428.807518 -431.886081)
			(xy 428.865357 -431.858864) (xy 428.92615 -431.839111) (xy 428.98894 -431.827133) (xy 429.052736 -431.82312)
			(xy 429.116532 -431.827133) (xy 429.179322 -431.839111) (xy 429.240115 -431.858864) (xy 429.297954 -431.886081)
			(xy 429.351925 -431.920332) (xy 429.401178 -431.961077) (xy 429.444935 -432.007674) (xy 429.482508 -432.059389)
			(xy 429.513302 -432.115404) (xy 429.536834 -432.174837) (xy 429.552731 -432.236751) (xy 429.560742 -432.300169)
			(xy 429.561244 -432.33213) (xy 429.560742 -432.364091) (xy 429.552731 -432.427509) (xy 429.536834 -432.489423)
			(xy 429.513302 -432.548856) (xy 429.482508 -432.604871) (xy 429.444935 -432.656586) (xy 429.401178 -432.703183)
			(xy 429.351925 -432.743928) (xy 429.297954 -432.778179) (xy 429.240115 -432.805396) (xy 429.179322 -432.825149)
			(xy 429.116532 -432.837127) (xy 429.052736 -432.841141) (xy 428.98894 -432.837127) (xy 428.92615 -432.825149)
			(xy 428.865357 -432.805396) (xy 428.807518 -432.778179) (xy 428.753547 -432.743928) (xy 428.704294 -432.703183)
			(xy 428.660537 -432.656586) (xy 428.622964 -432.604871) (xy 428.59217 -432.548856) (xy 428.568638 -432.489423)
			(xy 428.552741 -432.427509) (xy 428.54473 -432.364091) (xy 421.069637 -432.364091) (xy 421.041853 -432.402332)
			(xy 420.998096 -432.448929) (xy 420.948843 -432.489674) (xy 420.894872 -432.523925) (xy 420.837033 -432.551142)
			(xy 420.77624 -432.570895) (xy 420.71345 -432.582873) (xy 420.649654 -432.586887) (xy 420.585858 -432.582873)
			(xy 420.523068 -432.570895) (xy 420.462275 -432.551142) (xy 420.404436 -432.523925) (xy 420.350465 -432.489674)
			(xy 420.301212 -432.448929) (xy 420.257455 -432.402332) (xy 420.219882 -432.350617) (xy 420.189088 -432.294602)
			(xy 420.165556 -432.235169) (xy 420.149659 -432.173255) (xy 420.141648 -432.109837) (xy 419.711828 -432.109837)
			(xy 419.68202 -432.154891) (xy 419.644803 -432.196428) (xy 419.601935 -432.232103) (xy 419.554329 -432.261157)
			(xy 419.503 -432.282969) (xy 419.449043 -432.297075) (xy 419.393606 -432.303175) (xy 419.337872 -432.301138)
			(xy 419.283029 -432.291008) (xy 419.230245 -432.273001) (xy 419.180645 -432.2475) (xy 419.135287 -432.215049)
			(xy 419.095138 -432.17634) (xy 419.061052 -432.132197) (xy 419.033756 -432.083562) (xy 419.013833 -432.031471)
			(xy 419.001707 -431.977034) (xy 418.997636 -431.921412) (xy 417.138104 -431.921412) (xy 417.138104 -432.876198)
			(xy 421.395396 -432.876198) (xy 421.399467 -432.820576) (xy 421.411593 -432.766139) (xy 421.431516 -432.714048)
			(xy 421.458812 -432.665413) (xy 421.492898 -432.62127) (xy 421.533047 -432.582561) (xy 421.578405 -432.55011)
			(xy 421.628005 -432.524609) (xy 421.680789 -432.506602) (xy 421.735632 -432.496472) (xy 421.791366 -432.494435)
			(xy 421.846803 -432.500535) (xy 421.90076 -432.514641) (xy 421.952089 -432.536453) (xy 421.999695 -432.565507)
			(xy 422.042563 -432.601182) (xy 422.07978 -432.642719) (xy 422.110553 -432.689232) (xy 422.134225 -432.739729)
			(xy 422.150293 -432.793136) (xy 422.158413 -432.848312) (xy 422.158922 -432.876198) (xy 422.158413 -432.904084)
			(xy 422.150293 -432.95926) (xy 422.134225 -433.012667) (xy 422.110553 -433.063164) (xy 422.07978 -433.109677)
			(xy 422.042563 -433.151214) (xy 421.999695 -433.186889) (xy 421.952089 -433.215943) (xy 421.90076 -433.237755)
			(xy 421.846803 -433.251861) (xy 421.791366 -433.257961) (xy 421.735632 -433.255924) (xy 421.680789 -433.245794)
			(xy 421.628005 -433.227787) (xy 421.578405 -433.202286) (xy 421.533047 -433.169835) (xy 421.492898 -433.131126)
			(xy 421.458812 -433.086983) (xy 421.431516 -433.038348) (xy 421.411593 -432.986257) (xy 421.399467 -432.93182)
			(xy 421.395396 -432.876198) (xy 417.138104 -432.876198) (xy 417.138104 -433.504848) (xy 436.163466 -433.504848)
			(xy 436.163961 -433.472201) (xy 436.172325 -433.407443) (xy 436.188909 -433.344289) (xy 436.21344 -433.283778)
			(xy 436.245514 -433.226903) (xy 436.284604 -433.174602) (xy 436.330066 -433.127734) (xy 436.381154 -433.087071)
			(xy 436.40883 -433.069746) (xy 436.420416 -433.062125) (xy 436.439378 -433.041909) (xy 436.452216 -433.017344)
			(xy 436.457985 -432.990234) (xy 436.456262 -432.96257) (xy 436.447173 -432.936385) (xy 436.431387 -432.913603)
			(xy 436.421022 -432.904392) (xy 436.399706 -432.886214) (xy 436.36217 -432.844625) (xy 436.331124 -432.797992)
			(xy 436.307236 -432.747317) (xy 436.291022 -432.693692) (xy 436.28283 -432.638271) (xy 436.282338 -432.61026)
			(xy 436.282824 -432.583009) (xy 436.29058 -432.529061) (xy 436.305935 -432.476766) (xy 436.328577 -432.427189)
			(xy 436.358043 -432.381339) (xy 436.393734 -432.340148) (xy 436.434925 -432.304457) (xy 436.480775 -432.274991)
			(xy 436.530352 -432.252349) (xy 436.582647 -432.236994) (xy 436.636595 -432.229238) (xy 436.691097 -432.229238)
			(xy 436.745045 -432.236994) (xy 436.79734 -432.252349) (xy 436.846917 -432.274991) (xy 436.892767 -432.304457)
			(xy 436.933958 -432.340148) (xy 436.969649 -432.381339) (xy 436.999115 -432.427189) (xy 437.021757 -432.476766)
			(xy 437.037112 -432.529061) (xy 437.044868 -432.583009) (xy 437.045354 -432.61026) (xy 437.044869 -432.637701)
			(xy 437.037021 -432.692019) (xy 437.021467 -432.744651) (xy 436.99853 -432.794509) (xy 436.968681 -432.840565)
			(xy 436.932539 -432.881865) (xy 436.912004 -432.900074) (xy 436.901828 -432.909474) (xy 436.886455 -432.932503)
			(xy 436.877841 -432.958818) (xy 436.876622 -432.98648) (xy 436.882887 -433.013451) (xy 436.896173 -433.037744)
			(xy 436.915503 -433.057569) (xy 436.927244 -433.06492) (xy 436.955713 -433.082064) (xy 436.977956 -433.09921)
			(xy 439.32221 -433.09921) (xy 439.322696 -433.071959) (xy 439.330452 -433.018011) (xy 439.345807 -432.965716)
			(xy 439.368449 -432.916139) (xy 439.397915 -432.870289) (xy 439.433606 -432.829098) (xy 439.474797 -432.793407)
			(xy 439.520647 -432.763941) (xy 439.570224 -432.741299) (xy 439.622519 -432.725944) (xy 439.676467 -432.718188)
			(xy 439.730969 -432.718188) (xy 439.784917 -432.725944) (xy 439.837212 -432.741299) (xy 439.886789 -432.763941)
			(xy 439.932639 -432.793407) (xy 439.97383 -432.829098) (xy 440.009521 -432.870289) (xy 440.038987 -432.916139)
			(xy 440.061629 -432.965716) (xy 440.076984 -433.018011) (xy 440.08474 -433.071959) (xy 440.085226 -433.09921)
			(xy 440.084692 -433.127545) (xy 440.076267 -433.183585) (xy 440.059646 -433.237763) (xy 440.047888 -433.263548)
			(xy 440.043062 -433.274216) (xy 440.042808 -433.296568) (xy 440.086242 -433.38877) (xy 440.103768 -433.403248)
			(xy 440.114944 -433.406042) (xy 440.144584 -433.413895) (xy 440.201866 -433.435779) (xy 440.256099 -433.464396)
			(xy 440.306494 -433.49933) (xy 440.35232 -433.540073) (xy 440.392912 -433.586035) (xy 440.427678 -433.636546)
			(xy 440.456115 -433.690873) (xy 440.477808 -433.748227) (xy 440.492444 -433.807774) (xy 440.499808 -433.86865)
			(xy 440.500262 -433.89931) (xy 442.116462 -433.89931) (xy 442.120533 -433.843688) (xy 442.132659 -433.789251)
			(xy 442.152582 -433.73716) (xy 442.179878 -433.688525) (xy 442.213964 -433.644382) (xy 442.254113 -433.605673)
			(xy 442.299471 -433.573222) (xy 442.349071 -433.547721) (xy 442.401855 -433.529714) (xy 442.456698 -433.519584)
			(xy 442.512432 -433.517547) (xy 442.567869 -433.523647) (xy 442.621826 -433.537753) (xy 442.673155 -433.559565)
			(xy 442.720761 -433.588619) (xy 442.763629 -433.624294) (xy 442.800846 -433.665831) (xy 442.831619 -433.712344)
			(xy 442.855291 -433.762841) (xy 442.871359 -433.816248) (xy 442.879479 -433.871424) (xy 442.879988 -433.89931)
			(xy 442.879479 -433.927196) (xy 442.871359 -433.982372) (xy 442.855291 -434.035779) (xy 442.831619 -434.086276)
			(xy 442.800846 -434.132789) (xy 442.763629 -434.174326) (xy 442.720761 -434.210001) (xy 442.673155 -434.239055)
			(xy 442.621826 -434.260867) (xy 442.567869 -434.274973) (xy 442.512432 -434.281073) (xy 442.456698 -434.279036)
			(xy 442.401855 -434.268906) (xy 442.349071 -434.250899) (xy 442.299471 -434.225398) (xy 442.254113 -434.192947)
			(xy 442.213964 -434.154238) (xy 442.179878 -434.110095) (xy 442.152582 -434.06146) (xy 442.132659 -434.009369)
			(xy 442.120533 -433.954932) (xy 442.116462 -433.89931) (xy 440.500262 -433.89931) (xy 440.49976 -433.931271)
			(xy 440.491749 -433.994689) (xy 440.475852 -434.056603) (xy 440.45232 -434.116036) (xy 440.421526 -434.172051)
			(xy 440.383953 -434.223766) (xy 440.340196 -434.270363) (xy 440.290943 -434.311108) (xy 440.236972 -434.345359)
			(xy 440.179133 -434.372576) (xy 440.11834 -434.392329) (xy 440.05555 -434.404307) (xy 439.991754 -434.408321)
			(xy 439.927958 -434.404307) (xy 439.865168 -434.392329) (xy 439.804375 -434.372576) (xy 439.746536 -434.345359)
			(xy 439.692565 -434.311108) (xy 439.643312 -434.270363) (xy 439.599555 -434.223766) (xy 439.561982 -434.172051)
			(xy 439.531188 -434.116036) (xy 439.507656 -434.056603) (xy 439.491759 -433.994689) (xy 439.483748 -433.931271)
			(xy 439.483246 -433.89931) (xy 439.48375 -433.867023) (xy 439.491918 -433.802968) (xy 439.508138 -433.740465)
			(xy 439.532146 -433.680521) (xy 439.563557 -433.624102) (xy 439.582306 -433.597812) (xy 439.589164 -433.588414)
			(xy 439.593482 -433.566316) (xy 439.568082 -433.46751) (xy 439.553858 -433.450238) (xy 439.54319 -433.445412)
			(xy 439.51878 -433.433591) (xy 439.47331 -433.404026) (xy 439.432486 -433.36832) (xy 439.397128 -433.327193)
			(xy 439.367949 -433.281475) (xy 439.345538 -433.232085) (xy 439.330346 -433.18002) (xy 439.32268 -433.126328)
			(xy 439.32221 -433.09921) (xy 436.977956 -433.09921) (xy 437.008346 -433.122636) (xy 437.055248 -433.169718)
			(xy 437.095619 -433.222506) (xy 437.128772 -433.280102) (xy 437.154142 -433.341525) (xy 437.171297 -433.405729)
			(xy 437.179945 -433.47162) (xy 437.180482 -433.504848) (xy 437.17998 -433.536809) (xy 437.171969 -433.600227)
			(xy 437.156072 -433.662141) (xy 437.13254 -433.721574) (xy 437.101746 -433.777589) (xy 437.064173 -433.829304)
			(xy 437.020416 -433.875901) (xy 436.971163 -433.916646) (xy 436.917192 -433.950897) (xy 436.859353 -433.978114)
			(xy 436.79856 -433.997867) (xy 436.73577 -434.009845) (xy 436.671974 -434.013859) (xy 436.608178 -434.009845)
			(xy 436.545388 -433.997867) (xy 436.484595 -433.978114) (xy 436.426756 -433.950897) (xy 436.372785 -433.916646)
			(xy 436.323532 -433.875901) (xy 436.279775 -433.829304) (xy 436.242202 -433.777589) (xy 436.211408 -433.721574)
			(xy 436.187876 -433.662141) (xy 436.171979 -433.600227) (xy 436.163968 -433.536809) (xy 436.163466 -433.504848)
			(xy 417.138104 -433.504848) (xy 417.138104 -434.526647) (xy 417.32936 -434.526647) (xy 417.32936 -434.462725)
			(xy 417.337371 -434.399307) (xy 417.353268 -434.337393) (xy 417.3768 -434.27796) (xy 417.407594 -434.221945)
			(xy 417.445167 -434.17023) (xy 417.488924 -434.123633) (xy 417.538177 -434.082888) (xy 417.592148 -434.048637)
			(xy 417.649987 -434.02142) (xy 417.71078 -434.001667) (xy 417.77357 -433.989689) (xy 417.837366 -433.985676)
			(xy 417.853422 -433.986686) (xy 420.49522 -433.986686) (xy 420.499291 -433.931064) (xy 420.511417 -433.876627)
			(xy 420.53134 -433.824536) (xy 420.558636 -433.775901) (xy 420.592722 -433.731758) (xy 420.632871 -433.693049)
			(xy 420.678229 -433.660598) (xy 420.727829 -433.635097) (xy 420.780613 -433.61709) (xy 420.835456 -433.60696)
			(xy 420.89119 -433.604923) (xy 420.946627 -433.611023) (xy 421.000584 -433.625129) (xy 421.051913 -433.646941)
			(xy 421.099519 -433.675995) (xy 421.142387 -433.71167) (xy 421.179604 -433.753207) (xy 421.210377 -433.79972)
			(xy 421.234049 -433.850217) (xy 421.250117 -433.903624) (xy 421.258237 -433.9588) (xy 421.258746 -433.986686)
			(xy 421.258237 -434.014572) (xy 421.250117 -434.069748) (xy 421.234049 -434.123155) (xy 421.210377 -434.173652)
			(xy 421.179604 -434.220165) (xy 421.142387 -434.261702) (xy 421.099519 -434.297377) (xy 421.051913 -434.326431)
			(xy 421.000584 -434.348243) (xy 420.946627 -434.362349) (xy 420.89119 -434.368449) (xy 420.835456 -434.366412)
			(xy 420.780613 -434.356282) (xy 420.727829 -434.338275) (xy 420.678229 -434.312774) (xy 420.632871 -434.280323)
			(xy 420.592722 -434.241614) (xy 420.558636 -434.197471) (xy 420.53134 -434.148836) (xy 420.511417 -434.096745)
			(xy 420.499291 -434.042308) (xy 420.49522 -433.986686) (xy 417.853422 -433.986686) (xy 417.901162 -433.989689)
			(xy 417.963952 -434.001667) (xy 418.024745 -434.02142) (xy 418.082584 -434.048637) (xy 418.136555 -434.082888)
			(xy 418.185808 -434.123633) (xy 418.229565 -434.17023) (xy 418.267138 -434.221945) (xy 418.297932 -434.27796)
			(xy 418.321464 -434.337393) (xy 418.337361 -434.399307) (xy 418.345372 -434.462725) (xy 418.345874 -434.494686)
			(xy 418.345372 -434.526647) (xy 418.337361 -434.590065) (xy 418.321464 -434.651979) (xy 418.297932 -434.711412)
			(xy 418.267138 -434.767427) (xy 418.253073 -434.786786) (xy 423.289982 -434.786786) (xy 423.294053 -434.731164)
			(xy 423.306179 -434.676727) (xy 423.326102 -434.624636) (xy 423.353398 -434.576001) (xy 423.387484 -434.531858)
			(xy 423.427633 -434.493149) (xy 423.472991 -434.460698) (xy 423.522591 -434.435197) (xy 423.575375 -434.41719)
			(xy 423.630218 -434.40706) (xy 423.685952 -434.405023) (xy 423.741389 -434.411123) (xy 423.795346 -434.425229)
			(xy 423.846675 -434.447041) (xy 423.894281 -434.476095) (xy 423.937149 -434.51177) (xy 423.950479 -434.526647)
			(xy 426.21936 -434.526647) (xy 426.21936 -434.462725) (xy 426.227371 -434.399307) (xy 426.243268 -434.337393)
			(xy 426.2668 -434.27796) (xy 426.297594 -434.221945) (xy 426.335167 -434.17023) (xy 426.378924 -434.123633)
			(xy 426.428177 -434.082888) (xy 426.482148 -434.048637) (xy 426.539987 -434.02142) (xy 426.60078 -434.001667)
			(xy 426.66357 -433.989689) (xy 426.727366 -433.985676) (xy 426.743422 -433.986686) (xy 429.38522 -433.986686)
			(xy 429.389291 -433.931064) (xy 429.401417 -433.876627) (xy 429.42134 -433.824536) (xy 429.448636 -433.775901)
			(xy 429.482722 -433.731758) (xy 429.522871 -433.693049) (xy 429.568229 -433.660598) (xy 429.617829 -433.635097)
			(xy 429.670613 -433.61709) (xy 429.725456 -433.60696) (xy 429.78119 -433.604923) (xy 429.836627 -433.611023)
			(xy 429.890584 -433.625129) (xy 429.941913 -433.646941) (xy 429.989519 -433.675995) (xy 430.032387 -433.71167)
			(xy 430.069604 -433.753207) (xy 430.100377 -433.79972) (xy 430.124049 -433.850217) (xy 430.140117 -433.903624)
			(xy 430.148237 -433.9588) (xy 430.148746 -433.986686) (xy 430.148237 -434.014572) (xy 430.140117 -434.069748)
			(xy 430.124049 -434.123155) (xy 430.100377 -434.173652) (xy 430.069604 -434.220165) (xy 430.032387 -434.261702)
			(xy 429.989519 -434.297377) (xy 429.941913 -434.326431) (xy 429.890584 -434.348243) (xy 429.836627 -434.362349)
			(xy 429.78119 -434.368449) (xy 429.725456 -434.366412) (xy 429.670613 -434.356282) (xy 429.617829 -434.338275)
			(xy 429.568229 -434.312774) (xy 429.522871 -434.280323) (xy 429.482722 -434.241614) (xy 429.448636 -434.197471)
			(xy 429.42134 -434.148836) (xy 429.401417 -434.096745) (xy 429.389291 -434.042308) (xy 429.38522 -433.986686)
			(xy 426.743422 -433.986686) (xy 426.791162 -433.989689) (xy 426.853952 -434.001667) (xy 426.914745 -434.02142)
			(xy 426.972584 -434.048637) (xy 427.026555 -434.082888) (xy 427.075808 -434.123633) (xy 427.119565 -434.17023)
			(xy 427.157138 -434.221945) (xy 427.187932 -434.27796) (xy 427.211464 -434.337393) (xy 427.227361 -434.399307)
			(xy 427.235372 -434.462725) (xy 427.235874 -434.494686) (xy 427.235372 -434.526647) (xy 427.227361 -434.590065)
			(xy 427.211464 -434.651979) (xy 427.187932 -434.711412) (xy 427.157138 -434.767427) (xy 427.143073 -434.786786)
			(xy 432.179982 -434.786786) (xy 432.184053 -434.731164) (xy 432.196179 -434.676727) (xy 432.216102 -434.624636)
			(xy 432.243398 -434.576001) (xy 432.277484 -434.531858) (xy 432.317633 -434.493149) (xy 432.362991 -434.460698)
			(xy 432.412591 -434.435197) (xy 432.465375 -434.41719) (xy 432.520218 -434.40706) (xy 432.575952 -434.405023)
			(xy 432.631389 -434.411123) (xy 432.685346 -434.425229) (xy 432.736675 -434.447041) (xy 432.784281 -434.476095)
			(xy 432.827149 -434.51177) (xy 432.864366 -434.553307) (xy 432.895139 -434.59982) (xy 432.918811 -434.650317)
			(xy 432.934879 -434.703724) (xy 432.942999 -434.7589) (xy 432.943508 -434.786786) (xy 432.942999 -434.814672)
			(xy 432.934879 -434.869848) (xy 432.932664 -434.87721) (xy 436.66918 -434.87721) (xy 436.669682 -434.845249)
			(xy 436.677693 -434.781831) (xy 436.69359 -434.719917) (xy 436.717122 -434.660484) (xy 436.747916 -434.604469)
			(xy 436.785489 -434.552754) (xy 436.829246 -434.506157) (xy 436.878499 -434.465412) (xy 436.93247 -434.431161)
			(xy 436.990309 -434.403944) (xy 437.051102 -434.384191) (xy 437.113892 -434.372213) (xy 437.177688 -434.3682)
			(xy 437.241484 -434.372213) (xy 437.304274 -434.384191) (xy 437.365067 -434.403944) (xy 437.422906 -434.431161)
			(xy 437.476877 -434.465412) (xy 437.52613 -434.506157) (xy 437.569887 -434.552754) (xy 437.60746 -434.604469)
			(xy 437.638254 -434.660484) (xy 437.661786 -434.719917) (xy 437.677683 -434.781831) (xy 437.685694 -434.845249)
			(xy 437.686196 -434.87721) (xy 437.685615 -434.911023) (xy 437.676666 -434.978054) (xy 437.658914 -435.043309)
			(xy 437.632671 -435.105636) (xy 437.598401 -435.163936) (xy 437.577992 -435.1909) (xy 437.571286 -435.199282)
			(xy 441.486542 -435.199282) (xy 441.490613 -435.14366) (xy 441.502739 -435.089223) (xy 441.522662 -435.037132)
			(xy 441.549958 -434.988497) (xy 441.584044 -434.944354) (xy 441.624193 -434.905645) (xy 441.669551 -434.873194)
			(xy 441.719151 -434.847693) (xy 441.771935 -434.829686) (xy 441.826778 -434.819556) (xy 441.882512 -434.817519)
			(xy 441.937949 -434.823619) (xy 441.991906 -434.837725) (xy 442.043235 -434.859537) (xy 442.090841 -434.888591)
			(xy 442.133709 -434.924266) (xy 442.170926 -434.965803) (xy 442.201699 -435.012316) (xy 442.225371 -435.062813)
			(xy 442.241439 -435.11622) (xy 442.249559 -435.171396) (xy 442.250068 -435.199282) (xy 442.249559 -435.227168)
			(xy 442.241439 -435.282344) (xy 442.225371 -435.335751) (xy 442.201699 -435.386248) (xy 442.170926 -435.432761)
			(xy 442.133709 -435.474298) (xy 442.090841 -435.509973) (xy 442.043235 -435.539027) (xy 441.991906 -435.560839)
			(xy 441.937949 -435.574945) (xy 441.882512 -435.581045) (xy 441.826778 -435.579008) (xy 441.771935 -435.568878)
			(xy 441.719151 -435.550871) (xy 441.669551 -435.52537) (xy 441.624193 -435.492919) (xy 441.584044 -435.45421)
			(xy 441.549958 -435.410067) (xy 441.522662 -435.361432) (xy 441.502739 -435.309341) (xy 441.490613 -435.254904)
			(xy 441.486542 -435.199282) (xy 437.571286 -435.199282) (xy 437.57088 -435.19979) (xy 437.5658 -435.22138)
			(xy 437.585866 -435.319424) (xy 437.599074 -435.337204) (xy 437.60898 -435.342792) (xy 437.634315 -435.357254)
			(xy 437.680638 -435.392708) (xy 437.721021 -435.434804) (xy 437.754519 -435.482561) (xy 437.780352 -435.534863)
			(xy 437.797915 -435.59049) (xy 437.8068 -435.648143) (xy 437.807354 -435.67731) (xy 437.806868 -435.704561)
			(xy 437.799112 -435.758509) (xy 437.783757 -435.810804) (xy 437.761115 -435.860381) (xy 437.735311 -435.900533)
			(xy 442.625474 -435.900533) (xy 442.625474 -435.836611) (xy 442.633485 -435.773193) (xy 442.649382 -435.711279)
			(xy 442.672914 -435.651846) (xy 442.703708 -435.595831) (xy 442.741281 -435.544116) (xy 442.785038 -435.497519)
			(xy 442.834291 -435.456774) (xy 442.888262 -435.422523) (xy 442.946101 -435.395306) (xy 443.006894 -435.375553)
			(xy 443.069684 -435.363575) (xy 443.13348 -435.359562) (xy 443.197276 -435.363575) (xy 443.260066 -435.375553)
			(xy 443.320859 -435.395306) (xy 443.378698 -435.422523) (xy 443.432669 -435.456774) (xy 443.481922 -435.497519)
			(xy 443.525679 -435.544116) (xy 443.563252 -435.595831) (xy 443.594046 -435.651846) (xy 443.617578 -435.711279)
			(xy 443.633475 -435.773193) (xy 443.641486 -435.836611) (xy 443.641988 -435.868572) (xy 443.641486 -435.900533)
			(xy 443.633475 -435.963951) (xy 443.617578 -436.025865) (xy 443.594046 -436.085298) (xy 443.563252 -436.141313)
			(xy 443.525679 -436.193028) (xy 443.481922 -436.239625) (xy 443.432669 -436.28037) (xy 443.378698 -436.314621)
			(xy 443.320859 -436.341838) (xy 443.260066 -436.361591) (xy 443.197276 -436.373569) (xy 443.13348 -436.377583)
			(xy 443.069684 -436.373569) (xy 443.006894 -436.361591) (xy 442.946101 -436.341838) (xy 442.888262 -436.314621)
			(xy 442.834291 -436.28037) (xy 442.785038 -436.239625) (xy 442.741281 -436.193028) (xy 442.703708 -436.141313)
			(xy 442.672914 -436.085298) (xy 442.649382 -436.025865) (xy 442.633485 -435.963951) (xy 442.625474 -435.900533)
			(xy 437.735311 -435.900533) (xy 437.731649 -435.906231) (xy 437.695958 -435.947422) (xy 437.654767 -435.983113)
			(xy 437.608917 -436.012579) (xy 437.55934 -436.035221) (xy 437.507045 -436.050576) (xy 437.453097 -436.058332)
			(xy 437.398595 -436.058332) (xy 437.344647 -436.050576) (xy 437.292352 -436.035221) (xy 437.242775 -436.012579)
			(xy 437.196925 -435.983113) (xy 437.155734 -435.947422) (xy 437.120043 -435.906231) (xy 437.090577 -435.860381)
			(xy 437.067935 -435.810804) (xy 437.05258 -435.758509) (xy 437.044824 -435.704561) (xy 437.044338 -435.67731)
			(xy 437.044916 -435.647512) (xy 437.054189 -435.588641) (xy 437.072526 -435.531936) (xy 437.085486 -435.505098)
			(xy 437.090566 -435.494938) (xy 437.091328 -435.47284) (xy 437.052466 -435.380638) (xy 437.035956 -435.365652)
			(xy 437.025288 -435.36235) (xy 436.994709 -435.352215) (xy 436.93618 -435.3253) (xy 436.881519 -435.291207)
			(xy 436.831601 -435.250484) (xy 436.787227 -435.203782) (xy 436.749106 -435.15185) (xy 436.71785 -435.095519)
			(xy 436.693959 -435.035692) (xy 436.677815 -434.973326) (xy 436.669677 -434.909421) (xy 436.66918 -434.87721)
			(xy 432.932664 -434.87721) (xy 432.918811 -434.923255) (xy 432.895139 -434.973752) (xy 432.864366 -435.020265)
			(xy 432.827149 -435.061802) (xy 432.784281 -435.097477) (xy 432.736675 -435.126531) (xy 432.685346 -435.148343)
			(xy 432.631389 -435.162449) (xy 432.575952 -435.168549) (xy 432.520218 -435.166512) (xy 432.465375 -435.156382)
			(xy 432.412591 -435.138375) (xy 432.362991 -435.112874) (xy 432.317633 -435.080423) (xy 432.277484 -435.041714)
			(xy 432.243398 -434.997571) (xy 432.216102 -434.948936) (xy 432.196179 -434.896845) (xy 432.184053 -434.842408)
			(xy 432.179982 -434.786786) (xy 427.143073 -434.786786) (xy 427.119565 -434.819142) (xy 427.075808 -434.865739)
			(xy 427.026555 -434.906484) (xy 426.972584 -434.940735) (xy 426.914745 -434.967952) (xy 426.853952 -434.987705)
			(xy 426.791162 -434.999683) (xy 426.727366 -435.003697) (xy 426.66357 -434.999683) (xy 426.60078 -434.987705)
			(xy 426.539987 -434.967952) (xy 426.482148 -434.940735) (xy 426.428177 -434.906484) (xy 426.378924 -434.865739)
			(xy 426.335167 -434.819142) (xy 426.297594 -434.767427) (xy 426.2668 -434.711412) (xy 426.243268 -434.651979)
			(xy 426.227371 -434.590065) (xy 426.21936 -434.526647) (xy 423.950479 -434.526647) (xy 423.974366 -434.553307)
			(xy 424.005139 -434.59982) (xy 424.028811 -434.650317) (xy 424.044879 -434.703724) (xy 424.052999 -434.7589)
			(xy 424.053508 -434.786786) (xy 424.052999 -434.814672) (xy 424.044879 -434.869848) (xy 424.028811 -434.923255)
			(xy 424.005139 -434.973752) (xy 423.974366 -435.020265) (xy 423.937149 -435.061802) (xy 423.894281 -435.097477)
			(xy 423.846675 -435.126531) (xy 423.795346 -435.148343) (xy 423.741389 -435.162449) (xy 423.685952 -435.168549)
			(xy 423.630218 -435.166512) (xy 423.575375 -435.156382) (xy 423.522591 -435.138375) (xy 423.472991 -435.112874)
			(xy 423.427633 -435.080423) (xy 423.387484 -435.041714) (xy 423.353398 -434.997571) (xy 423.326102 -434.948936)
			(xy 423.306179 -434.896845) (xy 423.294053 -434.842408) (xy 423.289982 -434.786786) (xy 418.253073 -434.786786)
			(xy 418.229565 -434.819142) (xy 418.185808 -434.865739) (xy 418.136555 -434.906484) (xy 418.082584 -434.940735)
			(xy 418.024745 -434.967952) (xy 417.963952 -434.987705) (xy 417.901162 -434.999683) (xy 417.837366 -435.003697)
			(xy 417.77357 -434.999683) (xy 417.71078 -434.987705) (xy 417.649987 -434.967952) (xy 417.592148 -434.940735)
			(xy 417.538177 -434.906484) (xy 417.488924 -434.865739) (xy 417.445167 -434.819142) (xy 417.407594 -434.767427)
			(xy 417.3768 -434.711412) (xy 417.353268 -434.651979) (xy 417.337371 -434.590065) (xy 417.32936 -434.526647)
			(xy 417.138104 -434.526647) (xy 417.138104 -435.754207) (xy 417.328484 -435.754207) (xy 417.33369 -435.691339)
			(xy 417.346632 -435.629598) (xy 417.367112 -435.569932) (xy 417.394814 -435.513257) (xy 417.429314 -435.460443)
			(xy 417.470082 -435.412303) (xy 417.516492 -435.369575) (xy 417.56783 -435.332916) (xy 417.623308 -435.302888)
			(xy 417.682074 -435.279953) (xy 417.743226 -435.264463) (xy 417.805824 -435.256656) (xy 417.837366 -435.256178)
			(xy 417.867439 -435.256649) (xy 417.927164 -435.263764) (xy 417.985636 -435.277865) (xy 418.042039 -435.298756)
			(xy 418.069014 -435.312058) (xy 418.081722 -435.318004) (xy 418.109227 -435.323476) (xy 418.137183 -435.321256)
			(xy 418.163478 -435.311509) (xy 418.186128 -435.294973) (xy 418.203422 -435.272896) (xy 418.214054 -435.246946)
			(xy 418.21608 -435.233064) (xy 418.219764 -435.205465) (xy 418.233984 -435.151635) (xy 418.255874 -435.100443)
			(xy 418.284969 -435.052974) (xy 418.320653 -435.010236) (xy 418.362167 -434.973136) (xy 418.408631 -434.942462)
			(xy 418.459059 -434.918864) (xy 418.512381 -434.902843) (xy 418.567464 -434.89474) (xy 418.595302 -434.894228)
			(xy 418.622556 -434.894642) (xy 418.676508 -434.902399) (xy 418.728808 -434.917756) (xy 418.778389 -434.9404)
			(xy 418.824244 -434.969869) (xy 418.865438 -435.005564) (xy 418.901132 -435.046758) (xy 418.930601 -435.092612)
			(xy 418.953244 -435.142194) (xy 418.968601 -435.194494) (xy 418.976358 -435.248446) (xy 418.976358 -435.302954)
			(xy 418.968601 -435.356906) (xy 418.953244 -435.409206) (xy 418.930601 -435.458788) (xy 418.901132 -435.504642)
			(xy 418.865438 -435.545836) (xy 418.824244 -435.581531) (xy 418.778389 -435.611) (xy 418.728808 -435.633644)
			(xy 418.676508 -435.649001) (xy 418.622556 -435.656758) (xy 418.595302 -435.657244) (xy 418.565464 -435.656659)
			(xy 418.506518 -435.64735) (xy 418.477954 -435.638702) (xy 418.464464 -435.634837) (xy 418.436428 -435.633882)
			(xy 418.409188 -435.640582) (xy 418.384792 -435.654431) (xy 418.365078 -435.674387) (xy 418.351527 -435.69895)
			(xy 418.345161 -435.72627) (xy 418.345366 -435.740302) (xy 418.345874 -435.764686) (xy 418.345447 -435.796228)
			(xy 418.337646 -435.858827) (xy 418.322162 -435.91998) (xy 418.299232 -435.978749) (xy 418.26921 -436.03423)
			(xy 418.232555 -436.085571) (xy 418.231462 -436.086758) (xy 422.660062 -436.086758) (xy 422.664133 -436.031136)
			(xy 422.676259 -435.976699) (xy 422.696182 -435.924608) (xy 422.723478 -435.875973) (xy 422.757564 -435.83183)
			(xy 422.797713 -435.793121) (xy 422.843071 -435.76067) (xy 422.892671 -435.735169) (xy 422.945455 -435.717162)
			(xy 423.000298 -435.707032) (xy 423.056032 -435.704995) (xy 423.111469 -435.711095) (xy 423.165426 -435.725201)
			(xy 423.216755 -435.747013) (xy 423.245736 -435.7647) (xy 426.218375 -435.7647) (xy 426.222389 -435.700905)
			(xy 426.234366 -435.638116) (xy 426.254118 -435.577323) (xy 426.281333 -435.519485) (xy 426.315583 -435.465514)
			(xy 426.356326 -435.416261) (xy 426.402921 -435.372502) (xy 426.454633 -435.334928) (xy 426.510646 -435.304131)
			(xy 426.570077 -435.280597) (xy 426.631989 -435.264697) (xy 426.695405 -435.256682) (xy 426.727366 -435.256178)
			(xy 426.757439 -435.256649) (xy 426.817164 -435.263764) (xy 426.875636 -435.277865) (xy 426.932039 -435.298756)
			(xy 426.959014 -435.312058) (xy 426.97019 -435.317646) (xy 426.995082 -435.317392) (xy 427.09084 -435.266084)
			(xy 427.10481 -435.24551) (xy 427.10608 -435.233064) (xy 427.109764 -435.205465) (xy 427.123984 -435.151635)
			(xy 427.145874 -435.100443) (xy 427.174969 -435.052974) (xy 427.210653 -435.010236) (xy 427.252167 -434.973136)
			(xy 427.298631 -434.942462) (xy 427.349059 -434.918864) (xy 427.402381 -434.902843) (xy 427.457464 -434.89474)
			(xy 427.485302 -434.894228) (xy 427.512556 -434.894642) (xy 427.566508 -434.902399) (xy 427.618808 -434.917756)
			(xy 427.668389 -434.9404) (xy 427.714244 -434.969869) (xy 427.755438 -435.005564) (xy 427.791132 -435.046758)
			(xy 427.820601 -435.092612) (xy 427.843244 -435.142194) (xy 427.858601 -435.194494) (xy 427.866358 -435.248446)
			(xy 427.866358 -435.302954) (xy 427.858601 -435.356906) (xy 427.843244 -435.409206) (xy 427.820601 -435.458788)
			(xy 427.791132 -435.504642) (xy 427.755438 -435.545836) (xy 427.714244 -435.581531) (xy 427.668389 -435.611)
			(xy 427.618808 -435.633644) (xy 427.566508 -435.649001) (xy 427.512556 -435.656758) (xy 427.485302 -435.657244)
			(xy 427.455464 -435.656659) (xy 427.396518 -435.64735) (xy 427.367954 -435.638702) (xy 427.356016 -435.634892)
			(xy 427.331632 -435.638956) (xy 427.245018 -435.70525) (xy 427.234604 -435.727602) (xy 427.235366 -435.740302)
			(xy 427.235874 -435.764686) (xy 427.235816 -435.776068) (xy 427.234798 -435.79881) (xy 427.233842 -435.810152)
			(xy 427.232826 -435.821836) (xy 427.241208 -435.84368) (xy 427.317154 -435.914546) (xy 427.339506 -435.921404)
			(xy 427.35119 -435.919372) (xy 427.366263 -435.9171) (xy 427.396653 -435.914685) (xy 427.411896 -435.914546)
			(xy 427.439146 -435.915101) (xy 427.493091 -435.922857) (xy 427.545383 -435.93821) (xy 427.594957 -435.96085)
			(xy 427.640805 -435.990314) (xy 427.681994 -436.026004) (xy 427.717683 -436.067191) (xy 427.747148 -436.113039)
			(xy 427.769788 -436.162614) (xy 427.785143 -436.214905) (xy 427.792899 -436.26885) (xy 427.792899 -436.271924)
			(xy 430.190146 -436.271924) (xy 430.194217 -436.216302) (xy 430.206343 -436.161865) (xy 430.226266 -436.109774)
			(xy 430.253562 -436.061139) (xy 430.287648 -436.016996) (xy 430.327797 -435.978287) (xy 430.373155 -435.945836)
			(xy 430.422755 -435.920335) (xy 430.475539 -435.902328) (xy 430.530382 -435.892198) (xy 430.586116 -435.890161)
			(xy 430.641553 -435.896261) (xy 430.69551 -435.910367) (xy 430.746839 -435.932179) (xy 430.794445 -435.961233)
			(xy 430.837313 -435.996908) (xy 430.87453 -436.038445) (xy 430.905303 -436.084958) (xy 430.906147 -436.086758)
			(xy 431.550062 -436.086758) (xy 431.554133 -436.031136) (xy 431.566259 -435.976699) (xy 431.586182 -435.924608)
			(xy 431.613478 -435.875973) (xy 431.647564 -435.83183) (xy 431.687713 -435.793121) (xy 431.733071 -435.76067)
			(xy 431.782671 -435.735169) (xy 431.835455 -435.717162) (xy 431.890298 -435.707032) (xy 431.946032 -435.704995)
			(xy 432.001469 -435.711095) (xy 432.055426 -435.725201) (xy 432.106755 -435.747013) (xy 432.154361 -435.776067)
			(xy 432.197229 -435.811742) (xy 432.234446 -435.853279) (xy 432.265219 -435.899792) (xy 432.288891 -435.950289)
			(xy 432.304959 -436.003696) (xy 432.313079 -436.058872) (xy 432.313588 -436.086758) (xy 432.313079 -436.114644)
			(xy 432.304959 -436.16982) (xy 432.288891 -436.223227) (xy 432.265219 -436.273724) (xy 432.234446 -436.320237)
			(xy 432.197229 -436.361774) (xy 432.154361 -436.397449) (xy 432.106755 -436.426503) (xy 432.055426 -436.448315)
			(xy 432.001469 -436.462421) (xy 431.946032 -436.468521) (xy 431.890298 -436.466484) (xy 431.835455 -436.456354)
			(xy 431.782671 -436.438347) (xy 431.733071 -436.412846) (xy 431.687713 -436.380395) (xy 431.647564 -436.341686)
			(xy 431.613478 -436.297543) (xy 431.586182 -436.248908) (xy 431.566259 -436.196817) (xy 431.554133 -436.14238)
			(xy 431.550062 -436.086758) (xy 430.906147 -436.086758) (xy 430.928975 -436.135455) (xy 430.945043 -436.188862)
			(xy 430.953163 -436.244038) (xy 430.953672 -436.271924) (xy 430.953163 -436.29981) (xy 430.945043 -436.354986)
			(xy 430.928975 -436.408393) (xy 430.905303 -436.45889) (xy 430.87453 -436.505403) (xy 430.837313 -436.54694)
			(xy 430.794445 -436.582615) (xy 430.746839 -436.611669) (xy 430.69551 -436.633481) (xy 430.641553 -436.647587)
			(xy 430.586116 -436.653687) (xy 430.530382 -436.65165) (xy 430.475539 -436.64152) (xy 430.422755 -436.623513)
			(xy 430.373155 -436.598012) (xy 430.327797 -436.565561) (xy 430.287648 -436.526852) (xy 430.253562 -436.482709)
			(xy 430.226266 -436.434074) (xy 430.206343 -436.381983) (xy 430.194217 -436.327546) (xy 430.190146 -436.271924)
			(xy 427.792899 -436.271924) (xy 427.792899 -436.32335) (xy 427.785143 -436.377295) (xy 427.769788 -436.429586)
			(xy 427.747148 -436.479161) (xy 427.717683 -436.525009) (xy 427.681994 -436.566196) (xy 427.640805 -436.601886)
			(xy 427.594957 -436.63135) (xy 427.545383 -436.65399) (xy 427.493091 -436.669343) (xy 427.439146 -436.677099)
			(xy 427.411896 -436.677562) (xy 427.383645 -436.677047) (xy 427.327761 -436.668727) (xy 427.273714 -436.652254)
			(xy 427.222689 -436.627989) (xy 427.175801 -436.596463) (xy 427.134077 -436.558366) (xy 427.098429 -436.51453)
			(xy 427.069636 -436.465916) (xy 427.04833 -436.413586) (xy 427.034976 -436.358686) (xy 427.031912 -436.330598)
			(xy 427.030896 -436.318914) (xy 427.018704 -436.298848) (xy 426.931328 -436.242714) (xy 426.908214 -436.240174)
			(xy 426.897038 -436.243984) (xy 426.869721 -436.253246) (xy 426.813518 -436.266229) (xy 426.756207 -436.272778)
			(xy 426.727366 -436.273194) (xy 426.695405 -436.272718) (xy 426.631989 -436.264703) (xy 426.570077 -436.248803)
			(xy 426.510646 -436.225269) (xy 426.454633 -436.194472) (xy 426.402921 -436.156898) (xy 426.356326 -436.113139)
			(xy 426.315583 -436.063886) (xy 426.281333 -436.009915) (xy 426.254118 -435.952077) (xy 426.234366 -435.891284)
			(xy 426.222389 -435.828495) (xy 426.218375 -435.7647) (xy 423.245736 -435.7647) (xy 423.264361 -435.776067)
			(xy 423.307229 -435.811742) (xy 423.344446 -435.853279) (xy 423.375219 -435.899792) (xy 423.398891 -435.950289)
			(xy 423.414959 -436.003696) (xy 423.423079 -436.058872) (xy 423.423588 -436.086758) (xy 423.423079 -436.114644)
			(xy 423.414959 -436.16982) (xy 423.398891 -436.223227) (xy 423.375219 -436.273724) (xy 423.344446 -436.320237)
			(xy 423.307229 -436.361774) (xy 423.264361 -436.397449) (xy 423.216755 -436.426503) (xy 423.165426 -436.448315)
			(xy 423.111469 -436.462421) (xy 423.056032 -436.468521) (xy 423.000298 -436.466484) (xy 422.945455 -436.456354)
			(xy 422.892671 -436.438347) (xy 422.843071 -436.412846) (xy 422.797713 -436.380395) (xy 422.757564 -436.341686)
			(xy 422.723478 -436.297543) (xy 422.696182 -436.248908) (xy 422.676259 -436.196817) (xy 422.664133 -436.14238)
			(xy 422.660062 -436.086758) (xy 418.231462 -436.086758) (xy 418.189832 -436.131984) (xy 418.141695 -436.172757)
			(xy 418.088885 -436.207262) (xy 418.032213 -436.23497) (xy 417.972548 -436.255455) (xy 417.910808 -436.268403)
			(xy 417.847941 -436.273615) (xy 417.784911 -436.271011) (xy 417.722688 -436.26063) (xy 417.662226 -436.242633)
			(xy 417.604455 -436.217295) (xy 417.550262 -436.185006) (xy 417.500478 -436.146262) (xy 417.45587 -436.101658)
			(xy 417.417121 -436.051878) (xy 417.384827 -435.997688) (xy 417.359483 -435.939919) (xy 417.34148 -435.879459)
			(xy 417.331094 -435.817237) (xy 417.328484 -435.754207) (xy 417.138104 -435.754207) (xy 417.138104 -436.564786)
			(xy 418.217348 -436.564786) (xy 418.221419 -436.509164) (xy 418.233545 -436.454727) (xy 418.253468 -436.402636)
			(xy 418.280764 -436.354001) (xy 418.31485 -436.309858) (xy 418.354999 -436.271149) (xy 418.400357 -436.238698)
			(xy 418.449957 -436.213197) (xy 418.502741 -436.19519) (xy 418.557584 -436.18506) (xy 418.613318 -436.183023)
			(xy 418.668755 -436.189123) (xy 418.722712 -436.203229) (xy 418.774041 -436.225041) (xy 418.821647 -436.254095)
			(xy 418.864515 -436.28977) (xy 418.901732 -436.331307) (xy 418.932505 -436.37782) (xy 418.956177 -436.428317)
			(xy 418.972245 -436.481724) (xy 418.980365 -436.5369) (xy 418.980874 -436.564786) (xy 418.980365 -436.592672)
			(xy 418.972245 -436.647848) (xy 418.956177 -436.701255) (xy 418.932505 -436.751752) (xy 418.901732 -436.798265)
			(xy 418.864515 -436.839802) (xy 418.821647 -436.875477) (xy 418.774041 -436.904531) (xy 418.722712 -436.926343)
			(xy 418.668755 -436.940449) (xy 418.613318 -436.946549) (xy 418.557584 -436.944512) (xy 418.502741 -436.934382)
			(xy 418.449957 -436.916375) (xy 418.400357 -436.890874) (xy 418.354999 -436.858423) (xy 418.31485 -436.819714)
			(xy 418.280764 -436.775571) (xy 418.253468 -436.726936) (xy 418.233545 -436.674845) (xy 418.221419 -436.620408)
			(xy 418.217348 -436.564786) (xy 417.138104 -436.564786) (xy 417.138104 -438.374747) (xy 417.32936 -438.374747)
			(xy 417.32936 -438.310825) (xy 417.337371 -438.247407) (xy 417.353268 -438.185493) (xy 417.3768 -438.12606)
			(xy 417.407594 -438.070045) (xy 417.445167 -438.01833) (xy 417.488924 -437.971733) (xy 417.538177 -437.930988)
			(xy 417.592148 -437.896737) (xy 417.649987 -437.86952) (xy 417.71078 -437.849767) (xy 417.77357 -437.837789)
			(xy 417.837366 -437.833776) (xy 417.853422 -437.834786) (xy 420.49522 -437.834786) (xy 420.499291 -437.779164)
			(xy 420.511417 -437.724727) (xy 420.53134 -437.672636) (xy 420.558636 -437.624001) (xy 420.592722 -437.579858)
			(xy 420.632871 -437.541149) (xy 420.678229 -437.508698) (xy 420.727829 -437.483197) (xy 420.780613 -437.46519)
			(xy 420.835456 -437.45506) (xy 420.89119 -437.453023) (xy 420.946627 -437.459123) (xy 421.000584 -437.473229)
			(xy 421.051913 -437.495041) (xy 421.099519 -437.524095) (xy 421.142387 -437.55977) (xy 421.179604 -437.601307)
			(xy 421.210377 -437.64782) (xy 421.234049 -437.698317) (xy 421.250117 -437.751724) (xy 421.256136 -437.792622)
			(xy 426.43425 -437.792622) (xy 426.434752 -437.760661) (xy 426.442763 -437.697243) (xy 426.45866 -437.635329)
			(xy 426.482192 -437.575896) (xy 426.512986 -437.519881) (xy 426.550559 -437.468166) (xy 426.594316 -437.421569)
			(xy 426.643569 -437.380824) (xy 426.69754 -437.346573) (xy 426.755379 -437.319356) (xy 426.816172 -437.299603)
			(xy 426.878962 -437.287625) (xy 426.942758 -437.283612) (xy 427.006554 -437.287625) (xy 427.069344 -437.299603)
			(xy 427.072354 -437.300581) (xy 436.155586 -437.300581) (xy 436.155586 -437.236659) (xy 436.163597 -437.173241)
			(xy 436.179494 -437.111327) (xy 436.203026 -437.051894) (xy 436.23382 -436.995879) (xy 436.271393 -436.944164)
			(xy 436.31515 -436.897567) (xy 436.364403 -436.856822) (xy 436.418374 -436.822571) (xy 436.476213 -436.795354)
			(xy 436.537006 -436.775601) (xy 436.599796 -436.763623) (xy 436.663592 -436.75961) (xy 436.727388 -436.763623)
			(xy 436.790178 -436.775601) (xy 436.850971 -436.795354) (xy 436.90881 -436.822571) (xy 436.962781 -436.856822)
			(xy 437.012034 -436.897567) (xy 437.055791 -436.944164) (xy 437.058077 -436.94731) (xy 439.3217 -436.94731)
			(xy 439.325771 -436.891688) (xy 439.337897 -436.837251) (xy 439.35782 -436.78516) (xy 439.385116 -436.736525)
			(xy 439.419202 -436.692382) (xy 439.459351 -436.653673) (xy 439.504709 -436.621222) (xy 439.554309 -436.595721)
			(xy 439.607093 -436.577714) (xy 439.661936 -436.567584) (xy 439.71767 -436.565547) (xy 439.773107 -436.571647)
			(xy 439.827064 -436.585753) (xy 439.878393 -436.607565) (xy 439.925999 -436.636619) (xy 439.968867 -436.672294)
			(xy 440.006084 -436.713831) (xy 440.036857 -436.760344) (xy 440.060529 -436.810841) (xy 440.076597 -436.864248)
			(xy 440.084717 -436.919424) (xy 440.085226 -436.94731) (xy 440.084717 -436.975196) (xy 440.076597 -437.030372)
			(xy 440.060529 -437.083779) (xy 440.036857 -437.134276) (xy 440.006084 -437.180789) (xy 439.968867 -437.222326)
			(xy 439.925999 -437.258001) (xy 439.878393 -437.287055) (xy 439.827064 -437.308867) (xy 439.773107 -437.322973)
			(xy 439.71767 -437.329073) (xy 439.661936 -437.327036) (xy 439.607093 -437.316906) (xy 439.554309 -437.298899)
			(xy 439.504709 -437.273398) (xy 439.459351 -437.240947) (xy 439.419202 -437.202238) (xy 439.385116 -437.158095)
			(xy 439.35782 -437.10946) (xy 439.337897 -437.057369) (xy 439.325771 -437.002932) (xy 439.3217 -436.94731)
			(xy 437.058077 -436.94731) (xy 437.093364 -436.995879) (xy 437.124158 -437.051894) (xy 437.14769 -437.111327)
			(xy 437.163587 -437.173241) (xy 437.171598 -437.236659) (xy 437.1721 -437.26862) (xy 437.171598 -437.300581)
			(xy 437.163587 -437.363999) (xy 437.14769 -437.425913) (xy 437.124158 -437.485346) (xy 437.093364 -437.541361)
			(xy 437.055791 -437.593076) (xy 437.012034 -437.639673) (xy 436.962781 -437.680418) (xy 436.90881 -437.714669)
			(xy 436.850971 -437.741886) (xy 436.83397 -437.74741) (xy 442.116462 -437.74741) (xy 442.120533 -437.691788)
			(xy 442.132659 -437.637351) (xy 442.152582 -437.58526) (xy 442.179878 -437.536625) (xy 442.213964 -437.492482)
			(xy 442.254113 -437.453773) (xy 442.299471 -437.421322) (xy 442.349071 -437.395821) (xy 442.401855 -437.377814)
			(xy 442.456698 -437.367684) (xy 442.512432 -437.365647) (xy 442.567869 -437.371747) (xy 442.621826 -437.385853)
			(xy 442.673155 -437.407665) (xy 442.720761 -437.436719) (xy 442.763629 -437.472394) (xy 442.800846 -437.513931)
			(xy 442.831619 -437.560444) (xy 442.855291 -437.610941) (xy 442.871359 -437.664348) (xy 442.879479 -437.719524)
			(xy 442.879988 -437.74741) (xy 442.879479 -437.775296) (xy 442.871359 -437.830472) (xy 442.855291 -437.883879)
			(xy 442.831619 -437.934376) (xy 442.800846 -437.980889) (xy 442.763629 -438.022426) (xy 442.720761 -438.058101)
			(xy 442.673155 -438.087155) (xy 442.621826 -438.108967) (xy 442.567869 -438.123073) (xy 442.512432 -438.129173)
			(xy 442.456698 -438.127136) (xy 442.401855 -438.117006) (xy 442.349071 -438.098999) (xy 442.299471 -438.073498)
			(xy 442.254113 -438.041047) (xy 442.213964 -438.002338) (xy 442.179878 -437.958195) (xy 442.152582 -437.90956)
			(xy 442.132659 -437.857469) (xy 442.120533 -437.803032) (xy 442.116462 -437.74741) (xy 436.83397 -437.74741)
			(xy 436.790178 -437.761639) (xy 436.727388 -437.773617) (xy 436.663592 -437.777631) (xy 436.599796 -437.773617)
			(xy 436.537006 -437.761639) (xy 436.476213 -437.741886) (xy 436.418374 -437.714669) (xy 436.364403 -437.680418)
			(xy 436.31515 -437.639673) (xy 436.271393 -437.593076) (xy 436.23382 -437.541361) (xy 436.203026 -437.485346)
			(xy 436.179494 -437.425913) (xy 436.163597 -437.363999) (xy 436.155586 -437.300581) (xy 427.072354 -437.300581)
			(xy 427.130137 -437.319356) (xy 427.187976 -437.346573) (xy 427.241947 -437.380824) (xy 427.2912 -437.421569)
			(xy 427.334957 -437.468166) (xy 427.37253 -437.519881) (xy 427.403324 -437.575896) (xy 427.426856 -437.635329)
			(xy 427.442753 -437.697243) (xy 427.450764 -437.760661) (xy 427.451266 -437.792622) (xy 432.12334 -437.792622)
			(xy 432.127411 -437.737) (xy 432.139537 -437.682563) (xy 432.15946 -437.630472) (xy 432.186756 -437.581837)
			(xy 432.220842 -437.537694) (xy 432.260991 -437.498985) (xy 432.306349 -437.466534) (xy 432.355949 -437.441033)
			(xy 432.408733 -437.423026) (xy 432.463576 -437.412896) (xy 432.51931 -437.410859) (xy 432.574747 -437.416959)
			(xy 432.628704 -437.431065) (xy 432.680033 -437.452877) (xy 432.727639 -437.481931) (xy 432.770507 -437.517606)
			(xy 432.807724 -437.559143) (xy 432.838497 -437.605656) (xy 432.862169 -437.656153) (xy 432.878237 -437.70956)
			(xy 432.886357 -437.764736) (xy 432.886866 -437.792622) (xy 432.886357 -437.820508) (xy 432.878237 -437.875684)
			(xy 432.862169 -437.929091) (xy 432.838497 -437.979588) (xy 432.807724 -438.026101) (xy 432.770507 -438.067638)
			(xy 432.727639 -438.103313) (xy 432.680033 -438.132367) (xy 432.628704 -438.154179) (xy 432.574747 -438.168285)
			(xy 432.51931 -438.174385) (xy 432.463576 -438.172348) (xy 432.408733 -438.162218) (xy 432.355949 -438.144211)
			(xy 432.306349 -438.11871) (xy 432.260991 -438.086259) (xy 432.220842 -438.04755) (xy 432.186756 -438.003407)
			(xy 432.15946 -437.954772) (xy 432.139537 -437.902681) (xy 432.127411 -437.848244) (xy 432.12334 -437.792622)
			(xy 427.451266 -437.792622) (xy 427.45068 -437.826407) (xy 427.441729 -437.89338) (xy 427.423987 -437.958579)
			(xy 427.397768 -438.020854) (xy 427.363532 -438.079108) (xy 427.321884 -438.132315) (xy 427.273556 -438.179538)
			(xy 427.2194 -438.219945) (xy 427.190154 -438.236868) (xy 427.180502 -438.242202) (xy 427.167548 -438.259728)
			(xy 427.146974 -438.355994) (xy 427.151546 -438.37733) (xy 427.15815 -438.38622) (xy 427.175819 -438.411041)
			(xy 427.203906 -438.465103) (xy 427.22304 -438.522942) (xy 427.232734 -438.583089) (xy 427.233334 -438.61355)
			(xy 427.232848 -438.640801) (xy 427.225092 -438.694749) (xy 427.219206 -438.714796) (xy 436.172508 -438.714796)
			(xy 436.177715 -438.651931) (xy 436.190658 -438.590194) (xy 436.211138 -438.530531) (xy 436.23884 -438.47386)
			(xy 436.273339 -438.42105) (xy 436.314106 -438.372913) (xy 436.360513 -438.330188) (xy 436.411849 -438.293532)
			(xy 436.467325 -438.263506) (xy 436.526088 -438.240573) (xy 436.587237 -438.225085) (xy 436.649832 -438.217279)
			(xy 436.681372 -438.216802) (xy 436.709533 -438.217149) (xy 436.765511 -438.223357) (xy 436.820459 -438.235723)
			(xy 436.8737 -438.254093) (xy 436.899304 -438.265824) (xy 436.91048 -438.271158) (xy 436.934356 -438.270396)
			(xy 437.028336 -438.219342) (xy 437.041798 -438.19953) (xy 437.043576 -438.187084) (xy 437.047629 -438.159876)
			(xy 437.062466 -438.10691) (xy 437.084761 -438.056625) (xy 437.114051 -438.010066) (xy 437.149728 -437.9682)
			(xy 437.191051 -437.931896) (xy 437.237163 -437.901907) (xy 437.287106 -437.878856) (xy 437.339843 -437.863221)
			(xy 437.394279 -437.855328) (xy 437.421782 -437.854852) (xy 437.449033 -437.855394) (xy 437.50298 -437.863148)
			(xy 437.555275 -437.878501) (xy 437.604852 -437.90114) (xy 437.650702 -437.930604) (xy 437.691893 -437.966294)
			(xy 437.727585 -438.007483) (xy 437.757051 -438.053332) (xy 437.779693 -438.102909) (xy 437.795048 -438.155202)
			(xy 437.802805 -438.209149) (xy 437.802805 -438.263651) (xy 437.795048 -438.317598) (xy 437.779693 -438.369891)
			(xy 437.757051 -438.419468) (xy 437.727585 -438.465317) (xy 437.691893 -438.506506) (xy 437.650702 -438.542196)
			(xy 437.604852 -438.57166) (xy 437.555275 -438.594299) (xy 437.50298 -438.609652) (xy 437.449033 -438.617406)
			(xy 437.421782 -438.617868) (xy 437.395601 -438.617451) (xy 437.343727 -438.610307) (xy 437.318404 -438.603644)
			(xy 437.306466 -438.600342) (xy 437.283098 -438.604914) (xy 437.199024 -438.671208) (xy 437.189118 -438.693052)
			(xy 437.189372 -438.705498) (xy 437.18988 -438.72531) (xy 437.189422 -438.75685) (xy 437.181618 -438.819445)
			(xy 437.166132 -438.880595) (xy 437.143201 -438.939359) (xy 437.113178 -438.994836) (xy 437.076523 -439.046173)
			(xy 437.07541 -439.047382) (xy 441.486542 -439.047382) (xy 441.490613 -438.99176) (xy 441.502739 -438.937323)
			(xy 441.522662 -438.885232) (xy 441.549958 -438.836597) (xy 441.584044 -438.792454) (xy 441.624193 -438.753745)
			(xy 441.669551 -438.721294) (xy 441.719151 -438.695793) (xy 441.771935 -438.677786) (xy 441.826778 -438.667656)
			(xy 441.882512 -438.665619) (xy 441.937949 -438.671719) (xy 441.991906 -438.685825) (xy 442.043235 -438.707637)
			(xy 442.090841 -438.736691) (xy 442.133709 -438.772366) (xy 442.170926 -438.813903) (xy 442.201699 -438.860416)
			(xy 442.225371 -438.910913) (xy 442.241439 -438.96432) (xy 442.249559 -439.019496) (xy 442.250068 -439.047382)
			(xy 442.249559 -439.075268) (xy 442.241439 -439.130444) (xy 442.225371 -439.183851) (xy 442.201699 -439.234348)
			(xy 442.170926 -439.280861) (xy 442.133709 -439.322398) (xy 442.090841 -439.358073) (xy 442.043235 -439.387127)
			(xy 441.991906 -439.408939) (xy 441.937949 -439.423045) (xy 441.882512 -439.429145) (xy 441.826778 -439.427108)
			(xy 441.771935 -439.416978) (xy 441.719151 -439.398971) (xy 441.669551 -439.37347) (xy 441.624193 -439.341019)
			(xy 441.584044 -439.30231) (xy 441.549958 -439.258167) (xy 441.522662 -439.209532) (xy 441.502739 -439.157441)
			(xy 441.490613 -439.103004) (xy 441.486542 -439.047382) (xy 437.07541 -439.047382) (xy 437.0338 -439.092582)
			(xy 436.985664 -439.13335) (xy 436.932856 -439.167851) (xy 436.876186 -439.195555) (xy 436.816524 -439.216037)
			(xy 436.754786 -439.228982) (xy 436.691922 -439.234192) (xy 436.628896 -439.231585) (xy 436.566676 -439.221203)
			(xy 436.506219 -439.203205) (xy 436.448452 -439.177867) (xy 436.394262 -439.145578) (xy 436.344483 -439.106834)
			(xy 436.299878 -439.062231) (xy 436.261132 -439.012453) (xy 436.228842 -438.958264) (xy 436.203501 -438.900498)
			(xy 436.185501 -438.840041) (xy 436.175117 -438.777822) (xy 436.172508 -438.714796) (xy 427.219206 -438.714796)
			(xy 427.209737 -438.747044) (xy 427.187095 -438.796621) (xy 427.157629 -438.842471) (xy 427.121938 -438.883662)
			(xy 427.080747 -438.919353) (xy 427.034897 -438.948819) (xy 426.98532 -438.971461) (xy 426.933025 -438.986816)
			(xy 426.879077 -438.994572) (xy 426.824575 -438.994572) (xy 426.770627 -438.986816) (xy 426.718332 -438.971461)
			(xy 426.668755 -438.948819) (xy 426.622905 -438.919353) (xy 426.581714 -438.883662) (xy 426.546023 -438.842471)
			(xy 426.516557 -438.796621) (xy 426.493915 -438.747044) (xy 426.47856 -438.694749) (xy 426.470804 -438.640801)
			(xy 426.470318 -438.61355) (xy 426.470797 -438.586212) (xy 426.47858 -438.532094) (xy 426.494007 -438.479641)
			(xy 426.516764 -438.429926) (xy 426.546383 -438.383969) (xy 426.582259 -438.342711) (xy 426.602652 -438.324498)
			(xy 426.611034 -438.317386) (xy 426.620178 -438.297574) (xy 426.621194 -438.199276) (xy 426.612304 -438.17921)
			(xy 426.603922 -438.171844) (xy 426.581411 -438.151144) (xy 426.541035 -438.105209) (xy 426.506458 -438.054765)
			(xy 426.478176 -438.00054) (xy 426.4566 -437.943315) (xy 426.44204 -437.883916) (xy 426.434705 -437.823201)
			(xy 426.43425 -437.792622) (xy 421.256136 -437.792622) (xy 421.258237 -437.8069) (xy 421.258746 -437.834786)
			(xy 421.258237 -437.862672) (xy 421.250117 -437.917848) (xy 421.234049 -437.971255) (xy 421.210377 -438.021752)
			(xy 421.179604 -438.068265) (xy 421.142387 -438.109802) (xy 421.099519 -438.145477) (xy 421.051913 -438.174531)
			(xy 421.000584 -438.196343) (xy 420.946627 -438.210449) (xy 420.89119 -438.216549) (xy 420.835456 -438.214512)
			(xy 420.780613 -438.204382) (xy 420.727829 -438.186375) (xy 420.678229 -438.160874) (xy 420.632871 -438.128423)
			(xy 420.592722 -438.089714) (xy 420.558636 -438.045571) (xy 420.53134 -437.996936) (xy 420.511417 -437.944845)
			(xy 420.499291 -437.890408) (xy 420.49522 -437.834786) (xy 417.853422 -437.834786) (xy 417.901162 -437.837789)
			(xy 417.963952 -437.849767) (xy 418.024745 -437.86952) (xy 418.082584 -437.896737) (xy 418.136555 -437.930988)
			(xy 418.185808 -437.971733) (xy 418.229565 -438.01833) (xy 418.267138 -438.070045) (xy 418.297932 -438.12606)
			(xy 418.321464 -438.185493) (xy 418.337361 -438.247407) (xy 418.345372 -438.310825) (xy 418.345874 -438.342786)
			(xy 418.345372 -438.374747) (xy 418.337361 -438.438165) (xy 418.321464 -438.500079) (xy 418.297932 -438.559512)
			(xy 418.267138 -438.615527) (xy 418.253073 -438.634886) (xy 423.289982 -438.634886) (xy 423.294053 -438.579264)
			(xy 423.306179 -438.524827) (xy 423.326102 -438.472736) (xy 423.353398 -438.424101) (xy 423.387484 -438.379958)
			(xy 423.427633 -438.341249) (xy 423.472991 -438.308798) (xy 423.522591 -438.283297) (xy 423.575375 -438.26529)
			(xy 423.630218 -438.25516) (xy 423.685952 -438.253123) (xy 423.741389 -438.259223) (xy 423.795346 -438.273329)
			(xy 423.846675 -438.295141) (xy 423.894281 -438.324195) (xy 423.937149 -438.35987) (xy 423.974366 -438.401407)
			(xy 424.005139 -438.44792) (xy 424.028811 -438.498417) (xy 424.044879 -438.551824) (xy 424.052999 -438.607)
			(xy 424.053508 -438.634886) (xy 424.052999 -438.662772) (xy 424.044879 -438.717948) (xy 424.028811 -438.771355)
			(xy 424.005139 -438.821852) (xy 423.974366 -438.868365) (xy 423.937149 -438.909902) (xy 423.894281 -438.945577)
			(xy 423.846675 -438.974631) (xy 423.795346 -438.996443) (xy 423.741389 -439.010549) (xy 423.685952 -439.016649)
			(xy 423.630218 -439.014612) (xy 423.575375 -439.004482) (xy 423.522591 -438.986475) (xy 423.472991 -438.960974)
			(xy 423.427633 -438.928523) (xy 423.387484 -438.889814) (xy 423.353398 -438.845671) (xy 423.326102 -438.797036)
			(xy 423.306179 -438.744945) (xy 423.294053 -438.690508) (xy 423.289982 -438.634886) (xy 418.253073 -438.634886)
			(xy 418.229565 -438.667242) (xy 418.185808 -438.713839) (xy 418.136555 -438.754584) (xy 418.082584 -438.788835)
			(xy 418.024745 -438.816052) (xy 417.963952 -438.835805) (xy 417.901162 -438.847783) (xy 417.837366 -438.851797)
			(xy 417.77357 -438.847783) (xy 417.71078 -438.835805) (xy 417.649987 -438.816052) (xy 417.592148 -438.788835)
			(xy 417.538177 -438.754584) (xy 417.488924 -438.713839) (xy 417.445167 -438.667242) (xy 417.407594 -438.615527)
			(xy 417.3768 -438.559512) (xy 417.353268 -438.500079) (xy 417.337371 -438.438165) (xy 417.32936 -438.374747)
			(xy 417.138104 -438.374747) (xy 417.138104 -439.602307) (xy 417.328484 -439.602307) (xy 417.33369 -439.539439)
			(xy 417.346632 -439.477698) (xy 417.367112 -439.418032) (xy 417.394814 -439.361357) (xy 417.429314 -439.308543)
			(xy 417.470082 -439.260403) (xy 417.516492 -439.217675) (xy 417.56783 -439.181016) (xy 417.623308 -439.150988)
			(xy 417.682074 -439.128053) (xy 417.743226 -439.112563) (xy 417.805824 -439.104756) (xy 417.837366 -439.104278)
			(xy 417.867439 -439.104749) (xy 417.927164 -439.111864) (xy 417.985636 -439.125965) (xy 418.042039 -439.146856)
			(xy 418.069014 -439.160158) (xy 418.081722 -439.166104) (xy 418.109227 -439.171576) (xy 418.137183 -439.169356)
			(xy 418.163478 -439.159609) (xy 418.186128 -439.143073) (xy 418.203422 -439.120996) (xy 418.214054 -439.095046)
			(xy 418.21608 -439.081164) (xy 418.219764 -439.053565) (xy 418.233984 -438.999735) (xy 418.255874 -438.948543)
			(xy 418.284969 -438.901074) (xy 418.320653 -438.858336) (xy 418.362167 -438.821236) (xy 418.408631 -438.790562)
			(xy 418.459059 -438.766964) (xy 418.512381 -438.750943) (xy 418.567464 -438.74284) (xy 418.595302 -438.742328)
			(xy 418.622556 -438.742742) (xy 418.676508 -438.750499) (xy 418.728808 -438.765856) (xy 418.778389 -438.7885)
			(xy 418.824244 -438.817969) (xy 418.865438 -438.853664) (xy 418.901132 -438.894858) (xy 418.930601 -438.940712)
			(xy 418.953244 -438.990294) (xy 418.968601 -439.042594) (xy 418.976358 -439.096546) (xy 418.976358 -439.151054)
			(xy 418.968601 -439.205006) (xy 418.966107 -439.213498) (xy 428.721264 -439.213498) (xy 428.725335 -439.157876)
			(xy 428.737461 -439.103439) (xy 428.757384 -439.051348) (xy 428.78468 -439.002713) (xy 428.818766 -438.95857)
			(xy 428.858915 -438.919861) (xy 428.904273 -438.88741) (xy 428.953873 -438.861909) (xy 429.006657 -438.843902)
			(xy 429.0615 -438.833772) (xy 429.117234 -438.831735) (xy 429.172671 -438.837835) (xy 429.226628 -438.851941)
			(xy 429.277957 -438.873753) (xy 429.325563 -438.902807) (xy 429.368431 -438.938482) (xy 429.405648 -438.980019)
			(xy 429.436421 -439.026532) (xy 429.460093 -439.077029) (xy 429.476161 -439.130436) (xy 429.484281 -439.185612)
			(xy 429.48479 -439.213498) (xy 429.484281 -439.241384) (xy 429.476161 -439.29656) (xy 429.460093 -439.349967)
			(xy 429.436421 -439.400464) (xy 429.405648 -439.446977) (xy 429.368431 -439.488514) (xy 429.325563 -439.524189)
			(xy 429.323562 -439.52541) (xy 437.043828 -439.52541) (xy 437.047899 -439.469788) (xy 437.060025 -439.415351)
			(xy 437.079948 -439.36326) (xy 437.107244 -439.314625) (xy 437.14133 -439.270482) (xy 437.181479 -439.231773)
			(xy 437.226837 -439.199322) (xy 437.276437 -439.173821) (xy 437.329221 -439.155814) (xy 437.384064 -439.145684)
			(xy 437.439798 -439.143647) (xy 437.495235 -439.149747) (xy 437.549192 -439.163853) (xy 437.600521 -439.185665)
			(xy 437.648127 -439.214719) (xy 437.690995 -439.250394) (xy 437.728212 -439.291931) (xy 437.758985 -439.338444)
			(xy 437.782657 -439.388941) (xy 437.798725 -439.442348) (xy 437.806845 -439.497524) (xy 437.807354 -439.52541)
			(xy 437.806845 -439.553296) (xy 437.798725 -439.608472) (xy 437.782657 -439.661879) (xy 437.758985 -439.712376)
			(xy 437.728212 -439.758889) (xy 437.690995 -439.800426) (xy 437.648127 -439.836101) (xy 437.600521 -439.865155)
			(xy 437.549192 -439.886967) (xy 437.495235 -439.901073) (xy 437.439798 -439.907173) (xy 437.384064 -439.905136)
			(xy 437.329221 -439.895006) (xy 437.276437 -439.876999) (xy 437.226837 -439.851498) (xy 437.181479 -439.819047)
			(xy 437.14133 -439.780338) (xy 437.107244 -439.736195) (xy 437.079948 -439.68756) (xy 437.060025 -439.635469)
			(xy 437.047899 -439.581032) (xy 437.043828 -439.52541) (xy 429.323562 -439.52541) (xy 429.277957 -439.553243)
			(xy 429.226628 -439.575055) (xy 429.172671 -439.589161) (xy 429.117234 -439.595261) (xy 429.0615 -439.593224)
			(xy 429.006657 -439.583094) (xy 428.953873 -439.565087) (xy 428.904273 -439.539586) (xy 428.858915 -439.507135)
			(xy 428.818766 -439.468426) (xy 428.78468 -439.424283) (xy 428.757384 -439.375648) (xy 428.737461 -439.323557)
			(xy 428.725335 -439.26912) (xy 428.721264 -439.213498) (xy 418.966107 -439.213498) (xy 418.953244 -439.257306)
			(xy 418.930601 -439.306888) (xy 418.901132 -439.352742) (xy 418.865438 -439.393936) (xy 418.824244 -439.429631)
			(xy 418.778389 -439.4591) (xy 418.728808 -439.481744) (xy 418.676508 -439.497101) (xy 418.622556 -439.504858)
			(xy 418.595302 -439.505344) (xy 418.565464 -439.504759) (xy 418.506518 -439.49545) (xy 418.477954 -439.486802)
			(xy 418.464464 -439.482937) (xy 418.436428 -439.481982) (xy 418.409188 -439.488682) (xy 418.384792 -439.502531)
			(xy 418.365078 -439.522487) (xy 418.351527 -439.54705) (xy 418.345161 -439.57437) (xy 418.345366 -439.588402)
			(xy 418.345874 -439.612786) (xy 418.345447 -439.644328) (xy 418.337646 -439.706927) (xy 418.322162 -439.76808)
			(xy 418.299232 -439.826849) (xy 418.26921 -439.88233) (xy 418.232555 -439.933671) (xy 418.231462 -439.934858)
			(xy 422.660062 -439.934858) (xy 422.664133 -439.879236) (xy 422.676259 -439.824799) (xy 422.696182 -439.772708)
			(xy 422.723478 -439.724073) (xy 422.757564 -439.67993) (xy 422.797713 -439.641221) (xy 422.843071 -439.60877)
			(xy 422.892671 -439.583269) (xy 422.945455 -439.565262) (xy 423.000298 -439.555132) (xy 423.056032 -439.553095)
			(xy 423.111469 -439.559195) (xy 423.165426 -439.573301) (xy 423.216755 -439.595113) (xy 423.264361 -439.624167)
			(xy 423.307229 -439.659842) (xy 423.344446 -439.701379) (xy 423.375219 -439.747892) (xy 423.398891 -439.798389)
			(xy 423.414959 -439.851796) (xy 423.423079 -439.906972) (xy 423.423588 -439.934858) (xy 423.423079 -439.962744)
			(xy 423.414959 -440.01792) (xy 423.398891 -440.071327) (xy 423.375219 -440.121824) (xy 423.344446 -440.168337)
			(xy 423.307229 -440.209874) (xy 423.264361 -440.245549) (xy 423.216755 -440.274603) (xy 423.165426 -440.296415)
			(xy 423.111469 -440.310521) (xy 423.056032 -440.316621) (xy 423.000298 -440.314584) (xy 422.945455 -440.304454)
			(xy 422.892671 -440.286447) (xy 422.843071 -440.260946) (xy 422.797713 -440.228495) (xy 422.757564 -440.189786)
			(xy 422.723478 -440.145643) (xy 422.696182 -440.097008) (xy 422.676259 -440.044917) (xy 422.664133 -439.99048)
			(xy 422.660062 -439.934858) (xy 418.231462 -439.934858) (xy 418.189832 -439.980084) (xy 418.141695 -440.020857)
			(xy 418.088885 -440.055362) (xy 418.032213 -440.08307) (xy 417.972548 -440.103555) (xy 417.910808 -440.116503)
			(xy 417.847941 -440.121715) (xy 417.784911 -440.119111) (xy 417.722688 -440.10873) (xy 417.662226 -440.090733)
			(xy 417.604455 -440.065395) (xy 417.550262 -440.033106) (xy 417.500478 -439.994362) (xy 417.45587 -439.949758)
			(xy 417.417121 -439.899978) (xy 417.384827 -439.845788) (xy 417.359483 -439.788019) (xy 417.34148 -439.727559)
			(xy 417.331094 -439.665337) (xy 417.328484 -439.602307) (xy 417.138104 -439.602307) (xy 417.138104 -440.255406)
			(xy 417.138528 -440.265476) (xy 417.146245 -440.284078) (xy 417.15309 -440.291474) (xy 417.566856 -440.70524)
			(xy 417.574265 -440.711927) (xy 417.592701 -440.719519) (xy 417.60267 -440.719972)
		)
		(stroke
			(width 0)
			(type solid)
		)
		(fill yes)
		(layer "In15.Cu")
		(net "P3V3_AUX")
	)
	(gr_poly
		(pts
			(xy 43.424094 -367.660428) (xy 43.434165 -367.660007) (xy 43.452774 -367.652297) (xy 43.460162 -367.645442)
			(xy 44.26331 -366.842294) (xy 44.270709 -366.83545) (xy 44.289307 -366.82772) (xy 44.299378 -366.827308)
			(xy 55.923434 -366.827308) (xy 55.933502 -366.826879) (xy 55.952098 -366.819157) (xy 55.959502 -366.812322)
			(xy 56.075834 -366.69599) (xy 56.08323 -366.689139) (xy 56.101829 -366.681403) (xy 56.111902 -366.681004)
			(xy 57.145428 -366.681004) (xy 57.155432 -366.680511) (xy 57.173915 -366.672847) (xy 57.18806 -366.658695)
			(xy 57.195716 -366.640208) (xy 57.196228 -366.630204) (xy 57.196228 -366.61979) (xy 58.73369 -365.082328)
			(xy 58.741087 -365.075477) (xy 58.759685 -365.067735) (xy 58.769758 -365.067342) (xy 59.479434 -365.067342)
			(xy 59.4895 -365.066911) (xy 59.50809 -365.059182) (xy 59.515502 -365.052356) (xy 61.765434 -362.802424)
			(xy 61.772833 -362.79558) (xy 61.791432 -362.787854) (xy 61.801502 -362.787438) (xy 69.774816 -362.787438)
			(xy 69.779227 -362.787353) (xy 69.787916 -362.785824) (xy 69.792088 -362.78439) (xy 71.808848 -362.066332)
			(xy 71.814076 -362.064275) (xy 71.823553 -362.058245) (xy 71.827644 -362.054394) (xy 73.28281 -360.599228)
			(xy 73.290208 -360.59238) (xy 73.308806 -360.584645) (xy 73.318878 -360.584242) (xy 95.264732 -360.584242)
			(xy 95.27401 -360.583833) (xy 95.291331 -360.577177) (xy 95.298514 -360.571288) (xy 95.648018 -360.260646)
			(xy 95.657924 -360.260646) (xy 95.73514 -360.18343) (xy 95.737172 -360.181398) (xy 109.68482 -347.782642)
			(xy 109.703362 -347.766894) (xy 109.946694 -347.567758) (xy 109.950504 -347.564456) (xy 110.49254 -347.02242)
			(xy 110.522766 -347.016324) (xy 110.526322 -347.017848) (xy 110.52683 -347.018102) (xy 110.528862 -347.018864)
			(xy 110.556294 -347.032072) (xy 110.565137 -347.035897) (xy 110.584336 -347.037301) (xy 110.602694 -347.031508)
			(xy 110.610396 -347.025722) (xy 114.220752 -344.076274) (xy 114.224562 -344.072972) (xy 115.816888 -342.4809)
			(xy 115.820381 -342.477291) (xy 115.826007 -342.468972) (xy 115.828064 -342.46439) (xy 116.601748 -340.59622)
			(xy 116.601748 -338.138008) (xy 116.600478 -338.12734) (xy 114.933984 -330.496164) (xy 114.93293 -330.491942)
			(xy 114.929608 -330.4839) (xy 114.92738 -330.480162) (xy 114.152934 -329.249786) (xy 114.149296 -329.243587)
			(xy 114.145288 -329.229791) (xy 114.14506 -329.222608) (xy 114.14506 -329.109832) (xy 114.144623 -329.099768)
			(xy 114.136887 -329.081186) (xy 114.130074 -329.073764) (xy 113.493296 -328.436986) (xy 113.485901 -328.430131)
			(xy 113.467302 -328.422384) (xy 113.457228 -328.422) (xy 108.746798 -328.422) (xy 108.739848 -328.422244)
			(xy 108.72646 -328.425985) (xy 108.720382 -328.429366) (xy 108.697861 -328.442623) (xy 108.649961 -328.46352)
			(xy 108.599654 -328.477671) (xy 108.547884 -328.48481) (xy 108.521754 -328.485246) (xy 108.495627 -328.484796)
			(xy 108.443865 -328.477629) (xy 108.393563 -328.463476) (xy 108.345658 -328.442601) (xy 108.323126 -328.429366)
			(xy 108.317072 -328.425929) (xy 108.303669 -328.422186) (xy 108.29671 -328.422) (xy 98.704908 -328.422)
			(xy 98.694837 -328.421578) (xy 98.676231 -328.413866) (xy 98.66884 -328.407014) (xy 98.027236 -327.76541)
			(xy 98.020124 -327.758044) (xy 98.001328 -327.750424) (xy 69.019166 -327.750424) (xy 69.00037 -327.758044)
			(xy 68.993258 -327.76541) (xy 68.524628 -328.233786) (xy 68.517262 -328.240898) (xy 68.509642 -328.259694)
			(xy 68.509642 -332.283816) (xy 68.509214 -332.293884) (xy 68.501489 -332.312478) (xy 68.494656 -332.319884)
			(xy 65.430146 -335.384394) (xy 65.422745 -335.391233) (xy 65.404147 -335.398948) (xy 65.394078 -335.39938)
			(xy 64.981328 -335.39938) (xy 64.972946 -335.402428) (xy 64.947823 -335.410948) (xy 64.895582 -335.420147)
			(xy 64.86906 -335.420716) (xy 59.74588 -335.420716) (xy 59.71936 -335.420125) (xy 59.66712 -335.410934)
			(xy 59.641994 -335.402428) (xy 59.633612 -335.39938) (xy 22.352254 -335.39938) (xy 22.342187 -335.399811)
			(xy 22.323593 -335.407535) (xy 22.316186 -335.414366) (xy 22.002242 -335.72831) (xy 21.995393 -335.735707)
			(xy 21.987655 -335.754305) (xy 21.987256 -335.764378) (xy 21.987256 -336.654902) (xy 66.344546 -336.654902)
			(xy 66.345051 -336.626992) (xy 66.353184 -336.571767) (xy 66.369277 -336.518317) (xy 66.392987 -336.467782)
			(xy 66.423807 -336.421241) (xy 66.442082 -336.40014) (xy 66.448432 -336.393028) (xy 66.455036 -336.375756)
			(xy 66.455036 -336.288634) (xy 66.448432 -336.271362) (xy 66.442082 -336.26425) (xy 66.423803 -336.243151)
			(xy 66.392977 -336.196612) (xy 66.369262 -336.146077) (xy 66.353165 -336.092626) (xy 66.345031 -336.037399)
			(xy 66.344546 -336.009488) (xy 66.345032 -335.982237) (xy 66.352788 -335.928289) (xy 66.368143 -335.875994)
			(xy 66.390785 -335.826417) (xy 66.420251 -335.780567) (xy 66.455942 -335.739376) (xy 66.497133 -335.703685)
			(xy 66.542983 -335.674219) (xy 66.59256 -335.651577) (xy 66.644855 -335.636222) (xy 66.698803 -335.628466)
			(xy 66.753305 -335.628466) (xy 66.807253 -335.636222) (xy 66.859548 -335.651577) (xy 66.909125 -335.674219)
			(xy 66.954975 -335.703685) (xy 66.996166 -335.739376) (xy 67.031857 -335.780567) (xy 67.061323 -335.826417)
			(xy 67.083965 -335.875994) (xy 67.09932 -335.928289) (xy 67.107076 -335.982237) (xy 67.107562 -336.009488)
			(xy 67.107049 -336.037398) (xy 67.098918 -336.092622) (xy 67.082826 -336.146072) (xy 67.059118 -336.196607)
			(xy 67.0283 -336.243149) (xy 67.010026 -336.26425) (xy 67.003676 -336.271362) (xy 66.997072 -336.288634)
			(xy 66.997072 -336.375756) (xy 67.003676 -336.393028) (xy 67.010026 -336.40014) (xy 67.028301 -336.421242)
			(xy 67.059128 -336.46778) (xy 67.082844 -336.518314) (xy 67.098941 -336.571765) (xy 67.107076 -336.626991)
			(xy 67.107562 -336.654902) (xy 67.107076 -336.682153) (xy 67.09932 -336.736101) (xy 67.083965 -336.788396)
			(xy 67.061323 -336.837973) (xy 67.031857 -336.883823) (xy 66.996166 -336.925014) (xy 66.954975 -336.960705)
			(xy 66.909125 -336.990171) (xy 66.859548 -337.012813) (xy 66.807253 -337.028168) (xy 66.753305 -337.035924)
			(xy 66.698803 -337.035924) (xy 66.644855 -337.028168) (xy 66.59256 -337.012813) (xy 66.542983 -336.990171)
			(xy 66.497133 -336.960705) (xy 66.455942 -336.925014) (xy 66.420251 -336.883823) (xy 66.390785 -336.837973)
			(xy 66.368143 -336.788396) (xy 66.352788 -336.736101) (xy 66.345032 -336.682153) (xy 66.344546 -336.654902)
			(xy 21.987256 -336.654902) (xy 21.987256 -337.886548) (xy 67.302378 -337.886548) (xy 67.306449 -337.830926)
			(xy 67.318575 -337.776489) (xy 67.338498 -337.724398) (xy 67.365794 -337.675763) (xy 67.39988 -337.63162)
			(xy 67.440029 -337.592911) (xy 67.485387 -337.56046) (xy 67.534987 -337.534959) (xy 67.587771 -337.516952)
			(xy 67.642614 -337.506822) (xy 67.698348 -337.504785) (xy 67.753785 -337.510885) (xy 67.807742 -337.524991)
			(xy 67.859071 -337.546803) (xy 67.906677 -337.575857) (xy 67.949545 -337.611532) (xy 67.986762 -337.653069)
			(xy 68.017535 -337.699582) (xy 68.041207 -337.750079) (xy 68.057275 -337.803486) (xy 68.065395 -337.858662)
			(xy 68.065904 -337.886548) (xy 68.065395 -337.914434) (xy 68.057275 -337.96961) (xy 68.041207 -338.023017)
			(xy 68.017535 -338.073514) (xy 67.986762 -338.120027) (xy 67.949545 -338.161564) (xy 67.906677 -338.197239)
			(xy 67.859071 -338.226293) (xy 67.807742 -338.248105) (xy 67.753785 -338.262211) (xy 67.698348 -338.268311)
			(xy 67.642614 -338.266274) (xy 67.587771 -338.256144) (xy 67.534987 -338.238137) (xy 67.485387 -338.212636)
			(xy 67.440029 -338.180185) (xy 67.39988 -338.141476) (xy 67.365794 -338.097333) (xy 67.338498 -338.048698)
			(xy 67.318575 -337.996607) (xy 67.306449 -337.94217) (xy 67.302378 -337.886548) (xy 21.987256 -337.886548)
			(xy 21.987256 -338.781898) (xy 66.723258 -338.781898) (xy 66.727329 -338.726276) (xy 66.739455 -338.671839)
			(xy 66.759378 -338.619748) (xy 66.786674 -338.571113) (xy 66.82076 -338.52697) (xy 66.860909 -338.488261)
			(xy 66.906267 -338.45581) (xy 66.955867 -338.430309) (xy 67.008651 -338.412302) (xy 67.063494 -338.402172)
			(xy 67.119228 -338.400135) (xy 67.174665 -338.406235) (xy 67.228622 -338.420341) (xy 67.279951 -338.442153)
			(xy 67.327557 -338.471207) (xy 67.370425 -338.506882) (xy 67.407642 -338.548419) (xy 67.438415 -338.594932)
			(xy 67.462087 -338.645429) (xy 67.478155 -338.698836) (xy 67.486275 -338.754012) (xy 67.486784 -338.781898)
			(xy 67.486275 -338.809784) (xy 67.478155 -338.86496) (xy 67.462087 -338.918367) (xy 67.438415 -338.968864)
			(xy 67.407642 -339.015377) (xy 67.370425 -339.056914) (xy 67.327557 -339.092589) (xy 67.279951 -339.121643)
			(xy 67.228622 -339.143455) (xy 67.174665 -339.157561) (xy 67.119228 -339.163661) (xy 67.063494 -339.161624)
			(xy 67.008651 -339.151494) (xy 66.955867 -339.133487) (xy 66.906267 -339.107986) (xy 66.860909 -339.075535)
			(xy 66.82076 -339.036826) (xy 66.786674 -338.992683) (xy 66.759378 -338.944048) (xy 66.739455 -338.891957)
			(xy 66.727329 -338.83752) (xy 66.723258 -338.781898) (xy 21.987256 -338.781898) (xy 21.987256 -339.457538)
			(xy 68.062094 -339.457538) (xy 68.062604 -339.430064) (xy 68.070491 -339.375686) (xy 68.086105 -339.323004)
			(xy 68.109124 -339.273111) (xy 68.139071 -339.227041) (xy 68.156836 -339.206078) (xy 68.162932 -339.198966)
			(xy 68.169282 -339.181948) (xy 68.169282 -339.096096) (xy 68.162932 -339.079078) (xy 68.156836 -339.071966)
			(xy 68.139065 -339.05101) (xy 68.109143 -339.004925) (xy 68.086133 -338.955029) (xy 68.070509 -338.902352)
			(xy 68.062593 -338.847979) (xy 68.062094 -338.820506) (xy 68.06258 -338.793255) (xy 68.070336 -338.739307)
			(xy 68.085691 -338.687012) (xy 68.108333 -338.637435) (xy 68.137799 -338.591585) (xy 68.17349 -338.550394)
			(xy 68.214681 -338.514703) (xy 68.260531 -338.485237) (xy 68.310108 -338.462595) (xy 68.362403 -338.44724)
			(xy 68.416351 -338.439484) (xy 68.470853 -338.439484) (xy 68.524801 -338.44724) (xy 68.577096 -338.462595)
			(xy 68.626673 -338.485237) (xy 68.672523 -338.514703) (xy 68.713714 -338.550394) (xy 68.749405 -338.591585)
			(xy 68.778871 -338.637435) (xy 68.801513 -338.687012) (xy 68.816868 -338.739307) (xy 68.824624 -338.793255)
			(xy 68.82511 -338.820506) (xy 68.824625 -338.847981) (xy 68.816732 -338.90236) (xy 68.801112 -338.955042)
			(xy 68.798477 -338.960751) (xy 69.066891 -338.960751) (xy 69.066891 -338.906249) (xy 69.074648 -338.852301)
			(xy 69.090004 -338.800007) (xy 69.112645 -338.75043) (xy 69.142112 -338.704581) (xy 69.177804 -338.663392)
			(xy 69.218995 -338.627701) (xy 69.264846 -338.598237) (xy 69.314424 -338.575597) (xy 69.366719 -338.560244)
			(xy 69.420667 -338.55249) (xy 69.447918 -338.552028) (xy 69.473153 -338.552427) (xy 69.523187 -338.559046)
			(xy 69.571907 -338.572219) (xy 69.618459 -338.591714) (xy 69.64045 -338.604098) (xy 69.650102 -338.60994)
			(xy 69.6722 -338.611972) (xy 69.766688 -338.578444) (xy 69.78269 -338.56295) (xy 69.786754 -338.552536)
			(xy 69.797438 -338.525755) (xy 69.82573 -338.475516) (xy 69.861264 -338.430108) (xy 69.903228 -338.390568)
			(xy 69.950666 -338.357795) (xy 70.002498 -338.332538) (xy 70.057541 -338.315371) (xy 70.114541 -338.306687)
			(xy 70.14337 -338.306156) (xy 70.170619 -338.306706) (xy 70.224562 -338.314458) (xy 70.276854 -338.329807)
			(xy 70.326428 -338.352442) (xy 70.372277 -338.381902) (xy 70.413467 -338.417587) (xy 70.449159 -338.45877)
			(xy 70.478626 -338.504614) (xy 70.50127 -338.554184) (xy 70.516628 -338.606473) (xy 70.524389 -338.660415)
			(xy 70.524878 -338.687664) (xy 70.524231 -338.719227) (xy 70.513839 -338.781493) (xy 70.493348 -338.841202)
			(xy 70.478904 -338.869274) (xy 70.474078 -338.878164) (xy 70.472046 -338.897722) (xy 70.4977 -338.98586)
			(xy 70.510146 -339.001354) (xy 70.519036 -339.006434) (xy 70.544122 -339.021008) (xy 70.590007 -339.056505)
			(xy 70.629985 -339.098543) (xy 70.663133 -339.146153) (xy 70.688687 -339.198234) (xy 70.706055 -339.253586)
			(xy 70.714838 -339.31093) (xy 70.715378 -339.339936) (xy 70.714892 -339.367187) (xy 70.707136 -339.421135)
			(xy 70.691781 -339.47343) (xy 70.669139 -339.523007) (xy 70.639673 -339.568857) (xy 70.603982 -339.610048)
			(xy 70.562791 -339.645739) (xy 70.516941 -339.675205) (xy 70.467364 -339.697847) (xy 70.415069 -339.713202)
			(xy 70.361121 -339.720958) (xy 70.306619 -339.720958) (xy 70.252671 -339.713202) (xy 70.200376 -339.697847)
			(xy 70.150799 -339.675205) (xy 70.104949 -339.645739) (xy 70.063758 -339.610048) (xy 70.028067 -339.568857)
			(xy 69.998601 -339.523007) (xy 69.975959 -339.47343) (xy 69.960604 -339.421135) (xy 69.952848 -339.367187)
			(xy 69.952362 -339.339936) (xy 69.953016 -339.308373) (xy 69.963407 -339.246108) (xy 69.983894 -339.186399)
			(xy 69.998336 -339.158326) (xy 70.003162 -339.149436) (xy 70.005194 -339.129878) (xy 69.97954 -339.04174)
			(xy 69.967094 -339.026246) (xy 69.958204 -339.021166) (xy 69.950838 -339.017102) (xy 69.941186 -339.01126)
			(xy 69.919088 -339.009228) (xy 69.8246 -339.042756) (xy 69.808598 -339.05825) (xy 69.804534 -339.068664)
			(xy 69.79386 -339.095449) (xy 69.765567 -339.145689) (xy 69.730032 -339.191097) (xy 69.688066 -339.230637)
			(xy 69.640626 -339.263409) (xy 69.588793 -339.288665) (xy 69.533749 -339.305831) (xy 69.476747 -339.314514)
			(xy 69.447918 -339.315044) (xy 69.420667 -339.31451) (xy 69.366719 -339.306756) (xy 69.314424 -339.291403)
			(xy 69.264846 -339.268763) (xy 69.218995 -339.239299) (xy 69.177804 -339.203608) (xy 69.142112 -339.162419)
			(xy 69.112645 -339.11657) (xy 69.090004 -339.066993) (xy 69.074648 -339.014699) (xy 69.066891 -338.960751)
			(xy 68.798477 -338.960751) (xy 68.778087 -339.004935) (xy 68.748135 -339.051004) (xy 68.730368 -339.071966)
			(xy 68.724272 -339.079078) (xy 68.717922 -339.096096) (xy 68.717922 -339.181948) (xy 68.724272 -339.198966)
			(xy 68.730368 -339.206078) (xy 68.748113 -339.227055) (xy 68.778039 -339.273134) (xy 68.801054 -339.323024)
			(xy 68.816684 -339.375698) (xy 68.824607 -339.430067) (xy 68.82511 -339.457538) (xy 68.824624 -339.484789)
			(xy 68.816868 -339.538737) (xy 68.801513 -339.591032) (xy 68.778871 -339.640609) (xy 68.749405 -339.686459)
			(xy 68.713714 -339.72765) (xy 68.672523 -339.763341) (xy 68.626673 -339.792807) (xy 68.577096 -339.815449)
			(xy 68.524801 -339.830804) (xy 68.470853 -339.83856) (xy 68.416351 -339.83856) (xy 68.362403 -339.830804)
			(xy 68.310108 -339.815449) (xy 68.260531 -339.792807) (xy 68.214681 -339.763341) (xy 68.17349 -339.72765)
			(xy 68.137799 -339.686459) (xy 68.108333 -339.640609) (xy 68.085691 -339.591032) (xy 68.070336 -339.538737)
			(xy 68.06258 -339.484789) (xy 68.062094 -339.457538) (xy 21.987256 -339.457538) (xy 21.987256 -342.658954)
			(xy 21.987691 -342.669019) (xy 21.995425 -342.687603) (xy 22.002242 -342.695022) (xy 24.886666 -345.579446)
			(xy 24.893509 -345.586845) (xy 24.901232 -345.605444) (xy 24.901652 -345.615514) (xy 24.901652 -347.279722)
			(xy 24.902056 -347.28924) (xy 24.908982 -347.306973) (xy 24.915114 -347.314266) (xy 24.94153 -347.342714)
			(xy 24.957024 -347.350842) (xy 24.966168 -347.352112) (xy 24.993431 -347.356093) (xy 25.046505 -347.370882)
			(xy 25.096899 -347.393152) (xy 25.143565 -347.42244) (xy 25.185533 -347.458137) (xy 25.221928 -347.4995)
			(xy 25.251995 -347.545668) (xy 25.275107 -347.595682) (xy 25.290784 -347.6485) (xy 25.2987 -347.703024)
			(xy 25.299162 -347.730572) (xy 25.298678 -347.758484) (xy 25.290546 -347.813712) (xy 25.274452 -347.867165)
			(xy 25.250739 -347.917701) (xy 25.219913 -347.964242) (xy 25.201626 -347.985334) (xy 25.195276 -347.992446)
			(xy 25.188672 -348.009718) (xy 25.188672 -348.09684) (xy 25.195276 -348.114112) (xy 25.201626 -348.121224)
			(xy 25.219901 -348.142325) (xy 25.250723 -348.188865) (xy 25.274434 -348.2394) (xy 25.290529 -348.29285)
			(xy 25.298665 -348.348075) (xy 25.299162 -348.375986) (xy 25.299084 -348.388724) (xy 25.297432 -348.414145)
			(xy 25.29586 -348.426786) (xy 25.291673 -348.454227) (xy 25.276395 -348.507591) (xy 25.253547 -348.558179)
			(xy 25.223612 -348.604924) (xy 25.187222 -348.646839) (xy 25.145143 -348.683041) (xy 25.098264 -348.712765)
			(xy 25.047573 -348.735384) (xy 24.994141 -348.750421) (xy 24.966676 -348.754446) (xy 24.957532 -348.755462)
			(xy 24.94153 -348.76359) (xy 24.915114 -348.792292) (xy 24.908921 -348.799548) (xy 24.901988 -348.817304)
			(xy 24.901652 -348.826836) (xy 24.901652 -348.991682) (xy 28.727908 -348.991682) (xy 28.727908 -347.00591)
			(xy 28.728552 -346.976944) (xy 28.739422 -346.920044) (xy 28.749498 -346.89288) (xy 28.753308 -346.883736)
			(xy 28.753308 -346.747592) (xy 28.753782 -346.737583) (xy 28.761446 -346.719089) (xy 28.775603 -346.704937)
			(xy 28.794099 -346.697279) (xy 28.804108 -346.696792) (xy 32.182562 -346.696792) (xy 32.187453 -346.696927)
			(xy 32.197045 -346.698847) (xy 32.201612 -346.700602) (xy 32.220916 -346.708476) (xy 32.225483 -346.710203)
			(xy 32.235083 -346.711985) (xy 32.239966 -346.712032) (xy 32.258508 -346.712032) (xy 32.26851 -346.712511)
			(xy 32.286973 -346.720218) (xy 32.294322 -346.727018) (xy 32.423608 -346.85605) (xy 32.424116 -346.856812)
			(xy 32.460692 -346.892118) (xy 32.464371 -346.895872) (xy 32.470257 -346.90458) (xy 32.472376 -346.90939)
			(xy 32.511238 -347.005148) (xy 32.512982 -347.009719) (xy 32.514907 -347.019308) (xy 32.515048 -347.024198)
			(xy 32.515048 -348.375986) (xy 32.816546 -348.375986) (xy 32.817041 -348.348075) (xy 32.825177 -348.29285)
			(xy 32.841272 -348.2394) (xy 32.864984 -348.188865) (xy 32.895806 -348.142325) (xy 32.914082 -348.121224)
			(xy 32.920432 -348.114112) (xy 32.927036 -348.09684) (xy 32.927036 -348.009718) (xy 32.920432 -347.992446)
			(xy 32.914082 -347.985334) (xy 32.895796 -347.964241) (xy 32.86497 -347.917701) (xy 32.841257 -347.867164)
			(xy 32.825162 -347.813712) (xy 32.81703 -347.758484) (xy 32.816546 -347.730572) (xy 32.817032 -347.703321)
			(xy 32.824788 -347.649373) (xy 32.840143 -347.597078) (xy 32.862785 -347.547501) (xy 32.892251 -347.501651)
			(xy 32.927942 -347.46046) (xy 32.969133 -347.424769) (xy 33.014983 -347.395303) (xy 33.06456 -347.372661)
			(xy 33.116855 -347.357306) (xy 33.170803 -347.34955) (xy 33.225305 -347.34955) (xy 33.279253 -347.357306)
			(xy 33.331548 -347.372661) (xy 33.381125 -347.395303) (xy 33.426975 -347.424769) (xy 33.468166 -347.46046)
			(xy 33.503857 -347.501651) (xy 33.533323 -347.547501) (xy 33.555965 -347.597078) (xy 33.57132 -347.649373)
			(xy 33.579076 -347.703321) (xy 33.579562 -347.730572) (xy 33.579099 -347.758484) (xy 33.570955 -347.81371)
			(xy 33.554852 -347.867161) (xy 33.531133 -347.917695) (xy 33.500305 -347.964234) (xy 33.482026 -347.985334)
			(xy 33.475676 -347.992446) (xy 33.469072 -348.009718) (xy 33.469072 -348.09684) (xy 33.475676 -348.114112)
			(xy 33.482026 -348.121224) (xy 33.500294 -348.142332) (xy 33.531122 -348.188868) (xy 33.554839 -348.239401)
			(xy 33.570938 -348.29285) (xy 33.579075 -348.348075) (xy 33.579562 -348.375986) (xy 33.579076 -348.403237)
			(xy 33.57132 -348.457185) (xy 33.555965 -348.50948) (xy 33.533323 -348.559057) (xy 33.503857 -348.604907)
			(xy 33.468166 -348.646098) (xy 33.426975 -348.681789) (xy 33.381125 -348.711255) (xy 33.331548 -348.733897)
			(xy 33.279253 -348.749252) (xy 33.225305 -348.757008) (xy 33.170803 -348.757008) (xy 33.116855 -348.749252)
			(xy 33.06456 -348.733897) (xy 33.014983 -348.711255) (xy 32.969133 -348.681789) (xy 32.927942 -348.646098)
			(xy 32.892251 -348.604907) (xy 32.862785 -348.559057) (xy 32.840143 -348.50948) (xy 32.824788 -348.457185)
			(xy 32.817032 -348.403237) (xy 32.816546 -348.375986) (xy 32.515048 -348.375986) (xy 32.515048 -348.376748)
			(xy 32.515405 -348.386795) (xy 32.523002 -348.405391) (xy 32.52978 -348.412816) (xy 32.766762 -348.649544)
			(xy 32.76727 -348.650306) (xy 32.803846 -348.685612) (xy 32.807518 -348.689373) (xy 32.813408 -348.698075)
			(xy 32.81553 -348.702884) (xy 32.854392 -348.798642) (xy 32.856096 -348.803217) (xy 32.857893 -348.812811)
			(xy 32.857948 -348.817692) (xy 32.857948 -349.607632) (xy 33.774378 -349.607632) (xy 33.778449 -349.55201)
			(xy 33.790575 -349.497573) (xy 33.810498 -349.445482) (xy 33.837794 -349.396847) (xy 33.87188 -349.352704)
			(xy 33.912029 -349.313995) (xy 33.957387 -349.281544) (xy 34.006987 -349.256043) (xy 34.059771 -349.238036)
			(xy 34.114614 -349.227906) (xy 34.170348 -349.225869) (xy 34.225785 -349.231969) (xy 34.279742 -349.246075)
			(xy 34.331071 -349.267887) (xy 34.378677 -349.296941) (xy 34.421545 -349.332616) (xy 34.458762 -349.374153)
			(xy 34.489535 -349.420666) (xy 34.513207 -349.471163) (xy 34.529275 -349.52457) (xy 34.537395 -349.579746)
			(xy 34.537904 -349.607632) (xy 34.537395 -349.635518) (xy 34.529275 -349.690694) (xy 34.513207 -349.744101)
			(xy 34.489535 -349.794598) (xy 34.458762 -349.841111) (xy 34.421545 -349.882648) (xy 34.378677 -349.918323)
			(xy 34.331071 -349.947377) (xy 34.279742 -349.969189) (xy 34.225785 -349.983295) (xy 34.170348 -349.989395)
			(xy 34.114614 -349.987358) (xy 34.059771 -349.977228) (xy 34.006987 -349.959221) (xy 33.957387 -349.93372)
			(xy 33.912029 -349.901269) (xy 33.87188 -349.86256) (xy 33.837794 -349.818417) (xy 33.810498 -349.769782)
			(xy 33.790575 -349.717691) (xy 33.778449 -349.663254) (xy 33.774378 -349.607632) (xy 32.857948 -349.607632)
			(xy 32.857948 -350.502982) (xy 33.195258 -350.502982) (xy 33.199329 -350.44736) (xy 33.211455 -350.392923)
			(xy 33.231378 -350.340832) (xy 33.258674 -350.292197) (xy 33.29276 -350.248054) (xy 33.332909 -350.209345)
			(xy 33.378267 -350.176894) (xy 33.427867 -350.151393) (xy 33.480651 -350.133386) (xy 33.535494 -350.123256)
			(xy 33.591228 -350.121219) (xy 33.646665 -350.127319) (xy 33.700622 -350.141425) (xy 33.751951 -350.163237)
			(xy 33.799557 -350.192291) (xy 33.842425 -350.227966) (xy 33.879642 -350.269503) (xy 33.910415 -350.316016)
			(xy 33.934087 -350.366513) (xy 33.950155 -350.41992) (xy 33.958275 -350.475096) (xy 33.958784 -350.502982)
			(xy 33.958275 -350.530868) (xy 33.950155 -350.586044) (xy 33.934087 -350.639451) (xy 33.910415 -350.689948)
			(xy 33.879642 -350.736461) (xy 33.842425 -350.777998) (xy 33.799557 -350.813673) (xy 33.751951 -350.842727)
			(xy 33.700622 -350.864539) (xy 33.646665 -350.878645) (xy 33.591228 -350.884745) (xy 33.535494 -350.882708)
			(xy 33.480651 -350.872578) (xy 33.427867 -350.854571) (xy 33.378267 -350.82907) (xy 33.332909 -350.796619)
			(xy 33.29276 -350.75791) (xy 33.258674 -350.713767) (xy 33.231378 -350.665132) (xy 33.211455 -350.613041)
			(xy 33.199329 -350.558604) (xy 33.195258 -350.502982) (xy 32.857948 -350.502982) (xy 32.857948 -351.178622)
			(xy 34.534094 -351.178622) (xy 34.534595 -351.151148) (xy 34.542483 -351.096769) (xy 34.5581 -351.044087)
			(xy 34.581122 -350.994194) (xy 34.61107 -350.948124) (xy 34.628836 -350.927162) (xy 34.634932 -350.92005)
			(xy 34.641282 -350.903032) (xy 34.641282 -350.81718) (xy 34.634932 -350.800162) (xy 34.628836 -350.79305)
			(xy 34.611058 -350.7721) (xy 34.581137 -350.726014) (xy 34.558128 -350.676116) (xy 34.542506 -350.623437)
			(xy 34.534592 -350.569063) (xy 34.534094 -350.54159) (xy 34.53458 -350.514339) (xy 34.542336 -350.460391)
			(xy 34.557691 -350.408096) (xy 34.580333 -350.358519) (xy 34.609799 -350.312669) (xy 34.64549 -350.271478)
			(xy 34.686681 -350.235787) (xy 34.732531 -350.206321) (xy 34.782108 -350.183679) (xy 34.834403 -350.168324)
			(xy 34.888351 -350.160568) (xy 34.942853 -350.160568) (xy 34.996801 -350.168324) (xy 35.049096 -350.183679)
			(xy 35.098673 -350.206321) (xy 35.144523 -350.235787) (xy 35.185714 -350.271478) (xy 35.221405 -350.312669)
			(xy 35.250871 -350.358519) (xy 35.273513 -350.408096) (xy 35.288868 -350.460391) (xy 35.296624 -350.514339)
			(xy 35.29711 -350.54159) (xy 35.296615 -350.569064) (xy 35.288725 -350.623443) (xy 35.273107 -350.676126)
			(xy 35.270465 -350.681852) (xy 35.538875 -350.681852) (xy 35.538875 -350.627348) (xy 35.546632 -350.573398)
			(xy 35.561989 -350.521102) (xy 35.584631 -350.471523) (xy 35.614099 -350.425671) (xy 35.649793 -350.38448)
			(xy 35.690986 -350.348788) (xy 35.736839 -350.319322) (xy 35.786418 -350.296682) (xy 35.838716 -350.281329)
			(xy 35.892666 -350.273574) (xy 35.919918 -350.273112) (xy 35.945154 -350.273499) (xy 35.995188 -350.28012)
			(xy 36.043908 -350.293296) (xy 36.09046 -350.312796) (xy 36.11245 -350.325182) (xy 36.122102 -350.331024)
			(xy 36.1442 -350.333056) (xy 36.238688 -350.299528) (xy 36.25469 -350.284034) (xy 36.258754 -350.27362)
			(xy 36.269483 -350.246857) (xy 36.297765 -350.196615) (xy 36.333289 -350.151205) (xy 36.375246 -350.111661)
			(xy 36.422679 -350.078885) (xy 36.474506 -350.053625) (xy 36.529545 -350.036457) (xy 36.586542 -350.027771)
			(xy 36.61537 -350.02724) (xy 36.642624 -350.027683) (xy 36.696578 -350.035437) (xy 36.74888 -350.050792)
			(xy 36.798463 -350.073435) (xy 36.844318 -350.102904) (xy 36.885513 -350.1386) (xy 36.921207 -350.179796)
			(xy 36.950674 -350.225653) (xy 36.973314 -350.275237) (xy 36.988666 -350.327539) (xy 36.996418 -350.381494)
			(xy 36.996878 -350.408748) (xy 36.996225 -350.440311) (xy 36.985835 -350.502577) (xy 36.965347 -350.562286)
			(xy 36.950904 -350.590358) (xy 36.946078 -350.599248) (xy 36.944046 -350.618806) (xy 36.9697 -350.706944)
			(xy 36.982146 -350.722438) (xy 36.991036 -350.727518) (xy 37.016115 -350.742104) (xy 37.062 -350.777599)
			(xy 37.101978 -350.819635) (xy 37.135127 -350.867242) (xy 37.160682 -350.919322) (xy 37.178052 -350.974672)
			(xy 37.186837 -351.032014) (xy 37.187378 -351.06102) (xy 37.186892 -351.088271) (xy 37.179136 -351.142219)
			(xy 37.163781 -351.194514) (xy 37.141139 -351.244091) (xy 37.111673 -351.289941) (xy 37.075982 -351.331132)
			(xy 37.034791 -351.366823) (xy 36.988941 -351.396289) (xy 36.939364 -351.418931) (xy 36.887069 -351.434286)
			(xy 36.833121 -351.442042) (xy 36.778619 -351.442042) (xy 36.724671 -351.434286) (xy 36.672376 -351.418931)
			(xy 36.622799 -351.396289) (xy 36.576949 -351.366823) (xy 36.535758 -351.331132) (xy 36.500067 -351.289941)
			(xy 36.470601 -351.244091) (xy 36.447959 -351.194514) (xy 36.432604 -351.142219) (xy 36.424848 -351.088271)
			(xy 36.424362 -351.06102) (xy 36.42501 -351.029457) (xy 36.435403 -350.967191) (xy 36.455893 -350.907483)
			(xy 36.470336 -350.87941) (xy 36.475162 -350.87052) (xy 36.477194 -350.850962) (xy 36.45154 -350.762824)
			(xy 36.439094 -350.74733) (xy 36.430204 -350.74225) (xy 36.422838 -350.738186) (xy 36.413186 -350.732344)
			(xy 36.391088 -350.730312) (xy 36.2966 -350.76384) (xy 36.280598 -350.779334) (xy 36.276534 -350.789748)
			(xy 36.265852 -350.81653) (xy 36.23756 -350.86677) (xy 36.202027 -350.912178) (xy 36.160063 -350.951719)
			(xy 36.112624 -350.984492) (xy 36.060792 -351.009749) (xy 36.005748 -351.026915) (xy 35.948747 -351.035598)
			(xy 35.919918 -351.036128) (xy 35.892666 -351.035626) (xy 35.838716 -351.027871) (xy 35.786418 -351.012518)
			(xy 35.736839 -350.989878) (xy 35.690986 -350.960412) (xy 35.649793 -350.92472) (xy 35.614099 -350.883529)
			(xy 35.584631 -350.837677) (xy 35.561989 -350.788098) (xy 35.546632 -350.735802) (xy 35.538875 -350.681852)
			(xy 35.270465 -350.681852) (xy 35.250084 -350.726018) (xy 35.220134 -350.772088) (xy 35.202368 -350.79305)
			(xy 35.196272 -350.800162) (xy 35.189922 -350.81718) (xy 35.189922 -350.903032) (xy 35.196272 -350.92005)
			(xy 35.202368 -350.927162) (xy 35.220106 -350.948145) (xy 35.250032 -350.994222) (xy 35.273049 -351.044111)
			(xy 35.288681 -351.096783) (xy 35.296606 -351.151151) (xy 35.29711 -351.178622) (xy 35.296624 -351.205873)
			(xy 35.288868 -351.259821) (xy 35.273513 -351.312116) (xy 35.250871 -351.361693) (xy 35.221405 -351.407543)
			(xy 35.185714 -351.448734) (xy 35.144523 -351.484425) (xy 35.098673 -351.513891) (xy 35.049096 -351.536533)
			(xy 34.996801 -351.551888) (xy 34.942853 -351.559644) (xy 34.888351 -351.559644) (xy 34.834403 -351.551888)
			(xy 34.782108 -351.536533) (xy 34.732531 -351.513891) (xy 34.686681 -351.484425) (xy 34.64549 -351.448734)
			(xy 34.609799 -351.407543) (xy 34.580333 -351.361693) (xy 34.557691 -351.312116) (xy 34.542336 -351.259821)
			(xy 34.53458 -351.205873) (xy 34.534094 -351.178622) (xy 32.857948 -351.178622) (xy 32.857948 -351.795842)
			(xy 32.858339 -351.805915) (xy 32.866082 -351.824514) (xy 32.872934 -351.83191) (xy 33.417002 -352.375978)
			(xy 33.42441 -352.382809) (xy 33.443003 -352.390535) (xy 33.45307 -352.390964) (xy 37.73297 -352.390964)
			(xy 37.743039 -352.390532) (xy 37.761637 -352.382817) (xy 37.769038 -352.375978) (xy 37.92728 -352.217736)
			(xy 37.933995 -352.210272) (xy 37.941571 -352.191699) (xy 37.942012 -352.181668) (xy 37.942012 -350.04629)
			(xy 37.941645 -350.036244) (xy 37.934056 -350.017647) (xy 37.92728 -350.010222) (xy 37.101526 -349.184722)
			(xy 37.101018 -349.18396) (xy 37.064442 -349.148654) (xy 37.060762 -349.1449) (xy 37.054877 -349.136193)
			(xy 37.052758 -349.131382) (xy 37.013896 -349.035624) (xy 37.012182 -349.031052) (xy 37.010392 -349.021456)
			(xy 37.01034 -349.016574) (xy 37.01034 -347.048074) (xy 37.010785 -347.024077) (xy 37.018254 -346.97667)
			(xy 37.033067 -346.93102) (xy 37.054857 -346.888259) (xy 37.083083 -346.849445) (xy 37.099748 -346.832174)
			(xy 37.15639 -346.775532) (xy 37.157152 -346.775024) (xy 37.192458 -346.738448) (xy 37.19621 -346.734767)
			(xy 37.204919 -346.728882) (xy 37.20973 -346.726764) (xy 37.305488 -346.687902) (xy 37.310056 -346.686149)
			(xy 37.319648 -346.68423) (xy 37.324538 -346.684092) (xy 40.410892 -346.684092) (xy 40.434897 -346.684548)
			(xy 40.48231 -346.692095) (xy 40.527958 -346.706971) (xy 40.570713 -346.72881) (xy 40.609522 -346.757074)
			(xy 40.626792 -346.773754) (xy 40.775128 -346.92209) (xy 40.775636 -346.922852) (xy 40.812212 -346.958158)
			(xy 40.815889 -346.961914) (xy 40.821776 -346.97062) (xy 40.823896 -346.97543) (xy 40.862758 -347.071188)
			(xy 40.864509 -347.075756) (xy 40.86643 -347.085348) (xy 40.866568 -347.090238) (xy 40.866568 -348.375986)
			(xy 41.122346 -348.375986) (xy 41.122841 -348.348075) (xy 41.130977 -348.29285) (xy 41.147072 -348.2394)
			(xy 41.170784 -348.188865) (xy 41.201606 -348.142325) (xy 41.219882 -348.121224) (xy 41.226232 -348.114112)
			(xy 41.232836 -348.09684) (xy 41.232836 -348.009718) (xy 41.226232 -347.992446) (xy 41.219882 -347.985334)
			(xy 41.201596 -347.964241) (xy 41.17077 -347.917701) (xy 41.147057 -347.867164) (xy 41.130962 -347.813712)
			(xy 41.12283 -347.758484) (xy 41.122346 -347.730572) (xy 41.122832 -347.703321) (xy 41.130588 -347.649373)
			(xy 41.145943 -347.597078) (xy 41.168585 -347.547501) (xy 41.198051 -347.501651) (xy 41.233742 -347.46046)
			(xy 41.274933 -347.424769) (xy 41.320783 -347.395303) (xy 41.37036 -347.372661) (xy 41.422655 -347.357306)
			(xy 41.476603 -347.34955) (xy 41.531105 -347.34955) (xy 41.585053 -347.357306) (xy 41.637348 -347.372661)
			(xy 41.686925 -347.395303) (xy 41.732775 -347.424769) (xy 41.773966 -347.46046) (xy 41.809657 -347.501651)
			(xy 41.839123 -347.547501) (xy 41.861765 -347.597078) (xy 41.87712 -347.649373) (xy 41.884876 -347.703321)
			(xy 41.885362 -347.730572) (xy 41.884899 -347.758484) (xy 41.876755 -347.81371) (xy 41.860652 -347.867161)
			(xy 41.836933 -347.917695) (xy 41.806105 -347.964234) (xy 41.787826 -347.985334) (xy 41.781476 -347.992446)
			(xy 41.774872 -348.009718) (xy 41.774872 -348.09684) (xy 41.781476 -348.114112) (xy 41.787826 -348.121224)
			(xy 41.806094 -348.142332) (xy 41.836922 -348.188868) (xy 41.860639 -348.239401) (xy 41.876738 -348.29285)
			(xy 41.884875 -348.348075) (xy 41.885362 -348.375986) (xy 41.884876 -348.403237) (xy 41.87712 -348.457185)
			(xy 41.861765 -348.50948) (xy 41.839123 -348.559057) (xy 41.809657 -348.604907) (xy 41.773966 -348.646098)
			(xy 41.732775 -348.681789) (xy 41.686925 -348.711255) (xy 41.637348 -348.733897) (xy 41.585053 -348.749252)
			(xy 41.531105 -348.757008) (xy 41.476603 -348.757008) (xy 41.422655 -348.749252) (xy 41.37036 -348.733897)
			(xy 41.320783 -348.711255) (xy 41.274933 -348.681789) (xy 41.233742 -348.646098) (xy 41.198051 -348.604907)
			(xy 41.168585 -348.559057) (xy 41.145943 -348.50948) (xy 41.130588 -348.457185) (xy 41.122832 -348.403237)
			(xy 41.122346 -348.375986) (xy 40.866568 -348.375986) (xy 40.866568 -348.468188) (xy 40.866899 -348.478238)
			(xy 40.874513 -348.496834) (xy 40.8813 -348.504256) (xy 41.047162 -348.669864) (xy 41.04767 -348.670626)
			(xy 41.084246 -348.705932) (xy 41.087922 -348.709689) (xy 41.09381 -348.718394) (xy 41.09593 -348.723204)
			(xy 41.134792 -348.818962) (xy 41.136501 -348.823535) (xy 41.138295 -348.83313) (xy 41.138348 -348.838012)
			(xy 41.138348 -349.607632) (xy 42.080178 -349.607632) (xy 42.084249 -349.55201) (xy 42.096375 -349.497573)
			(xy 42.116298 -349.445482) (xy 42.143594 -349.396847) (xy 42.17768 -349.352704) (xy 42.217829 -349.313995)
			(xy 42.263187 -349.281544) (xy 42.312787 -349.256043) (xy 42.365571 -349.238036) (xy 42.420414 -349.227906)
			(xy 42.476148 -349.225869) (xy 42.531585 -349.231969) (xy 42.585542 -349.246075) (xy 42.636871 -349.267887)
			(xy 42.684477 -349.296941) (xy 42.727345 -349.332616) (xy 42.764562 -349.374153) (xy 42.795335 -349.420666)
			(xy 42.819007 -349.471163) (xy 42.835075 -349.52457) (xy 42.843195 -349.579746) (xy 42.843704 -349.607632)
			(xy 42.843195 -349.635518) (xy 42.835075 -349.690694) (xy 42.819007 -349.744101) (xy 42.795335 -349.794598)
			(xy 42.764562 -349.841111) (xy 42.727345 -349.882648) (xy 42.684477 -349.918323) (xy 42.636871 -349.947377)
			(xy 42.585542 -349.969189) (xy 42.531585 -349.983295) (xy 42.476148 -349.989395) (xy 42.420414 -349.987358)
			(xy 42.365571 -349.977228) (xy 42.312787 -349.959221) (xy 42.263187 -349.93372) (xy 42.217829 -349.901269)
			(xy 42.17768 -349.86256) (xy 42.143594 -349.818417) (xy 42.116298 -349.769782) (xy 42.096375 -349.717691)
			(xy 42.084249 -349.663254) (xy 42.080178 -349.607632) (xy 41.138348 -349.607632) (xy 41.138348 -350.502982)
			(xy 41.501058 -350.502982) (xy 41.505129 -350.44736) (xy 41.517255 -350.392923) (xy 41.537178 -350.340832)
			(xy 41.564474 -350.292197) (xy 41.59856 -350.248054) (xy 41.638709 -350.209345) (xy 41.684067 -350.176894)
			(xy 41.733667 -350.151393) (xy 41.786451 -350.133386) (xy 41.841294 -350.123256) (xy 41.897028 -350.121219)
			(xy 41.952465 -350.127319) (xy 42.006422 -350.141425) (xy 42.057751 -350.163237) (xy 42.105357 -350.192291)
			(xy 42.148225 -350.227966) (xy 42.185442 -350.269503) (xy 42.216215 -350.316016) (xy 42.239887 -350.366513)
			(xy 42.255955 -350.41992) (xy 42.264075 -350.475096) (xy 42.264584 -350.502982) (xy 42.264075 -350.530868)
			(xy 42.255955 -350.586044) (xy 42.239887 -350.639451) (xy 42.216215 -350.689948) (xy 42.185442 -350.736461)
			(xy 42.148225 -350.777998) (xy 42.105357 -350.813673) (xy 42.057751 -350.842727) (xy 42.006422 -350.864539)
			(xy 41.952465 -350.878645) (xy 41.897028 -350.884745) (xy 41.841294 -350.882708) (xy 41.786451 -350.872578)
			(xy 41.733667 -350.854571) (xy 41.684067 -350.82907) (xy 41.638709 -350.796619) (xy 41.59856 -350.75791)
			(xy 41.564474 -350.713767) (xy 41.537178 -350.665132) (xy 41.517255 -350.613041) (xy 41.505129 -350.558604)
			(xy 41.501058 -350.502982) (xy 41.138348 -350.502982) (xy 41.138348 -351.178622) (xy 42.839894 -351.178622)
			(xy 42.840395 -351.151148) (xy 42.848283 -351.096769) (xy 42.8639 -351.044087) (xy 42.886922 -350.994194)
			(xy 42.91687 -350.948124) (xy 42.934636 -350.927162) (xy 42.940732 -350.92005) (xy 42.947082 -350.903032)
			(xy 42.947082 -350.81718) (xy 42.940732 -350.800162) (xy 42.934636 -350.79305) (xy 42.916858 -350.7721)
			(xy 42.886937 -350.726014) (xy 42.863928 -350.676116) (xy 42.848306 -350.623437) (xy 42.840392 -350.569063)
			(xy 42.839894 -350.54159) (xy 42.84038 -350.514339) (xy 42.848136 -350.460391) (xy 42.863491 -350.408096)
			(xy 42.886133 -350.358519) (xy 42.915599 -350.312669) (xy 42.95129 -350.271478) (xy 42.992481 -350.235787)
			(xy 43.038331 -350.206321) (xy 43.087908 -350.183679) (xy 43.140203 -350.168324) (xy 43.194151 -350.160568)
			(xy 43.248653 -350.160568) (xy 43.302601 -350.168324) (xy 43.354896 -350.183679) (xy 43.404473 -350.206321)
			(xy 43.450323 -350.235787) (xy 43.491514 -350.271478) (xy 43.527205 -350.312669) (xy 43.556671 -350.358519)
			(xy 43.579313 -350.408096) (xy 43.594668 -350.460391) (xy 43.602424 -350.514339) (xy 43.60291 -350.54159)
			(xy 43.602415 -350.569064) (xy 43.594525 -350.623443) (xy 43.578907 -350.676126) (xy 43.576265 -350.681852)
			(xy 43.844675 -350.681852) (xy 43.844675 -350.627348) (xy 43.852432 -350.573398) (xy 43.867789 -350.521102)
			(xy 43.890431 -350.471523) (xy 43.919899 -350.425671) (xy 43.955593 -350.38448) (xy 43.996786 -350.348788)
			(xy 44.042639 -350.319322) (xy 44.092218 -350.296682) (xy 44.144516 -350.281329) (xy 44.198466 -350.273574)
			(xy 44.225718 -350.273112) (xy 44.250954 -350.273499) (xy 44.300988 -350.28012) (xy 44.349708 -350.293296)
			(xy 44.39626 -350.312796) (xy 44.41825 -350.325182) (xy 44.427902 -350.331024) (xy 44.45 -350.333056)
			(xy 44.544488 -350.299528) (xy 44.56049 -350.284034) (xy 44.564554 -350.27362) (xy 44.575283 -350.246857)
			(xy 44.603565 -350.196615) (xy 44.639089 -350.151205) (xy 44.681046 -350.111661) (xy 44.728479 -350.078885)
			(xy 44.780306 -350.053625) (xy 44.835345 -350.036457) (xy 44.892342 -350.027771) (xy 44.92117 -350.02724)
			(xy 44.948424 -350.027683) (xy 45.002378 -350.035437) (xy 45.05468 -350.050792) (xy 45.104263 -350.073435)
			(xy 45.150118 -350.102904) (xy 45.191313 -350.1386) (xy 45.227007 -350.179796) (xy 45.256474 -350.225653)
			(xy 45.279114 -350.275237) (xy 45.294466 -350.327539) (xy 45.302218 -350.381494) (xy 45.302678 -350.408748)
			(xy 45.302025 -350.440311) (xy 45.291635 -350.502577) (xy 45.271147 -350.562286) (xy 45.256704 -350.590358)
			(xy 45.251878 -350.599248) (xy 45.249846 -350.618806) (xy 45.2755 -350.706944) (xy 45.287946 -350.722438)
			(xy 45.296836 -350.727518) (xy 45.321915 -350.742104) (xy 45.3678 -350.777599) (xy 45.407778 -350.819635)
			(xy 45.440927 -350.867242) (xy 45.466482 -350.919322) (xy 45.483852 -350.974672) (xy 45.492637 -351.032014)
			(xy 45.493178 -351.06102) (xy 45.492692 -351.088271) (xy 45.484936 -351.142219) (xy 45.469581 -351.194514)
			(xy 45.446939 -351.244091) (xy 45.417473 -351.289941) (xy 45.381782 -351.331132) (xy 45.340591 -351.366823)
			(xy 45.294741 -351.396289) (xy 45.245164 -351.418931) (xy 45.192869 -351.434286) (xy 45.138921 -351.442042)
			(xy 45.084419 -351.442042) (xy 45.030471 -351.434286) (xy 44.978176 -351.418931) (xy 44.928599 -351.396289)
			(xy 44.882749 -351.366823) (xy 44.841558 -351.331132) (xy 44.805867 -351.289941) (xy 44.776401 -351.244091)
			(xy 44.753759 -351.194514) (xy 44.738404 -351.142219) (xy 44.730648 -351.088271) (xy 44.730162 -351.06102)
			(xy 44.73081 -351.029457) (xy 44.741203 -350.967191) (xy 44.761693 -350.907483) (xy 44.776136 -350.87941)
			(xy 44.780962 -350.87052) (xy 44.782994 -350.850962) (xy 44.75734 -350.762824) (xy 44.744894 -350.74733)
			(xy 44.736004 -350.74225) (xy 44.728638 -350.738186) (xy 44.718986 -350.732344) (xy 44.696888 -350.730312)
			(xy 44.6024 -350.76384) (xy 44.586398 -350.779334) (xy 44.582334 -350.789748) (xy 44.571652 -350.81653)
			(xy 44.54336 -350.86677) (xy 44.507827 -350.912178) (xy 44.465863 -350.951719) (xy 44.418424 -350.984492)
			(xy 44.366592 -351.009749) (xy 44.311548 -351.026915) (xy 44.254547 -351.035598) (xy 44.225718 -351.036128)
			(xy 44.198466 -351.035626) (xy 44.144516 -351.027871) (xy 44.092218 -351.012518) (xy 44.042639 -350.989878)
			(xy 43.996786 -350.960412) (xy 43.955593 -350.92472) (xy 43.919899 -350.883529) (xy 43.890431 -350.837677)
			(xy 43.867789 -350.788098) (xy 43.852432 -350.735802) (xy 43.844675 -350.681852) (xy 43.576265 -350.681852)
			(xy 43.555884 -350.726018) (xy 43.525934 -350.772088) (xy 43.508168 -350.79305) (xy 43.502072 -350.800162)
			(xy 43.495722 -350.81718) (xy 43.495722 -350.903032) (xy 43.502072 -350.92005) (xy 43.508168 -350.927162)
			(xy 43.525906 -350.948145) (xy 43.555832 -350.994222) (xy 43.578849 -351.044111) (xy 43.594481 -351.096783)
			(xy 43.602406 -351.151151) (xy 43.60291 -351.178622) (xy 43.602424 -351.205873) (xy 43.594668 -351.259821)
			(xy 43.579313 -351.312116) (xy 43.556671 -351.361693) (xy 43.527205 -351.407543) (xy 43.491514 -351.448734)
			(xy 43.450323 -351.484425) (xy 43.404473 -351.513891) (xy 43.354896 -351.536533) (xy 43.302601 -351.551888)
			(xy 43.248653 -351.559644) (xy 43.194151 -351.559644) (xy 43.140203 -351.551888) (xy 43.087908 -351.536533)
			(xy 43.038331 -351.513891) (xy 42.992481 -351.484425) (xy 42.95129 -351.448734) (xy 42.915599 -351.407543)
			(xy 42.886133 -351.361693) (xy 42.863491 -351.312116) (xy 42.848136 -351.259821) (xy 42.84038 -351.205873)
			(xy 42.839894 -351.178622) (xy 41.138348 -351.178622) (xy 41.138348 -351.752662) (xy 41.138781 -351.762731)
			(xy 41.146495 -351.781329) (xy 41.153334 -351.78873) (xy 41.750742 -352.386138) (xy 41.758129 -352.392994)
			(xy 41.776738 -352.400703) (xy 41.78681 -352.401124) (xy 45.97781 -352.401124) (xy 45.987882 -352.400724)
			(xy 46.006481 -352.392988) (xy 46.013878 -352.386138) (xy 46.26864 -352.131376) (xy 46.275332 -352.123894)
			(xy 46.282923 -352.105335) (xy 46.283372 -352.095308) (xy 46.283372 -350.082612) (xy 46.28303 -350.072564)
			(xy 46.275422 -350.053967) (xy 46.26864 -350.046544) (xy 45.469556 -349.247714) (xy 45.469302 -349.24746)
			(xy 45.406056 -349.183198) (xy 45.405802 -349.183198) (xy 45.38913 -349.165889) (xy 45.360859 -349.12703)
			(xy 45.339016 -349.084226) (xy 45.324141 -349.038531) (xy 45.316599 -348.991071) (xy 45.31614 -348.967044)
			(xy 45.31614 -347.060012) (xy 45.316546 -347.036014) (xy 45.324025 -346.988604) (xy 45.338847 -346.942955)
			(xy 45.360645 -346.900194) (xy 45.38888 -346.861382) (xy 45.405548 -346.844112) (xy 45.443648 -346.806012)
			(xy 45.44441 -346.805504) (xy 45.479716 -346.768928) (xy 45.483473 -346.765252) (xy 45.492178 -346.759364)
			(xy 45.496988 -346.757244) (xy 45.592746 -346.718382) (xy 45.597317 -346.71664) (xy 45.606906 -346.714713)
			(xy 45.611796 -346.714572) (xy 48.485552 -346.714572) (xy 48.509556 -346.715059) (xy 48.556967 -346.722599)
			(xy 48.602614 -346.737468) (xy 48.64537 -346.759301) (xy 48.684181 -346.787558) (xy 48.701452 -346.804234)
			(xy 48.892968 -346.99575) (xy 48.893476 -346.996512) (xy 48.930052 -347.031818) (xy 48.933726 -347.035577)
			(xy 48.939615 -347.044281) (xy 48.941736 -347.04909) (xy 48.980598 -347.144848) (xy 48.98234 -347.149419)
			(xy 48.984267 -347.159008) (xy 48.984408 -347.163898) (xy 48.984408 -348.247208) (xy 48.984797 -348.257251)
			(xy 48.992372 -348.275847) (xy 48.99914 -348.283276) (xy 49.091914 -348.375986) (xy 49.478946 -348.375986)
			(xy 49.479441 -348.348075) (xy 49.487577 -348.29285) (xy 49.503672 -348.2394) (xy 49.527384 -348.188865)
			(xy 49.558206 -348.142325) (xy 49.576482 -348.121224) (xy 49.582832 -348.114112) (xy 49.589436 -348.09684)
			(xy 49.589436 -348.009718) (xy 49.582832 -347.992446) (xy 49.576482 -347.985334) (xy 49.558196 -347.964241)
			(xy 49.52737 -347.917701) (xy 49.503657 -347.867164) (xy 49.487562 -347.813712) (xy 49.47943 -347.758484)
			(xy 49.478946 -347.730572) (xy 49.479432 -347.703321) (xy 49.487188 -347.649373) (xy 49.502543 -347.597078)
			(xy 49.525185 -347.547501) (xy 49.554651 -347.501651) (xy 49.590342 -347.46046) (xy 49.631533 -347.424769)
			(xy 49.677383 -347.395303) (xy 49.72696 -347.372661) (xy 49.779255 -347.357306) (xy 49.833203 -347.34955)
			(xy 49.887705 -347.34955) (xy 49.941653 -347.357306) (xy 49.993948 -347.372661) (xy 50.043525 -347.395303)
			(xy 50.089375 -347.424769) (xy 50.130566 -347.46046) (xy 50.166257 -347.501651) (xy 50.195723 -347.547501)
			(xy 50.218365 -347.597078) (xy 50.23372 -347.649373) (xy 50.241476 -347.703321) (xy 50.241962 -347.730572)
			(xy 50.241499 -347.758484) (xy 50.233355 -347.81371) (xy 50.217252 -347.867161) (xy 50.193533 -347.917695)
			(xy 50.162705 -347.964234) (xy 50.144426 -347.985334) (xy 50.138076 -347.992446) (xy 50.131472 -348.009718)
			(xy 50.131472 -348.09684) (xy 50.138076 -348.114112) (xy 50.144426 -348.121224) (xy 50.162694 -348.142332)
			(xy 50.193522 -348.188868) (xy 50.217239 -348.239401) (xy 50.233338 -348.29285) (xy 50.241475 -348.348075)
			(xy 50.241962 -348.375986) (xy 50.241476 -348.403237) (xy 50.23372 -348.457185) (xy 50.218365 -348.50948)
			(xy 50.195723 -348.559057) (xy 50.166257 -348.604907) (xy 50.130566 -348.646098) (xy 50.089375 -348.681789)
			(xy 50.043525 -348.711255) (xy 49.993948 -348.733897) (xy 49.941653 -348.749252) (xy 49.887705 -348.757008)
			(xy 49.833203 -348.757008) (xy 49.779255 -348.749252) (xy 49.72696 -348.733897) (xy 49.677383 -348.711255)
			(xy 49.631533 -348.681789) (xy 49.590342 -348.646098) (xy 49.554651 -348.604907) (xy 49.525185 -348.559057)
			(xy 49.502543 -348.50948) (xy 49.487188 -348.457185) (xy 49.479432 -348.403237) (xy 49.478946 -348.375986)
			(xy 49.091914 -348.375986) (xy 49.369472 -348.653354) (xy 49.36998 -348.654116) (xy 49.406556 -348.689422)
			(xy 49.410231 -348.69318) (xy 49.416119 -348.701885) (xy 49.41824 -348.706694) (xy 49.457102 -348.802452)
			(xy 49.458845 -348.807023) (xy 49.460771 -348.816612) (xy 49.460912 -348.821502) (xy 49.460912 -349.402908)
			(xy 49.461928 -349.408496) (xy 49.465453 -349.425037) (xy 49.469275 -349.458642) (xy 49.469548 -349.475552)
			(xy 49.469548 -349.607632) (xy 50.436778 -349.607632) (xy 50.440849 -349.55201) (xy 50.452975 -349.497573)
			(xy 50.472898 -349.445482) (xy 50.500194 -349.396847) (xy 50.53428 -349.352704) (xy 50.574429 -349.313995)
			(xy 50.619787 -349.281544) (xy 50.669387 -349.256043) (xy 50.722171 -349.238036) (xy 50.777014 -349.227906)
			(xy 50.832748 -349.225869) (xy 50.888185 -349.231969) (xy 50.942142 -349.246075) (xy 50.993471 -349.267887)
			(xy 51.041077 -349.296941) (xy 51.083945 -349.332616) (xy 51.121162 -349.374153) (xy 51.151935 -349.420666)
			(xy 51.175607 -349.471163) (xy 51.191675 -349.52457) (xy 51.199795 -349.579746) (xy 51.200304 -349.607632)
			(xy 51.199795 -349.635518) (xy 51.191675 -349.690694) (xy 51.175607 -349.744101) (xy 51.151935 -349.794598)
			(xy 51.121162 -349.841111) (xy 51.083945 -349.882648) (xy 51.041077 -349.918323) (xy 50.993471 -349.947377)
			(xy 50.942142 -349.969189) (xy 50.888185 -349.983295) (xy 50.832748 -349.989395) (xy 50.777014 -349.987358)
			(xy 50.722171 -349.977228) (xy 50.669387 -349.959221) (xy 50.619787 -349.93372) (xy 50.574429 -349.901269)
			(xy 50.53428 -349.86256) (xy 50.500194 -349.818417) (xy 50.472898 -349.769782) (xy 50.452975 -349.717691)
			(xy 50.440849 -349.663254) (xy 50.436778 -349.607632) (xy 49.469548 -349.607632) (xy 49.469548 -350.502982)
			(xy 49.857658 -350.502982) (xy 49.861729 -350.44736) (xy 49.873855 -350.392923) (xy 49.893778 -350.340832)
			(xy 49.921074 -350.292197) (xy 49.95516 -350.248054) (xy 49.995309 -350.209345) (xy 50.040667 -350.176894)
			(xy 50.090267 -350.151393) (xy 50.143051 -350.133386) (xy 50.197894 -350.123256) (xy 50.253628 -350.121219)
			(xy 50.309065 -350.127319) (xy 50.363022 -350.141425) (xy 50.414351 -350.163237) (xy 50.461957 -350.192291)
			(xy 50.504825 -350.227966) (xy 50.542042 -350.269503) (xy 50.572815 -350.316016) (xy 50.596487 -350.366513)
			(xy 50.612555 -350.41992) (xy 50.620675 -350.475096) (xy 50.621184 -350.502982) (xy 50.620675 -350.530868)
			(xy 50.612555 -350.586044) (xy 50.596487 -350.639451) (xy 50.572815 -350.689948) (xy 50.542042 -350.736461)
			(xy 50.504825 -350.777998) (xy 50.461957 -350.813673) (xy 50.414351 -350.842727) (xy 50.363022 -350.864539)
			(xy 50.309065 -350.878645) (xy 50.253628 -350.884745) (xy 50.197894 -350.882708) (xy 50.143051 -350.872578)
			(xy 50.090267 -350.854571) (xy 50.040667 -350.82907) (xy 49.995309 -350.796619) (xy 49.95516 -350.75791)
			(xy 49.921074 -350.713767) (xy 49.893778 -350.665132) (xy 49.873855 -350.613041) (xy 49.861729 -350.558604)
			(xy 49.857658 -350.502982) (xy 49.469548 -350.502982) (xy 49.469548 -351.178622) (xy 51.196494 -351.178622)
			(xy 51.196995 -351.151148) (xy 51.204883 -351.096769) (xy 51.2205 -351.044087) (xy 51.243522 -350.994194)
			(xy 51.27347 -350.948124) (xy 51.291236 -350.927162) (xy 51.297332 -350.92005) (xy 51.303682 -350.903032)
			(xy 51.303682 -350.81718) (xy 51.297332 -350.800162) (xy 51.291236 -350.79305) (xy 51.273458 -350.7721)
			(xy 51.243537 -350.726014) (xy 51.220528 -350.676116) (xy 51.204906 -350.623437) (xy 51.196992 -350.569063)
			(xy 51.196494 -350.54159) (xy 51.19698 -350.514339) (xy 51.204736 -350.460391) (xy 51.220091 -350.408096)
			(xy 51.242733 -350.358519) (xy 51.272199 -350.312669) (xy 51.30789 -350.271478) (xy 51.349081 -350.235787)
			(xy 51.394931 -350.206321) (xy 51.444508 -350.183679) (xy 51.496803 -350.168324) (xy 51.550751 -350.160568)
			(xy 51.605253 -350.160568) (xy 51.659201 -350.168324) (xy 51.711496 -350.183679) (xy 51.761073 -350.206321)
			(xy 51.806923 -350.235787) (xy 51.848114 -350.271478) (xy 51.883805 -350.312669) (xy 51.913271 -350.358519)
			(xy 51.935913 -350.408096) (xy 51.951268 -350.460391) (xy 51.959024 -350.514339) (xy 51.95951 -350.54159)
			(xy 51.959015 -350.569064) (xy 51.951125 -350.623443) (xy 51.935507 -350.676126) (xy 51.932865 -350.681852)
			(xy 52.201275 -350.681852) (xy 52.201275 -350.627348) (xy 52.209032 -350.573398) (xy 52.224389 -350.521102)
			(xy 52.247031 -350.471523) (xy 52.276499 -350.425671) (xy 52.312193 -350.38448) (xy 52.353386 -350.348788)
			(xy 52.399239 -350.319322) (xy 52.448818 -350.296682) (xy 52.501116 -350.281329) (xy 52.555066 -350.273574)
			(xy 52.582318 -350.273112) (xy 52.607554 -350.273499) (xy 52.657588 -350.28012) (xy 52.706308 -350.293296)
			(xy 52.75286 -350.312796) (xy 52.77485 -350.325182) (xy 52.784502 -350.331024) (xy 52.8066 -350.333056)
			(xy 52.901088 -350.299528) (xy 52.91709 -350.284034) (xy 52.921154 -350.27362) (xy 52.931883 -350.246857)
			(xy 52.960165 -350.196615) (xy 52.995689 -350.151205) (xy 53.037646 -350.111661) (xy 53.085079 -350.078885)
			(xy 53.136906 -350.053625) (xy 53.191945 -350.036457) (xy 53.248942 -350.027771) (xy 53.27777 -350.02724)
			(xy 53.305024 -350.027683) (xy 53.358978 -350.035437) (xy 53.41128 -350.050792) (xy 53.460863 -350.073435)
			(xy 53.506718 -350.102904) (xy 53.547913 -350.1386) (xy 53.583607 -350.179796) (xy 53.613074 -350.225653)
			(xy 53.635714 -350.275237) (xy 53.651066 -350.327539) (xy 53.658818 -350.381494) (xy 53.659278 -350.408748)
			(xy 53.658625 -350.440311) (xy 53.648235 -350.502577) (xy 53.627747 -350.562286) (xy 53.613304 -350.590358)
			(xy 53.608478 -350.599248) (xy 53.606446 -350.618806) (xy 53.6321 -350.706944) (xy 53.644546 -350.722438)
			(xy 53.653436 -350.727518) (xy 53.678515 -350.742104) (xy 53.7244 -350.777599) (xy 53.764378 -350.819635)
			(xy 53.797527 -350.867242) (xy 53.823082 -350.919322) (xy 53.840452 -350.974672) (xy 53.849237 -351.032014)
			(xy 53.849778 -351.06102) (xy 53.849292 -351.088271) (xy 53.841536 -351.142219) (xy 53.826181 -351.194514)
			(xy 53.803539 -351.244091) (xy 53.774073 -351.289941) (xy 53.738382 -351.331132) (xy 53.697191 -351.366823)
			(xy 53.651341 -351.396289) (xy 53.601764 -351.418931) (xy 53.549469 -351.434286) (xy 53.495521 -351.442042)
			(xy 53.441019 -351.442042) (xy 53.387071 -351.434286) (xy 53.334776 -351.418931) (xy 53.285199 -351.396289)
			(xy 53.239349 -351.366823) (xy 53.198158 -351.331132) (xy 53.162467 -351.289941) (xy 53.133001 -351.244091)
			(xy 53.110359 -351.194514) (xy 53.095004 -351.142219) (xy 53.087248 -351.088271) (xy 53.086762 -351.06102)
			(xy 53.08741 -351.029457) (xy 53.097803 -350.967191) (xy 53.118293 -350.907483) (xy 53.132736 -350.87941)
			(xy 53.137562 -350.87052) (xy 53.139594 -350.850962) (xy 53.11394 -350.762824) (xy 53.101494 -350.74733)
			(xy 53.092604 -350.74225) (xy 53.085238 -350.738186) (xy 53.075586 -350.732344) (xy 53.053488 -350.730312)
			(xy 52.959 -350.76384) (xy 52.942998 -350.779334) (xy 52.938934 -350.789748) (xy 52.928252 -350.81653)
			(xy 52.89996 -350.86677) (xy 52.864427 -350.912178) (xy 52.822463 -350.951719) (xy 52.775024 -350.984492)
			(xy 52.723192 -351.009749) (xy 52.668148 -351.026915) (xy 52.611147 -351.035598) (xy 52.582318 -351.036128)
			(xy 52.555066 -351.035626) (xy 52.501116 -351.027871) (xy 52.448818 -351.012518) (xy 52.399239 -350.989878)
			(xy 52.353386 -350.960412) (xy 52.312193 -350.92472) (xy 52.276499 -350.883529) (xy 52.247031 -350.837677)
			(xy 52.224389 -350.788098) (xy 52.209032 -350.735802) (xy 52.201275 -350.681852) (xy 51.932865 -350.681852)
			(xy 51.912484 -350.726018) (xy 51.882534 -350.772088) (xy 51.864768 -350.79305) (xy 51.858672 -350.800162)
			(xy 51.852322 -350.81718) (xy 51.852322 -350.903032) (xy 51.858672 -350.92005) (xy 51.864768 -350.927162)
			(xy 51.882506 -350.948145) (xy 51.912432 -350.994222) (xy 51.935449 -351.044111) (xy 51.951081 -351.096783)
			(xy 51.959006 -351.151151) (xy 51.95951 -351.178622) (xy 51.959024 -351.205873) (xy 51.951268 -351.259821)
			(xy 51.935913 -351.312116) (xy 51.913271 -351.361693) (xy 51.883805 -351.407543) (xy 51.848114 -351.448734)
			(xy 51.806923 -351.484425) (xy 51.761073 -351.513891) (xy 51.711496 -351.536533) (xy 51.659201 -351.551888)
			(xy 51.605253 -351.559644) (xy 51.550751 -351.559644) (xy 51.496803 -351.551888) (xy 51.444508 -351.536533)
			(xy 51.394931 -351.513891) (xy 51.349081 -351.484425) (xy 51.30789 -351.448734) (xy 51.272199 -351.407543)
			(xy 51.242733 -351.361693) (xy 51.220091 -351.312116) (xy 51.204736 -351.259821) (xy 51.19698 -351.205873)
			(xy 51.196494 -351.178622) (xy 49.469548 -351.178622) (xy 49.469548 -351.807018) (xy 49.469951 -351.81709)
			(xy 49.477686 -351.835688) (xy 49.484534 -351.843086) (xy 50.041048 -352.3996) (xy 50.048515 -352.406311)
			(xy 50.067086 -352.413889) (xy 50.077116 -352.414332) (xy 54.455568 -352.414332) (xy 54.465617 -352.41399)
			(xy 54.484213 -352.406384) (xy 54.491636 -352.3996) (xy 54.72684 -352.164396) (xy 54.733523 -352.156907)
			(xy 54.74112 -352.138354) (xy 54.741572 -352.128328) (xy 54.741572 -350.18345) (xy 54.74121 -350.173404)
			(xy 54.733616 -350.154808) (xy 54.72684 -350.147382) (xy 53.763926 -349.184722) (xy 53.763418 -349.18396)
			(xy 53.726842 -349.148654) (xy 53.723162 -349.1449) (xy 53.717277 -349.136193) (xy 53.715158 -349.131382)
			(xy 53.676296 -349.035624) (xy 53.674582 -349.031052) (xy 53.672792 -349.021456) (xy 53.67274 -349.016574)
			(xy 53.67274 -347.044518) (xy 53.673208 -347.020546) (xy 53.680706 -346.973191) (xy 53.695519 -346.927592)
			(xy 53.717284 -346.884872) (xy 53.745463 -346.846082) (xy 53.779364 -346.812179) (xy 53.818151 -346.783996)
			(xy 53.86087 -346.762229) (xy 53.906467 -346.747412) (xy 53.953822 -346.73991) (xy 53.977794 -346.739464)
			(xy 57.00141 -346.739464) (xy 57.025407 -346.739912) (xy 57.072815 -346.74738) (xy 57.118464 -346.762191)
			(xy 57.161225 -346.78398) (xy 57.200039 -346.812207) (xy 57.21731 -346.828872) (xy 57.371488 -346.98305)
			(xy 57.371996 -346.983812) (xy 57.408572 -347.019118) (xy 57.412248 -347.022875) (xy 57.418136 -347.03158)
			(xy 57.420256 -347.03639) (xy 57.459118 -347.132148) (xy 57.460861 -347.136719) (xy 57.462787 -347.146308)
			(xy 57.462928 -347.151198) (xy 57.462928 -348.375986) (xy 57.810146 -348.375986) (xy 57.810641 -348.348075)
			(xy 57.818777 -348.29285) (xy 57.834872 -348.2394) (xy 57.858584 -348.188865) (xy 57.889406 -348.142325)
			(xy 57.907682 -348.121224) (xy 57.914032 -348.114112) (xy 57.920636 -348.09684) (xy 57.920636 -348.009718)
			(xy 57.914032 -347.992446) (xy 57.907682 -347.985334) (xy 57.889396 -347.964241) (xy 57.85857 -347.917701)
			(xy 57.834857 -347.867164) (xy 57.818762 -347.813712) (xy 57.81063 -347.758484) (xy 57.810146 -347.730572)
			(xy 57.810632 -347.703321) (xy 57.818388 -347.649373) (xy 57.833743 -347.597078) (xy 57.856385 -347.547501)
			(xy 57.885851 -347.501651) (xy 57.921542 -347.46046) (xy 57.962733 -347.424769) (xy 58.008583 -347.395303)
			(xy 58.05816 -347.372661) (xy 58.110455 -347.357306) (xy 58.164403 -347.34955) (xy 58.218905 -347.34955)
			(xy 58.272853 -347.357306) (xy 58.325148 -347.372661) (xy 58.374725 -347.395303) (xy 58.420575 -347.424769)
			(xy 58.461766 -347.46046) (xy 58.497457 -347.501651) (xy 58.526923 -347.547501) (xy 58.549565 -347.597078)
			(xy 58.56492 -347.649373) (xy 58.572676 -347.703321) (xy 58.573162 -347.730572) (xy 58.572699 -347.758484)
			(xy 58.564555 -347.81371) (xy 58.548452 -347.867161) (xy 58.524733 -347.917695) (xy 58.493905 -347.964234)
			(xy 58.475626 -347.985334) (xy 58.469276 -347.992446) (xy 58.462672 -348.009718) (xy 58.462672 -348.09684)
			(xy 58.469276 -348.114112) (xy 58.475626 -348.121224) (xy 58.493894 -348.142332) (xy 58.524722 -348.188868)
			(xy 58.548439 -348.239401) (xy 58.564538 -348.29285) (xy 58.572675 -348.348075) (xy 58.573162 -348.375986)
			(xy 58.572676 -348.403237) (xy 58.56492 -348.457185) (xy 58.549565 -348.50948) (xy 58.526923 -348.559057)
			(xy 58.497457 -348.604907) (xy 58.461766 -348.646098) (xy 58.420575 -348.681789) (xy 58.374725 -348.711255)
			(xy 58.325148 -348.733897) (xy 58.272853 -348.749252) (xy 58.218905 -348.757008) (xy 58.164403 -348.757008)
			(xy 58.110455 -348.749252) (xy 58.05816 -348.733897) (xy 58.008583 -348.711255) (xy 57.962733 -348.681789)
			(xy 57.921542 -348.646098) (xy 57.885851 -348.604907) (xy 57.856385 -348.559057) (xy 57.833743 -348.50948)
			(xy 57.818388 -348.457185) (xy 57.810632 -348.403237) (xy 57.810146 -348.375986) (xy 57.462928 -348.375986)
			(xy 57.462928 -348.394528) (xy 57.463301 -348.404573) (xy 57.470887 -348.423169) (xy 57.47766 -348.430596)
			(xy 57.734962 -348.687644) (xy 57.73547 -348.688406) (xy 57.772046 -348.723712) (xy 57.775718 -348.727473)
			(xy 57.781608 -348.736175) (xy 57.78373 -348.740984) (xy 57.822592 -348.836742) (xy 57.824296 -348.841317)
			(xy 57.826093 -348.850911) (xy 57.826148 -348.855792) (xy 57.826148 -349.001842) (xy 62.002416 -349.001842)
			(xy 62.002416 -347.083888) (xy 62.002848 -347.05989) (xy 62.010317 -347.012481) (xy 62.025132 -346.966831)
			(xy 62.046925 -346.92407) (xy 62.075156 -346.885258) (xy 62.091824 -346.867988) (xy 62.126622 -346.83319)
			(xy 62.143905 -346.816528) (xy 62.182718 -346.788278) (xy 62.225471 -346.766447) (xy 62.271113 -346.751573)
			(xy 62.31852 -346.74402) (xy 62.342522 -346.743528) (xy 67.12585 -346.743528) (xy 67.149854 -346.744)
			(xy 67.197268 -346.751541) (xy 67.242915 -346.766413) (xy 67.285671 -346.788249) (xy 67.324481 -346.816511)
			(xy 67.34175 -346.83319) (xy 67.34175 -346.833444) (xy 68.401184 -347.892878) (xy 68.408598 -347.899701)
			(xy 68.427186 -347.907431) (xy 68.437252 -347.907864) (xy 71.578216 -347.907864) (xy 71.588287 -347.907456)
			(xy 71.606886 -347.899724) (xy 71.614284 -347.892878) (xy 73.335642 -346.17152) (xy 73.342472 -346.164112)
			(xy 73.350196 -346.145519) (xy 73.350628 -346.135452) (xy 73.350628 -343.52103) (xy 73.350206 -343.51096)
			(xy 73.342485 -343.492361) (xy 73.335642 -343.484962) (xy 72.191118 -342.340692) (xy 72.174468 -342.323397)
			(xy 72.146216 -342.284589) (xy 72.124382 -342.241838) (xy 72.109505 -342.196198) (xy 72.10195 -342.148793)
			(xy 72.101456 -342.124792) (xy 72.101456 -341.313516) (xy 72.101116 -341.303467) (xy 72.093507 -341.284871)
			(xy 72.086724 -341.277448) (xy 71.640954 -340.831932) (xy 71.624311 -340.81463) (xy 71.596051 -340.775825)
			(xy 71.57421 -340.733077) (xy 71.559326 -340.687439) (xy 71.551764 -340.640034) (xy 71.551292 -340.616032)
			(xy 71.551292 -338.357972) (xy 71.550914 -338.347928) (xy 71.543331 -338.329332) (xy 71.53656 -338.321904)
			(xy 70.651624 -337.437222) (xy 70.651624 -337.436714) (xy 70.626224 -337.411314) (xy 70.609596 -337.394014)
			(xy 70.581409 -337.355185) (xy 70.559635 -337.312428) (xy 70.544808 -337.266794) (xy 70.537294 -337.219405)
			(xy 70.536816 -337.195414) (xy 70.536816 -335.332832) (xy 70.537213 -335.308833) (xy 70.54469 -335.261422)
			(xy 70.559513 -335.215772) (xy 70.581314 -335.173011) (xy 70.609553 -335.134201) (xy 70.626224 -335.116932)
			(xy 70.677278 -335.065878) (xy 70.694579 -335.049235) (xy 70.733387 -335.020983) (xy 70.776136 -334.999149)
			(xy 70.821774 -334.98427) (xy 70.869177 -334.976712) (xy 70.893178 -334.976216) (xy 73.870312 -334.976216)
			(xy 73.894318 -334.976653) (xy 73.941733 -334.984203) (xy 73.98738 -334.999083) (xy 74.030136 -335.020927)
			(xy 74.068943 -335.049196) (xy 74.086212 -335.065878) (xy 74.214228 -335.193894) (xy 74.214736 -335.194656)
			(xy 74.251312 -335.229962) (xy 74.25499 -335.233718) (xy 74.260877 -335.242424) (xy 74.262996 -335.247234)
			(xy 74.301858 -335.342992) (xy 74.30361 -335.34756) (xy 74.305531 -335.357152) (xy 74.305668 -335.362042)
			(xy 74.305668 -336.644488) (xy 74.305777 -336.64779) (xy 74.70013 -336.64779) (xy 74.700632 -336.61988)
			(xy 74.708766 -336.564655) (xy 74.724861 -336.511205) (xy 74.748571 -336.46067) (xy 74.779391 -336.414129)
			(xy 74.797666 -336.393028) (xy 74.804016 -336.385916) (xy 74.81062 -336.368644) (xy 74.81062 -336.281522)
			(xy 74.804016 -336.26425) (xy 74.797666 -336.257138) (xy 74.779379 -336.236046) (xy 74.748554 -336.189505)
			(xy 74.724841 -336.138968) (xy 74.708747 -336.085516) (xy 74.700614 -336.030288) (xy 74.70013 -336.002376)
			(xy 74.700616 -335.975125) (xy 74.708372 -335.921177) (xy 74.723727 -335.868882) (xy 74.746369 -335.819305)
			(xy 74.775835 -335.773455) (xy 74.811526 -335.732264) (xy 74.852717 -335.696573) (xy 74.898567 -335.667107)
			(xy 74.948144 -335.644465) (xy 75.000439 -335.62911) (xy 75.054387 -335.621354) (xy 75.108889 -335.621354)
			(xy 75.162837 -335.62911) (xy 75.215132 -335.644465) (xy 75.264709 -335.667107) (xy 75.310559 -335.696573)
			(xy 75.35175 -335.732264) (xy 75.387441 -335.773455) (xy 75.416907 -335.819305) (xy 75.439549 -335.868882)
			(xy 75.454904 -335.921177) (xy 75.46266 -335.975125) (xy 75.463146 -336.002376) (xy 75.46263 -336.030286)
			(xy 75.4545 -336.08551) (xy 75.438409 -336.13896) (xy 75.414702 -336.189496) (xy 75.383884 -336.236037)
			(xy 75.36561 -336.257138) (xy 75.35926 -336.26425) (xy 75.352656 -336.281522) (xy 75.352656 -336.368644)
			(xy 75.35926 -336.385916) (xy 75.36561 -336.393028) (xy 75.383877 -336.414137) (xy 75.414706 -336.460673)
			(xy 75.438423 -336.511205) (xy 75.454522 -336.564654) (xy 75.462659 -336.619879) (xy 75.463146 -336.64779)
			(xy 75.46266 -336.675041) (xy 75.454904 -336.728989) (xy 75.439549 -336.781284) (xy 75.416907 -336.830861)
			(xy 75.387441 -336.876711) (xy 75.35175 -336.917902) (xy 75.310559 -336.953593) (xy 75.264709 -336.983059)
			(xy 75.215132 -337.005701) (xy 75.162837 -337.021056) (xy 75.108889 -337.028812) (xy 75.054387 -337.028812)
			(xy 75.000439 -337.021056) (xy 74.948144 -337.005701) (xy 74.898567 -336.983059) (xy 74.852717 -336.953593)
			(xy 74.811526 -336.917902) (xy 74.775835 -336.876711) (xy 74.746369 -336.830861) (xy 74.723727 -336.781284)
			(xy 74.708372 -336.728989) (xy 74.700616 -336.675041) (xy 74.70013 -336.64779) (xy 74.305777 -336.64779)
			(xy 74.305999 -336.654538) (xy 74.313613 -336.673134) (xy 74.3204 -336.680556) (xy 74.707496 -337.067652)
			(xy 74.714172 -337.075065) (xy 74.721748 -337.093501) (xy 74.722228 -337.103466) (xy 74.722228 -337.879436)
			(xy 75.657962 -337.879436) (xy 75.662033 -337.823814) (xy 75.674159 -337.769377) (xy 75.694082 -337.717286)
			(xy 75.721378 -337.668651) (xy 75.755464 -337.624508) (xy 75.795613 -337.585799) (xy 75.840971 -337.553348)
			(xy 75.890571 -337.527847) (xy 75.943355 -337.50984) (xy 75.998198 -337.49971) (xy 76.053932 -337.497673)
			(xy 76.109369 -337.503773) (xy 76.163326 -337.517879) (xy 76.214655 -337.539691) (xy 76.262261 -337.568745)
			(xy 76.305129 -337.60442) (xy 76.342346 -337.645957) (xy 76.373119 -337.69247) (xy 76.396791 -337.742967)
			(xy 76.412859 -337.796374) (xy 76.420979 -337.85155) (xy 76.421488 -337.879436) (xy 76.420979 -337.907322)
			(xy 76.412859 -337.962498) (xy 76.396791 -338.015905) (xy 76.373119 -338.066402) (xy 76.342346 -338.112915)
			(xy 76.305129 -338.154452) (xy 76.262261 -338.190127) (xy 76.214655 -338.219181) (xy 76.163326 -338.240993)
			(xy 76.109369 -338.255099) (xy 76.053932 -338.261199) (xy 75.998198 -338.259162) (xy 75.943355 -338.249032)
			(xy 75.890571 -338.231025) (xy 75.840971 -338.205524) (xy 75.795613 -338.173073) (xy 75.755464 -338.134364)
			(xy 75.721378 -338.090221) (xy 75.694082 -338.041586) (xy 75.674159 -337.989495) (xy 75.662033 -337.935058)
			(xy 75.657962 -337.879436) (xy 74.722228 -337.879436) (xy 74.722228 -338.774786) (xy 75.078842 -338.774786)
			(xy 75.082913 -338.719164) (xy 75.095039 -338.664727) (xy 75.114962 -338.612636) (xy 75.142258 -338.564001)
			(xy 75.176344 -338.519858) (xy 75.216493 -338.481149) (xy 75.261851 -338.448698) (xy 75.311451 -338.423197)
			(xy 75.364235 -338.40519) (xy 75.419078 -338.39506) (xy 75.474812 -338.393023) (xy 75.530249 -338.399123)
			(xy 75.584206 -338.413229) (xy 75.635535 -338.435041) (xy 75.683141 -338.464095) (xy 75.726009 -338.49977)
			(xy 75.763226 -338.541307) (xy 75.793999 -338.58782) (xy 75.817671 -338.638317) (xy 75.833739 -338.691724)
			(xy 75.841859 -338.7469) (xy 75.842368 -338.774786) (xy 75.841859 -338.802672) (xy 75.833739 -338.857848)
			(xy 75.817671 -338.911255) (xy 75.793999 -338.961752) (xy 75.763226 -339.008265) (xy 75.726009 -339.049802)
			(xy 75.683141 -339.085477) (xy 75.635535 -339.114531) (xy 75.584206 -339.136343) (xy 75.530249 -339.150449)
			(xy 75.474812 -339.156549) (xy 75.419078 -339.154512) (xy 75.364235 -339.144382) (xy 75.311451 -339.126375)
			(xy 75.261851 -339.100874) (xy 75.216493 -339.068423) (xy 75.176344 -339.029714) (xy 75.142258 -338.985571)
			(xy 75.114962 -338.936936) (xy 75.095039 -338.884845) (xy 75.082913 -338.830408) (xy 75.078842 -338.774786)
			(xy 74.722228 -338.774786) (xy 74.722228 -339.450426) (xy 76.417678 -339.450426) (xy 76.418185 -339.422952)
			(xy 76.426073 -339.368574) (xy 76.441688 -339.315892) (xy 76.464708 -339.265999) (xy 76.494655 -339.219929)
			(xy 76.51242 -339.198966) (xy 76.518516 -339.191854) (xy 76.524866 -339.174836) (xy 76.524866 -339.088984)
			(xy 76.518516 -339.071966) (xy 76.51242 -339.064854) (xy 76.494641 -339.043904) (xy 76.464721 -338.997818)
			(xy 76.441712 -338.94792) (xy 76.42609 -338.895241) (xy 76.418176 -338.840867) (xy 76.417678 -338.813394)
			(xy 76.418164 -338.786143) (xy 76.42592 -338.732195) (xy 76.441275 -338.6799) (xy 76.463917 -338.630323)
			(xy 76.493383 -338.584473) (xy 76.529074 -338.543282) (xy 76.570265 -338.507591) (xy 76.616115 -338.478125)
			(xy 76.665692 -338.455483) (xy 76.717987 -338.440128) (xy 76.771935 -338.432372) (xy 76.826437 -338.432372)
			(xy 76.880385 -338.440128) (xy 76.93268 -338.455483) (xy 76.982257 -338.478125) (xy 77.028107 -338.507591)
			(xy 77.069298 -338.543282) (xy 77.104989 -338.584473) (xy 77.134455 -338.630323) (xy 77.157097 -338.6799)
			(xy 77.172452 -338.732195) (xy 77.180208 -338.786143) (xy 77.180694 -338.813394) (xy 77.180206 -338.840869)
			(xy 77.172314 -338.895248) (xy 77.156695 -338.947931) (xy 77.154055 -338.953651) (xy 77.422479 -338.953651)
			(xy 77.422479 -338.899149) (xy 77.430236 -338.845201) (xy 77.445591 -338.792906) (xy 77.468232 -338.743329)
			(xy 77.497699 -338.697479) (xy 77.53339 -338.656289) (xy 77.57458 -338.620597) (xy 77.620431 -338.591131)
			(xy 77.670008 -338.56849) (xy 77.722303 -338.553135) (xy 77.776251 -338.545379) (xy 77.803502 -338.544916)
			(xy 77.828737 -338.54531) (xy 77.878772 -338.551929) (xy 77.927492 -338.565102) (xy 77.974044 -338.5846)
			(xy 77.996034 -338.596986) (xy 78.005686 -338.602828) (xy 78.027784 -338.60486) (xy 78.122272 -338.571332)
			(xy 78.138274 -338.555838) (xy 78.142338 -338.545424) (xy 78.153082 -338.518668) (xy 78.181362 -338.468427)
			(xy 78.216884 -338.423016) (xy 78.258839 -338.383472) (xy 78.30627 -338.350695) (xy 78.358094 -338.325434)
			(xy 78.413132 -338.308264) (xy 78.470127 -338.299576) (xy 78.498954 -338.299044) (xy 78.526202 -338.299621)
			(xy 78.580144 -338.30737) (xy 78.632434 -338.322717) (xy 78.682008 -338.345349) (xy 78.727856 -338.374806)
			(xy 78.769045 -338.410488) (xy 78.804738 -338.451669) (xy 78.834206 -338.49751) (xy 78.85685 -338.547078)
			(xy 78.87221 -338.599364) (xy 78.879972 -338.653304) (xy 78.880462 -338.680552) (xy 78.879812 -338.712115)
			(xy 78.869421 -338.774381) (xy 78.848932 -338.83409) (xy 78.834488 -338.862162) (xy 78.829662 -338.871052)
			(xy 78.82763 -338.89061) (xy 78.853284 -338.978748) (xy 78.86573 -338.994242) (xy 78.87462 -338.999322)
			(xy 78.89972 -339.013872) (xy 78.945601 -339.049377) (xy 78.985575 -339.091421) (xy 79.01872 -339.139034)
			(xy 79.044271 -339.191118) (xy 79.061638 -339.246472) (xy 79.070422 -339.303817) (xy 79.070962 -339.332824)
			(xy 79.070476 -339.360075) (xy 79.06272 -339.414023) (xy 79.047365 -339.466318) (xy 79.024723 -339.515895)
			(xy 78.995257 -339.561745) (xy 78.959566 -339.602936) (xy 78.918375 -339.638627) (xy 78.872525 -339.668093)
			(xy 78.822948 -339.690735) (xy 78.770653 -339.70609) (xy 78.716705 -339.713846) (xy 78.662203 -339.713846)
			(xy 78.608255 -339.70609) (xy 78.55596 -339.690735) (xy 78.506383 -339.668093) (xy 78.460533 -339.638627)
			(xy 78.419342 -339.602936) (xy 78.383651 -339.561745) (xy 78.354185 -339.515895) (xy 78.331543 -339.466318)
			(xy 78.316188 -339.414023) (xy 78.308432 -339.360075) (xy 78.307946 -339.332824) (xy 78.308586 -339.30126)
			(xy 78.31898 -339.238994) (xy 78.339474 -339.179286) (xy 78.35392 -339.151214) (xy 78.358746 -339.142324)
			(xy 78.360778 -339.122766) (xy 78.335124 -339.034628) (xy 78.322678 -339.019134) (xy 78.313788 -339.014054)
			(xy 78.306422 -339.00999) (xy 78.29677 -339.004148) (xy 78.274672 -339.002116) (xy 78.180184 -339.035644)
			(xy 78.164182 -339.051138) (xy 78.160118 -339.061552) (xy 78.149451 -339.088341) (xy 78.121157 -339.138581)
			(xy 78.085622 -339.183989) (xy 78.043656 -339.22353) (xy 77.996215 -339.256302) (xy 77.94438 -339.281558)
			(xy 77.889334 -339.298722) (xy 77.832332 -339.307403) (xy 77.803502 -339.307932) (xy 77.776251 -339.307421)
			(xy 77.722303 -339.299665) (xy 77.670008 -339.28431) (xy 77.620431 -339.261669) (xy 77.57458 -339.232203)
			(xy 77.53339 -339.196511) (xy 77.497699 -339.155321) (xy 77.468232 -339.109471) (xy 77.445591 -339.059894)
			(xy 77.430236 -339.007599) (xy 77.422479 -338.953651) (xy 77.154055 -338.953651) (xy 77.133671 -338.997823)
			(xy 77.103719 -339.043892) (xy 77.085952 -339.064854) (xy 77.079856 -339.071966) (xy 77.073506 -339.088984)
			(xy 77.073506 -339.174836) (xy 77.079856 -339.191854) (xy 77.085952 -339.198966) (xy 77.103689 -339.21995)
			(xy 77.133616 -339.266026) (xy 77.156633 -339.315915) (xy 77.172266 -339.368587) (xy 77.18019 -339.422955)
			(xy 77.180694 -339.450426) (xy 77.180208 -339.477677) (xy 77.172452 -339.531625) (xy 77.157097 -339.58392)
			(xy 77.134455 -339.633497) (xy 77.104989 -339.679347) (xy 77.069298 -339.720538) (xy 77.028107 -339.756229)
			(xy 76.982257 -339.785695) (xy 76.93268 -339.808337) (xy 76.880385 -339.823692) (xy 76.826437 -339.831448)
			(xy 76.771935 -339.831448) (xy 76.717987 -339.823692) (xy 76.665692 -339.808337) (xy 76.616115 -339.785695)
			(xy 76.570265 -339.756229) (xy 76.529074 -339.720538) (xy 76.493383 -339.679347) (xy 76.463917 -339.633497)
			(xy 76.441275 -339.58392) (xy 76.42592 -339.531625) (xy 76.418164 -339.477677) (xy 76.417678 -339.450426)
			(xy 74.722228 -339.450426) (xy 74.722228 -339.956902) (xy 74.722645 -339.966972) (xy 74.730371 -339.98557)
			(xy 74.737214 -339.99297) (xy 75.405742 -340.661498) (xy 75.413134 -340.668349) (xy 75.431739 -340.676062)
			(xy 75.44181 -340.676484) (xy 79.616808 -340.676484) (xy 79.626878 -340.676067) (xy 79.645476 -340.668341)
			(xy 79.652876 -340.661498) (xy 79.77124 -340.543134) (xy 79.77795 -340.535666) (xy 79.785531 -340.517097)
			(xy 79.785972 -340.507066) (xy 79.785972 -338.251292) (xy 79.785588 -338.241248) (xy 79.778009 -338.222652)
			(xy 79.77124 -338.215224) (xy 79.034386 -337.47837) (xy 79.026988 -337.471527) (xy 79.008387 -337.46381)
			(xy 78.998318 -337.463384) (xy 78.9432 -337.463384) (xy 78.933153 -337.463043) (xy 78.914565 -337.455428)
			(xy 78.900363 -337.441222) (xy 78.892754 -337.422631) (xy 78.8924 -337.412584) (xy 78.8924 -335.18856)
			(xy 78.898496 -335.182464) (xy 78.898496 -335.18221) (xy 78.99781 -335.082642) (xy 79.015091 -335.065977)
			(xy 79.053902 -335.03772) (xy 79.096655 -335.015884) (xy 79.142298 -335.001004) (xy 79.189707 -334.993449)
			(xy 79.21371 -334.99298) (xy 82.285332 -334.99298) (xy 82.309335 -334.993477) (xy 82.356747 -335.001014)
			(xy 82.402394 -335.015881) (xy 82.44515 -335.037711) (xy 82.483961 -335.065966) (xy 82.501232 -335.082642)
			(xy 82.565748 -335.147158) (xy 82.566256 -335.14792) (xy 82.602832 -335.183226) (xy 82.606505 -335.186986)
			(xy 82.612395 -335.195689) (xy 82.614516 -335.200498) (xy 82.653378 -335.296256) (xy 82.655121 -335.300827)
			(xy 82.657047 -335.310416) (xy 82.657188 -335.315306) (xy 82.657188 -336.601308) (xy 82.657556 -336.611354)
			(xy 82.665144 -336.629951) (xy 82.668211 -336.633312) (xy 83.057746 -336.633312) (xy 83.058257 -336.605402)
			(xy 83.066389 -336.550177) (xy 83.08248 -336.496727) (xy 83.106189 -336.446192) (xy 83.137008 -336.399651)
			(xy 83.155282 -336.37855) (xy 83.161632 -336.371438) (xy 83.168236 -336.354166) (xy 83.168236 -336.267044)
			(xy 83.161632 -336.249772) (xy 83.155282 -336.24266) (xy 83.137008 -336.221557) (xy 83.106181 -336.175019)
			(xy 83.082465 -336.124486) (xy 83.066367 -336.071035) (xy 83.058232 -336.015809) (xy 83.057746 -335.987898)
			(xy 83.058232 -335.960647) (xy 83.065988 -335.906699) (xy 83.081343 -335.854404) (xy 83.103985 -335.804827)
			(xy 83.133451 -335.758977) (xy 83.169142 -335.717786) (xy 83.210333 -335.682095) (xy 83.256183 -335.652629)
			(xy 83.30576 -335.629987) (xy 83.358055 -335.614632) (xy 83.412003 -335.606876) (xy 83.466505 -335.606876)
			(xy 83.520453 -335.614632) (xy 83.572748 -335.629987) (xy 83.622325 -335.652629) (xy 83.668175 -335.682095)
			(xy 83.709366 -335.717786) (xy 83.745057 -335.758977) (xy 83.774523 -335.804827) (xy 83.797165 -335.854404)
			(xy 83.81252 -335.906699) (xy 83.820276 -335.960647) (xy 83.820762 -335.987898) (xy 83.820255 -336.015808)
			(xy 83.812122 -336.071033) (xy 83.796029 -336.124483) (xy 83.77232 -336.175018) (xy 83.7415 -336.221559)
			(xy 83.723226 -336.24266) (xy 83.716876 -336.249772) (xy 83.710272 -336.267044) (xy 83.710272 -336.354166)
			(xy 83.716876 -336.371438) (xy 83.723226 -336.37855) (xy 83.741506 -336.399648) (xy 83.772332 -336.446187)
			(xy 83.796047 -336.496722) (xy 83.812143 -336.550174) (xy 83.820277 -336.605401) (xy 83.820762 -336.633312)
			(xy 83.820276 -336.660563) (xy 83.81252 -336.714511) (xy 83.797165 -336.766806) (xy 83.774523 -336.816383)
			(xy 83.745057 -336.862233) (xy 83.709366 -336.903424) (xy 83.668175 -336.939115) (xy 83.622325 -336.968581)
			(xy 83.572748 -336.991223) (xy 83.520453 -337.006578) (xy 83.466505 -337.014334) (xy 83.412003 -337.014334)
			(xy 83.358055 -337.006578) (xy 83.30576 -336.991223) (xy 83.256183 -336.968581) (xy 83.210333 -336.939115)
			(xy 83.169142 -336.903424) (xy 83.133451 -336.862233) (xy 83.103985 -336.816383) (xy 83.081343 -336.766806)
			(xy 83.065988 -336.714511) (xy 83.058232 -336.660563) (xy 83.057746 -336.633312) (xy 82.668211 -336.633312)
			(xy 82.67192 -336.637376) (xy 82.893154 -336.858356) (xy 82.893662 -336.859118) (xy 82.930238 -336.894424)
			(xy 82.933911 -336.898183) (xy 82.939801 -336.906887) (xy 82.941922 -336.911696) (xy 82.980784 -337.007454)
			(xy 82.982494 -337.012027) (xy 82.984287 -337.021622) (xy 82.98434 -337.026504) (xy 82.98434 -337.864958)
			(xy 84.015578 -337.864958) (xy 84.019649 -337.809336) (xy 84.031775 -337.754899) (xy 84.051698 -337.702808)
			(xy 84.078994 -337.654173) (xy 84.11308 -337.61003) (xy 84.153229 -337.571321) (xy 84.198587 -337.53887)
			(xy 84.248187 -337.513369) (xy 84.300971 -337.495362) (xy 84.355814 -337.485232) (xy 84.411548 -337.483195)
			(xy 84.466985 -337.489295) (xy 84.520942 -337.503401) (xy 84.572271 -337.525213) (xy 84.619877 -337.554267)
			(xy 84.662745 -337.589942) (xy 84.699962 -337.631479) (xy 84.730735 -337.677992) (xy 84.754407 -337.728489)
			(xy 84.770475 -337.781896) (xy 84.778595 -337.837072) (xy 84.779104 -337.864958) (xy 84.778595 -337.892844)
			(xy 84.770475 -337.94802) (xy 84.754407 -338.001427) (xy 84.730735 -338.051924) (xy 84.699962 -338.098437)
			(xy 84.662745 -338.139974) (xy 84.619877 -338.175649) (xy 84.572271 -338.204703) (xy 84.520942 -338.226515)
			(xy 84.466985 -338.240621) (xy 84.411548 -338.246721) (xy 84.355814 -338.244684) (xy 84.300971 -338.234554)
			(xy 84.248187 -338.216547) (xy 84.198587 -338.191046) (xy 84.153229 -338.158595) (xy 84.11308 -338.119886)
			(xy 84.078994 -338.075743) (xy 84.051698 -338.027108) (xy 84.031775 -337.975017) (xy 84.019649 -337.92058)
			(xy 84.015578 -337.864958) (xy 82.98434 -337.864958) (xy 82.98434 -338.760308) (xy 83.436458 -338.760308)
			(xy 83.440529 -338.704686) (xy 83.452655 -338.650249) (xy 83.472578 -338.598158) (xy 83.499874 -338.549523)
			(xy 83.53396 -338.50538) (xy 83.574109 -338.466671) (xy 83.619467 -338.43422) (xy 83.669067 -338.408719)
			(xy 83.721851 -338.390712) (xy 83.776694 -338.380582) (xy 83.832428 -338.378545) (xy 83.887865 -338.384645)
			(xy 83.941822 -338.398751) (xy 83.993151 -338.420563) (xy 84.040757 -338.449617) (xy 84.083625 -338.485292)
			(xy 84.120842 -338.526829) (xy 84.151615 -338.573342) (xy 84.175287 -338.623839) (xy 84.191355 -338.677246)
			(xy 84.199475 -338.732422) (xy 84.199984 -338.760308) (xy 84.199475 -338.788194) (xy 84.191355 -338.84337)
			(xy 84.175287 -338.896777) (xy 84.151615 -338.947274) (xy 84.120842 -338.993787) (xy 84.083625 -339.035324)
			(xy 84.040757 -339.070999) (xy 83.993151 -339.100053) (xy 83.941822 -339.121865) (xy 83.887865 -339.135971)
			(xy 83.832428 -339.142071) (xy 83.776694 -339.140034) (xy 83.721851 -339.129904) (xy 83.669067 -339.111897)
			(xy 83.619467 -339.086396) (xy 83.574109 -339.053945) (xy 83.53396 -339.015236) (xy 83.499874 -338.971093)
			(xy 83.472578 -338.922458) (xy 83.452655 -338.870367) (xy 83.440529 -338.81593) (xy 83.436458 -338.760308)
			(xy 82.98434 -338.760308) (xy 82.98434 -339.435948) (xy 84.775294 -339.435948) (xy 84.775751 -339.408472)
			(xy 84.78365 -339.354092) (xy 84.799277 -339.301409) (xy 84.822308 -339.251517) (xy 84.852266 -339.205449)
			(xy 84.870036 -339.184488) (xy 84.876132 -339.177376) (xy 84.882482 -339.160358) (xy 84.882482 -339.074506)
			(xy 84.876132 -339.057488) (xy 84.870036 -339.050376) (xy 84.85227 -339.029416) (xy 84.822347 -338.983333)
			(xy 84.799336 -338.933438) (xy 84.783711 -338.880761) (xy 84.775794 -338.826388) (xy 84.775294 -338.798916)
			(xy 84.77578 -338.771665) (xy 84.783536 -338.717717) (xy 84.798891 -338.665422) (xy 84.821533 -338.615845)
			(xy 84.850999 -338.569995) (xy 84.88669 -338.528804) (xy 84.927881 -338.493113) (xy 84.973731 -338.463647)
			(xy 85.023308 -338.441005) (xy 85.075603 -338.42565) (xy 85.129551 -338.417894) (xy 85.184053 -338.417894)
			(xy 85.238001 -338.42565) (xy 85.290296 -338.441005) (xy 85.339873 -338.463647) (xy 85.385723 -338.493113)
			(xy 85.426914 -338.528804) (xy 85.462605 -338.569995) (xy 85.492071 -338.615845) (xy 85.514713 -338.665422)
			(xy 85.530068 -338.717717) (xy 85.537824 -338.771665) (xy 85.53831 -338.798916) (xy 85.537831 -338.826391)
			(xy 85.529937 -338.880771) (xy 85.514315 -338.933453) (xy 85.511686 -338.93915) (xy 85.780101 -338.93915)
			(xy 85.780101 -338.88465) (xy 85.787858 -338.830704) (xy 85.803213 -338.778411) (xy 85.825854 -338.728835)
			(xy 85.85532 -338.682987) (xy 85.891011 -338.641799) (xy 85.932201 -338.606109) (xy 85.978051 -338.576645)
			(xy 86.027628 -338.554007) (xy 86.079921 -338.538654) (xy 86.133868 -338.5309) (xy 86.161118 -338.530438)
			(xy 86.186353 -338.530835) (xy 86.236387 -338.537455) (xy 86.285107 -338.550628) (xy 86.331659 -338.570124)
			(xy 86.35365 -338.582508) (xy 86.363302 -338.58835) (xy 86.3854 -338.590382) (xy 86.479888 -338.556854)
			(xy 86.49589 -338.54136) (xy 86.499954 -338.530946) (xy 86.510643 -338.504167) (xy 86.538934 -338.453928)
			(xy 86.574467 -338.40852) (xy 86.61643 -338.368979) (xy 86.663868 -338.336206) (xy 86.715699 -338.310948)
			(xy 86.770741 -338.293782) (xy 86.827741 -338.285097) (xy 86.85657 -338.284566) (xy 86.883821 -338.285083)
			(xy 86.937769 -338.292835) (xy 86.990064 -338.308186) (xy 87.039642 -338.330823) (xy 87.085494 -338.360286)
			(xy 87.126686 -338.395974) (xy 87.162381 -338.437161) (xy 87.19185 -338.483009) (xy 87.214494 -338.532584)
			(xy 87.229853 -338.584877) (xy 87.237613 -338.638823) (xy 87.238078 -338.666074) (xy 87.237435 -338.697638)
			(xy 87.227041 -338.759903) (xy 87.206549 -338.819612) (xy 87.192104 -338.847684) (xy 87.187278 -338.856574)
			(xy 87.185246 -338.876132) (xy 87.2109 -338.96427) (xy 87.223346 -338.979764) (xy 87.232236 -338.984844)
			(xy 87.257326 -338.999411) (xy 87.303211 -339.034909) (xy 87.343189 -339.076948) (xy 87.376337 -339.124559)
			(xy 87.40189 -339.176642) (xy 87.419257 -339.231994) (xy 87.428039 -339.289339) (xy 87.428578 -339.318346)
			(xy 87.428092 -339.345597) (xy 87.420336 -339.399545) (xy 87.404981 -339.45184) (xy 87.382339 -339.501417)
			(xy 87.352873 -339.547267) (xy 87.317182 -339.588458) (xy 87.275991 -339.624149) (xy 87.230141 -339.653615)
			(xy 87.180564 -339.676257) (xy 87.128269 -339.691612) (xy 87.074321 -339.699368) (xy 87.019819 -339.699368)
			(xy 86.965871 -339.691612) (xy 86.913576 -339.676257) (xy 86.863999 -339.653615) (xy 86.818149 -339.624149)
			(xy 86.776958 -339.588458) (xy 86.741267 -339.547267) (xy 86.711801 -339.501417) (xy 86.689159 -339.45184)
			(xy 86.673804 -339.399545) (xy 86.666048 -339.345597) (xy 86.665562 -339.318346) (xy 86.66622 -339.286783)
			(xy 86.676609 -339.224518) (xy 86.697095 -339.164809) (xy 86.711536 -339.136736) (xy 86.716362 -339.127846)
			(xy 86.718394 -339.108288) (xy 86.69274 -339.02015) (xy 86.680294 -339.004656) (xy 86.671404 -338.999576)
			(xy 86.664038 -338.995512) (xy 86.654386 -338.98967) (xy 86.632288 -338.987638) (xy 86.5378 -339.021166)
			(xy 86.521798 -339.03666) (xy 86.517734 -339.047074) (xy 86.507012 -339.07384) (xy 86.47873 -339.124082)
			(xy 86.443204 -339.169493) (xy 86.401247 -339.209037) (xy 86.353813 -339.241813) (xy 86.301985 -339.267072)
			(xy 86.246944 -339.28424) (xy 86.189946 -339.292924) (xy 86.161118 -339.293454) (xy 86.133868 -339.2929)
			(xy 86.079921 -339.285146) (xy 86.027628 -339.269793) (xy 85.978051 -339.247155) (xy 85.932201 -339.217691)
			(xy 85.891011 -339.182001) (xy 85.85532 -339.140813) (xy 85.825854 -339.094965) (xy 85.803213 -339.045389)
			(xy 85.787858 -338.993096) (xy 85.780101 -338.93915) (xy 85.511686 -338.93915) (xy 85.491289 -338.983346)
			(xy 85.461336 -339.029414) (xy 85.443568 -339.050376) (xy 85.437472 -339.057488) (xy 85.431122 -339.074506)
			(xy 85.431122 -339.160358) (xy 85.437472 -339.177376) (xy 85.443568 -339.184488) (xy 85.461318 -339.205461)
			(xy 85.491243 -339.251541) (xy 85.514257 -339.301433) (xy 85.529886 -339.354107) (xy 85.537808 -339.408477)
			(xy 85.53831 -339.435948) (xy 85.537824 -339.463199) (xy 85.530068 -339.517147) (xy 85.514713 -339.569442)
			(xy 85.492071 -339.619019) (xy 85.462605 -339.664869) (xy 85.426914 -339.70606) (xy 85.385723 -339.741751)
			(xy 85.339873 -339.771217) (xy 85.290296 -339.793859) (xy 85.238001 -339.809214) (xy 85.184053 -339.81697)
			(xy 85.129551 -339.81697) (xy 85.075603 -339.809214) (xy 85.023308 -339.793859) (xy 84.973731 -339.771217)
			(xy 84.927881 -339.741751) (xy 84.88669 -339.70606) (xy 84.850999 -339.664869) (xy 84.821533 -339.619019)
			(xy 84.798891 -339.569442) (xy 84.783536 -339.517147) (xy 84.77578 -339.463199) (xy 84.775294 -339.435948)
			(xy 82.98434 -339.435948) (xy 82.98434 -339.862414) (xy 82.984748 -339.872485) (xy 82.99248 -339.891084)
			(xy 82.999326 -339.898482) (xy 83.732624 -340.63178) (xy 83.740102 -340.638477) (xy 83.758664 -340.646064)
			(xy 83.768692 -340.646512) (xy 87.987886 -340.646512) (xy 87.997936 -340.646185) (xy 88.016533 -340.638569)
			(xy 88.023954 -340.63178) (xy 88.11768 -340.538054) (xy 88.124387 -340.530583) (xy 88.131968 -340.512016)
			(xy 88.132412 -340.501986) (xy 88.132412 -338.098892) (xy 88.132044 -338.088846) (xy 88.124456 -338.070249)
			(xy 88.11768 -338.062824) (xy 87.339424 -337.284822) (xy 87.3228 -337.267519) (xy 87.294612 -337.22869)
			(xy 87.272837 -337.185934) (xy 87.25801 -337.140302) (xy 87.250494 -337.092912) (xy 87.250016 -337.068922)
			(xy 87.250016 -335.3054) (xy 87.250456 -335.281403) (xy 87.257923 -335.233994) (xy 87.272736 -335.188344)
			(xy 87.294527 -335.145583) (xy 87.322757 -335.10677) (xy 87.339424 -335.0895) (xy 87.36711 -335.061814)
			(xy 87.384403 -335.045162) (xy 87.423212 -335.01691) (xy 87.465963 -334.995077) (xy 87.511603 -334.9802)
			(xy 87.559009 -334.972645) (xy 87.58301 -334.972152) (xy 90.575892 -334.972152) (xy 90.599898 -334.972591)
			(xy 90.647313 -334.980139) (xy 90.692961 -334.995018) (xy 90.735717 -335.016862) (xy 90.774524 -335.045131)
			(xy 90.791792 -335.061814) (xy 90.931238 -335.20126) (xy 90.931746 -335.202022) (xy 90.968322 -335.237328)
			(xy 90.971994 -335.241088) (xy 90.977885 -335.249791) (xy 90.980006 -335.2546) (xy 91.018868 -335.350358)
			(xy 91.020579 -335.354931) (xy 91.022371 -335.364526) (xy 91.022424 -335.369408) (xy 91.022424 -336.635598)
			(xy 91.022844 -336.645668) (xy 91.030568 -336.664266) (xy 91.03741 -336.671666) (xy 91.049871 -336.684112)
			(xy 91.388946 -336.684112) (xy 91.389457 -336.656202) (xy 91.397589 -336.600977) (xy 91.41368 -336.547527)
			(xy 91.437389 -336.496992) (xy 91.468208 -336.450451) (xy 91.486482 -336.42935) (xy 91.492832 -336.422238)
			(xy 91.499436 -336.404966) (xy 91.499436 -336.317844) (xy 91.492832 -336.300572) (xy 91.486482 -336.29346)
			(xy 91.468208 -336.272357) (xy 91.437381 -336.225819) (xy 91.413665 -336.175286) (xy 91.397567 -336.121835)
			(xy 91.389432 -336.066609) (xy 91.388946 -336.038698) (xy 91.389432 -336.011447) (xy 91.397188 -335.957499)
			(xy 91.412543 -335.905204) (xy 91.435185 -335.855627) (xy 91.464651 -335.809777) (xy 91.500342 -335.768586)
			(xy 91.541533 -335.732895) (xy 91.587383 -335.703429) (xy 91.63696 -335.680787) (xy 91.689255 -335.665432)
			(xy 91.743203 -335.657676) (xy 91.797705 -335.657676) (xy 91.851653 -335.665432) (xy 91.903948 -335.680787)
			(xy 91.953525 -335.703429) (xy 91.999375 -335.732895) (xy 92.040566 -335.768586) (xy 92.076257 -335.809777)
			(xy 92.105723 -335.855627) (xy 92.128365 -335.905204) (xy 92.14372 -335.957499) (xy 92.151476 -336.011447)
			(xy 92.151962 -336.038698) (xy 92.151455 -336.066608) (xy 92.143322 -336.121833) (xy 92.127229 -336.175283)
			(xy 92.10352 -336.225818) (xy 92.0727 -336.272359) (xy 92.054426 -336.29346) (xy 92.048076 -336.300572)
			(xy 92.041472 -336.317844) (xy 92.041472 -336.404966) (xy 92.048076 -336.422238) (xy 92.054426 -336.42935)
			(xy 92.072706 -336.450448) (xy 92.103532 -336.496987) (xy 92.127247 -336.547522) (xy 92.143343 -336.600974)
			(xy 92.151477 -336.656201) (xy 92.151962 -336.684112) (xy 92.151476 -336.711363) (xy 92.14372 -336.765311)
			(xy 92.128365 -336.817606) (xy 92.105723 -336.867183) (xy 92.076257 -336.913033) (xy 92.040566 -336.954224)
			(xy 91.999375 -336.989915) (xy 91.953525 -337.019381) (xy 91.903948 -337.042023) (xy 91.851653 -337.057378)
			(xy 91.797705 -337.065134) (xy 91.743203 -337.065134) (xy 91.689255 -337.057378) (xy 91.63696 -337.042023)
			(xy 91.587383 -337.019381) (xy 91.541533 -336.989915) (xy 91.500342 -336.954224) (xy 91.464651 -336.913033)
			(xy 91.435185 -336.867183) (xy 91.412543 -336.817606) (xy 91.397188 -336.765311) (xy 91.389432 -336.711363)
			(xy 91.388946 -336.684112) (xy 91.049871 -336.684112) (xy 91.249754 -336.883756) (xy 91.250262 -336.884518)
			(xy 91.286838 -336.919824) (xy 91.290511 -336.923583) (xy 91.296401 -336.932287) (xy 91.298522 -336.937096)
			(xy 91.337384 -337.032854) (xy 91.339094 -337.037427) (xy 91.340887 -337.047022) (xy 91.34094 -337.051904)
			(xy 91.34094 -337.915758) (xy 92.346778 -337.915758) (xy 92.350849 -337.860136) (xy 92.362975 -337.805699)
			(xy 92.382898 -337.753608) (xy 92.410194 -337.704973) (xy 92.44428 -337.66083) (xy 92.484429 -337.622121)
			(xy 92.529787 -337.58967) (xy 92.579387 -337.564169) (xy 92.632171 -337.546162) (xy 92.687014 -337.536032)
			(xy 92.742748 -337.533995) (xy 92.798185 -337.540095) (xy 92.852142 -337.554201) (xy 92.903471 -337.576013)
			(xy 92.951077 -337.605067) (xy 92.993945 -337.640742) (xy 93.031162 -337.682279) (xy 93.061935 -337.728792)
			(xy 93.085607 -337.779289) (xy 93.101675 -337.832696) (xy 93.109795 -337.887872) (xy 93.110304 -337.915758)
			(xy 93.109795 -337.943644) (xy 93.101675 -337.99882) (xy 93.085607 -338.052227) (xy 93.061935 -338.102724)
			(xy 93.031162 -338.149237) (xy 92.993945 -338.190774) (xy 92.951077 -338.226449) (xy 92.903471 -338.255503)
			(xy 92.852142 -338.277315) (xy 92.798185 -338.291421) (xy 92.742748 -338.297521) (xy 92.687014 -338.295484)
			(xy 92.632171 -338.285354) (xy 92.579387 -338.267347) (xy 92.529787 -338.241846) (xy 92.484429 -338.209395)
			(xy 92.44428 -338.170686) (xy 92.410194 -338.126543) (xy 92.382898 -338.077908) (xy 92.362975 -338.025817)
			(xy 92.350849 -337.97138) (xy 92.346778 -337.915758) (xy 91.34094 -337.915758) (xy 91.34094 -338.811108)
			(xy 91.767658 -338.811108) (xy 91.771729 -338.755486) (xy 91.783855 -338.701049) (xy 91.803778 -338.648958)
			(xy 91.831074 -338.600323) (xy 91.86516 -338.55618) (xy 91.905309 -338.517471) (xy 91.950667 -338.48502)
			(xy 92.000267 -338.459519) (xy 92.053051 -338.441512) (xy 92.107894 -338.431382) (xy 92.163628 -338.429345)
			(xy 92.219065 -338.435445) (xy 92.273022 -338.449551) (xy 92.324351 -338.471363) (xy 92.371957 -338.500417)
			(xy 92.414825 -338.536092) (xy 92.452042 -338.577629) (xy 92.482815 -338.624142) (xy 92.506487 -338.674639)
			(xy 92.522555 -338.728046) (xy 92.530675 -338.783222) (xy 92.531184 -338.811108) (xy 92.530675 -338.838994)
			(xy 92.522555 -338.89417) (xy 92.506487 -338.947577) (xy 92.482815 -338.998074) (xy 92.452042 -339.044587)
			(xy 92.414825 -339.086124) (xy 92.371957 -339.121799) (xy 92.324351 -339.150853) (xy 92.273022 -339.172665)
			(xy 92.219065 -339.186771) (xy 92.163628 -339.192871) (xy 92.107894 -339.190834) (xy 92.053051 -339.180704)
			(xy 92.000267 -339.162697) (xy 91.950667 -339.137196) (xy 91.905309 -339.104745) (xy 91.86516 -339.066036)
			(xy 91.831074 -339.021893) (xy 91.803778 -338.973258) (xy 91.783855 -338.921167) (xy 91.771729 -338.86673)
			(xy 91.767658 -338.811108) (xy 91.34094 -338.811108) (xy 91.34094 -339.486748) (xy 93.106494 -339.486748)
			(xy 93.106951 -339.459272) (xy 93.11485 -339.404892) (xy 93.130477 -339.352209) (xy 93.153508 -339.302317)
			(xy 93.183466 -339.256249) (xy 93.201236 -339.235288) (xy 93.207332 -339.228176) (xy 93.213682 -339.211158)
			(xy 93.213682 -339.125306) (xy 93.207332 -339.108288) (xy 93.201236 -339.101176) (xy 93.18347 -339.080216)
			(xy 93.153547 -339.034133) (xy 93.130536 -338.984238) (xy 93.114911 -338.931561) (xy 93.106994 -338.877188)
			(xy 93.106494 -338.849716) (xy 93.10698 -338.822465) (xy 93.114736 -338.768517) (xy 93.130091 -338.716222)
			(xy 93.152733 -338.666645) (xy 93.182199 -338.620795) (xy 93.21789 -338.579604) (xy 93.259081 -338.543913)
			(xy 93.304931 -338.514447) (xy 93.354508 -338.491805) (xy 93.406803 -338.47645) (xy 93.460751 -338.468694)
			(xy 93.515253 -338.468694) (xy 93.569201 -338.47645) (xy 93.621496 -338.491805) (xy 93.671073 -338.514447)
			(xy 93.716923 -338.543913) (xy 93.758114 -338.579604) (xy 93.793805 -338.620795) (xy 93.823271 -338.666645)
			(xy 93.845913 -338.716222) (xy 93.861268 -338.768517) (xy 93.869024 -338.822465) (xy 93.86951 -338.849716)
			(xy 93.869031 -338.877191) (xy 93.861137 -338.931571) (xy 93.845515 -338.984253) (xy 93.842886 -338.98995)
			(xy 94.111301 -338.98995) (xy 94.111301 -338.93545) (xy 94.119058 -338.881504) (xy 94.134413 -338.829211)
			(xy 94.157054 -338.779635) (xy 94.18652 -338.733787) (xy 94.222211 -338.692599) (xy 94.263401 -338.656909)
			(xy 94.309251 -338.627445) (xy 94.358828 -338.604807) (xy 94.411121 -338.589454) (xy 94.465068 -338.5817)
			(xy 94.492318 -338.581238) (xy 94.517553 -338.581635) (xy 94.567587 -338.588255) (xy 94.616307 -338.601428)
			(xy 94.662859 -338.620924) (xy 94.68485 -338.633308) (xy 94.694502 -338.63915) (xy 94.7166 -338.641182)
			(xy 94.811088 -338.607654) (xy 94.82709 -338.59216) (xy 94.831154 -338.581746) (xy 94.841843 -338.554967)
			(xy 94.870134 -338.504728) (xy 94.905667 -338.45932) (xy 94.94763 -338.419779) (xy 94.995068 -338.387006)
			(xy 95.046899 -338.361748) (xy 95.101941 -338.344582) (xy 95.158941 -338.335897) (xy 95.18777 -338.335366)
			(xy 95.215021 -338.335883) (xy 95.268969 -338.343635) (xy 95.321264 -338.358986) (xy 95.370842 -338.381623)
			(xy 95.416694 -338.411086) (xy 95.457886 -338.446774) (xy 95.493581 -338.487961) (xy 95.52305 -338.533809)
			(xy 95.545694 -338.583384) (xy 95.561053 -338.635677) (xy 95.568813 -338.689623) (xy 95.569278 -338.716874)
			(xy 95.568635 -338.748438) (xy 95.558241 -338.810703) (xy 95.537749 -338.870412) (xy 95.523304 -338.898484)
			(xy 95.518478 -338.907374) (xy 95.516446 -338.926932) (xy 95.5421 -339.01507) (xy 95.554546 -339.030564)
			(xy 95.563436 -339.035644) (xy 95.588526 -339.050211) (xy 95.634411 -339.085709) (xy 95.674389 -339.127748)
			(xy 95.707537 -339.175359) (xy 95.73309 -339.227442) (xy 95.750457 -339.282794) (xy 95.759239 -339.340139)
			(xy 95.759778 -339.369146) (xy 95.759292 -339.396397) (xy 95.751536 -339.450345) (xy 95.736181 -339.50264)
			(xy 95.713539 -339.552217) (xy 95.684073 -339.598067) (xy 95.648382 -339.639258) (xy 95.607191 -339.674949)
			(xy 95.561341 -339.704415) (xy 95.511764 -339.727057) (xy 95.459469 -339.742412) (xy 95.405521 -339.750168)
			(xy 95.351019 -339.750168) (xy 95.297071 -339.742412) (xy 95.244776 -339.727057) (xy 95.195199 -339.704415)
			(xy 95.149349 -339.674949) (xy 95.108158 -339.639258) (xy 95.072467 -339.598067) (xy 95.043001 -339.552217)
			(xy 95.020359 -339.50264) (xy 95.005004 -339.450345) (xy 94.997248 -339.396397) (xy 94.996762 -339.369146)
			(xy 94.99742 -339.337583) (xy 95.007809 -339.275318) (xy 95.028295 -339.215609) (xy 95.042736 -339.187536)
			(xy 95.047562 -339.178646) (xy 95.049594 -339.159088) (xy 95.02394 -339.07095) (xy 95.011494 -339.055456)
			(xy 95.002604 -339.050376) (xy 94.995238 -339.046312) (xy 94.985586 -339.04047) (xy 94.963488 -339.038438)
			(xy 94.869 -339.071966) (xy 94.852998 -339.08746) (xy 94.848934 -339.097874) (xy 94.838212 -339.12464)
			(xy 94.80993 -339.174882) (xy 94.774404 -339.220293) (xy 94.732447 -339.259837) (xy 94.685013 -339.292613)
			(xy 94.633185 -339.317872) (xy 94.578144 -339.33504) (xy 94.521146 -339.343724) (xy 94.492318 -339.344254)
			(xy 94.465068 -339.3437) (xy 94.411121 -339.335946) (xy 94.358828 -339.320593) (xy 94.309251 -339.297955)
			(xy 94.263401 -339.268491) (xy 94.222211 -339.232801) (xy 94.18652 -339.191613) (xy 94.157054 -339.145765)
			(xy 94.134413 -339.096189) (xy 94.119058 -339.043896) (xy 94.111301 -338.98995) (xy 93.842886 -338.98995)
			(xy 93.822489 -339.034146) (xy 93.792536 -339.080214) (xy 93.774768 -339.101176) (xy 93.768672 -339.108288)
			(xy 93.762322 -339.125306) (xy 93.762322 -339.211158) (xy 93.768672 -339.228176) (xy 93.774768 -339.235288)
			(xy 93.792518 -339.256261) (xy 93.822443 -339.302341) (xy 93.845457 -339.352233) (xy 93.861086 -339.404907)
			(xy 93.869008 -339.459277) (xy 93.86951 -339.486748) (xy 93.869024 -339.513999) (xy 93.861268 -339.567947)
			(xy 93.845913 -339.620242) (xy 93.823271 -339.669819) (xy 93.793805 -339.715669) (xy 93.758114 -339.75686)
			(xy 93.716923 -339.792551) (xy 93.671073 -339.822017) (xy 93.621496 -339.844659) (xy 93.569201 -339.860014)
			(xy 93.515253 -339.86777) (xy 93.460751 -339.86777) (xy 93.406803 -339.860014) (xy 93.354508 -339.844659)
			(xy 93.304931 -339.822017) (xy 93.259081 -339.792551) (xy 93.21789 -339.75686) (xy 93.182199 -339.715669)
			(xy 93.152733 -339.669819) (xy 93.130091 -339.620242) (xy 93.114736 -339.567947) (xy 93.10698 -339.513999)
			(xy 93.106494 -339.486748) (xy 91.34094 -339.486748) (xy 91.34094 -339.979254) (xy 91.341379 -339.989322)
			(xy 91.349089 -340.007921) (xy 91.355926 -340.015322) (xy 92.028264 -340.68766) (xy 92.035731 -340.694372)
			(xy 92.054301 -340.701951) (xy 92.064332 -340.702392) (xy 96.235266 -340.702392) (xy 96.245313 -340.702034)
			(xy 96.263908 -340.694437) (xy 96.271334 -340.68766) (xy 96.4438 -340.515194) (xy 96.450492 -340.507712)
			(xy 96.458082 -340.489153) (xy 96.458532 -340.479126) (xy 96.458532 -338.164932) (xy 96.45819 -338.154883)
			(xy 96.450584 -338.136287) (xy 96.4438 -338.128864) (xy 95.670624 -337.355942) (xy 95.654009 -337.33863)
			(xy 95.62582 -337.299804) (xy 95.604044 -337.25705) (xy 95.589214 -337.211419) (xy 95.581696 -337.164032)
			(xy 95.581216 -337.140042) (xy 95.581216 -335.35366) (xy 95.58163 -335.329662) (xy 95.589104 -335.282252)
			(xy 95.603922 -335.236601) (xy 95.625719 -335.193841) (xy 95.653955 -335.155029) (xy 95.670624 -335.13776)
			(xy 95.698056 -335.110328) (xy 95.715369 -335.093715) (xy 95.754195 -335.065526) (xy 95.796948 -335.043749)
			(xy 95.842579 -335.028919) (xy 95.889966 -335.0214) (xy 95.913956 -335.02092) (xy 99.145852 -335.02092)
			(xy 99.169851 -335.021326) (xy 99.217261 -335.028801) (xy 99.262912 -335.043622) (xy 99.305672 -335.065421)
			(xy 99.344483 -335.093658) (xy 99.361752 -335.110328) (xy 99.451668 -335.200244) (xy 99.452176 -335.201006)
			(xy 99.488752 -335.236312) (xy 99.492425 -335.240072) (xy 99.498314 -335.248775) (xy 99.500436 -335.253584)
			(xy 99.539298 -335.349342) (xy 99.541065 -335.353905) (xy 99.542975 -335.3635) (xy 99.543108 -335.368392)
			(xy 99.543108 -340.462108) (xy 99.542723 -340.482625) (xy 99.53711 -340.523277) (xy 99.531932 -340.543134)
			(xy 99.519232 -340.588346) (xy 99.514152 -340.600538) (xy 99.497642 -340.628478) (xy 99.497388 -340.628732)
			(xy 99.480868 -340.657931) (xy 99.453395 -340.719138) (xy 99.432524 -340.7829) (xy 99.41849 -340.848506)
			(xy 99.411448 -340.915227) (xy 99.411028 -340.948772) (xy 99.41144 -340.982317) (xy 99.418486 -341.049037)
			(xy 99.432525 -341.114642) (xy 99.453399 -341.178403) (xy 99.480876 -341.239609) (xy 99.497388 -341.268812)
			(xy 99.497642 -341.269066) (xy 99.514152 -341.297006) (xy 99.519232 -341.309198) (xy 99.531932 -341.35441)
			(xy 99.537125 -341.374264) (xy 99.542727 -341.414918) (xy 99.543108 -341.435436) (xy 99.543108 -341.594186)
			(xy 99.664774 -341.594186) (xy 99.665262 -341.566275) (xy 99.673398 -341.511049) (xy 99.689495 -341.457599)
			(xy 99.713209 -341.407064) (xy 99.744033 -341.360524) (xy 99.76231 -341.339424) (xy 99.76866 -341.332312)
			(xy 99.775264 -341.31504) (xy 99.775264 -341.227918) (xy 99.76866 -341.210646) (xy 99.76231 -341.203534)
			(xy 99.744028 -341.182437) (xy 99.713201 -341.135898) (xy 99.689486 -341.085363) (xy 99.673391 -341.031911)
			(xy 99.665258 -340.976684) (xy 99.664774 -340.948772) (xy 99.66526 -340.921521) (xy 99.673016 -340.867573)
			(xy 99.688371 -340.815278) (xy 99.711013 -340.765701) (xy 99.740479 -340.719851) (xy 99.77617 -340.67866)
			(xy 99.817361 -340.642969) (xy 99.863211 -340.613503) (xy 99.912788 -340.590861) (xy 99.965083 -340.575506)
			(xy 100.019031 -340.56775) (xy 100.073533 -340.56775) (xy 100.127481 -340.575506) (xy 100.179776 -340.590861)
			(xy 100.229353 -340.613503) (xy 100.275203 -340.642969) (xy 100.316394 -340.67866) (xy 100.352085 -340.719851)
			(xy 100.381551 -340.765701) (xy 100.404193 -340.815278) (xy 100.419548 -340.867573) (xy 100.427304 -340.921521)
			(xy 100.42779 -340.948772) (xy 100.42732 -340.976683) (xy 100.419177 -341.031909) (xy 100.403075 -341.08536)
			(xy 100.379358 -341.135894) (xy 100.348531 -341.182434) (xy 100.330254 -341.203534) (xy 100.323904 -341.210646)
			(xy 100.3173 -341.227918) (xy 100.3173 -341.31504) (xy 100.323904 -341.332312) (xy 100.330254 -341.339424)
			(xy 100.348526 -341.360528) (xy 100.379353 -341.407066) (xy 100.403068 -341.4576) (xy 100.419166 -341.51105)
			(xy 100.427303 -341.566275) (xy 100.42779 -341.594186) (xy 100.427304 -341.621437) (xy 100.419548 -341.675385)
			(xy 100.404193 -341.72768) (xy 100.381551 -341.777257) (xy 100.352085 -341.823107) (xy 100.316394 -341.864298)
			(xy 100.275203 -341.899989) (xy 100.229353 -341.929455) (xy 100.179776 -341.952097) (xy 100.127481 -341.967452)
			(xy 100.073533 -341.975208) (xy 100.019031 -341.975208) (xy 99.965083 -341.967452) (xy 99.912788 -341.952097)
			(xy 99.863211 -341.929455) (xy 99.817361 -341.899989) (xy 99.77617 -341.864298) (xy 99.740479 -341.823107)
			(xy 99.711013 -341.777257) (xy 99.688371 -341.72768) (xy 99.673016 -341.675385) (xy 99.66526 -341.621437)
			(xy 99.664774 -341.594186) (xy 99.543108 -341.594186) (xy 99.543108 -342.825832) (xy 100.622606 -342.825832)
			(xy 100.626677 -342.77021) (xy 100.638803 -342.715773) (xy 100.658726 -342.663682) (xy 100.686022 -342.615047)
			(xy 100.720108 -342.570904) (xy 100.760257 -342.532195) (xy 100.805615 -342.499744) (xy 100.855215 -342.474243)
			(xy 100.907999 -342.456236) (xy 100.962842 -342.446106) (xy 101.018576 -342.444069) (xy 101.074013 -342.450169)
			(xy 101.12797 -342.464275) (xy 101.179299 -342.486087) (xy 101.226905 -342.515141) (xy 101.269773 -342.550816)
			(xy 101.30699 -342.592353) (xy 101.337763 -342.638866) (xy 101.361435 -342.689363) (xy 101.377503 -342.74277)
			(xy 101.385623 -342.797946) (xy 101.386132 -342.825832) (xy 101.385623 -342.853718) (xy 101.377503 -342.908894)
			(xy 101.361435 -342.962301) (xy 101.337763 -343.012798) (xy 101.30699 -343.059311) (xy 101.269773 -343.100848)
			(xy 101.226905 -343.136523) (xy 101.179299 -343.165577) (xy 101.12797 -343.187389) (xy 101.074013 -343.201495)
			(xy 101.018576 -343.207595) (xy 100.962842 -343.205558) (xy 100.907999 -343.195428) (xy 100.855215 -343.177421)
			(xy 100.805615 -343.15192) (xy 100.760257 -343.119469) (xy 100.720108 -343.08076) (xy 100.686022 -343.036617)
			(xy 100.658726 -342.987982) (xy 100.638803 -342.935891) (xy 100.626677 -342.881454) (xy 100.622606 -342.825832)
			(xy 99.543108 -342.825832) (xy 99.543108 -343.721182) (xy 100.043486 -343.721182) (xy 100.047557 -343.66556)
			(xy 100.059683 -343.611123) (xy 100.079606 -343.559032) (xy 100.106902 -343.510397) (xy 100.140988 -343.466254)
			(xy 100.181137 -343.427545) (xy 100.226495 -343.395094) (xy 100.276095 -343.369593) (xy 100.328879 -343.351586)
			(xy 100.383722 -343.341456) (xy 100.439456 -343.339419) (xy 100.494893 -343.345519) (xy 100.54885 -343.359625)
			(xy 100.600179 -343.381437) (xy 100.647785 -343.410491) (xy 100.690653 -343.446166) (xy 100.72787 -343.487703)
			(xy 100.758643 -343.534216) (xy 100.782315 -343.584713) (xy 100.798383 -343.63812) (xy 100.806503 -343.693296)
			(xy 100.807012 -343.721182) (xy 100.806503 -343.749068) (xy 100.798383 -343.804244) (xy 100.782315 -343.857651)
			(xy 100.758643 -343.908148) (xy 100.72787 -343.954661) (xy 100.690653 -343.996198) (xy 100.647785 -344.031873)
			(xy 100.600179 -344.060927) (xy 100.54885 -344.082739) (xy 100.494893 -344.096845) (xy 100.439456 -344.102945)
			(xy 100.383722 -344.100908) (xy 100.328879 -344.090778) (xy 100.276095 -344.072771) (xy 100.226495 -344.04727)
			(xy 100.181137 -344.014819) (xy 100.140988 -343.97611) (xy 100.106902 -343.931967) (xy 100.079606 -343.883332)
			(xy 100.059683 -343.831241) (xy 100.047557 -343.776804) (xy 100.043486 -343.721182) (xy 99.543108 -343.721182)
			(xy 99.543108 -344.396822) (xy 101.382322 -344.396822) (xy 101.382816 -344.369348) (xy 101.390705 -344.314968)
			(xy 101.406323 -344.262286) (xy 101.429346 -344.212393) (xy 101.459297 -344.166324) (xy 101.477064 -344.145362)
			(xy 101.48316 -344.13825) (xy 101.48951 -344.121232) (xy 101.48951 -344.03538) (xy 101.48316 -344.018362)
			(xy 101.477064 -344.01125) (xy 101.45929 -343.990296) (xy 101.429368 -343.944212) (xy 101.406358 -343.894315)
			(xy 101.390734 -343.841637) (xy 101.38282 -343.787263) (xy 101.382322 -343.75979) (xy 101.382808 -343.732539)
			(xy 101.390564 -343.678591) (xy 101.405919 -343.626296) (xy 101.428561 -343.576719) (xy 101.458027 -343.530869)
			(xy 101.493718 -343.489678) (xy 101.534909 -343.453987) (xy 101.580759 -343.424521) (xy 101.630336 -343.401879)
			(xy 101.682631 -343.386524) (xy 101.736579 -343.378768) (xy 101.791081 -343.378768) (xy 101.845029 -343.386524)
			(xy 101.897324 -343.401879) (xy 101.946901 -343.424521) (xy 101.992751 -343.453987) (xy 102.033942 -343.489678)
			(xy 102.069633 -343.530869) (xy 102.099099 -343.576719) (xy 102.121741 -343.626296) (xy 102.137096 -343.678591)
			(xy 102.144852 -343.732539) (xy 102.145338 -343.75979) (xy 102.144836 -343.787264) (xy 102.136947 -343.841643)
			(xy 102.12133 -343.894324) (xy 102.118686 -343.900054) (xy 102.387075 -343.900054) (xy 102.387075 -343.845546)
			(xy 102.394833 -343.791594) (xy 102.410191 -343.739296) (xy 102.432835 -343.689715) (xy 102.462306 -343.643862)
			(xy 102.498003 -343.60267) (xy 102.539199 -343.566979) (xy 102.585055 -343.537513) (xy 102.634639 -343.514875)
			(xy 102.686939 -343.499523) (xy 102.740892 -343.491772) (xy 102.768146 -343.491312) (xy 102.793382 -343.491687)
			(xy 102.843417 -343.498312) (xy 102.892137 -343.511491) (xy 102.938688 -343.530994) (xy 102.960678 -343.543382)
			(xy 102.97033 -343.549224) (xy 102.992428 -343.551256) (xy 103.086916 -343.517728) (xy 103.102918 -343.502234)
			(xy 103.106982 -343.49182) (xy 103.117687 -343.465047) (xy 103.145972 -343.414804) (xy 103.1815 -343.369393)
			(xy 103.22346 -343.32985) (xy 103.270896 -343.297075) (xy 103.322727 -343.271817) (xy 103.377769 -343.254651)
			(xy 103.434769 -343.245969) (xy 103.463598 -343.24544) (xy 103.490853 -343.245857) (xy 103.544808 -343.253615)
			(xy 103.59711 -343.268973) (xy 103.646693 -343.291619) (xy 103.692548 -343.321092) (xy 103.733742 -343.35679)
			(xy 103.769436 -343.397988) (xy 103.798903 -343.443847) (xy 103.821543 -343.493433) (xy 103.836895 -343.545737)
			(xy 103.844646 -343.599693) (xy 103.845106 -343.626948) (xy 103.844449 -343.658511) (xy 103.834061 -343.720776)
			(xy 103.813574 -343.780485) (xy 103.799132 -343.808558) (xy 103.794306 -343.817448) (xy 103.792274 -343.837006)
			(xy 103.817928 -343.925144) (xy 103.830374 -343.940638) (xy 103.839264 -343.945718) (xy 103.864349 -343.960293)
			(xy 103.910233 -343.995791) (xy 103.95021 -344.037829) (xy 103.983358 -344.085439) (xy 104.008911 -344.13752)
			(xy 104.026281 -344.192871) (xy 104.035065 -344.250214) (xy 104.035606 -344.27922) (xy 104.03512 -344.306471)
			(xy 104.027364 -344.360419) (xy 104.012009 -344.412714) (xy 103.989367 -344.462291) (xy 103.959901 -344.508141)
			(xy 103.92421 -344.549332) (xy 103.883019 -344.585023) (xy 103.837169 -344.614489) (xy 103.787592 -344.637131)
			(xy 103.735297 -344.652486) (xy 103.681349 -344.660242) (xy 103.626847 -344.660242) (xy 103.572899 -344.652486)
			(xy 103.520604 -344.637131) (xy 103.471027 -344.614489) (xy 103.425177 -344.585023) (xy 103.383986 -344.549332)
			(xy 103.348295 -344.508141) (xy 103.318829 -344.462291) (xy 103.296187 -344.412714) (xy 103.280832 -344.360419)
			(xy 103.273076 -344.306471) (xy 103.27259 -344.27922) (xy 103.273235 -344.247657) (xy 103.283628 -344.185391)
			(xy 103.30412 -344.125682) (xy 103.318564 -344.09761) (xy 103.32339 -344.08872) (xy 103.325422 -344.069162)
			(xy 103.299768 -343.981024) (xy 103.287322 -343.96553) (xy 103.278432 -343.96045) (xy 103.271066 -343.956386)
			(xy 103.261414 -343.950544) (xy 103.239316 -343.948512) (xy 103.144828 -343.98204) (xy 103.128826 -343.997534)
			(xy 103.124762 -344.007948) (xy 103.114056 -344.03472) (xy 103.085767 -344.084959) (xy 103.050238 -344.130367)
			(xy 103.008277 -344.169908) (xy 102.960841 -344.202682) (xy 102.909013 -344.227941) (xy 102.853972 -344.245109)
			(xy 102.796974 -344.253796) (xy 102.768146 -344.254328) (xy 102.740892 -344.253828) (xy 102.686939 -344.246077)
			(xy 102.634639 -344.230725) (xy 102.585055 -344.208087) (xy 102.539199 -344.178621) (xy 102.498003 -344.14293)
			(xy 102.462306 -344.101738) (xy 102.432835 -344.055885) (xy 102.410191 -344.006304) (xy 102.394833 -343.954006)
			(xy 102.387075 -343.900054) (xy 102.118686 -343.900054) (xy 102.098309 -343.944217) (xy 102.068361 -343.990287)
			(xy 102.050596 -344.01125) (xy 102.0445 -344.018362) (xy 102.03815 -344.03538) (xy 102.03815 -344.121232)
			(xy 102.0445 -344.13825) (xy 102.050596 -344.145362) (xy 102.068322 -344.166354) (xy 102.098253 -344.212428)
			(xy 102.121273 -344.262314) (xy 102.136908 -344.314985) (xy 102.144834 -344.369352) (xy 102.145338 -344.396822)
			(xy 102.144852 -344.424073) (xy 102.137096 -344.478021) (xy 102.121741 -344.530316) (xy 102.099099 -344.579893)
			(xy 102.069633 -344.625743) (xy 102.033942 -344.666934) (xy 101.992751 -344.702625) (xy 101.946901 -344.732091)
			(xy 101.897324 -344.754733) (xy 101.845029 -344.770088) (xy 101.791081 -344.777844) (xy 101.736579 -344.777844)
			(xy 101.682631 -344.770088) (xy 101.630336 -344.754733) (xy 101.580759 -344.732091) (xy 101.534909 -344.702625)
			(xy 101.493718 -344.666934) (xy 101.458027 -344.625743) (xy 101.428561 -344.579893) (xy 101.405919 -344.530316)
			(xy 101.390564 -344.478021) (xy 101.382808 -344.424073) (xy 101.382322 -344.396822) (xy 99.543108 -344.396822)
			(xy 99.543108 -345.030044) (xy 99.543478 -345.040089) (xy 99.551067 -345.058685) (xy 99.55784 -345.066112)
			(xy 100.131626 -345.639898) (xy 100.139023 -345.646742) (xy 100.157625 -345.654459) (xy 100.167694 -345.654884)
			(xy 103.76281 -345.654884) (xy 103.77288 -345.654468) (xy 103.791478 -345.646741) (xy 103.798878 -345.639898)
			(xy 104.72166 -344.717116) (xy 104.728381 -344.709656) (xy 104.735955 -344.691081) (xy 104.736392 -344.681048)
			(xy 104.736392 -343.119964) (xy 104.736018 -343.109919) (xy 104.728432 -343.091323) (xy 104.72166 -343.083896)
			(xy 103.946452 -342.308942) (xy 103.929842 -342.291626) (xy 103.901651 -342.252801) (xy 103.879873 -342.210049)
			(xy 103.865043 -342.164419) (xy 103.857524 -342.117032) (xy 103.857044 -342.093042) (xy 103.857044 -340.32698)
			(xy 103.857492 -340.302983) (xy 103.86496 -340.255576) (xy 103.879772 -340.209927) (xy 103.901561 -340.167166)
			(xy 103.929787 -340.128352) (xy 103.946452 -340.11108) (xy 104.018842 -340.03869) (xy 104.036117 -340.022019)
			(xy 104.074931 -339.99377) (xy 104.117687 -339.971941) (xy 104.163331 -339.957068) (xy 104.210739 -339.949519)
			(xy 104.234742 -339.949028) (xy 108.558584 -339.949028) (xy 108.582579 -339.949453) (xy 108.629977 -339.956959)
			(xy 108.675617 -339.971787) (xy 108.718376 -339.993574) (xy 108.757199 -340.021781) (xy 108.791132 -340.055716)
			(xy 108.819337 -340.094541) (xy 108.841121 -340.137301) (xy 108.855946 -340.182943) (xy 108.863448 -340.230341)
			(xy 108.863892 -340.254336) (xy 108.863892 -345.265502) (xy 108.863304 -345.29224) (xy 108.853904 -345.344886)
			(xy 108.835481 -345.395091) (xy 108.808595 -345.44132) (xy 108.791756 -345.462098) (xy 106.408982 -348.283784)
			(xy 106.391421 -348.303669) (xy 106.350681 -348.337642) (xy 106.304689 -348.364074) (xy 106.254826 -348.382171)
			(xy 106.202586 -348.391389) (xy 106.176064 -348.391988) (xy 104.830118 -348.391988) (xy 104.820047 -348.392399)
			(xy 104.801448 -348.400127) (xy 104.79405 -348.406974) (xy 103.642414 -349.55861) (xy 103.625155 -349.575052)
			(xy 103.586522 -349.602969) (xy 103.544022 -349.624546) (xy 103.498686 -349.63926) (xy 103.451615 -349.646753)
			(xy 103.427784 -349.647256) (xy 86.530434 -349.647256) (xy 86.520386 -349.647602) (xy 86.501789 -349.655206)
			(xy 86.494366 -349.661988) (xy 82.499708 -353.656646) (xy 82.482458 -353.673097) (xy 82.443822 -353.701011)
			(xy 82.404625 -353.720908) (xy 86.731602 -353.720908) (xy 86.731602 -353.7204) (xy 86.732107 -353.684076)
			(xy 86.740428 -353.611907) (xy 86.756926 -353.541157) (xy 86.768686 -353.506786) (xy 86.777091 -353.481771)
			(xy 86.78616 -353.42979) (xy 86.786161 -353.377025) (xy 86.777094 -353.325043) (xy 86.768686 -353.30003)
			(xy 86.756903 -353.265622) (xy 86.740404 -353.194786) (xy 86.732102 -353.122528) (xy 86.731602 -353.086162)
			(xy 86.731602 -353.085654) (xy 86.732095 -353.049288) (xy 86.740406 -352.977032) (xy 86.756914 -352.906198)
			(xy 86.768686 -352.871786) (xy 86.777091 -352.846771) (xy 86.78616 -352.79479) (xy 86.786161 -352.742025)
			(xy 86.777094 -352.690043) (xy 86.768686 -352.66503) (xy 86.756903 -352.630622) (xy 86.740404 -352.559786)
			(xy 86.732102 -352.487528) (xy 86.731602 -352.451162) (xy 86.731602 -352.450654) (xy 86.732095 -352.414288)
			(xy 86.740406 -352.342032) (xy 86.756914 -352.271198) (xy 86.768686 -352.236786) (xy 86.777091 -352.211771)
			(xy 86.78616 -352.15979) (xy 86.786161 -352.107025) (xy 86.777094 -352.055043) (xy 86.768686 -352.03003)
			(xy 86.756903 -351.995622) (xy 86.740404 -351.924786) (xy 86.732102 -351.852528) (xy 86.731602 -351.816162)
			(xy 86.731602 -351.815654) (xy 86.732095 -351.779288) (xy 86.740406 -351.707032) (xy 86.756914 -351.636198)
			(xy 86.768686 -351.601786) (xy 86.777091 -351.576771) (xy 86.78616 -351.52479) (xy 86.786161 -351.472025)
			(xy 86.777094 -351.420043) (xy 86.768686 -351.39503) (xy 86.756903 -351.360622) (xy 86.740404 -351.289786)
			(xy 86.732102 -351.217528) (xy 86.731602 -351.181162) (xy 86.731602 -351.180654) (xy 86.732095 -351.144288)
			(xy 86.740406 -351.072032) (xy 86.756914 -351.001198) (xy 86.768686 -350.966786) (xy 86.777091 -350.941771)
			(xy 86.78616 -350.88979) (xy 86.786161 -350.837025) (xy 86.777094 -350.785043) (xy 86.768686 -350.76003)
			(xy 86.75692 -350.725661) (xy 86.740428 -350.65491) (xy 86.732115 -350.58274) (xy 86.731602 -350.546416)
			(xy 86.731602 -350.545908) (xy 86.732153 -350.510263) (xy 86.740134 -350.43942) (xy 86.755996 -350.369917)
			(xy 86.77954 -350.302626) (xy 86.81047 -350.238395) (xy 86.848397 -350.17803) (xy 86.892844 -350.122291)
			(xy 86.943252 -350.071879) (xy 86.998987 -350.027427) (xy 87.059349 -349.989495) (xy 87.123578 -349.95856)
			(xy 87.190867 -349.935011) (xy 87.260369 -349.919143) (xy 87.331211 -349.911156) (xy 87.366856 -349.910654)
			(xy 87.367364 -349.910654) (xy 87.403687 -349.911166) (xy 87.475857 -349.919483) (xy 87.546607 -349.935979)
			(xy 87.580978 -349.947738) (xy 87.605991 -349.956148) (xy 87.657973 -349.965216) (xy 87.710739 -349.965216)
			(xy 87.762721 -349.956148) (xy 87.787734 -349.947738) (xy 87.822146 -349.935967) (xy 87.89298 -349.919463)
			(xy 87.965236 -349.911156) (xy 88.001602 -349.910654) (xy 88.00211 -349.910654) (xy 88.038476 -349.911154)
			(xy 88.110732 -349.919462) (xy 88.181566 -349.935967) (xy 88.215978 -349.947738) (xy 88.240991 -349.956148)
			(xy 88.292973 -349.965216) (xy 88.345739 -349.965216) (xy 88.397721 -349.956148) (xy 88.422734 -349.947738)
			(xy 88.457146 -349.935967) (xy 88.52798 -349.919463) (xy 88.600236 -349.911156) (xy 88.636602 -349.910654)
			(xy 88.63711 -349.910654) (xy 88.673476 -349.911154) (xy 88.745732 -349.919462) (xy 88.816566 -349.935967)
			(xy 88.850978 -349.947738) (xy 88.875991 -349.956148) (xy 88.927973 -349.965216) (xy 88.980739 -349.965216)
			(xy 89.032721 -349.956148) (xy 89.057734 -349.947738) (xy 89.092146 -349.935967) (xy 89.16298 -349.919463)
			(xy 89.235236 -349.911156) (xy 89.271602 -349.910654) (xy 89.27211 -349.910654) (xy 89.308476 -349.911154)
			(xy 89.380732 -349.919462) (xy 89.451566 -349.935967) (xy 89.485978 -349.947738) (xy 89.510991 -349.956148)
			(xy 89.562973 -349.965216) (xy 89.615739 -349.965216) (xy 89.667721 -349.956148) (xy 89.692734 -349.947738)
			(xy 89.727146 -349.935967) (xy 89.79798 -349.919463) (xy 89.870236 -349.911156) (xy 89.906602 -349.910654)
			(xy 89.90711 -349.910654) (xy 89.943476 -349.911154) (xy 90.015732 -349.919462) (xy 90.086566 -349.935967)
			(xy 90.120978 -349.947738) (xy 90.145991 -349.956148) (xy 90.197973 -349.965216) (xy 90.250739 -349.965216)
			(xy 90.302721 -349.956148) (xy 90.327734 -349.947738) (xy 90.362146 -349.935967) (xy 90.43298 -349.919463)
			(xy 90.505236 -349.911156) (xy 90.541602 -349.910654) (xy 90.54211 -349.910654) (xy 90.578476 -349.911154)
			(xy 90.650732 -349.919462) (xy 90.721566 -349.935967) (xy 90.755978 -349.947738) (xy 90.780991 -349.956148)
			(xy 90.832973 -349.965216) (xy 90.885739 -349.965216) (xy 90.937721 -349.956148) (xy 90.962734 -349.947738)
			(xy 90.997146 -349.935967) (xy 91.06798 -349.919463) (xy 91.140236 -349.911156) (xy 91.176602 -349.910654)
			(xy 91.17711 -349.910654) (xy 91.213476 -349.911154) (xy 91.285732 -349.919462) (xy 91.356566 -349.935967)
			(xy 91.390978 -349.947738) (xy 91.415991 -349.956148) (xy 91.467973 -349.965216) (xy 91.520739 -349.965216)
			(xy 91.572721 -349.956148) (xy 91.597734 -349.947738) (xy 91.632146 -349.935967) (xy 91.70298 -349.919463)
			(xy 91.775236 -349.911156) (xy 91.811602 -349.910654) (xy 91.81211 -349.910654) (xy 91.848476 -349.911154)
			(xy 91.920732 -349.919462) (xy 91.991566 -349.935967) (xy 92.025978 -349.947738) (xy 92.050991 -349.956148)
			(xy 92.102973 -349.965216) (xy 92.155739 -349.965216) (xy 92.207721 -349.956148) (xy 92.232734 -349.947738)
			(xy 92.267146 -349.935967) (xy 92.33798 -349.919463) (xy 92.410236 -349.911156) (xy 92.446602 -349.910654)
			(xy 92.44711 -349.910654) (xy 92.483476 -349.911154) (xy 92.555732 -349.919462) (xy 92.626566 -349.935967)
			(xy 92.660978 -349.947738) (xy 92.685991 -349.956148) (xy 92.737973 -349.965216) (xy 92.790739 -349.965216)
			(xy 92.842721 -349.956148) (xy 92.867734 -349.947738) (xy 92.902146 -349.935967) (xy 92.97298 -349.919463)
			(xy 93.045236 -349.911156) (xy 93.081602 -349.910654) (xy 93.08211 -349.910654) (xy 93.118476 -349.911154)
			(xy 93.190732 -349.919462) (xy 93.261566 -349.935967) (xy 93.295978 -349.947738) (xy 93.320991 -349.956148)
			(xy 93.372973 -349.965216) (xy 93.425739 -349.965216) (xy 93.477721 -349.956148) (xy 93.502734 -349.947738)
			(xy 93.537105 -349.935979) (xy 93.607855 -349.919484) (xy 93.680025 -349.911168) (xy 93.716348 -349.910654)
			(xy 93.716856 -349.910654) (xy 93.752504 -349.911169) (xy 93.823351 -349.919147) (xy 93.892859 -349.935007)
			(xy 93.960154 -349.958551) (xy 94.02439 -349.989482) (xy 94.084759 -350.027411) (xy 94.140501 -350.07186)
			(xy 94.190916 -350.122272) (xy 94.235368 -350.178012) (xy 94.273301 -350.238378) (xy 94.304235 -350.302612)
			(xy 94.327783 -350.369906) (xy 94.343647 -350.439414) (xy 94.351629 -350.510261) (xy 94.35211 -350.545908)
			(xy 94.35211 -350.546416) (xy 94.351581 -350.582739) (xy 94.34327 -350.654908) (xy 94.326781 -350.725658)
			(xy 94.315026 -350.76003) (xy 94.306612 -350.785042) (xy 94.297545 -350.837024) (xy 94.297546 -350.889791)
			(xy 94.306616 -350.941773) (xy 94.315026 -350.966786) (xy 94.326786 -351.001201) (xy 94.343294 -351.072034)
			(xy 94.351605 -351.144289) (xy 94.35211 -351.180654) (xy 94.35211 -351.181162) (xy 94.351593 -351.217527)
			(xy 94.343292 -351.289783) (xy 94.326793 -351.360617) (xy 94.315026 -351.39503) (xy 94.306612 -351.420042)
			(xy 94.297545 -351.472024) (xy 94.297546 -351.524791) (xy 94.306616 -351.576773) (xy 94.315026 -351.601786)
			(xy 94.326797 -351.636153) (xy 94.343287 -351.706905) (xy 94.351598 -351.779076) (xy 94.35211 -351.8154)
			(xy 94.35211 -351.815908) (xy 94.351627 -351.850219) (xy 94.344223 -351.91844) (xy 94.329512 -351.985467)
			(xy 94.307667 -352.050519) (xy 94.27894 -352.112839) (xy 94.243668 -352.171701) (xy 94.202259 -352.226421)
			(xy 94.155196 -352.276362) (xy 94.103027 -352.320942) (xy 94.046359 -352.359642) (xy 94.016322 -352.376232)
			(xy 94.007771 -352.381305) (xy 93.9951 -352.396601) (xy 93.989225 -352.415574) (xy 93.989652 -352.425508)
			(xy 93.991176 -352.460306) (xy 93.990727 -352.486168) (xy 93.983745 -352.537418) (xy 93.969896 -352.587253)
			(xy 93.949435 -352.634758) (xy 93.922738 -352.679059) (xy 93.890296 -352.719343) (xy 93.871796 -352.73742)
			(xy 93.863922 -352.744786) (xy 93.855794 -352.763836) (xy 93.855794 -352.859086) (xy 93.863922 -352.877882)
			(xy 93.871796 -352.885248) (xy 93.890305 -352.903358) (xy 93.922813 -352.943663) (xy 93.949569 -352.987995)
			(xy 93.970082 -353.03554) (xy 93.983975 -353.085422) (xy 93.990991 -353.136726) (xy 93.99143 -353.162616)
			(xy 93.99099 -353.189987) (xy 93.983169 -353.244168) (xy 93.967674 -353.296672) (xy 93.944826 -353.346419)
			(xy 93.915095 -353.392384) (xy 93.89745 -353.413314) (xy 93.891354 -353.420426) (xy 93.885004 -353.437444)
			(xy 93.885004 -353.522788) (xy 93.891354 -353.539806) (xy 93.89745 -353.546918) (xy 93.915056 -353.567877)
			(xy 93.944775 -353.613841) (xy 93.967618 -353.663582) (xy 93.983116 -353.716077) (xy 93.990952 -353.770249)
			(xy 93.99143 -353.797616) (xy 93.990974 -353.823944) (xy 93.983748 -353.876102) (xy 93.969409 -353.926768)
			(xy 93.948229 -353.974977) (xy 93.920612 -354.01981) (xy 93.887085 -354.060413) (xy 93.867986 -354.07854)
			(xy 93.860874 -354.085144) (xy 93.852492 -354.102416) (xy 93.846142 -354.191316) (xy 93.851984 -354.209858)
			(xy 93.85808 -354.217478) (xy 93.874192 -354.237978) (xy 93.901292 -354.282522) (xy 93.922072 -354.330342)
			(xy 93.936146 -354.380546) (xy 93.943251 -354.4322) (xy 93.943678 -354.45827) (xy 93.943217 -354.485523)
			(xy 93.935463 -354.539476) (xy 93.920109 -354.591776) (xy 93.897468 -354.641358) (xy 93.868 -354.687213)
			(xy 93.832306 -354.728406) (xy 93.791113 -354.7641) (xy 93.745258 -354.793568) (xy 93.695676 -354.816209)
			(xy 93.643376 -354.831563) (xy 93.589423 -354.839317) (xy 93.56217 -354.839778) (xy 93.533989 -354.839267)
			(xy 93.478242 -354.830966) (xy 93.42432 -354.814563) (xy 93.373394 -354.790415) (xy 93.326569 -354.759046)
			(xy 93.305376 -354.740464) (xy 93.298264 -354.73386) (xy 93.280738 -354.727256) (xy 93.193108 -354.727256)
			(xy 93.175582 -354.734114) (xy 93.16847 -354.740464) (xy 93.147286 -354.759166) (xy 93.100394 -354.790697)
			(xy 93.049364 -354.814968) (xy 92.995313 -354.831449) (xy 92.939422 -354.839777) (xy 92.911168 -354.840286)
			(xy 92.883666 -354.839821) (xy 92.829232 -354.831924) (xy 92.776495 -354.816297) (xy 92.726546 -354.793264)
			(xy 92.68042 -354.763302) (xy 92.63907 -354.727031) (xy 92.620846 -354.706428) (xy 92.613988 -354.698046)
			(xy 92.594938 -354.688902) (xy 92.498926 -354.685092) (xy 92.479622 -354.692712) (xy 92.472002 -354.700332)
			(xy 92.450374 -354.720979) (xy 92.401929 -354.756021) (xy 92.348609 -354.783073) (xy 92.29172 -354.801472)
			(xy 92.232657 -354.810766) (xy 92.202762 -354.81133) (xy 92.1747 -354.810835) (xy 92.119184 -354.802595)
			(xy 92.065474 -354.786314) (xy 92.014727 -354.762341) (xy 91.968039 -354.731195) (xy 91.926415 -354.693547)
			(xy 91.890754 -354.650209) (xy 91.875864 -354.626418) (xy 91.86926 -354.61575) (xy 91.84767 -354.602796)
			(xy 91.73845 -354.5967) (xy 91.71559 -354.607368) (xy 91.70797 -354.617528) (xy 91.689791 -354.640507)
			(xy 91.647619 -354.681181) (xy 91.599726 -354.71493) (xy 91.547235 -354.740961) (xy 91.491383 -354.758662)
			(xy 91.433481 -354.767617) (xy 91.404186 -354.76815) (xy 91.374745 -354.767578) (xy 91.316562 -354.758542)
			(xy 91.260458 -354.740672) (xy 91.207767 -354.714393) (xy 91.15974 -354.680328) (xy 91.138248 -354.6602)
			(xy 91.131136 -354.653342) (xy 91.112848 -354.645976) (xy 91.02217 -354.645976) (xy 91.003882 -354.653342)
			(xy 90.99677 -354.6602) (xy 90.975265 -354.680314) (xy 90.927241 -354.714383) (xy 90.874554 -354.74067)
			(xy 90.818454 -354.758551) (xy 90.760272 -354.767602) (xy 90.730832 -354.76815) (xy 90.702652 -354.767668)
			(xy 90.64691 -354.759354) (xy 90.592996 -354.742931) (xy 90.542085 -354.718756) (xy 90.495283 -354.687356)
			(xy 90.453608 -354.649413) (xy 90.417969 -354.605753) (xy 90.389138 -354.557326) (xy 90.367745 -354.505184)
			(xy 90.354253 -354.450464) (xy 90.351102 -354.422456) (xy 90.34907 -354.402644) (xy 90.320368 -354.376228)
			(xy 89.897966 -354.376228) (xy 89.869264 -354.402644) (xy 89.867232 -354.422456) (xy 89.864083 -354.450461)
			(xy 89.850594 -354.505176) (xy 89.829201 -354.557311) (xy 89.800369 -354.605731) (xy 89.764727 -354.649382)
			(xy 89.72305 -354.687313) (xy 89.676246 -354.718699) (xy 89.625333 -354.742856) (xy 89.571419 -354.75926)
			(xy 89.515679 -354.767551) (xy 89.459325 -354.767551) (xy 89.403585 -354.75926) (xy 89.349671 -354.742856)
			(xy 89.298758 -354.718699) (xy 89.251954 -354.687313) (xy 89.210277 -354.649382) (xy 89.174635 -354.605731)
			(xy 89.145803 -354.557311) (xy 89.12441 -354.505176) (xy 89.110921 -354.450461) (xy 89.107772 -354.422456)
			(xy 89.10574 -354.402644) (xy 89.077038 -354.376228) (xy 89.03462 -354.376228) (xy 89.024597 -354.376637)
			(xy 89.006075 -354.384305) (xy 88.991901 -354.398482) (xy 88.984235 -354.417005) (xy 88.98382 -354.427028)
			(xy 88.98382 -354.429568) (xy 88.983315 -354.45682) (xy 88.975563 -354.510768) (xy 88.960211 -354.563065)
			(xy 88.937573 -354.612644) (xy 88.90811 -354.658497) (xy 88.87242 -354.699689) (xy 88.831232 -354.735383)
			(xy 88.785383 -354.764852) (xy 88.735806 -354.787496) (xy 88.683511 -354.802853) (xy 88.629563 -354.810612)
			(xy 88.602312 -354.811076) (xy 88.572261 -354.810494) (xy 88.512904 -354.80106) (xy 88.455759 -354.78244)
			(xy 88.402239 -354.755094) (xy 88.353666 -354.719697) (xy 88.332056 -354.698808) (xy 88.325452 -354.692204)
			(xy 88.308434 -354.684584) (xy 88.222328 -354.679504) (xy 88.204548 -354.685092) (xy 88.197182 -354.690934)
			(xy 88.176892 -354.706404) (xy 88.13298 -354.732385) (xy 88.086 -354.752287) (xy 88.036787 -354.765755)
			(xy 87.986219 -354.772551) (xy 87.960708 -354.772976) (xy 87.931827 -354.772419) (xy 87.874725 -354.763719)
			(xy 87.819589 -354.746503) (xy 87.767682 -354.721164) (xy 87.720192 -354.688283) (xy 87.698834 -354.668836)
			(xy 87.691976 -354.662486) (xy 87.674958 -354.655374) (xy 87.588852 -354.652834) (xy 87.571326 -354.65893)
			(xy 87.56396 -354.664772) (xy 87.543298 -354.681482) (xy 87.498197 -354.709584) (xy 87.449634 -354.731159)
			(xy 87.398549 -354.74579) (xy 87.345927 -354.753195) (xy 87.319358 -354.753672) (xy 87.292104 -354.753261)
			(xy 87.238152 -354.745498) (xy 87.185853 -354.730136) (xy 87.136274 -354.707487) (xy 87.090422 -354.678013)
			(xy 87.049231 -354.642314) (xy 87.01354 -354.601116) (xy 86.984076 -354.555258) (xy 86.961437 -354.505673)
			(xy 86.946085 -354.453372) (xy 86.938333 -354.399418) (xy 86.93785 -354.372164) (xy 86.938465 -354.340853)
			(xy 86.948677 -354.279071) (xy 86.95817 -354.249228) (xy 86.960971 -354.239661) (xy 86.959753 -354.21978)
			(xy 86.951059 -354.201859) (xy 86.943946 -354.194872) (xy 86.919253 -354.172305) (xy 86.874286 -354.122773)
			(xy 86.834775 -354.068789) (xy 86.801159 -354.01095) (xy 86.773809 -353.949897) (xy 86.75303 -353.886308)
			(xy 86.739051 -353.820886) (xy 86.732028 -353.754357) (xy 86.731602 -353.720908) (xy 82.404625 -353.720908)
			(xy 82.401319 -353.722586) (xy 82.355982 -353.737298) (xy 82.308909 -353.74479) (xy 82.285078 -353.745292)
			(xy 66.739008 -353.745292) (xy 66.715328 -353.74482) (xy 66.668538 -353.737487) (xy 66.623443 -353.723011)
			(xy 66.581127 -353.70174) (xy 66.542607 -353.674185) (xy 66.525394 -353.657916) (xy 66.523108 -353.655376)
			(xy 66.522854 -353.655376) (xy 63.876428 -351.00895) (xy 63.873142 -351.005541) (xy 63.867772 -350.997742)
			(xy 63.86576 -350.993456) (xy 63.843154 -350.942402) (xy 63.841177 -350.938141) (xy 63.835944 -350.930342)
			(xy 63.83274 -350.926908) (xy 63.097664 -350.191832) (xy 63.089282 -350.188022) (xy 63.065498 -350.176529)
			(xy 63.021944 -350.146647) (xy 63.002668 -350.128586) (xy 63.000382 -350.126046) (xy 63.000128 -350.126046)
			(xy 62.091824 -349.217742) (xy 62.075209 -349.20043) (xy 62.04702 -349.161604) (xy 62.025244 -349.11885)
			(xy 62.010414 -349.073219) (xy 62.002896 -349.025832) (xy 62.002416 -349.001842) (xy 57.826148 -349.001842)
			(xy 57.826148 -349.607632) (xy 58.767978 -349.607632) (xy 58.772049 -349.55201) (xy 58.784175 -349.497573)
			(xy 58.804098 -349.445482) (xy 58.831394 -349.396847) (xy 58.86548 -349.352704) (xy 58.905629 -349.313995)
			(xy 58.950987 -349.281544) (xy 59.000587 -349.256043) (xy 59.053371 -349.238036) (xy 59.108214 -349.227906)
			(xy 59.163948 -349.225869) (xy 59.219385 -349.231969) (xy 59.273342 -349.246075) (xy 59.324671 -349.267887)
			(xy 59.372277 -349.296941) (xy 59.415145 -349.332616) (xy 59.452362 -349.374153) (xy 59.483135 -349.420666)
			(xy 59.506807 -349.471163) (xy 59.522875 -349.52457) (xy 59.530995 -349.579746) (xy 59.531504 -349.607632)
			(xy 59.530995 -349.635518) (xy 59.522875 -349.690694) (xy 59.506807 -349.744101) (xy 59.483135 -349.794598)
			(xy 59.452362 -349.841111) (xy 59.415145 -349.882648) (xy 59.372277 -349.918323) (xy 59.324671 -349.947377)
			(xy 59.273342 -349.969189) (xy 59.219385 -349.983295) (xy 59.163948 -349.989395) (xy 59.108214 -349.987358)
			(xy 59.053371 -349.977228) (xy 59.000587 -349.959221) (xy 58.950987 -349.93372) (xy 58.905629 -349.901269)
			(xy 58.86548 -349.86256) (xy 58.831394 -349.818417) (xy 58.804098 -349.769782) (xy 58.784175 -349.717691)
			(xy 58.772049 -349.663254) (xy 58.767978 -349.607632) (xy 57.826148 -349.607632) (xy 57.826148 -350.502982)
			(xy 58.188858 -350.502982) (xy 58.192929 -350.44736) (xy 58.205055 -350.392923) (xy 58.224978 -350.340832)
			(xy 58.252274 -350.292197) (xy 58.28636 -350.248054) (xy 58.326509 -350.209345) (xy 58.371867 -350.176894)
			(xy 58.421467 -350.151393) (xy 58.474251 -350.133386) (xy 58.529094 -350.123256) (xy 58.584828 -350.121219)
			(xy 58.640265 -350.127319) (xy 58.694222 -350.141425) (xy 58.745551 -350.163237) (xy 58.793157 -350.192291)
			(xy 58.836025 -350.227966) (xy 58.873242 -350.269503) (xy 58.904015 -350.316016) (xy 58.927687 -350.366513)
			(xy 58.943755 -350.41992) (xy 58.951875 -350.475096) (xy 58.952384 -350.502982) (xy 58.951875 -350.530868)
			(xy 58.943755 -350.586044) (xy 58.927687 -350.639451) (xy 58.904015 -350.689948) (xy 58.873242 -350.736461)
			(xy 58.836025 -350.777998) (xy 58.793157 -350.813673) (xy 58.745551 -350.842727) (xy 58.694222 -350.864539)
			(xy 58.640265 -350.878645) (xy 58.584828 -350.884745) (xy 58.529094 -350.882708) (xy 58.474251 -350.872578)
			(xy 58.421467 -350.854571) (xy 58.371867 -350.82907) (xy 58.326509 -350.796619) (xy 58.28636 -350.75791)
			(xy 58.252274 -350.713767) (xy 58.224978 -350.665132) (xy 58.205055 -350.613041) (xy 58.192929 -350.558604)
			(xy 58.188858 -350.502982) (xy 57.826148 -350.502982) (xy 57.826148 -351.178622) (xy 59.527694 -351.178622)
			(xy 59.528195 -351.151148) (xy 59.536083 -351.096769) (xy 59.5517 -351.044087) (xy 59.574722 -350.994194)
			(xy 59.60467 -350.948124) (xy 59.622436 -350.927162) (xy 59.628532 -350.92005) (xy 59.634882 -350.903032)
			(xy 59.634882 -350.81718) (xy 59.628532 -350.800162) (xy 59.622436 -350.79305) (xy 59.604658 -350.7721)
			(xy 59.574737 -350.726014) (xy 59.551728 -350.676116) (xy 59.536106 -350.623437) (xy 59.528192 -350.569063)
			(xy 59.527694 -350.54159) (xy 59.52818 -350.514339) (xy 59.535936 -350.460391) (xy 59.551291 -350.408096)
			(xy 59.573933 -350.358519) (xy 59.603399 -350.312669) (xy 59.63909 -350.271478) (xy 59.680281 -350.235787)
			(xy 59.726131 -350.206321) (xy 59.775708 -350.183679) (xy 59.828003 -350.168324) (xy 59.881951 -350.160568)
			(xy 59.936453 -350.160568) (xy 59.990401 -350.168324) (xy 60.042696 -350.183679) (xy 60.092273 -350.206321)
			(xy 60.138123 -350.235787) (xy 60.179314 -350.271478) (xy 60.215005 -350.312669) (xy 60.244471 -350.358519)
			(xy 60.267113 -350.408096) (xy 60.282468 -350.460391) (xy 60.290224 -350.514339) (xy 60.29071 -350.54159)
			(xy 60.290215 -350.569064) (xy 60.282325 -350.623443) (xy 60.266707 -350.676126) (xy 60.264065 -350.681852)
			(xy 60.532475 -350.681852) (xy 60.532475 -350.627348) (xy 60.540232 -350.573398) (xy 60.555589 -350.521102)
			(xy 60.578231 -350.471523) (xy 60.607699 -350.425671) (xy 60.643393 -350.38448) (xy 60.684586 -350.348788)
			(xy 60.730439 -350.319322) (xy 60.780018 -350.296682) (xy 60.832316 -350.281329) (xy 60.886266 -350.273574)
			(xy 60.913518 -350.273112) (xy 60.938754 -350.273499) (xy 60.988788 -350.28012) (xy 61.037508 -350.293296)
			(xy 61.08406 -350.312796) (xy 61.10605 -350.325182) (xy 61.115702 -350.331024) (xy 61.1378 -350.333056)
			(xy 61.232288 -350.299528) (xy 61.24829 -350.284034) (xy 61.252354 -350.27362) (xy 61.263083 -350.246857)
			(xy 61.291365 -350.196615) (xy 61.326889 -350.151205) (xy 61.368846 -350.111661) (xy 61.416279 -350.078885)
			(xy 61.468106 -350.053625) (xy 61.523145 -350.036457) (xy 61.580142 -350.027771) (xy 61.60897 -350.02724)
			(xy 61.636224 -350.027683) (xy 61.690178 -350.035437) (xy 61.74248 -350.050792) (xy 61.792063 -350.073435)
			(xy 61.837918 -350.102904) (xy 61.879113 -350.1386) (xy 61.914807 -350.179796) (xy 61.944274 -350.225653)
			(xy 61.966914 -350.275237) (xy 61.982266 -350.327539) (xy 61.990018 -350.381494) (xy 61.990478 -350.408748)
			(xy 61.989825 -350.440311) (xy 61.979435 -350.502577) (xy 61.958947 -350.562286) (xy 61.944504 -350.590358)
			(xy 61.939678 -350.599248) (xy 61.937646 -350.618806) (xy 61.9633 -350.706944) (xy 61.975746 -350.722438)
			(xy 61.984636 -350.727518) (xy 62.009715 -350.742104) (xy 62.0556 -350.777599) (xy 62.095578 -350.819635)
			(xy 62.128727 -350.867242) (xy 62.154282 -350.919322) (xy 62.171652 -350.974672) (xy 62.180437 -351.032014)
			(xy 62.180978 -351.06102) (xy 62.180492 -351.088271) (xy 62.172736 -351.142219) (xy 62.157381 -351.194514)
			(xy 62.134739 -351.244091) (xy 62.105273 -351.289941) (xy 62.069582 -351.331132) (xy 62.028391 -351.366823)
			(xy 61.982541 -351.396289) (xy 61.932964 -351.418931) (xy 61.880669 -351.434286) (xy 61.826721 -351.442042)
			(xy 61.772219 -351.442042) (xy 61.718271 -351.434286) (xy 61.665976 -351.418931) (xy 61.616399 -351.396289)
			(xy 61.570549 -351.366823) (xy 61.529358 -351.331132) (xy 61.493667 -351.289941) (xy 61.464201 -351.244091)
			(xy 61.441559 -351.194514) (xy 61.426204 -351.142219) (xy 61.418448 -351.088271) (xy 61.417962 -351.06102)
			(xy 61.41861 -351.029457) (xy 61.429003 -350.967191) (xy 61.449493 -350.907483) (xy 61.463936 -350.87941)
			(xy 61.468762 -350.87052) (xy 61.470794 -350.850962) (xy 61.44514 -350.762824) (xy 61.432694 -350.74733)
			(xy 61.423804 -350.74225) (xy 61.416438 -350.738186) (xy 61.406786 -350.732344) (xy 61.384688 -350.730312)
			(xy 61.2902 -350.76384) (xy 61.274198 -350.779334) (xy 61.270134 -350.789748) (xy 61.259452 -350.81653)
			(xy 61.23116 -350.86677) (xy 61.195627 -350.912178) (xy 61.153663 -350.951719) (xy 61.106224 -350.984492)
			(xy 61.054392 -351.009749) (xy 60.999348 -351.026915) (xy 60.942347 -351.035598) (xy 60.913518 -351.036128)
			(xy 60.886266 -351.035626) (xy 60.832316 -351.027871) (xy 60.780018 -351.012518) (xy 60.730439 -350.989878)
			(xy 60.684586 -350.960412) (xy 60.643393 -350.92472) (xy 60.607699 -350.883529) (xy 60.578231 -350.837677)
			(xy 60.555589 -350.788098) (xy 60.540232 -350.735802) (xy 60.532475 -350.681852) (xy 60.264065 -350.681852)
			(xy 60.243684 -350.726018) (xy 60.213734 -350.772088) (xy 60.195968 -350.79305) (xy 60.189872 -350.800162)
			(xy 60.183522 -350.81718) (xy 60.183522 -350.903032) (xy 60.189872 -350.92005) (xy 60.195968 -350.927162)
			(xy 60.213706 -350.948145) (xy 60.243632 -350.994222) (xy 60.266649 -351.044111) (xy 60.282281 -351.096783)
			(xy 60.290206 -351.151151) (xy 60.29071 -351.178622) (xy 60.290224 -351.205873) (xy 60.282468 -351.259821)
			(xy 60.267113 -351.312116) (xy 60.244471 -351.361693) (xy 60.215005 -351.407543) (xy 60.179314 -351.448734)
			(xy 60.138123 -351.484425) (xy 60.092273 -351.513891) (xy 60.042696 -351.536533) (xy 59.990401 -351.551888)
			(xy 59.936453 -351.559644) (xy 59.881951 -351.559644) (xy 59.828003 -351.551888) (xy 59.775708 -351.536533)
			(xy 59.726131 -351.513891) (xy 59.680281 -351.484425) (xy 59.63909 -351.448734) (xy 59.603399 -351.407543)
			(xy 59.573933 -351.361693) (xy 59.551291 -351.312116) (xy 59.535936 -351.259821) (xy 59.52818 -351.205873)
			(xy 59.527694 -351.178622) (xy 57.826148 -351.178622) (xy 57.826148 -353.80295) (xy 57.825783 -353.825112)
			(xy 57.8194 -353.868975) (xy 57.813448 -353.890326) (xy 57.811416 -353.897438) (xy 57.811416 -356.303834)
			(xy 57.810965 -356.31384) (xy 57.80324 -356.332303) (xy 57.79643 -356.339648) (xy 55.331868 -358.80421)
			(xy 55.324489 -358.810965) (xy 55.306045 -358.818667) (xy 55.296054 -358.819196) (xy 53.105558 -358.819196)
			(xy 53.101748 -358.822752) (xy 47.321724 -358.822752) (xy 47.312834 -358.826308) (xy 47.2948 -358.832912)
			(xy 45.102018 -358.832912) (xy 45.09197 -358.833261) (xy 45.073375 -358.840864) (xy 45.06595 -358.847644)
			(xy 43.954192 -359.959402) (xy 43.946804 -359.966145) (xy 43.928367 -359.973854) (xy 43.918378 -359.974388)
			(xy 41.051734 -359.974388) (xy 41.041729 -359.973934) (xy 41.023267 -359.966209) (xy 41.01592 -359.959402)
			(xy 36.007548 -354.95103) (xy 36.000122 -354.944223) (xy 35.981543 -354.936483) (xy 35.97148 -354.936044)
			(xy 32.381444 -354.936044) (xy 32.371478 -354.93556) (xy 32.353042 -354.92799) (xy 32.34563 -354.921312)
			(xy 29.656278 -352.23196) (xy 29.649518 -352.224585) (xy 29.64182 -352.206138) (xy 29.641292 -352.196146)
			(xy 29.641292 -349.489014) (xy 29.640944 -349.478966) (xy 29.63334 -349.460371) (xy 29.62656 -349.452946)
			(xy 29.485336 -349.311722) (xy 29.477915 -349.304908) (xy 29.459332 -349.297172) (xy 29.449268 -349.296736)
			(xy 29.032962 -349.296736) (xy 29.008989 -349.296319) (xy 28.961634 -349.288813) (xy 28.916035 -349.273991)
			(xy 28.873317 -349.252219) (xy 28.83453 -349.224033) (xy 28.80063 -349.190127) (xy 28.772451 -349.151335)
			(xy 28.750687 -349.108613) (xy 28.735874 -349.063012) (xy 28.728377 -349.015655) (xy 28.727908 -348.991682)
			(xy 24.901652 -348.991682) (xy 24.901652 -349.607632) (xy 25.493978 -349.607632) (xy 25.498049 -349.55201)
			(xy 25.510175 -349.497573) (xy 25.530098 -349.445482) (xy 25.557394 -349.396847) (xy 25.59148 -349.352704)
			(xy 25.631629 -349.313995) (xy 25.676987 -349.281544) (xy 25.726587 -349.256043) (xy 25.779371 -349.238036)
			(xy 25.834214 -349.227906) (xy 25.889948 -349.225869) (xy 25.945385 -349.231969) (xy 25.999342 -349.246075)
			(xy 26.050671 -349.267887) (xy 26.098277 -349.296941) (xy 26.141145 -349.332616) (xy 26.178362 -349.374153)
			(xy 26.209135 -349.420666) (xy 26.232807 -349.471163) (xy 26.248875 -349.52457) (xy 26.256995 -349.579746)
			(xy 26.257504 -349.607632) (xy 26.256995 -349.635518) (xy 26.248875 -349.690694) (xy 26.232807 -349.744101)
			(xy 26.209135 -349.794598) (xy 26.178362 -349.841111) (xy 26.141145 -349.882648) (xy 26.098277 -349.918323)
			(xy 26.050671 -349.947377) (xy 25.999342 -349.969189) (xy 25.945385 -349.983295) (xy 25.889948 -349.989395)
			(xy 25.834214 -349.987358) (xy 25.779371 -349.977228) (xy 25.726587 -349.959221) (xy 25.676987 -349.93372)
			(xy 25.631629 -349.901269) (xy 25.59148 -349.86256) (xy 25.557394 -349.818417) (xy 25.530098 -349.769782)
			(xy 25.510175 -349.717691) (xy 25.498049 -349.663254) (xy 25.493978 -349.607632) (xy 24.901652 -349.607632)
			(xy 24.901652 -350.119442) (xy 24.90202 -350.128877) (xy 24.908829 -350.146474) (xy 24.921544 -350.160414)
			(xy 24.929846 -350.164908) (xy 25.01138 -350.205294) (xy 25.019088 -350.208736) (xy 25.035811 -350.210945)
			(xy 25.044146 -350.209612) (xy 25.05583 -350.207072) (xy 25.076362 -350.190967) (xy 25.120966 -350.163884)
			(xy 25.168837 -350.143118) (xy 25.219088 -350.129055) (xy 25.270785 -350.121955) (xy 25.296876 -350.121474)
			(xy 25.324131 -350.121935) (xy 25.378087 -350.12969) (xy 25.430391 -350.145045) (xy 25.479976 -350.167687)
			(xy 25.525835 -350.197156) (xy 25.567032 -350.232851) (xy 25.60273 -350.274046) (xy 25.632202 -350.319903)
			(xy 25.654847 -350.369487) (xy 25.670205 -350.421789) (xy 25.677963 -350.475745) (xy 25.677963 -350.530255)
			(xy 25.670205 -350.584211) (xy 25.654847 -350.636513) (xy 25.632202 -350.686097) (xy 25.60273 -350.731954)
			(xy 25.567032 -350.773149) (xy 25.525835 -350.808844) (xy 25.479976 -350.838313) (xy 25.430391 -350.860955)
			(xy 25.378087 -350.87631) (xy 25.324131 -350.884065) (xy 25.296876 -350.88449) (xy 25.27191 -350.884081)
			(xy 25.222405 -350.877567) (xy 25.174173 -350.864654) (xy 25.128036 -350.845561) (xy 25.084782 -350.820615)
			(xy 25.06472 -350.80575) (xy 25.0601 -350.80239) (xy 25.04971 -350.797649) (xy 25.044146 -350.796352)
			(xy 25.035812 -350.794965) (xy 25.019071 -350.797172) (xy 25.01138 -350.80067) (xy 24.929846 -350.841056)
			(xy 24.921605 -350.845637) (xy 24.908904 -350.859547) (xy 24.902079 -350.877104) (xy 24.901652 -350.886522)
			(xy 24.901652 -351.178622) (xy 26.253694 -351.178622) (xy 26.254195 -351.151148) (xy 26.262083 -351.096769)
			(xy 26.2777 -351.044087) (xy 26.300722 -350.994194) (xy 26.33067 -350.948124) (xy 26.348436 -350.927162)
			(xy 26.354532 -350.92005) (xy 26.360882 -350.903032) (xy 26.360882 -350.81718) (xy 26.354532 -350.800162)
			(xy 26.348436 -350.79305) (xy 26.330658 -350.7721) (xy 26.300737 -350.726014) (xy 26.277728 -350.676116)
			(xy 26.262106 -350.623437) (xy 26.254192 -350.569063) (xy 26.253694 -350.54159) (xy 26.25418 -350.514339)
			(xy 26.261936 -350.460391) (xy 26.277291 -350.408096) (xy 26.299933 -350.358519) (xy 26.329399 -350.312669)
			(xy 26.36509 -350.271478) (xy 26.406281 -350.235787) (xy 26.452131 -350.206321) (xy 26.501708 -350.183679)
			(xy 26.554003 -350.168324) (xy 26.607951 -350.160568) (xy 26.662453 -350.160568) (xy 26.716401 -350.168324)
			(xy 26.768696 -350.183679) (xy 26.818273 -350.206321) (xy 26.864123 -350.235787) (xy 26.905314 -350.271478)
			(xy 26.941005 -350.312669) (xy 26.970471 -350.358519) (xy 26.993113 -350.408096) (xy 27.008468 -350.460391)
			(xy 27.016224 -350.514339) (xy 27.01671 -350.54159) (xy 27.016215 -350.569064) (xy 27.008325 -350.623443)
			(xy 26.992707 -350.676126) (xy 26.990065 -350.681852) (xy 27.258475 -350.681852) (xy 27.258475 -350.627348)
			(xy 27.266232 -350.573398) (xy 27.281589 -350.521102) (xy 27.304231 -350.471523) (xy 27.333699 -350.425671)
			(xy 27.369393 -350.38448) (xy 27.410586 -350.348788) (xy 27.456439 -350.319322) (xy 27.506018 -350.296682)
			(xy 27.558316 -350.281329) (xy 27.612266 -350.273574) (xy 27.639518 -350.273112) (xy 27.664754 -350.273499)
			(xy 27.714788 -350.28012) (xy 27.763508 -350.293296) (xy 27.81006 -350.312796) (xy 27.83205 -350.325182)
			(xy 27.841702 -350.331024) (xy 27.8638 -350.333056) (xy 27.958288 -350.299528) (xy 27.97429 -350.284034)
			(xy 27.978354 -350.27362) (xy 27.989083 -350.246857) (xy 28.017365 -350.196615) (xy 28.052889 -350.151205)
			(xy 28.094846 -350.111661) (xy 28.142279 -350.078885) (xy 28.194106 -350.053625) (xy 28.249145 -350.036457)
			(xy 28.306142 -350.027771) (xy 28.33497 -350.02724) (xy 28.362224 -350.027683) (xy 28.416178 -350.035437)
			(xy 28.46848 -350.050792) (xy 28.518063 -350.073435) (xy 28.563918 -350.102904) (xy 28.605113 -350.1386)
			(xy 28.640807 -350.179796) (xy 28.670274 -350.225653) (xy 28.692914 -350.275237) (xy 28.708266 -350.327539)
			(xy 28.716018 -350.381494) (xy 28.716478 -350.408748) (xy 28.715825 -350.440311) (xy 28.705435 -350.502577)
			(xy 28.684947 -350.562286) (xy 28.670504 -350.590358) (xy 28.665678 -350.599248) (xy 28.663646 -350.618806)
			(xy 28.6893 -350.706944) (xy 28.701746 -350.722438) (xy 28.710636 -350.727518) (xy 28.735715 -350.742104)
			(xy 28.7816 -350.777599) (xy 28.821578 -350.819635) (xy 28.854727 -350.867242) (xy 28.880282 -350.919322)
			(xy 28.897652 -350.974672) (xy 28.906437 -351.032014) (xy 28.906978 -351.06102) (xy 28.906492 -351.088271)
			(xy 28.898736 -351.142219) (xy 28.883381 -351.194514) (xy 28.860739 -351.244091) (xy 28.831273 -351.289941)
			(xy 28.795582 -351.331132) (xy 28.754391 -351.366823) (xy 28.708541 -351.396289) (xy 28.658964 -351.418931)
			(xy 28.606669 -351.434286) (xy 28.552721 -351.442042) (xy 28.498219 -351.442042) (xy 28.444271 -351.434286)
			(xy 28.391976 -351.418931) (xy 28.342399 -351.396289) (xy 28.296549 -351.366823) (xy 28.255358 -351.331132)
			(xy 28.219667 -351.289941) (xy 28.190201 -351.244091) (xy 28.167559 -351.194514) (xy 28.152204 -351.142219)
			(xy 28.144448 -351.088271) (xy 28.143962 -351.06102) (xy 28.14461 -351.029457) (xy 28.155003 -350.967191)
			(xy 28.175493 -350.907483) (xy 28.189936 -350.87941) (xy 28.194762 -350.87052) (xy 28.196794 -350.850962)
			(xy 28.17114 -350.762824) (xy 28.158694 -350.74733) (xy 28.149804 -350.74225) (xy 28.142438 -350.738186)
			(xy 28.132786 -350.732344) (xy 28.110688 -350.730312) (xy 28.0162 -350.76384) (xy 28.000198 -350.779334)
			(xy 27.996134 -350.789748) (xy 27.985452 -350.81653) (xy 27.95716 -350.86677) (xy 27.921627 -350.912178)
			(xy 27.879663 -350.951719) (xy 27.832224 -350.984492) (xy 27.780392 -351.009749) (xy 27.725348 -351.026915)
			(xy 27.668347 -351.035598) (xy 27.639518 -351.036128) (xy 27.612266 -351.035626) (xy 27.558316 -351.027871)
			(xy 27.506018 -351.012518) (xy 27.456439 -350.989878) (xy 27.410586 -350.960412) (xy 27.369393 -350.92472)
			(xy 27.333699 -350.883529) (xy 27.304231 -350.837677) (xy 27.281589 -350.788098) (xy 27.266232 -350.735802)
			(xy 27.258475 -350.681852) (xy 26.990065 -350.681852) (xy 26.969684 -350.726018) (xy 26.939734 -350.772088)
			(xy 26.921968 -350.79305) (xy 26.915872 -350.800162) (xy 26.909522 -350.81718) (xy 26.909522 -350.903032)
			(xy 26.915872 -350.92005) (xy 26.921968 -350.927162) (xy 26.939706 -350.948145) (xy 26.969632 -350.994222)
			(xy 26.992649 -351.044111) (xy 27.008281 -351.096783) (xy 27.016206 -351.151151) (xy 27.01671 -351.178622)
			(xy 27.016224 -351.205873) (xy 27.008468 -351.259821) (xy 26.993113 -351.312116) (xy 26.970471 -351.361693)
			(xy 26.941005 -351.407543) (xy 26.905314 -351.448734) (xy 26.864123 -351.484425) (xy 26.818273 -351.513891)
			(xy 26.768696 -351.536533) (xy 26.716401 -351.551888) (xy 26.662453 -351.559644) (xy 26.607951 -351.559644)
			(xy 26.554003 -351.551888) (xy 26.501708 -351.536533) (xy 26.452131 -351.513891) (xy 26.406281 -351.484425)
			(xy 26.36509 -351.448734) (xy 26.329399 -351.407543) (xy 26.299933 -351.361693) (xy 26.277291 -351.312116)
			(xy 26.261936 -351.259821) (xy 26.25418 -351.205873) (xy 26.253694 -351.178622) (xy 24.901652 -351.178622)
			(xy 24.901652 -351.641918) (xy 24.917908 -351.66681) (xy 24.931878 -351.67316) (xy 24.956782 -351.684776)
			(xy 25.003254 -351.714102) (xy 25.045036 -351.749793) (xy 25.081266 -351.79111) (xy 25.111192 -351.837198)
			(xy 25.134196 -351.887102) (xy 25.149802 -351.939791) (xy 25.157687 -351.994174) (xy 25.157687 -352.049125)
			(xy 25.149803 -352.103508) (xy 25.134197 -352.156196) (xy 25.111193 -352.206101) (xy 25.081267 -352.252189)
			(xy 25.045037 -352.293505) (xy 25.003255 -352.329197) (xy 24.956784 -352.358524) (xy 24.931878 -352.370136)
			(xy 24.917908 -352.376486) (xy 24.901652 -352.401378) (xy 24.901652 -355.2444) (xy 28.446982 -355.2444)
			(xy 28.451053 -355.188778) (xy 28.463179 -355.134341) (xy 28.483102 -355.08225) (xy 28.510398 -355.033615)
			(xy 28.544484 -354.989472) (xy 28.584633 -354.950763) (xy 28.629991 -354.918312) (xy 28.679591 -354.892811)
			(xy 28.732375 -354.874804) (xy 28.787218 -354.864674) (xy 28.842952 -354.862637) (xy 28.898389 -354.868737)
			(xy 28.952346 -354.882843) (xy 29.003675 -354.904655) (xy 29.051281 -354.933709) (xy 29.094149 -354.969384)
			(xy 29.131366 -355.010921) (xy 29.162139 -355.057434) (xy 29.185811 -355.107931) (xy 29.201879 -355.161338)
			(xy 29.209999 -355.216514) (xy 29.210508 -355.2444) (xy 29.209999 -355.272286) (xy 29.201879 -355.327462)
			(xy 29.185811 -355.380869) (xy 29.162139 -355.431366) (xy 29.131366 -355.477879) (xy 29.094149 -355.519416)
			(xy 29.051281 -355.555091) (xy 29.003675 -355.584145) (xy 28.952346 -355.605957) (xy 28.898389 -355.620063)
			(xy 28.842952 -355.626163) (xy 28.787218 -355.624126) (xy 28.732375 -355.613996) (xy 28.679591 -355.595989)
			(xy 28.629991 -355.570488) (xy 28.584633 -355.538037) (xy 28.544484 -355.499328) (xy 28.510398 -355.455185)
			(xy 28.483102 -355.40655) (xy 28.463179 -355.354459) (xy 28.451053 -355.300022) (xy 28.446982 -355.2444)
			(xy 24.901652 -355.2444) (xy 24.901652 -355.854) (xy 31.291782 -355.854) (xy 31.295853 -355.798378)
			(xy 31.307979 -355.743941) (xy 31.327902 -355.69185) (xy 31.355198 -355.643215) (xy 31.389284 -355.599072)
			(xy 31.429433 -355.560363) (xy 31.474791 -355.527912) (xy 31.524391 -355.502411) (xy 31.577175 -355.484404)
			(xy 31.632018 -355.474274) (xy 31.687752 -355.472237) (xy 31.743189 -355.478337) (xy 31.797146 -355.492443)
			(xy 31.848475 -355.514255) (xy 31.896081 -355.543309) (xy 31.938949 -355.578984) (xy 31.976166 -355.620521)
			(xy 32.006939 -355.667034) (xy 32.030611 -355.717531) (xy 32.046679 -355.770938) (xy 32.054799 -355.826114)
			(xy 32.055308 -355.854) (xy 32.434782 -355.854) (xy 32.438853 -355.798378) (xy 32.450979 -355.743941)
			(xy 32.470902 -355.69185) (xy 32.498198 -355.643215) (xy 32.532284 -355.599072) (xy 32.572433 -355.560363)
			(xy 32.617791 -355.527912) (xy 32.667391 -355.502411) (xy 32.720175 -355.484404) (xy 32.775018 -355.474274)
			(xy 32.830752 -355.472237) (xy 32.886189 -355.478337) (xy 32.940146 -355.492443) (xy 32.991475 -355.514255)
			(xy 33.039081 -355.543309) (xy 33.081949 -355.578984) (xy 33.119166 -355.620521) (xy 33.149939 -355.667034)
			(xy 33.173611 -355.717531) (xy 33.184102 -355.7524) (xy 34.669982 -355.7524) (xy 34.674053 -355.696778)
			(xy 34.686179 -355.642341) (xy 34.706102 -355.59025) (xy 34.733398 -355.541615) (xy 34.767484 -355.497472)
			(xy 34.807633 -355.458763) (xy 34.852991 -355.426312) (xy 34.902591 -355.400811) (xy 34.955375 -355.382804)
			(xy 35.010218 -355.372674) (xy 35.065952 -355.370637) (xy 35.121389 -355.376737) (xy 35.175346 -355.390843)
			(xy 35.226675 -355.412655) (xy 35.274281 -355.441709) (xy 35.317149 -355.477384) (xy 35.354366 -355.518921)
			(xy 35.385139 -355.565434) (xy 35.408811 -355.615931) (xy 35.424879 -355.669338) (xy 35.432999 -355.724514)
			(xy 35.433508 -355.7524) (xy 35.432999 -355.780286) (xy 35.424879 -355.835462) (xy 35.408811 -355.888869)
			(xy 35.385139 -355.939366) (xy 35.354366 -355.985879) (xy 35.317149 -356.027416) (xy 35.274281 -356.063091)
			(xy 35.226675 -356.092145) (xy 35.175346 -356.113957) (xy 35.121389 -356.128063) (xy 35.065952 -356.134163)
			(xy 35.010218 -356.132126) (xy 34.955375 -356.121996) (xy 34.902591 -356.103989) (xy 34.852991 -356.078488)
			(xy 34.807633 -356.046037) (xy 34.767484 -356.007328) (xy 34.733398 -355.963185) (xy 34.706102 -355.91455)
			(xy 34.686179 -355.862459) (xy 34.674053 -355.808022) (xy 34.669982 -355.7524) (xy 33.184102 -355.7524)
			(xy 33.189679 -355.770938) (xy 33.197799 -355.826114) (xy 33.198308 -355.854) (xy 33.197799 -355.881886)
			(xy 33.189679 -355.937062) (xy 33.173611 -355.990469) (xy 33.149939 -356.040966) (xy 33.119166 -356.087479)
			(xy 33.081949 -356.129016) (xy 33.039081 -356.164691) (xy 32.991475 -356.193745) (xy 32.940146 -356.215557)
			(xy 32.886189 -356.229663) (xy 32.830752 -356.235763) (xy 32.775018 -356.233726) (xy 32.720175 -356.223596)
			(xy 32.667391 -356.205589) (xy 32.617791 -356.180088) (xy 32.572433 -356.147637) (xy 32.532284 -356.108928)
			(xy 32.498198 -356.064785) (xy 32.470902 -356.01615) (xy 32.450979 -355.964059) (xy 32.438853 -355.909622)
			(xy 32.434782 -355.854) (xy 32.055308 -355.854) (xy 32.054799 -355.881886) (xy 32.046679 -355.937062)
			(xy 32.030611 -355.990469) (xy 32.006939 -356.040966) (xy 31.976166 -356.087479) (xy 31.938949 -356.129016)
			(xy 31.896081 -356.164691) (xy 31.848475 -356.193745) (xy 31.797146 -356.215557) (xy 31.743189 -356.229663)
			(xy 31.687752 -356.235763) (xy 31.632018 -356.233726) (xy 31.577175 -356.223596) (xy 31.524391 -356.205589)
			(xy 31.474791 -356.180088) (xy 31.429433 -356.147637) (xy 31.389284 -356.108928) (xy 31.355198 -356.064785)
			(xy 31.327902 -356.01615) (xy 31.307979 -355.964059) (xy 31.295853 -355.909622) (xy 31.291782 -355.854)
			(xy 24.901652 -355.854) (xy 24.901652 -356.3874) (xy 27.964382 -356.3874) (xy 27.968453 -356.331778)
			(xy 27.980579 -356.277341) (xy 28.000502 -356.22525) (xy 28.027798 -356.176615) (xy 28.061884 -356.132472)
			(xy 28.102033 -356.093763) (xy 28.147391 -356.061312) (xy 28.196991 -356.035811) (xy 28.249775 -356.017804)
			(xy 28.304618 -356.007674) (xy 28.360352 -356.005637) (xy 28.415789 -356.011737) (xy 28.469746 -356.025843)
			(xy 28.521075 -356.047655) (xy 28.568681 -356.076709) (xy 28.611549 -356.112384) (xy 28.648766 -356.153921)
			(xy 28.679539 -356.200434) (xy 28.703211 -356.250931) (xy 28.719279 -356.304338) (xy 28.727399 -356.359514)
			(xy 28.727908 -356.3874) (xy 28.727399 -356.415286) (xy 28.719279 -356.470462) (xy 28.703211 -356.523869)
			(xy 28.689789 -356.5525) (xy 30.618682 -356.5525) (xy 30.622753 -356.496878) (xy 30.634879 -356.442441)
			(xy 30.654802 -356.39035) (xy 30.682098 -356.341715) (xy 30.716184 -356.297572) (xy 30.756333 -356.258863)
			(xy 30.801691 -356.226412) (xy 30.851291 -356.200911) (xy 30.904075 -356.182904) (xy 30.958918 -356.172774)
			(xy 31.014652 -356.170737) (xy 31.070089 -356.176837) (xy 31.124046 -356.190943) (xy 31.175375 -356.212755)
			(xy 31.222981 -356.241809) (xy 31.265849 -356.277484) (xy 31.303066 -356.319021) (xy 31.333839 -356.365534)
			(xy 31.357511 -356.416031) (xy 31.373579 -356.469438) (xy 31.381699 -356.524614) (xy 31.382208 -356.5525)
			(xy 31.381699 -356.580386) (xy 31.373579 -356.635562) (xy 31.357511 -356.688969) (xy 31.333839 -356.739466)
			(xy 31.303066 -356.785979) (xy 31.265849 -356.827516) (xy 31.222981 -356.863191) (xy 31.175375 -356.892245)
			(xy 31.124046 -356.914057) (xy 31.070089 -356.928163) (xy 31.014652 -356.934263) (xy 30.958918 -356.932226)
			(xy 30.904075 -356.922096) (xy 30.851291 -356.904089) (xy 30.801691 -356.878588) (xy 30.756333 -356.846137)
			(xy 30.716184 -356.807428) (xy 30.682098 -356.763285) (xy 30.654802 -356.71465) (xy 30.634879 -356.662559)
			(xy 30.622753 -356.608122) (xy 30.618682 -356.5525) (xy 28.689789 -356.5525) (xy 28.679539 -356.574366)
			(xy 28.648766 -356.620879) (xy 28.611549 -356.662416) (xy 28.568681 -356.698091) (xy 28.521075 -356.727145)
			(xy 28.469746 -356.748957) (xy 28.415789 -356.763063) (xy 28.360352 -356.769163) (xy 28.304618 -356.767126)
			(xy 28.249775 -356.756996) (xy 28.196991 -356.738989) (xy 28.147391 -356.713488) (xy 28.102033 -356.681037)
			(xy 28.061884 -356.642328) (xy 28.027798 -356.598185) (xy 28.000502 -356.54955) (xy 27.980579 -356.497459)
			(xy 27.968453 -356.443022) (xy 27.964382 -356.3874) (xy 24.901652 -356.3874) (xy 24.901652 -357.44531)
			(xy 24.902109 -357.455189) (xy 24.909545 -357.473494) (xy 24.91613 -357.48087) (xy 24.916384 -357.481124)
			(xy 24.92121 -357.48595) (xy 27.558492 -357.48595) (xy 27.558978 -357.458699) (xy 27.566734 -357.404751)
			(xy 27.582089 -357.352456) (xy 27.604731 -357.302879) (xy 27.634197 -357.257029) (xy 27.669888 -357.215838)
			(xy 27.711079 -357.180147) (xy 27.756929 -357.150681) (xy 27.806506 -357.128039) (xy 27.858801 -357.112684)
			(xy 27.912749 -357.104928) (xy 27.967251 -357.104928) (xy 28.021199 -357.112684) (xy 28.073494 -357.128039)
			(xy 28.123071 -357.150681) (xy 28.168921 -357.180147) (xy 28.210112 -357.215838) (xy 28.245803 -357.257029)
			(xy 28.275269 -357.302879) (xy 28.297911 -357.352456) (xy 28.313266 -357.404751) (xy 28.321022 -357.458699)
			(xy 28.321508 -357.48595) (xy 28.320903 -357.515135) (xy 28.312012 -357.572824) (xy 28.294445 -357.628489)
			(xy 28.280176 -357.6574) (xy 30.275782 -357.6574) (xy 30.279853 -357.601778) (xy 30.291979 -357.547341)
			(xy 30.311902 -357.49525) (xy 30.339198 -357.446615) (xy 30.373284 -357.402472) (xy 30.413433 -357.363763)
			(xy 30.458791 -357.331312) (xy 30.508391 -357.305811) (xy 30.561175 -357.287804) (xy 30.616018 -357.277674)
			(xy 30.671752 -357.275637) (xy 30.727189 -357.281737) (xy 30.781146 -357.295843) (xy 30.832475 -357.317655)
			(xy 30.880081 -357.346709) (xy 30.922949 -357.382384) (xy 30.960166 -357.423921) (xy 30.990939 -357.470434)
			(xy 31.014611 -357.520931) (xy 31.030679 -357.574338) (xy 31.038799 -357.629514) (xy 31.039308 -357.6574)
			(xy 33.857182 -357.6574) (xy 33.861253 -357.601778) (xy 33.873379 -357.547341) (xy 33.893302 -357.49525)
			(xy 33.920598 -357.446615) (xy 33.954684 -357.402472) (xy 33.994833 -357.363763) (xy 34.040191 -357.331312)
			(xy 34.089791 -357.305811) (xy 34.142575 -357.287804) (xy 34.197418 -357.277674) (xy 34.253152 -357.275637)
			(xy 34.308589 -357.281737) (xy 34.362546 -357.295843) (xy 34.413875 -357.317655) (xy 34.461481 -357.346709)
			(xy 34.504349 -357.382384) (xy 34.541566 -357.423921) (xy 34.572339 -357.470434) (xy 34.596011 -357.520931)
			(xy 34.612079 -357.574338) (xy 34.620199 -357.629514) (xy 34.620708 -357.6574) (xy 34.620199 -357.685286)
			(xy 34.612079 -357.740462) (xy 34.596011 -357.793869) (xy 34.572339 -357.844366) (xy 34.541566 -357.890879)
			(xy 34.504349 -357.932416) (xy 34.461481 -357.968091) (xy 34.413875 -357.997145) (xy 34.362546 -358.018957)
			(xy 34.308589 -358.033063) (xy 34.253152 -358.039163) (xy 34.197418 -358.037126) (xy 34.142575 -358.026996)
			(xy 34.089791 -358.008989) (xy 34.040191 -357.983488) (xy 33.994833 -357.951037) (xy 33.954684 -357.912328)
			(xy 33.920598 -357.868185) (xy 33.893302 -357.81955) (xy 33.873379 -357.767459) (xy 33.861253 -357.713022)
			(xy 33.857182 -357.6574) (xy 31.039308 -357.6574) (xy 31.038799 -357.685286) (xy 31.030679 -357.740462)
			(xy 31.014611 -357.793869) (xy 30.990939 -357.844366) (xy 30.960166 -357.890879) (xy 30.922949 -357.932416)
			(xy 30.880081 -357.968091) (xy 30.832475 -357.997145) (xy 30.781146 -358.018957) (xy 30.727189 -358.033063)
			(xy 30.671752 -358.039163) (xy 30.616018 -358.037126) (xy 30.561175 -358.026996) (xy 30.508391 -358.008989)
			(xy 30.458791 -357.983488) (xy 30.413433 -357.951037) (xy 30.373284 -357.912328) (xy 30.339198 -357.868185)
			(xy 30.311902 -357.81955) (xy 30.291979 -357.767459) (xy 30.279853 -357.713022) (xy 30.275782 -357.6574)
			(xy 28.280176 -357.6574) (xy 28.268611 -357.680831) (xy 28.235112 -357.728632) (xy 28.194729 -357.770778)
			(xy 28.171902 -357.788972) (xy 28.161264 -357.797592) (xy 28.144733 -357.819409) (xy 28.134603 -357.844838)
			(xy 28.131606 -357.872047) (xy 28.135959 -357.899071) (xy 28.147346 -357.923963) (xy 28.164946 -357.944927)
			(xy 28.175966 -357.953056) (xy 28.197369 -357.968418) (xy 28.23617 -358.004055) (xy 28.269701 -358.044691)
			(xy 28.297324 -358.089552) (xy 28.318514 -358.137786) (xy 28.332869 -358.188476) (xy 28.340115 -358.240658)
			(xy 28.340558 -358.267) (xy 29.259782 -358.267) (xy 29.263853 -358.211378) (xy 29.275979 -358.156941)
			(xy 29.295902 -358.10485) (xy 29.323198 -358.056215) (xy 29.357284 -358.012072) (xy 29.397433 -357.973363)
			(xy 29.442791 -357.940912) (xy 29.492391 -357.915411) (xy 29.545175 -357.897404) (xy 29.600018 -357.887274)
			(xy 29.655752 -357.885237) (xy 29.711189 -357.891337) (xy 29.765146 -357.905443) (xy 29.816475 -357.927255)
			(xy 29.864081 -357.956309) (xy 29.906949 -357.991984) (xy 29.944166 -358.033521) (xy 29.974939 -358.080034)
			(xy 29.998611 -358.130531) (xy 30.014679 -358.183938) (xy 30.022799 -358.239114) (xy 30.023308 -358.267)
			(xy 30.022799 -358.294886) (xy 30.014679 -358.350062) (xy 29.998611 -358.403469) (xy 29.974939 -358.453966)
			(xy 29.944166 -358.500479) (xy 29.906949 -358.542016) (xy 29.864081 -358.577691) (xy 29.816475 -358.606745)
			(xy 29.765146 -358.628557) (xy 29.711189 -358.642663) (xy 29.655752 -358.648763) (xy 29.600018 -358.646726)
			(xy 29.545175 -358.636596) (xy 29.492391 -358.618589) (xy 29.442791 -358.593088) (xy 29.397433 -358.560637)
			(xy 29.357284 -358.521928) (xy 29.323198 -358.477785) (xy 29.295902 -358.42915) (xy 29.275979 -358.377059)
			(xy 29.263853 -358.322622) (xy 29.259782 -358.267) (xy 28.340558 -358.267) (xy 28.340072 -358.294251)
			(xy 28.332316 -358.348199) (xy 28.316961 -358.400494) (xy 28.294319 -358.450071) (xy 28.264853 -358.495921)
			(xy 28.229162 -358.537112) (xy 28.187971 -358.572803) (xy 28.142121 -358.602269) (xy 28.092544 -358.624911)
			(xy 28.040249 -358.640266) (xy 27.986301 -358.648022) (xy 27.931799 -358.648022) (xy 27.877851 -358.640266)
			(xy 27.825556 -358.624911) (xy 27.775979 -358.602269) (xy 27.730129 -358.572803) (xy 27.688938 -358.537112)
			(xy 27.653247 -358.495921) (xy 27.623781 -358.450071) (xy 27.601139 -358.400494) (xy 27.585784 -358.348199)
			(xy 27.578028 -358.294251) (xy 27.577542 -358.267) (xy 27.578092 -358.237813) (xy 27.586992 -358.18012)
			(xy 27.604568 -358.124454) (xy 27.630413 -358.072111) (xy 27.663922 -358.024312) (xy 27.704316 -357.982169)
			(xy 27.727148 -357.963978) (xy 27.737729 -357.955296) (xy 27.754252 -357.933492) (xy 27.76438 -357.908077)
			(xy 27.767381 -357.880884) (xy 27.763041 -357.853872) (xy 27.751672 -357.828989) (xy 27.734092 -357.808026)
			(xy 27.723084 -357.799894) (xy 27.701646 -357.784578) (xy 27.662848 -357.748932) (xy 27.629322 -357.708287)
			(xy 27.601704 -357.663419) (xy 27.580519 -357.615178) (xy 27.566171 -357.564481) (xy 27.558932 -357.512294)
			(xy 27.558492 -357.48595) (xy 24.92121 -357.48595) (xy 26.59126 -359.156) (xy 31.621982 -359.156)
			(xy 31.626053 -359.100378) (xy 31.638179 -359.045941) (xy 31.658102 -358.99385) (xy 31.685398 -358.945215)
			(xy 31.719484 -358.901072) (xy 31.759633 -358.862363) (xy 31.804991 -358.829912) (xy 31.854591 -358.804411)
			(xy 31.907375 -358.786404) (xy 31.962218 -358.776274) (xy 32.017952 -358.774237) (xy 32.073389 -358.780337)
			(xy 32.127346 -358.794443) (xy 32.178675 -358.816255) (xy 32.226281 -358.845309) (xy 32.269149 -358.880984)
			(xy 32.306366 -358.922521) (xy 32.337139 -358.969034) (xy 32.360811 -359.019531) (xy 32.376879 -359.072938)
			(xy 32.384999 -359.128114) (xy 32.385508 -359.156) (xy 32.384999 -359.183886) (xy 32.376879 -359.239062)
			(xy 32.360811 -359.292469) (xy 32.352475 -359.310251) (xy 35.686978 -359.310251) (xy 35.686978 -359.255749)
			(xy 35.694734 -359.201801) (xy 35.710089 -359.149506) (xy 35.732731 -359.099929) (xy 35.762197 -359.054079)
			(xy 35.797888 -359.012888) (xy 35.839079 -358.977197) (xy 35.884929 -358.947731) (xy 35.934506 -358.925089)
			(xy 35.986801 -358.909734) (xy 36.040749 -358.901978) (xy 36.068 -358.901492) (xy 36.096113 -358.902001)
			(xy 36.151727 -358.910272) (xy 36.205524 -358.926621) (xy 36.256337 -358.950693) (xy 36.303064 -358.981965)
			(xy 36.344692 -359.019761) (xy 36.362894 -359.041192) (xy 36.370514 -359.050336) (xy 36.391596 -359.059988)
			(xy 36.495482 -359.057448) (xy 36.51631 -359.046526) (xy 36.523168 -359.037128) (xy 36.541324 -359.013594)
			(xy 36.583643 -358.971861) (xy 36.631921 -358.937195) (xy 36.68499 -358.910434) (xy 36.741567 -358.892225)
			(xy 36.800283 -358.883009) (xy 36.83 -358.882442) (xy 36.857255 -358.882828) (xy 36.91121 -358.890585)
			(xy 36.963511 -358.905943) (xy 37.013095 -358.928587) (xy 37.058951 -358.958057) (xy 37.100147 -358.993753)
			(xy 37.135843 -359.034949) (xy 37.165313 -359.080805) (xy 37.187957 -359.130389) (xy 37.203315 -359.18269)
			(xy 37.211072 -359.236645) (xy 37.211072 -359.291155) (xy 37.203315 -359.34511) (xy 37.187957 -359.397411)
			(xy 37.165313 -359.446995) (xy 37.135843 -359.492851) (xy 37.100147 -359.534047) (xy 37.058951 -359.569743)
			(xy 37.013095 -359.599213) (xy 36.963511 -359.621857) (xy 36.91121 -359.637215) (xy 36.857255 -359.644972)
			(xy 36.83 -359.645458) (xy 36.801888 -359.644931) (xy 36.746275 -359.636661) (xy 36.692479 -359.620314)
			(xy 36.641667 -359.596246) (xy 36.594939 -359.564978) (xy 36.553309 -359.527187) (xy 36.535106 -359.505758)
			(xy 36.527486 -359.496614) (xy 36.506404 -359.486962) (xy 36.402518 -359.489502) (xy 36.38169 -359.500424)
			(xy 36.374832 -359.509822) (xy 36.35669 -359.533367) (xy 36.314367 -359.575097) (xy 36.266085 -359.60976)
			(xy 36.213014 -359.636519) (xy 36.156435 -359.654726) (xy 36.097718 -359.663941) (xy 36.068 -359.664508)
			(xy 36.040749 -359.664022) (xy 35.986801 -359.656266) (xy 35.934506 -359.640911) (xy 35.884929 -359.618269)
			(xy 35.839079 -359.588803) (xy 35.797888 -359.553112) (xy 35.762197 -359.511921) (xy 35.732731 -359.466071)
			(xy 35.710089 -359.416494) (xy 35.694734 -359.364199) (xy 35.686978 -359.310251) (xy 32.352475 -359.310251)
			(xy 32.337139 -359.342966) (xy 32.306366 -359.389479) (xy 32.269149 -359.431016) (xy 32.226281 -359.466691)
			(xy 32.178675 -359.495745) (xy 32.127346 -359.517557) (xy 32.073389 -359.531663) (xy 32.017952 -359.537763)
			(xy 31.962218 -359.535726) (xy 31.907375 -359.525596) (xy 31.854591 -359.507589) (xy 31.804991 -359.482088)
			(xy 31.759633 -359.449637) (xy 31.719484 -359.410928) (xy 31.685398 -359.366785) (xy 31.658102 -359.31815)
			(xy 31.638179 -359.266059) (xy 31.626053 -359.211622) (xy 31.621982 -359.156) (xy 26.59126 -359.156)
			(xy 27.02306 -359.5878) (xy 29.259782 -359.5878) (xy 29.263853 -359.532178) (xy 29.275979 -359.477741)
			(xy 29.295902 -359.42565) (xy 29.323198 -359.377015) (xy 29.357284 -359.332872) (xy 29.397433 -359.294163)
			(xy 29.442791 -359.261712) (xy 29.492391 -359.236211) (xy 29.545175 -359.218204) (xy 29.600018 -359.208074)
			(xy 29.655752 -359.206037) (xy 29.711189 -359.212137) (xy 29.765146 -359.226243) (xy 29.816475 -359.248055)
			(xy 29.864081 -359.277109) (xy 29.906949 -359.312784) (xy 29.944166 -359.354321) (xy 29.974939 -359.400834)
			(xy 29.998611 -359.451331) (xy 30.014679 -359.504738) (xy 30.022799 -359.559914) (xy 30.023308 -359.5878)
			(xy 30.022799 -359.615686) (xy 30.014679 -359.670862) (xy 29.998611 -359.724269) (xy 29.974939 -359.774766)
			(xy 29.944166 -359.821279) (xy 29.906949 -359.862816) (xy 29.864081 -359.898491) (xy 29.816475 -359.927545)
			(xy 29.765146 -359.949357) (xy 29.711189 -359.963463) (xy 29.655752 -359.969563) (xy 29.600018 -359.967526)
			(xy 29.545175 -359.957396) (xy 29.492391 -359.939389) (xy 29.442791 -359.913888) (xy 29.397433 -359.881437)
			(xy 29.357284 -359.842728) (xy 29.323198 -359.798585) (xy 29.295902 -359.74995) (xy 29.275979 -359.697859)
			(xy 29.263853 -359.643422) (xy 29.259782 -359.5878) (xy 27.02306 -359.5878) (xy 27.60726 -360.172)
			(xy 31.621982 -360.172) (xy 31.626053 -360.116378) (xy 31.638179 -360.061941) (xy 31.658102 -360.00985)
			(xy 31.685398 -359.961215) (xy 31.719484 -359.917072) (xy 31.759633 -359.878363) (xy 31.804991 -359.845912)
			(xy 31.854591 -359.820411) (xy 31.907375 -359.802404) (xy 31.962218 -359.792274) (xy 32.017952 -359.790237)
			(xy 32.073389 -359.796337) (xy 32.127346 -359.810443) (xy 32.178675 -359.832255) (xy 32.226281 -359.861309)
			(xy 32.269149 -359.896984) (xy 32.306366 -359.938521) (xy 32.337139 -359.985034) (xy 32.360811 -360.035531)
			(xy 32.376879 -360.088938) (xy 32.384999 -360.144114) (xy 32.385508 -360.172) (xy 32.384999 -360.199886)
			(xy 32.376879 -360.255062) (xy 32.360811 -360.308469) (xy 32.337139 -360.358966) (xy 32.306366 -360.405479)
			(xy 32.269149 -360.447016) (xy 32.226281 -360.482691) (xy 32.178675 -360.511745) (xy 32.127346 -360.533557)
			(xy 32.073389 -360.547663) (xy 32.017952 -360.553763) (xy 31.962218 -360.551726) (xy 31.907375 -360.541596)
			(xy 31.854591 -360.523589) (xy 31.804991 -360.498088) (xy 31.759633 -360.465637) (xy 31.719484 -360.426928)
			(xy 31.685398 -360.382785) (xy 31.658102 -360.33415) (xy 31.638179 -360.282059) (xy 31.626053 -360.227622)
			(xy 31.621982 -360.172) (xy 27.60726 -360.172) (xy 29.51226 -362.077) (xy 37.946582 -362.077) (xy 37.950653 -362.021378)
			(xy 37.962779 -361.966941) (xy 37.982702 -361.91485) (xy 38.009998 -361.866215) (xy 38.044084 -361.822072)
			(xy 38.084233 -361.783363) (xy 38.129591 -361.750912) (xy 38.179191 -361.725411) (xy 38.231975 -361.707404)
			(xy 38.286818 -361.697274) (xy 38.342552 -361.695237) (xy 38.397989 -361.701337) (xy 38.451946 -361.715443)
			(xy 38.503275 -361.737255) (xy 38.550881 -361.766309) (xy 38.593749 -361.801984) (xy 38.630966 -361.843521)
			(xy 38.661739 -361.890034) (xy 38.685411 -361.940531) (xy 38.701479 -361.993938) (xy 38.709599 -362.049114)
			(xy 38.710108 -362.077) (xy 38.709599 -362.104886) (xy 38.701479 -362.160062) (xy 38.685411 -362.213469)
			(xy 38.661739 -362.263966) (xy 38.630966 -362.310479) (xy 38.593749 -362.352016) (xy 38.550881 -362.387691)
			(xy 38.503275 -362.416745) (xy 38.451946 -362.438557) (xy 38.397989 -362.452663) (xy 38.342552 -362.458763)
			(xy 38.286818 -362.456726) (xy 38.231975 -362.446596) (xy 38.179191 -362.428589) (xy 38.129591 -362.403088)
			(xy 38.084233 -362.370637) (xy 38.044084 -362.331928) (xy 38.009998 -362.287785) (xy 37.982702 -362.23915)
			(xy 37.962779 -362.187059) (xy 37.950653 -362.132622) (xy 37.946582 -362.077) (xy 29.51226 -362.077)
			(xy 30.52826 -363.093) (xy 35.558982 -363.093) (xy 35.563053 -363.037378) (xy 35.575179 -362.982941)
			(xy 35.595102 -362.93085) (xy 35.622398 -362.882215) (xy 35.656484 -362.838072) (xy 35.696633 -362.799363)
			(xy 35.741991 -362.766912) (xy 35.791591 -362.741411) (xy 35.844375 -362.723404) (xy 35.899218 -362.713274)
			(xy 35.954952 -362.711237) (xy 36.010389 -362.717337) (xy 36.064346 -362.731443) (xy 36.115675 -362.753255)
			(xy 36.163281 -362.782309) (xy 36.206149 -362.817984) (xy 36.238634 -362.85424) (xy 46.115224 -362.85424)
			(xy 46.115708 -362.82687) (xy 46.12352 -362.772692) (xy 46.139005 -362.720189) (xy 46.161843 -362.670441)
			(xy 46.191564 -362.624474) (xy 46.209204 -362.603542) (xy 46.2153 -362.59643) (xy 46.22165 -362.579412)
			(xy 46.22165 -362.494068) (xy 46.2153 -362.47705) (xy 46.209204 -362.469938) (xy 46.191603 -362.448973)
			(xy 46.161879 -362.40301) (xy 46.139032 -362.353269) (xy 46.123534 -362.300772) (xy 46.115702 -362.246599)
			(xy 46.115698 -362.191862) (xy 46.123521 -362.137687) (xy 46.139011 -362.085187) (xy 46.16185 -362.035443)
			(xy 46.191567 -361.989475) (xy 46.209204 -361.968542) (xy 46.2153 -361.96143) (xy 46.22165 -361.944412)
			(xy 46.22165 -361.859068) (xy 46.2153 -361.84205) (xy 46.209204 -361.834938) (xy 46.191603 -361.813973)
			(xy 46.161879 -361.76801) (xy 46.139032 -361.718269) (xy 46.123534 -361.665772) (xy 46.115702 -361.611599)
			(xy 46.115698 -361.556862) (xy 46.123521 -361.502687) (xy 46.139011 -361.450187) (xy 46.16185 -361.400443)
			(xy 46.191567 -361.354475) (xy 46.209204 -361.333542) (xy 46.2153 -361.32643) (xy 46.22165 -361.309412)
			(xy 46.22165 -361.224068) (xy 46.2153 -361.20705) (xy 46.209204 -361.199938) (xy 46.191603 -361.178973)
			(xy 46.161879 -361.13301) (xy 46.139032 -361.083269) (xy 46.123534 -361.030772) (xy 46.115702 -360.976599)
			(xy 46.115698 -360.921862) (xy 46.123521 -360.867687) (xy 46.139011 -360.815187) (xy 46.16185 -360.765443)
			(xy 46.191567 -360.719475) (xy 46.209204 -360.698542) (xy 46.2153 -360.69143) (xy 46.22165 -360.674412)
			(xy 46.22165 -360.589068) (xy 46.2153 -360.57205) (xy 46.209204 -360.564938) (xy 46.191603 -360.543973)
			(xy 46.161879 -360.49801) (xy 46.139032 -360.448269) (xy 46.123534 -360.395772) (xy 46.115702 -360.341599)
			(xy 46.115698 -360.286862) (xy 46.123521 -360.232687) (xy 46.139011 -360.180187) (xy 46.16185 -360.130443)
			(xy 46.191567 -360.084475) (xy 46.209204 -360.063542) (xy 46.2153 -360.05643) (xy 46.22165 -360.039412)
			(xy 46.22165 -359.954068) (xy 46.2153 -359.93705) (xy 46.209204 -359.929938) (xy 46.19157 -359.909002)
			(xy 46.161857 -359.86303) (xy 46.13902 -359.813284) (xy 46.123528 -359.760784) (xy 46.115699 -359.706609)
			(xy 46.115224 -359.67924) (xy 46.115693 -359.651987) (xy 46.123445 -359.598034) (xy 46.138798 -359.545735)
			(xy 46.161438 -359.496152) (xy 46.190905 -359.450298) (xy 46.226598 -359.409104) (xy 46.267791 -359.373409)
			(xy 46.313645 -359.343942) (xy 46.363227 -359.3213) (xy 46.415526 -359.305947) (xy 46.469479 -359.298193)
			(xy 46.496732 -359.297732) (xy 46.524103 -359.298172) (xy 46.578284 -359.305995) (xy 46.630788 -359.321489)
			(xy 46.680534 -359.344337) (xy 46.726499 -359.374068) (xy 46.74743 -359.391712) (xy 46.754542 -359.397808)
			(xy 46.77156 -359.404158) (xy 46.856904 -359.404158) (xy 46.873922 -359.397808) (xy 46.881034 -359.391712)
			(xy 46.901967 -359.374071) (xy 46.947935 -359.344347) (xy 46.997681 -359.321501) (xy 47.050183 -359.306005)
			(xy 47.104361 -359.298176) (xy 47.159103 -359.298176) (xy 47.213281 -359.306005) (xy 47.265783 -359.321501)
			(xy 47.315529 -359.344347) (xy 47.361497 -359.374071) (xy 47.38243 -359.391712) (xy 47.389542 -359.397808)
			(xy 47.40656 -359.404158) (xy 47.491904 -359.404158) (xy 47.508922 -359.397808) (xy 47.516034 -359.391712)
			(xy 47.536982 -359.374092) (xy 47.58295 -359.344377) (xy 47.632694 -359.321537) (xy 47.685191 -359.306042)
			(xy 47.739364 -359.298209) (xy 47.766732 -359.297732) (xy 47.793558 -359.298162) (xy 47.846678 -359.305703)
			(xy 47.898219 -359.320605) (xy 47.947167 -359.342574) (xy 47.992559 -359.371178) (xy 48.033501 -359.405853)
			(xy 48.069187 -359.445917) (xy 48.098914 -359.490581) (xy 48.122097 -359.538966) (xy 48.13828 -359.590119)
			(xy 48.14316 -359.616502) (xy 48.144938 -359.627424) (xy 48.156876 -359.645458) (xy 48.240442 -359.697274)
			(xy 48.262032 -359.700068) (xy 48.272446 -359.69702) (xy 48.299366 -359.689407) (xy 48.354711 -359.681252)
			(xy 48.382682 -359.680764) (xy 48.410053 -359.681225) (xy 48.464233 -359.689042) (xy 48.516736 -359.704531)
			(xy 48.566483 -359.727374) (xy 48.612449 -359.757101) (xy 48.63338 -359.774744) (xy 48.640492 -359.78084)
			(xy 48.65751 -359.78719) (xy 48.742854 -359.78719) (xy 48.759872 -359.78084) (xy 48.766984 -359.774744)
			(xy 48.787917 -359.757103) (xy 48.833885 -359.727379) (xy 48.883631 -359.704533) (xy 48.936133 -359.689037)
			(xy 48.990311 -359.681208) (xy 49.045053 -359.681208) (xy 49.099231 -359.689037) (xy 49.151733 -359.704533)
			(xy 49.201479 -359.727379) (xy 49.247447 -359.757103) (xy 49.26838 -359.774744) (xy 49.275492 -359.78084)
			(xy 49.29251 -359.78719) (xy 49.377854 -359.78719) (xy 49.394872 -359.78084) (xy 49.401984 -359.774744)
			(xy 49.422917 -359.757103) (xy 49.468885 -359.727379) (xy 49.518631 -359.704533) (xy 49.571133 -359.689037)
			(xy 49.625311 -359.681208) (xy 49.680053 -359.681208) (xy 49.734231 -359.689037) (xy 49.786733 -359.704533)
			(xy 49.836479 -359.727379) (xy 49.882447 -359.757103) (xy 49.90338 -359.774744) (xy 49.910492 -359.78084)
			(xy 49.92751 -359.78719) (xy 50.012854 -359.78719) (xy 50.029872 -359.78084) (xy 50.036984 -359.774744)
			(xy 50.057917 -359.757106) (xy 50.103889 -359.727392) (xy 50.153636 -359.704555) (xy 50.206137 -359.689064)
			(xy 50.260313 -359.681237) (xy 50.287682 -359.680764) (xy 50.31765 -359.68129) (xy 50.376858 -359.690599)
			(xy 50.405538 -359.699306) (xy 50.415698 -359.702608) (xy 50.436018 -359.70083) (xy 50.519584 -359.655364)
			(xy 50.532284 -359.639362) (xy 50.535078 -359.628948) (xy 50.542719 -359.602235) (xy 50.564657 -359.551191)
			(xy 50.59377 -359.50387) (xy 50.629442 -359.461274) (xy 50.670916 -359.424306) (xy 50.717316 -359.393746)
			(xy 50.76766 -359.370244) (xy 50.82088 -359.354295) (xy 50.875852 -359.346237) (xy 50.903632 -359.345738)
			(xy 50.932527 -359.346241) (xy 50.989656 -359.354951) (xy 51.044816 -359.372184) (xy 51.096745 -359.397542)
			(xy 51.120802 -359.413556) (xy 51.128422 -359.41889) (xy 51.146964 -359.423462) (xy 51.233578 -359.411778)
			(xy 51.250088 -359.402634) (xy 51.256184 -359.395522) (xy 51.274429 -359.374664) (xy 51.315856 -359.33786)
			(xy 51.362173 -359.30744) (xy 51.412405 -359.284044) (xy 51.465495 -359.268163) (xy 51.520323 -359.260134)
			(xy 51.54803 -359.259632) (xy 51.573982 -359.26006) (xy 51.625404 -359.267112) (xy 51.675397 -359.281066)
			(xy 51.723038 -359.301667) (xy 51.767447 -359.328534) (xy 51.807806 -359.36117) (xy 51.825906 -359.379774)
			(xy 51.832764 -359.386886) (xy 51.85029 -359.395268) (xy 51.939698 -359.400348) (xy 51.957986 -359.394252)
			(xy 51.965606 -359.387902) (xy 51.986326 -359.370947) (xy 52.031651 -359.34245) (xy 52.080513 -359.320564)
			(xy 52.131953 -359.305717) (xy 52.184963 -359.298202) (xy 52.211732 -359.297732) (xy 52.239103 -359.298172)
			(xy 52.293284 -359.305995) (xy 52.345788 -359.321489) (xy 52.395534 -359.344337) (xy 52.441499 -359.374068)
			(xy 52.46243 -359.391712) (xy 52.469542 -359.397808) (xy 52.48656 -359.404158) (xy 52.571904 -359.404158)
			(xy 52.588922 -359.397808) (xy 52.596034 -359.391712) (xy 52.616982 -359.374092) (xy 52.66295 -359.344377)
			(xy 52.712694 -359.321537) (xy 52.765191 -359.306042) (xy 52.819364 -359.298209) (xy 52.846732 -359.297732)
			(xy 52.873988 -359.298125) (xy 52.927943 -359.305888) (xy 52.980245 -359.32125) (xy 53.029828 -359.343899)
			(xy 53.075683 -359.373374) (xy 53.116876 -359.409075) (xy 53.152569 -359.450275) (xy 53.182036 -359.496136)
			(xy 53.204675 -359.545723) (xy 53.220028 -359.598027) (xy 53.22778 -359.651984) (xy 53.22824 -359.67924)
			(xy 53.227753 -359.707176) (xy 53.219642 -359.762456) (xy 53.203555 -359.815961) (xy 53.179837 -359.866548)
			(xy 53.148995 -359.913135) (xy 53.130704 -359.934256) (xy 53.1241 -359.941368) (xy 53.117496 -359.95864)
			(xy 53.11775 -360.045762) (xy 53.124354 -360.063034) (xy 53.130704 -360.070146) (xy 53.149106 -360.091278)
			(xy 53.180168 -360.137913) (xy 53.204071 -360.188592) (xy 53.2203 -360.242224) (xy 53.228505 -360.297653)
			(xy 53.229002 -360.32567) (xy 53.228517 -360.352922) (xy 53.220764 -360.406873) (xy 53.205411 -360.459171)
			(xy 53.182772 -360.508751) (xy 53.153306 -360.554605) (xy 53.117615 -360.595798) (xy 53.076424 -360.631492)
			(xy 53.030572 -360.66096) (xy 52.980993 -360.683603) (xy 52.928696 -360.698959) (xy 52.874746 -360.706715)
			(xy 52.847494 -360.707178) (xy 52.819383 -360.706684) (xy 52.763768 -360.698437) (xy 52.709964 -360.682124)
			(xy 52.659135 -360.658096) (xy 52.612379 -360.626873) (xy 52.591208 -360.608372) (xy 52.58435 -360.602022)
			(xy 52.567586 -360.595418) (xy 52.481734 -360.593894) (xy 52.464716 -360.59999) (xy 52.457604 -360.605832)
			(xy 52.4369 -360.622757) (xy 52.391624 -360.651213) (xy 52.342812 -360.673053) (xy 52.291423 -360.687848)
			(xy 52.23847 -360.695308) (xy 52.211732 -360.695748) (xy 52.185781 -360.695285) (xy 52.13436 -360.688242)
			(xy 52.084367 -360.674294) (xy 52.036727 -360.6537) (xy 51.992316 -360.626839) (xy 51.951956 -360.594207)
			(xy 51.933856 -360.575606) (xy 51.926998 -360.568494) (xy 51.909472 -360.560112) (xy 51.820064 -360.555032)
			(xy 51.801776 -360.561128) (xy 51.794156 -360.567478) (xy 51.773411 -360.584402) (xy 51.728093 -360.612904)
			(xy 51.679237 -360.634796) (xy 51.627803 -360.64965) (xy 51.574798 -360.657174) (xy 51.54803 -360.657648)
			(xy 51.519137 -360.6571) (xy 51.46201 -360.6484) (xy 51.40685 -360.631181) (xy 51.35492 -360.605836)
			(xy 51.33086 -360.58983) (xy 51.32324 -360.584496) (xy 51.304698 -360.579924) (xy 51.218084 -360.591608)
			(xy 51.201574 -360.600752) (xy 51.195478 -360.607864) (xy 51.17592 -360.629454) (xy 51.1683 -360.637328)
			(xy 51.160934 -360.656886) (xy 51.166014 -360.75366) (xy 51.175412 -360.772202) (xy 51.183794 -360.77906)
			(xy 51.205176 -360.797302) (xy 51.242916 -360.838946) (xy 51.274139 -360.885676) (xy 51.298169 -360.936481)
			(xy 51.314486 -360.990261) (xy 51.322737 -361.045853) (xy 51.32324 -361.073954) (xy 51.322702 -361.101204)
			(xy 51.314952 -361.155151) (xy 51.299604 -361.207445) (xy 51.276969 -361.257023) (xy 51.247509 -361.302875)
			(xy 51.211823 -361.344067) (xy 51.170638 -361.379762) (xy 51.124792 -361.409231) (xy 51.075219 -361.431876)
			(xy 51.022927 -361.447236) (xy 50.968982 -361.454996) (xy 50.941732 -361.455462) (xy 50.913823 -361.455008)
			(xy 50.858598 -361.446901) (xy 50.80515 -361.430813) (xy 50.77968 -361.419394) (xy 50.770028 -361.414822)
			(xy 50.7492 -361.41406) (xy 50.660808 -361.449112) (xy 50.645822 -361.463844) (xy 50.642012 -361.473496)
			(xy 50.630964 -361.499689) (xy 50.602339 -361.548798) (xy 50.56674 -361.593113) (xy 50.524956 -361.631652)
			(xy 50.477913 -361.663561) (xy 50.426655 -361.688132) (xy 50.372317 -361.70482) (xy 50.316104 -361.713257)
			(xy 50.287682 -361.71378) (xy 50.260311 -361.713329) (xy 50.206131 -361.705509) (xy 50.153628 -361.690016)
			(xy 50.103881 -361.667171) (xy 50.057915 -361.637443) (xy 50.036984 -361.6198) (xy 50.029872 -361.613704)
			(xy 50.012854 -361.607354) (xy 49.92751 -361.607354) (xy 49.910492 -361.613704) (xy 49.90338 -361.6198)
			(xy 49.882447 -361.637441) (xy 49.836479 -361.667165) (xy 49.786733 -361.690011) (xy 49.734231 -361.705507)
			(xy 49.680053 -361.713336) (xy 49.625311 -361.713336) (xy 49.571133 -361.705507) (xy 49.518631 -361.690011)
			(xy 49.468885 -361.667165) (xy 49.422917 -361.637441) (xy 49.401984 -361.6198) (xy 49.394872 -361.613704)
			(xy 49.377854 -361.607354) (xy 49.29251 -361.607354) (xy 49.275492 -361.613704) (xy 49.26838 -361.6198)
			(xy 49.247447 -361.637441) (xy 49.201479 -361.667165) (xy 49.151733 -361.690011) (xy 49.099231 -361.705507)
			(xy 49.045053 -361.713336) (xy 48.990311 -361.713336) (xy 48.936133 -361.705507) (xy 48.883631 -361.690011)
			(xy 48.833885 -361.667165) (xy 48.787917 -361.637441) (xy 48.766984 -361.6198) (xy 48.759872 -361.613704)
			(xy 48.742854 -361.607354) (xy 48.65751 -361.607354) (xy 48.640492 -361.613704) (xy 48.63338 -361.6198)
			(xy 48.612429 -361.637415) (xy 48.566461 -361.667131) (xy 48.516718 -361.689971) (xy 48.464222 -361.705468)
			(xy 48.41005 -361.713302) (xy 48.382682 -361.71378) (xy 48.359066 -361.713447) (xy 48.312192 -361.707641)
			(xy 48.266392 -361.696097) (xy 48.244252 -361.687872) (xy 48.235108 -361.684062) (xy 48.21555 -361.684316)
			(xy 48.132746 -361.718352) (xy 48.118776 -361.731814) (xy 48.114712 -361.740704) (xy 48.102724 -361.766129)
			(xy 48.072367 -361.813437) (xy 48.05426 -361.834938) (xy 48.048164 -361.84205) (xy 48.041814 -361.859068)
			(xy 48.041814 -361.944412) (xy 48.048164 -361.96143) (xy 48.05426 -361.968542) (xy 48.071879 -361.98949)
			(xy 48.101595 -362.035458) (xy 48.124436 -362.085201) (xy 48.139931 -362.137699) (xy 48.147764 -362.191872)
			(xy 48.14824 -362.21924) (xy 48.147759 -362.246491) (xy 48.139998 -362.300437) (xy 48.12464 -362.35273)
			(xy 48.101996 -362.402305) (xy 48.072529 -362.448154) (xy 48.036837 -362.489343) (xy 47.995647 -362.525034)
			(xy 47.949798 -362.5545) (xy 47.900222 -362.577143) (xy 47.847929 -362.5925) (xy 47.793983 -362.60026)
			(xy 47.766732 -362.600748) (xy 47.737254 -362.600203) (xy 47.679001 -362.591137) (xy 47.622836 -362.573217)
			(xy 47.570096 -362.546868) (xy 47.522039 -362.512719) (xy 47.50054 -362.492544) (xy 47.493193 -362.486026)
			(xy 47.475042 -362.478573) (xy 47.465234 -362.478066) (xy 47.411894 -362.478066) (xy 47.405036 -362.485432)
			(xy 47.398486 -362.492754) (xy 47.391052 -362.510924) (xy 47.390558 -362.520738) (xy 47.390558 -362.552742)
			(xy 47.391043 -362.562556) (xy 47.39849 -362.58072) (xy 47.405036 -362.588048) (xy 47.42523 -362.609529)
			(xy 47.459372 -362.657593) (xy 47.485715 -362.710337) (xy 47.503632 -362.766506) (xy 47.512694 -362.824762)
			(xy 47.51324 -362.85424) (xy 47.512759 -362.881491) (xy 47.504998 -362.935437) (xy 47.48964 -362.98773)
			(xy 47.466996 -363.037305) (xy 47.437529 -363.083154) (xy 47.401837 -363.124343) (xy 47.360647 -363.160034)
			(xy 47.314798 -363.1895) (xy 47.265222 -363.212143) (xy 47.212929 -363.2275) (xy 47.158983 -363.23526)
			(xy 47.131732 -363.235748) (xy 47.104362 -363.235276) (xy 47.050183 -363.227461) (xy 46.997679 -363.211974)
			(xy 46.947932 -363.189134) (xy 46.901965 -363.159409) (xy 46.881034 -363.141768) (xy 46.873922 -363.135672)
			(xy 46.856904 -363.129322) (xy 46.77156 -363.129322) (xy 46.754542 -363.135672) (xy 46.74743 -363.141768)
			(xy 46.726493 -363.159402) (xy 46.680522 -363.189115) (xy 46.630776 -363.211953) (xy 46.578276 -363.227445)
			(xy 46.524101 -363.235274) (xy 46.496732 -363.235748) (xy 46.469483 -363.235192) (xy 46.41554 -363.227441)
			(xy 46.363249 -363.212092) (xy 46.313675 -363.189457) (xy 46.267826 -363.159998) (xy 46.226637 -363.124314)
			(xy 46.190945 -363.083131) (xy 46.161477 -363.037288) (xy 46.138833 -362.987718) (xy 46.123474 -362.93543)
			(xy 46.115713 -362.881489) (xy 46.115224 -362.85424) (xy 36.238634 -362.85424) (xy 36.243366 -362.859521)
			(xy 36.274139 -362.906034) (xy 36.297811 -362.956531) (xy 36.313879 -363.009938) (xy 36.321999 -363.065114)
			(xy 36.322508 -363.093) (xy 36.321999 -363.120886) (xy 36.313879 -363.176062) (xy 36.297811 -363.229469)
			(xy 36.274139 -363.279966) (xy 36.243366 -363.326479) (xy 36.206149 -363.368016) (xy 36.163281 -363.403691)
			(xy 36.115675 -363.432745) (xy 36.064346 -363.454557) (xy 36.010389 -363.468663) (xy 35.954952 -363.474763)
			(xy 35.899218 -363.472726) (xy 35.844375 -363.462596) (xy 35.791591 -363.444589) (xy 35.741991 -363.419088)
			(xy 35.696633 -363.386637) (xy 35.656484 -363.347928) (xy 35.622398 -363.303785) (xy 35.595102 -363.25515)
			(xy 35.575179 -363.203059) (xy 35.563053 -363.148622) (xy 35.558982 -363.093) (xy 30.52826 -363.093)
			(xy 31.16326 -363.728) (xy 34.161982 -363.728) (xy 34.166053 -363.672378) (xy 34.178179 -363.617941)
			(xy 34.198102 -363.56585) (xy 34.225398 -363.517215) (xy 34.259484 -363.473072) (xy 34.299633 -363.434363)
			(xy 34.344991 -363.401912) (xy 34.394591 -363.376411) (xy 34.447375 -363.358404) (xy 34.502218 -363.348274)
			(xy 34.557952 -363.346237) (xy 34.613389 -363.352337) (xy 34.667346 -363.366443) (xy 34.718675 -363.388255)
			(xy 34.766281 -363.417309) (xy 34.809149 -363.452984) (xy 34.846366 -363.494521) (xy 34.877139 -363.541034)
			(xy 34.900811 -363.591531) (xy 34.916879 -363.644938) (xy 34.924999 -363.700114) (xy 34.925508 -363.728)
			(xy 34.924999 -363.755886) (xy 34.916879 -363.811062) (xy 34.900811 -363.864469) (xy 34.877139 -363.914966)
			(xy 34.846366 -363.961479) (xy 34.809149 -364.003016) (xy 34.766281 -364.038691) (xy 34.718675 -364.067745)
			(xy 34.667346 -364.089557) (xy 34.613389 -364.103663) (xy 34.564886 -364.109) (xy 35.559492 -364.109)
			(xy 35.559978 -364.081749) (xy 35.567734 -364.027801) (xy 35.583089 -363.975506) (xy 35.605731 -363.925929)
			(xy 35.635197 -363.880079) (xy 35.670888 -363.838888) (xy 35.712079 -363.803197) (xy 35.757929 -363.773731)
			(xy 35.807506 -363.751089) (xy 35.859801 -363.735734) (xy 35.913749 -363.727978) (xy 35.968251 -363.727978)
			(xy 36.022199 -363.735734) (xy 36.074494 -363.751089) (xy 36.124071 -363.773731) (xy 36.169921 -363.803197)
			(xy 36.211112 -363.838888) (xy 36.246803 -363.880079) (xy 36.276269 -363.925929) (xy 36.298911 -363.975506)
			(xy 36.314266 -364.027801) (xy 36.322022 -364.081749) (xy 36.322508 -364.109) (xy 36.322005 -364.137749)
			(xy 36.313352 -364.194592) (xy 36.296272 -364.249494) (xy 36.271152 -364.301214) (xy 36.238559 -364.348581)
			(xy 36.199231 -364.390525) (xy 36.176966 -364.40872) (xy 36.167568 -364.416086) (xy 36.157408 -364.437168)
			(xy 36.157916 -364.5408) (xy 36.16833 -364.561882) (xy 36.177728 -364.568994) (xy 36.2004 -364.587168)
			(xy 36.203652 -364.590584) (xy 39.286178 -364.590584) (xy 39.290249 -364.534962) (xy 39.302375 -364.480525)
			(xy 39.322298 -364.428434) (xy 39.349594 -364.379799) (xy 39.38368 -364.335656) (xy 39.423829 -364.296947)
			(xy 39.469187 -364.264496) (xy 39.518787 -364.238995) (xy 39.571571 -364.220988) (xy 39.626414 -364.210858)
			(xy 39.682148 -364.208821) (xy 39.737585 -364.214921) (xy 39.791542 -364.229027) (xy 39.842871 -364.250839)
			(xy 39.890477 -364.279893) (xy 39.933345 -364.315568) (xy 39.970562 -364.357105) (xy 40.001335 -364.403618)
			(xy 40.025007 -364.454115) (xy 40.041075 -364.507522) (xy 40.049195 -364.562698) (xy 40.049704 -364.590584)
			(xy 40.049195 -364.61847) (xy 40.041075 -364.673646) (xy 40.025007 -364.727053) (xy 40.001335 -364.77755)
			(xy 39.970562 -364.824063) (xy 39.933345 -364.8656) (xy 39.890477 -364.901275) (xy 39.842871 -364.930329)
			(xy 39.791542 -364.952141) (xy 39.737585 -364.966247) (xy 39.682148 -364.972347) (xy 39.626414 -364.97031)
			(xy 39.571571 -364.96018) (xy 39.518787 -364.942173) (xy 39.469187 -364.916672) (xy 39.423829 -364.884221)
			(xy 39.38368 -364.845512) (xy 39.349594 -364.801369) (xy 39.322298 -364.752734) (xy 39.302375 -364.700643)
			(xy 39.290249 -364.646206) (xy 39.286178 -364.590584) (xy 36.203652 -364.590584) (xy 36.240465 -364.629252)
			(xy 36.273688 -364.676923) (xy 36.299301 -364.729078) (xy 36.316712 -364.784513) (xy 36.32552 -364.841947)
			(xy 36.326064 -364.871) (xy 36.325578 -364.898251) (xy 36.317822 -364.952199) (xy 36.302467 -365.004494)
			(xy 36.279825 -365.054071) (xy 36.250359 -365.099921) (xy 36.214668 -365.141112) (xy 36.173477 -365.176803)
			(xy 36.127627 -365.206269) (xy 36.07805 -365.228911) (xy 36.025755 -365.244266) (xy 35.971807 -365.252022)
			(xy 35.917305 -365.252022) (xy 35.863357 -365.244266) (xy 35.811062 -365.228911) (xy 35.761485 -365.206269)
			(xy 35.715635 -365.176803) (xy 35.674444 -365.141112) (xy 35.638753 -365.099921) (xy 35.609287 -365.054071)
			(xy 35.586645 -365.004494) (xy 35.57129 -364.952199) (xy 35.563534 -364.898251) (xy 35.563048 -364.871)
			(xy 35.56353 -364.84225) (xy 35.572184 -364.785405) (xy 35.589267 -364.730502) (xy 35.614391 -364.678781)
			(xy 35.646989 -364.631415) (xy 35.686323 -364.589473) (xy 35.70859 -364.57128) (xy 35.717988 -364.563914)
			(xy 35.728148 -364.542832) (xy 35.72764 -364.4392) (xy 35.717226 -364.418118) (xy 35.707828 -364.411006)
			(xy 35.685147 -364.392843) (xy 35.645085 -364.350755) (xy 35.611864 -364.303082) (xy 35.586253 -364.250925)
			(xy 35.568843 -364.195488) (xy 35.560036 -364.138053) (xy 35.559492 -364.109) (xy 34.564886 -364.109)
			(xy 34.557952 -364.109763) (xy 34.502218 -364.107726) (xy 34.447375 -364.097596) (xy 34.394591 -364.079589)
			(xy 34.344991 -364.054088) (xy 34.299633 -364.021637) (xy 34.259484 -363.982928) (xy 34.225398 -363.938785)
			(xy 34.198102 -363.89015) (xy 34.178179 -363.838059) (xy 34.166053 -363.783622) (xy 34.161982 -363.728)
			(xy 31.16326 -363.728) (xy 33.318958 -365.883698) (xy 34.673284 -365.883698) (xy 34.677355 -365.828076)
			(xy 34.689481 -365.773639) (xy 34.709404 -365.721548) (xy 34.7367 -365.672913) (xy 34.770786 -365.62877)
			(xy 34.810935 -365.590061) (xy 34.856293 -365.55761) (xy 34.905893 -365.532109) (xy 34.958677 -365.514102)
			(xy 35.01352 -365.503972) (xy 35.069254 -365.501935) (xy 35.124691 -365.508035) (xy 35.178648 -365.522141)
			(xy 35.229977 -365.543953) (xy 35.277583 -365.573007) (xy 35.320451 -365.608682) (xy 35.34641 -365.637654)
			(xy 39.929749 -365.637654) (xy 39.929749 -365.583146) (xy 39.937507 -365.529193) (xy 39.952864 -365.476893)
			(xy 39.975508 -365.427311) (xy 40.004978 -365.381456) (xy 40.040674 -365.340263) (xy 40.081869 -365.304568)
			(xy 40.127725 -365.2751) (xy 40.177308 -365.252458) (xy 40.229608 -365.237104) (xy 40.283562 -365.229348)
			(xy 40.310816 -365.228886) (xy 40.338124 -365.229343) (xy 40.392178 -365.237159) (xy 40.444565 -365.252601)
			(xy 40.494216 -365.275353) (xy 40.540117 -365.304951) (xy 40.58133 -365.34079) (xy 40.617013 -365.382137)
			(xy 40.646437 -365.428149) (xy 40.669002 -365.477886) (xy 40.684246 -365.530332) (xy 40.688514 -365.557308)
			(xy 40.690038 -365.566706) (xy 40.699182 -365.58347) (xy 40.766746 -365.639096) (xy 40.78478 -365.645192)
			(xy 40.794432 -365.644684) (xy 40.813736 -365.644176) (xy 40.840309 -365.644685) (xy 40.89294 -365.652065)
			(xy 40.944038 -365.666678) (xy 40.992614 -365.68824) (xy 41.037727 -365.716335) (xy 41.078505 -365.750418)
			(xy 41.114158 -365.78983) (xy 41.129458 -365.811562) (xy 41.135046 -365.819944) (xy 41.151048 -365.830612)
			(xy 41.239948 -365.849154) (xy 41.258998 -365.845852) (xy 41.267634 -365.840518) (xy 41.290547 -365.826607)
			(xy 41.339456 -365.80467) (xy 41.390957 -365.789802) (xy 41.444032 -365.782297) (xy 41.470834 -365.781844)
			(xy 41.49808 -365.782428) (xy 41.552017 -365.790188) (xy 41.604301 -365.805544) (xy 41.653868 -365.828184)
			(xy 41.699708 -365.857648) (xy 41.740889 -365.893335) (xy 41.776573 -365.934519) (xy 41.806032 -365.980362)
			(xy 41.828668 -366.02993) (xy 41.844019 -366.082216) (xy 41.851774 -366.136154) (xy 41.851774 -366.190646)
			(xy 41.844019 -366.244584) (xy 41.828668 -366.29687) (xy 41.806032 -366.346438) (xy 41.776573 -366.392281)
			(xy 41.740889 -366.433465) (xy 41.699708 -366.469152) (xy 41.653868 -366.498616) (xy 41.604301 -366.521256)
			(xy 41.552017 -366.536612) (xy 41.49808 -366.544372) (xy 41.470834 -366.54486) (xy 41.43883 -366.54359)
			(xy 41.427654 -366.542574) (xy 41.407588 -366.549686) (xy 41.336468 -366.616996) (xy 41.32834 -366.636808)
			(xy 41.328594 -366.647984) (xy 41.328848 -366.659668) (xy 41.328362 -366.686919) (xy 41.320606 -366.740867)
			(xy 41.305251 -366.793162) (xy 41.282609 -366.842739) (xy 41.253143 -366.888589) (xy 41.217452 -366.92978)
			(xy 41.176261 -366.965471) (xy 41.130411 -366.994937) (xy 41.080834 -367.017579) (xy 41.028539 -367.032934)
			(xy 40.974591 -367.04069) (xy 40.920089 -367.04069) (xy 40.866141 -367.032934) (xy 40.813846 -367.017579)
			(xy 40.764269 -366.994937) (xy 40.718419 -366.965471) (xy 40.677228 -366.92978) (xy 40.641537 -366.888589)
			(xy 40.612071 -366.842739) (xy 40.589429 -366.793162) (xy 40.574074 -366.740867) (xy 40.566318 -366.686919)
			(xy 40.565832 -366.659668) (xy 40.56624 -366.634507) (xy 40.572854 -366.584621) (xy 40.585963 -366.536036)
			(xy 40.60534 -366.489593) (xy 40.617648 -366.467644) (xy 40.622474 -366.459262) (xy 40.625522 -366.441228)
			(xy 40.607488 -366.35563) (xy 40.597328 -366.340136) (xy 40.589454 -366.334294) (xy 40.569062 -366.318937)
			(xy 40.532164 -366.283659) (xy 40.500294 -366.243781) (xy 40.474019 -366.200014) (xy 40.453807 -366.153137)
			(xy 40.440019 -366.103986) (xy 40.436038 -366.07877) (xy 40.434514 -366.069372) (xy 40.42537 -366.052608)
			(xy 40.357806 -365.996982) (xy 40.339772 -365.990886) (xy 40.33012 -365.991394) (xy 40.310816 -365.991902)
			(xy 40.283562 -365.991452) (xy 40.229608 -365.983696) (xy 40.177308 -365.968342) (xy 40.127725 -365.9457)
			(xy 40.081869 -365.916232) (xy 40.040674 -365.880537) (xy 40.004978 -365.839344) (xy 39.975508 -365.793489)
			(xy 39.952864 -365.743907) (xy 39.937507 -365.691607) (xy 39.929749 -365.637654) (xy 35.34641 -365.637654)
			(xy 35.357668 -365.650219) (xy 35.388441 -365.696732) (xy 35.412113 -365.747229) (xy 35.428181 -365.800636)
			(xy 35.436301 -365.855812) (xy 35.43681 -365.883698) (xy 35.436301 -365.911584) (xy 35.428181 -365.96676)
			(xy 35.412113 -366.020167) (xy 35.391785 -366.06353) (xy 38.846504 -366.06353) (xy 38.850575 -366.007908)
			(xy 38.862701 -365.953471) (xy 38.882624 -365.90138) (xy 38.90992 -365.852745) (xy 38.944006 -365.808602)
			(xy 38.984155 -365.769893) (xy 39.029513 -365.737442) (xy 39.079113 -365.711941) (xy 39.131897 -365.693934)
			(xy 39.18674 -365.683804) (xy 39.242474 -365.681767) (xy 39.297911 -365.687867) (xy 39.351868 -365.701973)
			(xy 39.403197 -365.723785) (xy 39.450803 -365.752839) (xy 39.493671 -365.788514) (xy 39.530888 -365.830051)
			(xy 39.561661 -365.876564) (xy 39.585333 -365.927061) (xy 39.601401 -365.980468) (xy 39.609521 -366.035644)
			(xy 39.61003 -366.06353) (xy 39.609521 -366.091416) (xy 39.601401 -366.146592) (xy 39.585333 -366.199999)
			(xy 39.561661 -366.250496) (xy 39.530888 -366.297009) (xy 39.493671 -366.338546) (xy 39.450803 -366.374221)
			(xy 39.403197 -366.403275) (xy 39.351868 -366.425087) (xy 39.297911 -366.439193) (xy 39.242474 -366.445293)
			(xy 39.18674 -366.443256) (xy 39.131897 -366.433126) (xy 39.079113 -366.415119) (xy 39.029513 -366.389618)
			(xy 38.984155 -366.357167) (xy 38.944006 -366.318458) (xy 38.90992 -366.274315) (xy 38.882624 -366.22568)
			(xy 38.862701 -366.173589) (xy 38.850575 -366.119152) (xy 38.846504 -366.06353) (xy 35.391785 -366.06353)
			(xy 35.388441 -366.070664) (xy 35.357668 -366.117177) (xy 35.320451 -366.158714) (xy 35.277583 -366.194389)
			(xy 35.229977 -366.223443) (xy 35.178648 -366.245255) (xy 35.124691 -366.259361) (xy 35.069254 -366.265461)
			(xy 35.01352 -366.263424) (xy 34.958677 -366.253294) (xy 34.905893 -366.235287) (xy 34.856293 -366.209786)
			(xy 34.810935 -366.177335) (xy 34.770786 -366.138626) (xy 34.7367 -366.094483) (xy 34.709404 -366.045848)
			(xy 34.689481 -365.993757) (xy 34.677355 -365.93932) (xy 34.673284 -365.883698) (xy 33.318958 -365.883698)
			(xy 33.852358 -366.417098) (xy 33.866328 -366.424464) (xy 33.873948 -366.425734) (xy 33.902514 -366.431352)
			(xy 33.957631 -366.450098) (xy 34.009259 -366.477) (xy 34.056201 -366.511434) (xy 34.097366 -366.552599)
			(xy 34.1318 -366.599541) (xy 34.158702 -366.651169) (xy 34.177448 -366.706286) (xy 34.183066 -366.734852)
			(xy 34.184336 -366.742472) (xy 34.191702 -366.756442) (xy 34.886138 -367.450878) (xy 34.893537 -367.457721)
			(xy 34.912136 -367.465445) (xy 34.922206 -367.465864) (xy 34.956496 -367.465864) (xy 34.967608 -367.46531)
			(xy 34.987773 -367.455968) (xy 34.995358 -367.44783) (xy 35.052762 -367.380012) (xy 35.058604 -367.358676)
			(xy 35.056826 -367.3475) (xy 35.054336 -367.331743) (xy 35.051668 -367.299952) (xy 35.051492 -367.284)
			(xy 35.051978 -367.256749) (xy 35.059734 -367.202801) (xy 35.075089 -367.150506) (xy 35.097731 -367.100929)
			(xy 35.127197 -367.055079) (xy 35.162888 -367.013888) (xy 35.204079 -366.978197) (xy 35.249929 -366.948731)
			(xy 35.299506 -366.926089) (xy 35.351801 -366.910734) (xy 35.405749 -366.902978) (xy 35.460251 -366.902978)
			(xy 35.514199 -366.910734) (xy 35.566494 -366.926089) (xy 35.616071 -366.948731) (xy 35.661921 -366.978197)
			(xy 35.703112 -367.013888) (xy 35.738803 -367.055079) (xy 35.768269 -367.100929) (xy 35.790911 -367.150506)
			(xy 35.806266 -367.202801) (xy 35.814022 -367.256749) (xy 35.814508 -367.284) (xy 35.814349 -367.299952)
			(xy 35.811681 -367.331745) (xy 35.809174 -367.3475) (xy 35.807396 -367.358676) (xy 35.813238 -367.380012)
			(xy 35.870642 -367.44783) (xy 35.878232 -367.455966) (xy 35.898391 -367.465321) (xy 35.909504 -367.465864)
			(xy 39.442898 -367.465864) (xy 39.452778 -367.465409) (xy 39.471087 -367.457978) (xy 39.478458 -367.451386)
			(xy 39.497984 -367.432937) (xy 39.541285 -367.401143) (xy 39.588617 -367.375737) (xy 39.639045 -367.357223)
			(xy 39.691572 -367.345966) (xy 39.745158 -367.342189) (xy 39.798744 -367.345966) (xy 39.851271 -367.357223)
			(xy 39.901699 -367.375737) (xy 39.949031 -367.401143) (xy 39.992332 -367.432937) (xy 40.011858 -367.451386)
			(xy 40.019241 -367.457964) (xy 40.03754 -367.465407) (xy 40.047418 -367.465864) (xy 41.202356 -367.465864)
			(xy 41.21242 -367.466299) (xy 41.231004 -367.474035) (xy 41.238424 -367.48085) (xy 41.403016 -367.645442)
			(xy 41.410413 -367.652292) (xy 41.429011 -367.66003) (xy 41.439084 -367.660428)
		)
		(stroke
			(width 0)
			(type solid)
		)
		(fill yes)
		(layer "In15.Cu")
		(net "GND")
	)
	(gr_poly
		(pts
			(xy 106.405934 -395.859) (xy 106.416949 -395.858453) (xy 106.436954 -395.849225) (xy 106.444542 -395.84122)
			(xy 106.501946 -395.774164) (xy 106.508042 -395.752828) (xy 106.506264 -395.741652) (xy 106.503411 -395.722156)
			(xy 106.500362 -395.682869) (xy 106.500168 -395.663166) (xy 106.50067 -395.631205) (xy 106.508681 -395.567787)
			(xy 106.524578 -395.505873) (xy 106.54811 -395.44644) (xy 106.578904 -395.390425) (xy 106.616477 -395.33871)
			(xy 106.660234 -395.292113) (xy 106.709487 -395.251368) (xy 106.763458 -395.217117) (xy 106.821297 -395.1899)
			(xy 106.88209 -395.170147) (xy 106.94488 -395.158169) (xy 107.008676 -395.154156) (xy 107.072472 -395.158169)
			(xy 107.135262 -395.170147) (xy 107.196055 -395.1899) (xy 107.253894 -395.217117) (xy 107.307865 -395.251368)
			(xy 107.357118 -395.292113) (xy 107.400875 -395.33871) (xy 107.438448 -395.390425) (xy 107.469242 -395.44644)
			(xy 107.492774 -395.505873) (xy 107.508671 -395.567787) (xy 107.516682 -395.631205) (xy 107.517184 -395.663166)
			(xy 107.516994 -395.682869) (xy 107.513945 -395.722156) (xy 107.511088 -395.741652) (xy 107.50931 -395.752828)
			(xy 107.515406 -395.774164) (xy 107.57281 -395.84122) (xy 107.580384 -395.84924) (xy 107.6004 -395.858452)
			(xy 107.611418 -395.859) (xy 112.071658 -395.859) (xy 112.081723 -395.858566) (xy 112.100313 -395.850837)
			(xy 112.107726 -395.844014) (xy 113.167414 -394.784326) (xy 113.174812 -394.777479) (xy 113.19341 -394.769746)
			(xy 113.203482 -394.76934) (xy 113.321338 -394.76934) (xy 113.331048 -394.768904) (xy 113.349074 -394.761676)
			(xy 113.363126 -394.748269) (xy 113.367566 -394.739622) (xy 113.41227 -394.642086) (xy 113.408206 -394.612876)
			(xy 113.3983 -394.601446) (xy 113.380886 -394.580553) (xy 113.351539 -394.534761) (xy 113.329005 -394.48526)
			(xy 113.313742 -394.433056) (xy 113.306059 -394.379213) (xy 113.30559 -394.352018) (xy 113.306076 -394.324767)
			(xy 113.313832 -394.270819) (xy 113.329187 -394.218524) (xy 113.351829 -394.168947) (xy 113.381295 -394.123097)
			(xy 113.416986 -394.081906) (xy 113.458177 -394.046215) (xy 113.504027 -394.016749) (xy 113.553604 -393.994107)
			(xy 113.605899 -393.978752) (xy 113.659847 -393.970996) (xy 113.714349 -393.970996) (xy 113.768297 -393.978752)
			(xy 113.820592 -393.994107) (xy 113.870169 -394.016749) (xy 113.916019 -394.046215) (xy 113.95721 -394.081906)
			(xy 113.992901 -394.123097) (xy 114.022367 -394.168947) (xy 114.045009 -394.218524) (xy 114.060364 -394.270819)
			(xy 114.06812 -394.324767) (xy 114.068606 -394.352018) (xy 114.068118 -394.379209) (xy 114.060394 -394.433039)
			(xy 114.045117 -394.485231) (xy 114.022596 -394.53473) (xy 113.993287 -394.580538) (xy 113.975896 -394.601446)
			(xy 113.96599 -394.612876) (xy 113.961926 -394.642086) (xy 114.00663 -394.739622) (xy 114.011049 -394.748283)
			(xy 114.025105 -394.761696) (xy 114.043144 -394.768909) (xy 114.052858 -394.76934) (xy 133.420358 -394.76934)
			(xy 133.430422 -394.768905) (xy 133.449006 -394.761169) (xy 133.456426 -394.754354) (xy 134.117334 -394.093446)
			(xy 134.124179 -394.086048) (xy 134.131904 -394.067449) (xy 134.13232 -394.057378) (xy 134.13232 -393.596368)
			(xy 134.131838 -393.58486) (xy 134.121921 -393.564094) (xy 134.11327 -393.55649) (xy 134.091209 -393.538305)
			(xy 134.052265 -393.496449) (xy 134.020006 -393.449249) (xy 133.995156 -393.397761) (xy 133.978272 -393.34314)
			(xy 133.969732 -393.28661) (xy 133.969729 -393.229439) (xy 133.978261 -393.172909) (xy 133.995138 -393.118285)
			(xy 134.019981 -393.066794) (xy 134.052234 -393.019589) (xy 134.091172 -392.977729) (xy 134.11327 -392.95959)
			(xy 134.121902 -392.951972) (xy 134.131809 -392.931214) (xy 134.13232 -392.919712) (xy 134.13232 -390.5504)
			(xy 134.131994 -390.541853) (xy 134.126368 -390.525712) (xy 134.115744 -390.512321) (xy 134.108698 -390.507474)
			(xy 134.024878 -390.454642) (xy 133.999224 -390.453118) (xy 133.987032 -390.458706) (xy 133.964782 -390.468801)
			(xy 133.918051 -390.483055) (xy 133.869729 -390.490269) (xy 133.8453 -390.49071) (xy 133.819313 -390.4902)
			(xy 133.767978 -390.48207) (xy 133.718547 -390.466009) (xy 133.672238 -390.442413) (xy 133.63019 -390.411863)
			(xy 133.593438 -390.375112) (xy 133.562888 -390.333064) (xy 133.539292 -390.286754) (xy 133.523231 -390.237324)
			(xy 133.5151 -390.185989) (xy 133.514592 -390.160002) (xy 133.515115 -390.133241) (xy 133.523745 -390.080419)
			(xy 133.540763 -390.029674) (xy 133.565726 -389.98233) (xy 133.597984 -389.93962) (xy 133.636694 -389.902659)
			(xy 133.680849 -389.87241) (xy 133.704838 -389.860536) (xy 133.716014 -389.855456) (xy 133.731 -389.835644)
			(xy 133.74751 -389.74141) (xy 133.748887 -389.729306) (xy 133.741595 -389.706099) (xy 133.73354 -389.69696)
			(xy 133.690614 -389.654034) (xy 133.682592 -389.646871) (xy 133.662506 -389.639255) (xy 133.651752 -389.639302)
			(xy 133.564884 -389.644382) (xy 133.545834 -389.654288) (xy 133.538976 -389.662924) (xy 133.523918 -389.681279)
			(xy 133.489229 -389.713693) (xy 133.450079 -389.740547) (xy 133.407349 -389.761237) (xy 133.362003 -389.775296)
			(xy 133.315064 -389.782408) (xy 133.291326 -389.782812) (xy 133.265931 -389.782306) (xy 133.215796 -389.774179)
			(xy 133.167608 -389.758131) (xy 133.122611 -389.734575) (xy 133.081966 -389.704118) (xy 133.046721 -389.667548)
			(xy 133.017785 -389.625807) (xy 132.995904 -389.579972) (xy 132.988304 -389.555736) (xy 132.98678 -389.549894)
			(xy 132.666486 -388.996174) (xy 132.662422 -388.991856) (xy 132.646232 -388.974147) (xy 132.618855 -388.934745)
			(xy 132.597764 -388.89165) (xy 132.583446 -388.845856) (xy 132.576232 -388.798422) (xy 132.575808 -388.774432)
			(xy 132.575894 -388.762384) (xy 132.577677 -388.738355) (xy 132.579364 -388.726426) (xy 132.580634 -388.717536)
			(xy 132.577586 -388.700518) (xy 132.535422 -388.629652) (xy 132.522214 -388.618476) (xy 132.513832 -388.615428)
			(xy 132.491148 -388.606645) (xy 132.44868 -388.582929) (xy 132.410515 -388.552774) (xy 132.377619 -388.516943)
			(xy 132.350827 -388.476346) (xy 132.34035 -388.454392) (xy 132.334 -388.440676) (xy 132.308854 -388.42442)
			(xy 132.02666 -388.42442) (xy 132.017271 -388.424848) (xy 131.999745 -388.431591) (xy 131.985799 -388.444168)
			(xy 131.981194 -388.45236) (xy 131.93395 -388.54634) (xy 131.936236 -388.574788) (xy 131.944872 -388.586472)
			(xy 131.961182 -388.609449) (xy 131.986229 -388.659915) (xy 131.994656 -388.686802) (xy 131.99618 -388.692644)
			(xy 132.315966 -389.245602) (xy 132.32003 -389.24992) (xy 132.336219 -389.267629) (xy 132.363595 -389.307032)
			(xy 132.384685 -389.350128) (xy 132.399004 -389.39592) (xy 132.40622 -389.443354) (xy 132.406644 -389.467344)
			(xy 132.406154 -389.492131) (xy 132.398393 -389.541093) (xy 132.383068 -389.588238) (xy 132.360557 -389.632405)
			(xy 132.331413 -389.672508) (xy 132.296356 -389.707558) (xy 132.256247 -389.736692) (xy 132.212075 -389.759194)
			(xy 132.164926 -389.774509) (xy 132.115963 -389.78226) (xy 132.091176 -389.782812) (xy 132.065783 -389.782302)
			(xy 132.015654 -389.774169) (xy 131.967472 -389.758115) (xy 131.922482 -389.734556) (xy 131.881843 -389.704099)
			(xy 131.846605 -389.667529) (xy 131.817674 -389.625789) (xy 131.795799 -389.579957) (xy 131.788154 -389.555736)
			(xy 131.78663 -389.549894) (xy 131.466082 -388.995412) (xy 131.462018 -388.991094) (xy 131.445941 -388.973415)
			(xy 131.418757 -388.934116) (xy 131.397802 -388.891171) (xy 131.383554 -388.84556) (xy 131.376338 -388.798324)
			(xy 131.375912 -388.774432) (xy 131.375998 -388.762384) (xy 131.377781 -388.738355) (xy 131.379468 -388.726426)
			(xy 131.380738 -388.717536) (xy 131.37769 -388.700518) (xy 131.335526 -388.629652) (xy 131.322318 -388.618476)
			(xy 131.313936 -388.615428) (xy 131.291252 -388.606646) (xy 131.248784 -388.58293) (xy 131.210618 -388.552774)
			(xy 131.177722 -388.516944) (xy 131.150929 -388.476347) (xy 131.140454 -388.454392) (xy 131.134104 -388.440676)
			(xy 131.108958 -388.42442) (xy 130.82651 -388.42442) (xy 130.817126 -388.424856) (xy 130.799613 -388.43161)
			(xy 130.785682 -388.44419) (xy 130.781044 -388.45236) (xy 130.7338 -388.54634) (xy 130.736086 -388.574788)
			(xy 130.744722 -388.586472) (xy 130.760909 -388.609286) (xy 130.785816 -388.659369) (xy 130.794252 -388.68604)
			(xy 130.795776 -388.691882) (xy 131.11607 -389.245602) (xy 131.120134 -389.24992) (xy 131.136323 -389.267629)
			(xy 131.163698 -389.307032) (xy 131.184788 -389.350128) (xy 131.199107 -389.395921) (xy 131.206323 -389.443354)
			(xy 131.206748 -389.467344) (xy 131.206258 -389.492131) (xy 131.198497 -389.541093) (xy 131.183172 -389.588238)
			(xy 131.160661 -389.632406) (xy 131.131518 -389.672509) (xy 131.09646 -389.707559) (xy 131.056352 -389.736694)
			(xy 131.012179 -389.759196) (xy 130.965031 -389.774512) (xy 130.916067 -389.782263) (xy 130.89128 -389.782812)
			(xy 130.865887 -389.782303) (xy 130.815757 -389.77417) (xy 130.767575 -389.758117) (xy 130.722584 -389.734558)
			(xy 130.681945 -389.7041) (xy 130.646706 -389.66753) (xy 130.617775 -389.62579) (xy 130.595899 -389.579958)
			(xy 130.588258 -389.555736) (xy 130.586734 -389.549894) (xy 130.26644 -388.996174) (xy 130.262376 -388.991856)
			(xy 130.246162 -388.974157) (xy 130.218734 -388.934767) (xy 130.197592 -388.891675) (xy 130.183223 -388.845877)
			(xy 130.17596 -388.798431) (xy 130.175508 -388.774432) (xy 130.175666 -388.76238) (xy 130.177575 -388.738352)
			(xy 130.179318 -388.726426) (xy 130.180588 -388.717536) (xy 130.17754 -388.700518) (xy 130.135376 -388.629652)
			(xy 130.122168 -388.618476) (xy 130.113786 -388.615428) (xy 130.092045 -388.607023) (xy 130.0512 -388.58457)
			(xy 130.014242 -388.556171) (xy 129.982029 -388.522485) (xy 129.955309 -388.484294) (xy 129.934705 -388.442487)
			(xy 129.920693 -388.398033) (xy 129.9136 -388.351967) (xy 129.913126 -388.328662) (xy 129.913219 -388.318406)
			(xy 129.91462 -388.297942) (xy 129.91592 -388.287768) (xy 129.917444 -388.276084) (xy 129.909824 -388.253478)
			(xy 129.47523 -387.818884) (xy 129.466228 -387.810843) (xy 129.443295 -387.80342) (xy 129.431288 -387.80466)
			(xy 129.33807 -387.819392) (xy 129.318512 -387.833362) (xy 129.312924 -387.844284) (xy 129.302289 -387.864297)
			(xy 129.276364 -387.90147) (xy 129.245603 -387.934753) (xy 129.228342 -387.94944) (xy 129.219452 -387.956552)
			(xy 129.210054 -387.97611) (xy 129.20726 -388.075424) (xy 129.215896 -388.09549) (xy 129.224278 -388.10311)
			(xy 129.242701 -388.120597) (xy 129.274045 -388.160564) (xy 129.298344 -388.205167) (xy 129.314927 -388.253175)
			(xy 129.323338 -388.303266) (xy 129.323846 -388.328662) (xy 129.323774 -388.33802) (xy 129.322628 -388.356702)
			(xy 129.32156 -388.366) (xy 129.320544 -388.37489) (xy 129.324354 -388.391654) (xy 129.368296 -388.461504)
			(xy 129.382012 -388.471918) (xy 129.390394 -388.474712) (xy 129.41449 -388.483195) (xy 129.459777 -388.506825)
			(xy 129.50067 -388.537438) (xy 129.536101 -388.574234) (xy 129.565147 -388.616253) (xy 129.58705 -388.662401)
			(xy 129.59461 -388.686802) (xy 129.596134 -388.692644) (xy 129.91592 -389.245602) (xy 129.919984 -389.24992)
			(xy 129.936202 -389.267618) (xy 129.963636 -389.307006) (xy 129.984784 -389.350098) (xy 129.999158 -389.395896)
			(xy 130.006425 -389.443343) (xy 130.006852 -389.467344) (xy 130.006387 -389.492146) (xy 129.998617 -389.541136)
			(xy 129.983275 -389.588308) (xy 129.96074 -389.632496) (xy 129.931567 -389.672614) (xy 129.896475 -389.707671)
			(xy 129.856328 -389.736804) (xy 129.812117 -389.759295) (xy 129.764931 -389.77459) (xy 129.715932 -389.782311)
			(xy 129.69113 -389.782812) (xy 129.665735 -389.782307) (xy 129.615599 -389.77418) (xy 129.567411 -389.758132)
			(xy 129.522413 -389.734576) (xy 129.481768 -389.70412) (xy 129.446522 -389.66755) (xy 129.417585 -389.625808)
			(xy 129.395705 -389.579973) (xy 129.388108 -389.555736) (xy 129.386584 -389.549894) (xy 129.066036 -388.995412)
			(xy 129.061972 -388.991094) (xy 129.045866 -388.973426) (xy 129.018624 -388.934142) (xy 128.997611 -388.891201)
			(xy 128.983308 -388.845585) (xy 128.97604 -388.798334) (xy 128.975612 -388.774432) (xy 128.97577 -388.76238)
			(xy 128.977679 -388.738352) (xy 128.979422 -388.726426) (xy 128.980692 -388.717536) (xy 128.977644 -388.700518)
			(xy 128.93548 -388.629652) (xy 128.922272 -388.618476) (xy 128.91389 -388.615428) (xy 128.892149 -388.607023)
			(xy 128.851304 -388.584571) (xy 128.814345 -388.556172) (xy 128.782131 -388.522486) (xy 128.755411 -388.484295)
			(xy 128.734806 -388.442487) (xy 128.720794 -388.398034) (xy 128.713701 -388.351967) (xy 128.71323 -388.328662)
			(xy 128.71373 -388.303264) (xy 128.72213 -388.253168) (xy 128.738709 -388.205155) (xy 128.763009 -388.160549)
			(xy 128.794359 -388.120582) (xy 128.812798 -388.10311) (xy 128.82118 -388.09549) (xy 128.829816 -388.075424)
			(xy 128.827022 -387.97611) (xy 128.817624 -387.956552) (xy 128.808734 -387.94944) (xy 128.790171 -387.933639)
			(xy 128.757441 -387.897513) (xy 128.730366 -387.856977) (xy 128.709531 -387.812906) (xy 128.695387 -387.766256)
			(xy 128.68824 -387.718036) (xy 128.68783 -387.693662) (xy 128.688269 -387.669546) (xy 128.695275 -387.621826)
			(xy 128.709133 -387.575628) (xy 128.729551 -387.531931) (xy 128.74244 -387.511544) (xy 128.748282 -387.502654)
			(xy 128.751838 -387.482588) (xy 128.730756 -387.390386) (xy 128.718564 -387.373622) (xy 128.709674 -387.368288)
			(xy 128.688871 -387.355433) (xy 128.650951 -387.324556) (xy 128.617999 -387.288426) (xy 128.590733 -387.247833)
			(xy 128.569749 -387.203663) (xy 128.555508 -387.156882) (xy 128.548318 -387.108513) (xy 128.547876 -387.084062)
			(xy 128.548644 -387.052132) (xy 128.560923 -386.989462) (xy 128.57226 -386.959602) (xy 128.577848 -386.945378)
			(xy 128.572006 -386.91566) (xy 128.535938 -386.879592) (xy 128.528536 -386.872756) (xy 128.509938 -386.865046)
			(xy 128.49987 -386.864606) (xy 127.0254 -386.864606) (xy 127.013984 -386.86507) (xy 126.993363 -386.874859)
			(xy 126.985776 -386.883402) (xy 126.92888 -386.954014) (xy 126.923546 -386.976366) (xy 126.926086 -386.987542)
			(xy 126.930884 -387.011382) (xy 126.935971 -387.059746) (xy 126.936246 -387.084062) (xy 126.935642 -387.117382)
			(xy 126.925972 -387.183316) (xy 126.906845 -387.247152) (xy 126.89332 -387.27761) (xy 126.88906 -387.28808)
			(xy 126.889136 -387.310654) (xy 126.898884 -387.331016) (xy 126.90729 -387.33857) (xy 126.929539 -387.357243)
			(xy 126.969606 -387.399297) (xy 127.004031 -387.446083) (xy 127.03226 -387.496848) (xy 127.05384 -387.550776)
			(xy 127.068424 -387.607001) (xy 127.075777 -387.664619) (xy 127.0762 -387.693662) (xy 127.075749 -387.722666)
			(xy 127.068418 -387.780209) (xy 127.053882 -387.836366) (xy 127.032372 -387.890238) (xy 127.004233 -387.940964)
			(xy 126.969915 -387.987732) (xy 126.929968 -388.029793) (xy 126.907798 -388.0485) (xy 126.900686 -388.054088)
			(xy 126.891542 -388.069328) (xy 126.876302 -388.152132) (xy 126.879096 -388.169404) (xy 126.883668 -388.177532)
			(xy 126.896263 -388.20071) (xy 126.914151 -388.250331) (xy 126.923234 -388.302289) (xy 126.9238 -388.328662)
			(xy 127.51308 -388.328662) (xy 127.513602 -388.303407) (xy 127.521915 -388.253585) (xy 127.538316 -388.205811)
			(xy 127.562357 -388.161388) (xy 127.593381 -388.121528) (xy 127.630543 -388.087318) (xy 127.672829 -388.059692)
			(xy 127.719085 -388.039402) (xy 127.76805 -388.027002) (xy 127.818388 -388.022831) (xy 127.868726 -388.027002)
			(xy 127.917691 -388.039402) (xy 127.963947 -388.059692) (xy 128.006233 -388.087318) (xy 128.043395 -388.121528)
			(xy 128.074419 -388.161388) (xy 128.09846 -388.205811) (xy 128.114861 -388.253585) (xy 128.123174 -388.303407)
			(xy 128.123696 -388.328662) (xy 128.123628 -388.338021) (xy 128.122484 -388.356703) (xy 128.12141 -388.366)
			(xy 128.120394 -388.37489) (xy 128.124204 -388.391654) (xy 128.168146 -388.461504) (xy 128.181862 -388.471918)
			(xy 128.190244 -388.474712) (xy 128.214273 -388.483178) (xy 128.259445 -388.506731) (xy 128.30025 -388.537231)
			(xy 128.335629 -388.573886) (xy 128.364665 -388.615746) (xy 128.386603 -388.661724) (xy 128.394206 -388.68604)
			(xy 128.39573 -388.691882) (xy 128.716024 -389.245602) (xy 128.720088 -389.24992) (xy 128.736278 -389.26764)
			(xy 128.763704 -389.307028) (xy 128.78485 -389.350114) (xy 128.799227 -389.395906) (xy 128.806504 -389.443346)
			(xy 128.806956 -389.467344) (xy 128.806547 -389.49215) (xy 128.798775 -389.54115) (xy 128.783431 -389.58833)
			(xy 128.760892 -389.632527) (xy 128.731714 -389.672651) (xy 128.696615 -389.707715) (xy 128.656462 -389.736854)
			(xy 128.612243 -389.75935) (xy 128.565048 -389.774648) (xy 128.516041 -389.782371) (xy 128.491234 -389.782812)
			(xy 128.465841 -389.782282) (xy 128.415708 -389.774156) (xy 128.367524 -389.75811) (xy 128.322529 -389.734556)
			(xy 128.281886 -389.704103) (xy 128.246643 -389.667535) (xy 128.217708 -389.625797) (xy 128.195829 -389.579965)
			(xy 128.188212 -389.555736) (xy 128.186688 -389.549894) (xy 127.866394 -388.996174) (xy 127.86233 -388.991856)
			(xy 127.846167 -388.974126) (xy 127.8188 -388.934722) (xy 127.79771 -388.891631) (xy 127.783384 -388.845846)
			(xy 127.77615 -388.79842) (xy 127.775716 -388.774432) (xy 127.775797 -388.762384) (xy 127.777579 -388.738355)
			(xy 127.779272 -388.726426) (xy 127.780542 -388.717536) (xy 127.777494 -388.700518) (xy 127.73533 -388.629652)
			(xy 127.722122 -388.618476) (xy 127.71374 -388.615428) (xy 127.691986 -388.607049) (xy 127.651128 -388.584604)
			(xy 127.614159 -388.556208) (xy 127.581937 -388.52252) (xy 127.555213 -388.484324) (xy 127.534608 -388.442508)
			(xy 127.520601 -388.398046) (xy 127.513518 -388.35197) (xy 127.51308 -388.328662) (xy 126.9238 -388.328662)
			(xy 126.923728 -388.33802) (xy 126.922582 -388.356702) (xy 126.921514 -388.366) (xy 126.920498 -388.37489)
			(xy 126.924308 -388.391654) (xy 126.96825 -388.461504) (xy 126.981966 -388.471918) (xy 126.990348 -388.474712)
			(xy 127.014382 -388.483168) (xy 127.059559 -388.506717) (xy 127.100367 -388.537216) (xy 127.135747 -388.573874)
			(xy 127.16478 -388.615738) (xy 127.186713 -388.661721) (xy 127.19431 -388.68604) (xy 127.195834 -388.691882)
			(xy 127.516128 -389.245602) (xy 127.520192 -389.24992) (xy 127.536409 -389.267618) (xy 127.563843 -389.307007)
			(xy 127.58499 -389.350098) (xy 127.599364 -389.395896) (xy 127.606631 -389.443344) (xy 127.60706 -389.467344)
			(xy 127.606595 -389.492146) (xy 127.598825 -389.541137) (xy 127.583483 -389.588309) (xy 127.560948 -389.632498)
			(xy 127.531775 -389.672616) (xy 127.496683 -389.707674) (xy 127.456537 -389.736808) (xy 127.412326 -389.7593)
			(xy 127.365139 -389.774596) (xy 127.31614 -389.782319) (xy 127.291338 -389.782812) (xy 127.265942 -389.782307)
			(xy 127.215806 -389.774182) (xy 127.167616 -389.758134) (xy 127.122618 -389.734579) (xy 127.081971 -389.704123)
			(xy 127.046724 -389.667553) (xy 127.017787 -389.625811) (xy 126.995906 -389.579975) (xy 126.988316 -389.555736)
			(xy 126.986792 -389.549894) (xy 126.666498 -388.996174) (xy 126.662434 -388.991856) (xy 126.646243 -388.974148)
			(xy 126.618866 -388.934746) (xy 126.597774 -388.89165) (xy 126.583455 -388.845857) (xy 126.576241 -388.798422)
			(xy 126.57582 -388.774432) (xy 126.575906 -388.762384) (xy 126.577689 -388.738355) (xy 126.579376 -388.726426)
			(xy 126.580646 -388.717536) (xy 126.577598 -388.700518) (xy 126.535434 -388.629652) (xy 126.522226 -388.618476)
			(xy 126.513844 -388.615428) (xy 126.490935 -388.606542) (xy 126.448073 -388.582519) (xy 126.409614 -388.551939)
			(xy 126.37655 -388.515594) (xy 126.362714 -388.495286) (xy 126.356364 -388.485634) (xy 126.336806 -388.473696)
			(xy 126.24689 -388.464298) (xy 126.235539 -388.463769) (xy 126.214168 -388.471408) (xy 126.205742 -388.47903)
			(xy 126.134876 -388.549896) (xy 126.127476 -388.556739) (xy 126.108878 -388.564465) (xy 126.098808 -388.564882)
			(xy 126.021338 -388.564882) (xy 126.01131 -388.565295) (xy 125.992777 -388.572957) (xy 125.978589 -388.58713)
			(xy 125.970906 -388.605655) (xy 125.970538 -388.615682) (xy 125.970538 -388.627366) (xy 125.975618 -388.63778)
			(xy 125.981108 -388.649499) (xy 125.990389 -388.67366) (xy 125.99416 -388.68604) (xy 125.995684 -388.691882)
			(xy 126.315978 -389.245602) (xy 126.320042 -389.24992) (xy 126.33623 -389.26763) (xy 126.363605 -389.307033)
			(xy 126.384695 -389.350128) (xy 126.399013 -389.395921) (xy 126.406229 -389.443354) (xy 126.406656 -389.467344)
			(xy 126.406166 -389.492131) (xy 126.398405 -389.541094) (xy 126.38308 -389.58824) (xy 126.360569 -389.632408)
			(xy 126.331426 -389.672511) (xy 126.296369 -389.707562) (xy 126.25626 -389.736698) (xy 126.212088 -389.759201)
			(xy 126.164939 -389.774518) (xy 126.115975 -389.782271) (xy 126.091188 -389.782812) (xy 126.065795 -389.782303)
			(xy 126.015664 -389.774171) (xy 125.967481 -389.758119) (xy 125.922489 -389.734561) (xy 125.881849 -389.704103)
			(xy 125.846608 -389.667533) (xy 125.817677 -389.625793) (xy 125.7958 -389.57996) (xy 125.788166 -389.555736)
			(xy 125.786642 -389.549894) (xy 125.466348 -388.996174) (xy 125.462284 -388.991856) (xy 125.446069 -388.974157)
			(xy 125.418641 -388.934767) (xy 125.397498 -388.891675) (xy 125.383129 -388.845878) (xy 125.375866 -388.798432)
			(xy 125.375416 -388.774432) (xy 125.375574 -388.76238) (xy 125.377483 -388.738352) (xy 125.379226 -388.726426)
			(xy 125.380496 -388.717536) (xy 125.377448 -388.700518) (xy 125.335284 -388.629652) (xy 125.322076 -388.618476)
			(xy 125.313694 -388.615428) (xy 125.293516 -388.607668) (xy 125.255396 -388.587276) (xy 125.237748 -388.574788)
			(xy 125.23105 -388.570205) (xy 125.215634 -388.565163) (xy 125.207522 -388.564882) (xy 124.821442 -388.564882)
			(xy 124.811414 -388.565294) (xy 124.792879 -388.572956) (xy 124.77869 -388.587129) (xy 124.771006 -388.605654)
			(xy 124.770642 -388.615682) (xy 124.770642 -388.627366) (xy 124.775722 -388.63778) (xy 124.781213 -388.649499)
			(xy 124.790497 -388.673659) (xy 124.794264 -388.68604) (xy 124.795788 -388.691882) (xy 125.116082 -389.245602)
			(xy 125.120146 -389.24992) (xy 125.136339 -389.267627) (xy 125.163721 -389.307028) (xy 125.184818 -389.350123)
			(xy 125.199141 -389.395917) (xy 125.206359 -389.443353) (xy 125.20676 -389.467344) (xy 125.20627 -389.492131)
			(xy 125.198509 -389.541094) (xy 125.183184 -389.58824) (xy 125.160673 -389.632409) (xy 125.13153 -389.672513)
			(xy 125.096473 -389.707564) (xy 125.056365 -389.7367) (xy 125.012192 -389.759204) (xy 124.965043 -389.774521)
			(xy 124.916079 -389.782274) (xy 124.891292 -389.782812) (xy 124.865899 -389.782304) (xy 124.815767 -389.774172)
			(xy 124.767584 -389.75812) (xy 124.722591 -389.734562) (xy 124.681951 -389.704105) (xy 124.64671 -389.667535)
			(xy 124.617778 -389.625795) (xy 124.595901 -389.579961) (xy 124.58827 -389.555736) (xy 124.586746 -389.549894)
			(xy 124.266452 -388.996174) (xy 124.262388 -388.991856) (xy 124.246173 -388.974157) (xy 124.218744 -388.934767)
			(xy 124.197601 -388.891676) (xy 124.183232 -388.845878) (xy 124.175969 -388.798432) (xy 124.17552 -388.774432)
			(xy 124.175678 -388.76238) (xy 124.177587 -388.738352) (xy 124.17933 -388.726426) (xy 124.1806 -388.717536)
			(xy 124.177552 -388.700518) (xy 124.135388 -388.629652) (xy 124.12218 -388.618476) (xy 124.113798 -388.615428)
			(xy 124.09362 -388.607668) (xy 124.055499 -388.587276) (xy 124.037852 -388.574788) (xy 124.031154 -388.570204)
			(xy 124.015738 -388.565161) (xy 124.007626 -388.564882) (xy 123.621546 -388.564882) (xy 123.611517 -388.565293)
			(xy 123.592982 -388.572955) (xy 123.578791 -388.587128) (xy 123.571106 -388.605654) (xy 123.570746 -388.615682)
			(xy 123.570746 -388.627366) (xy 123.575826 -388.63778) (xy 123.581418 -388.649675) (xy 123.59083 -388.674217)
			(xy 123.594622 -388.686802) (xy 123.596146 -388.692644) (xy 123.915932 -389.245602) (xy 123.919996 -389.24992)
			(xy 123.936213 -389.267618) (xy 123.963646 -389.307007) (xy 123.984794 -389.350098) (xy 123.999167 -389.395896)
			(xy 124.006434 -389.443344) (xy 124.006864 -389.467344) (xy 124.006399 -389.492146) (xy 123.998629 -389.541137)
			(xy 123.983287 -389.588309) (xy 123.960752 -389.632499) (xy 123.93158 -389.672617) (xy 123.896487 -389.707676)
			(xy 123.856341 -389.73681) (xy 123.81213 -389.759303) (xy 123.764943 -389.774599) (xy 123.715944 -389.782322)
			(xy 123.691142 -389.782812) (xy 123.665746 -389.782307) (xy 123.615609 -389.774183) (xy 123.567419 -389.758136)
			(xy 123.52242 -389.73458) (xy 123.481773 -389.704125) (xy 123.446526 -389.667554) (xy 123.417588 -389.625813)
			(xy 123.395706 -389.579977) (xy 123.38812 -389.555736) (xy 123.386596 -389.549894) (xy 123.066048 -388.995412)
			(xy 123.061984 -388.991094) (xy 123.045882 -388.973424) (xy 123.018647 -388.934138) (xy 122.99764 -388.891197)
			(xy 122.983341 -388.845582) (xy 122.976076 -388.798333) (xy 122.975624 -388.774432) (xy 122.975782 -388.76238)
			(xy 122.977691 -388.738352) (xy 122.979434 -388.726426) (xy 122.980704 -388.717536) (xy 122.977656 -388.700518)
			(xy 122.935492 -388.629652) (xy 122.922284 -388.618476) (xy 122.913902 -388.615428) (xy 122.893724 -388.607668)
			(xy 122.855603 -388.587277) (xy 122.837956 -388.574788) (xy 122.831258 -388.570204) (xy 122.815842 -388.565159)
			(xy 122.80773 -388.564882) (xy 122.421396 -388.564882) (xy 122.411388 -388.56537) (xy 122.392894 -388.57303)
			(xy 122.378738 -388.587182) (xy 122.371073 -388.605674) (xy 122.370596 -388.615682) (xy 122.370596 -388.627366)
			(xy 122.375676 -388.63778) (xy 122.381166 -388.649499) (xy 122.390449 -388.673659) (xy 122.394218 -388.68604)
			(xy 122.395742 -388.691882) (xy 122.716036 -389.245602) (xy 122.7201 -389.24992) (xy 122.736317 -389.267618)
			(xy 122.76375 -389.307007) (xy 122.784897 -389.350098) (xy 122.79927 -389.395896) (xy 122.806537 -389.443344)
			(xy 122.806968 -389.467344) (xy 122.806503 -389.492146) (xy 122.798733 -389.541138) (xy 122.783391 -389.58831)
			(xy 122.760857 -389.6325) (xy 122.731684 -389.672619) (xy 122.696592 -389.707678) (xy 122.656445 -389.736813)
			(xy 122.612234 -389.759306) (xy 122.565048 -389.774602) (xy 122.516048 -389.782326) (xy 122.491246 -389.782812)
			(xy 122.46585 -389.782308) (xy 122.415712 -389.774183) (xy 122.367522 -389.758137) (xy 122.322523 -389.734582)
			(xy 122.281875 -389.704126) (xy 122.246627 -389.667556) (xy 122.217689 -389.625814) (xy 122.195807 -389.579978)
			(xy 122.188224 -389.555736) (xy 122.1867 -389.549894) (xy 121.866406 -388.996174) (xy 121.862342 -388.991856)
			(xy 121.846151 -388.974148) (xy 121.818772 -388.934746) (xy 121.79768 -388.891651) (xy 121.783361 -388.845857)
			(xy 121.776147 -388.798423) (xy 121.775728 -388.774432) (xy 121.775814 -388.762384) (xy 121.777597 -388.738355)
			(xy 121.779284 -388.726426) (xy 121.780554 -388.717536) (xy 121.777506 -388.700518) (xy 121.735342 -388.629652)
			(xy 121.722134 -388.618476) (xy 121.713752 -388.615428) (xy 121.693575 -388.607665) (xy 121.655458 -388.587269)
			(xy 121.637806 -388.574788) (xy 121.63111 -388.570197) (xy 121.615694 -388.565137) (xy 121.60758 -388.564882)
			(xy 121.2215 -388.564882) (xy 121.211491 -388.56537) (xy 121.192996 -388.573029) (xy 121.178839 -388.587181)
			(xy 121.171173 -388.605673) (xy 121.1707 -388.615682) (xy 121.1707 -388.627366) (xy 121.17578 -388.63778)
			(xy 121.18127 -388.649499) (xy 121.190553 -388.673659) (xy 121.194322 -388.68604) (xy 121.195846 -388.691882)
			(xy 121.51614 -389.245602) (xy 121.520204 -389.24992) (xy 121.536421 -389.267618) (xy 121.563853 -389.307007)
			(xy 121.585 -389.350099) (xy 121.599373 -389.395897) (xy 121.60664 -389.443344) (xy 121.607072 -389.467344)
			(xy 121.606607 -389.492146) (xy 121.598837 -389.541138) (xy 121.583495 -389.588311) (xy 121.560961 -389.632501)
			(xy 121.531788 -389.67262) (xy 121.496696 -389.707679) (xy 121.45655 -389.736815) (xy 121.412339 -389.759308)
			(xy 121.365152 -389.774605) (xy 121.316153 -389.78233) (xy 121.29135 -389.782812) (xy 121.265954 -389.782308)
			(xy 121.215816 -389.774184) (xy 121.167625 -389.758138) (xy 121.122625 -389.734583) (xy 121.081977 -389.704128)
			(xy 121.046728 -389.667558) (xy 121.01779 -389.625816) (xy 120.995907 -389.579979) (xy 120.988328 -389.555736)
			(xy 120.986804 -389.549894) (xy 120.66651 -388.996174) (xy 120.662446 -388.991856) (xy 120.646255 -388.974148)
			(xy 120.618876 -388.934746) (xy 120.597783 -388.891651) (xy 120.583464 -388.845857) (xy 120.57625 -388.798423)
			(xy 120.575832 -388.774432) (xy 120.575918 -388.762384) (xy 120.577701 -388.738355) (xy 120.579388 -388.726426)
			(xy 120.580658 -388.717536) (xy 120.57761 -388.700518) (xy 120.535446 -388.629652) (xy 120.522238 -388.618476)
			(xy 120.513856 -388.615428) (xy 120.492117 -388.607021) (xy 120.451275 -388.584566) (xy 120.41432 -388.556166)
			(xy 120.382111 -388.522479) (xy 120.355394 -388.484289) (xy 120.334792 -388.442482) (xy 120.320782 -388.39803)
			(xy 120.31369 -388.351966) (xy 120.313196 -388.328662) (xy 120.313699 -388.303653) (xy 120.32185 -388.254305)
			(xy 120.337928 -388.206942) (xy 120.349264 -388.184644) (xy 120.357138 -388.169658) (xy 120.352312 -388.136638)
			(xy 120.228868 -388.013194) (xy 120.222015 -388.005798) (xy 120.214272 -387.9872) (xy 120.213882 -387.977126)
			(xy 120.213882 -387.91388) (xy 120.211342 -387.902704) (xy 120.208548 -387.89737) (xy 120.193479 -387.86555)
			(xy 120.172199 -387.798439) (xy 120.161428 -387.728864) (xy 120.160796 -387.693662) (xy 120.161418 -387.658458)
			(xy 120.172163 -387.588875) (xy 120.193456 -387.521765) (xy 120.208548 -387.489954) (xy 120.21101 -387.484629)
			(xy 120.213705 -387.473212) (xy 120.213882 -387.467348) (xy 120.213882 -387.457442) (xy 120.18873 -387.438963)
			(xy 120.14319 -387.396287) (xy 120.103869 -387.34782) (xy 120.071495 -387.294462) (xy 120.046668 -387.2372)
			(xy 120.02985 -387.177098) (xy 120.021351 -387.115268) (xy 120.020842 -387.084062) (xy 120.021303 -387.054581)
			(xy 120.02888 -386.996109) (xy 120.043904 -386.939094) (xy 120.066126 -386.884481) (xy 120.095177 -386.833174)
			(xy 120.130577 -386.786022) (xy 120.17174 -386.743808) (xy 120.194578 -386.72516) (xy 120.203976 -386.717794)
			(xy 120.213882 -386.69722) (xy 120.213882 -386.655818) (xy 120.209564 -386.64134) (xy 120.204992 -386.63499)
			(xy 120.191498 -386.614308) (xy 120.170134 -386.569787) (xy 120.155624 -386.522586) (xy 120.14829 -386.473753)
			(xy 120.147842 -386.449062) (xy 120.148096 -386.43687) (xy 120.14835 -386.427218) (xy 120.142254 -386.409184)
			(xy 120.08358 -386.341874) (xy 120.066816 -386.333238) (xy 120.05691 -386.332222) (xy 120.029994 -386.328875)
			(xy 119.977688 -386.314536) (xy 119.928424 -386.291852) (xy 119.883523 -386.26143) (xy 119.84419 -386.224088)
			(xy 119.81148 -386.180827) (xy 119.786269 -386.132807) (xy 119.769235 -386.081316) (xy 119.764556 -386.0546)
			(xy 119.763032 -386.045202) (xy 119.490236 -385.57327) (xy 119.48287 -385.567428) (xy 119.464095 -385.551623)
			(xy 119.430968 -385.515413) (xy 119.403553 -385.474708) (xy 119.382453 -385.430399) (xy 119.368129 -385.383459)
			(xy 119.360897 -385.334918) (xy 119.360442 -385.31038) (xy 119.360927 -385.284393) (xy 119.369061 -385.23306)
			(xy 119.385125 -385.183631) (xy 119.408725 -385.137325) (xy 119.439278 -385.09528) (xy 119.476033 -385.058533)
			(xy 119.518084 -385.027988) (xy 119.564396 -385.004399) (xy 119.613828 -384.988344) (xy 119.665163 -384.980221)
			(xy 119.69115 -384.979672) (xy 119.717163 -384.980153) (xy 119.768549 -384.988294) (xy 119.818025 -385.004381)
			(xy 119.864371 -385.028019) (xy 119.906444 -385.058624) (xy 119.943204 -385.09544) (xy 119.973744 -385.137559)
			(xy 119.997312 -385.183941) (xy 120.013324 -385.233442) (xy 120.017794 -385.259072) (xy 120.019318 -385.26847)
			(xy 120.11914 -385.44119) (xy 120.125201 -385.45055) (xy 120.143453 -385.463317) (xy 120.165391 -385.467167)
			(xy 120.17629 -385.464812) (xy 120.193054 -385.46024) (xy 120.213882 -385.433062) (xy 120.213882 -383.396744)
			(xy 120.213448 -383.386679) (xy 120.205717 -383.368091) (xy 120.198896 -383.360676) (xy 119.96928 -383.13106)
			(xy 119.960472 -383.123137) (xy 119.938022 -383.115663) (xy 119.914599 -383.119007) (xy 119.90451 -383.125218)
			(xy 119.883672 -383.139031) (xy 119.838712 -383.160891) (xy 119.790975 -383.175735) (xy 119.741546 -383.183223)
			(xy 119.71655 -383.183638) (xy 119.690557 -383.183159) (xy 119.639211 -383.175034) (xy 119.589768 -383.158976)
			(xy 119.543445 -383.135382) (xy 119.501385 -383.104831) (xy 119.464621 -383.068076) (xy 119.43406 -383.026023)
			(xy 119.410454 -382.979706) (xy 119.394385 -382.930267) (xy 119.386248 -382.878923) (xy 119.385842 -382.85293)
			(xy 119.386282 -382.827935) (xy 119.393768 -382.778509) (xy 119.408604 -382.730771) (xy 119.430454 -382.685809)
			(xy 119.444262 -382.66497) (xy 119.449046 -382.657508) (xy 119.45358 -382.640384) (xy 119.451979 -382.622742)
			(xy 119.444434 -382.606714) (xy 119.43842 -382.6002) (xy 119.410226 -382.572006) (xy 119.402824 -382.565171)
			(xy 119.384225 -382.557462) (xy 119.374158 -382.55702) (xy 118.90248 -382.55702) (xy 118.89384 -382.557354)
			(xy 118.877544 -382.563101) (xy 118.864106 -382.573962) (xy 118.8593 -382.58115) (xy 118.806976 -382.66624)
			(xy 118.805706 -382.692402) (xy 118.811802 -382.70434) (xy 118.822913 -382.727519) (xy 118.838633 -382.776455)
			(xy 118.84661 -382.827231) (xy 118.847108 -382.85293) (xy 118.846598 -382.878917) (xy 118.838468 -382.930252)
			(xy 118.822407 -382.979682) (xy 118.798811 -383.025992) (xy 118.768261 -383.06804) (xy 118.73151 -383.104791)
			(xy 118.689462 -383.135341) (xy 118.643152 -383.158937) (xy 118.593722 -383.174998) (xy 118.542387 -383.183128)
			(xy 118.490413 -383.183128) (xy 118.439078 -383.174998) (xy 118.389648 -383.158937) (xy 118.343338 -383.135341)
			(xy 118.30129 -383.104791) (xy 118.264539 -383.06804) (xy 118.233989 -383.025992) (xy 118.210393 -382.979682)
			(xy 118.194332 -382.930252) (xy 118.186202 -382.878917) (xy 118.185692 -382.85293) (xy 118.186173 -382.827228)
			(xy 118.194126 -382.776444) (xy 118.209859 -382.727507) (xy 118.220998 -382.70434) (xy 118.227094 -382.692402)
			(xy 118.225824 -382.66624) (xy 118.1735 -382.58115) (xy 118.168665 -382.573993) (xy 118.155221 -382.563168)
			(xy 118.138949 -382.557409) (xy 118.13032 -382.55702) (xy 117.702584 -382.55702) (xy 117.693944 -382.557353)
			(xy 117.677647 -382.5631) (xy 117.664207 -382.573961) (xy 117.659404 -382.58115) (xy 117.60708 -382.66624)
			(xy 117.60581 -382.692402) (xy 117.611906 -382.70434) (xy 117.623017 -382.727519) (xy 117.638737 -382.776455)
			(xy 117.646713 -382.827231) (xy 117.647212 -382.85293) (xy 117.646702 -382.878917) (xy 117.638572 -382.930252)
			(xy 117.622511 -382.979682) (xy 117.598915 -383.025992) (xy 117.568365 -383.06804) (xy 117.531614 -383.104791)
			(xy 117.489566 -383.135341) (xy 117.443256 -383.158937) (xy 117.393826 -383.174998) (xy 117.342491 -383.183128)
			(xy 117.290517 -383.183128) (xy 117.239182 -383.174998) (xy 117.189752 -383.158937) (xy 117.143442 -383.135341)
			(xy 117.101394 -383.104791) (xy 117.064643 -383.06804) (xy 117.034093 -383.025992) (xy 117.010497 -382.979682)
			(xy 116.994436 -382.930252) (xy 116.986306 -382.878917) (xy 116.985796 -382.85293) (xy 116.986277 -382.827228)
			(xy 116.994227 -382.776443) (xy 117.009956 -382.727504) (xy 117.021102 -382.70434) (xy 117.027198 -382.692402)
			(xy 117.025928 -382.66624) (xy 116.973604 -382.58115) (xy 116.968769 -382.573993) (xy 116.955326 -382.563166)
			(xy 116.939054 -382.557406) (xy 116.930424 -382.55702) (xy 116.502688 -382.55702) (xy 116.494047 -382.557353)
			(xy 116.47775 -382.563098) (xy 116.464309 -382.573959) (xy 116.459508 -382.58115) (xy 116.407184 -382.66624)
			(xy 116.405914 -382.692402) (xy 116.41201 -382.70434) (xy 116.423121 -382.727519) (xy 116.43884 -382.776455)
			(xy 116.446817 -382.827231) (xy 116.447316 -382.85293) (xy 116.446806 -382.878917) (xy 116.438676 -382.930252)
			(xy 116.422615 -382.979682) (xy 116.399019 -383.025992) (xy 116.368469 -383.06804) (xy 116.331718 -383.104791)
			(xy 116.28967 -383.135341) (xy 116.24336 -383.158937) (xy 116.19393 -383.174998) (xy 116.142595 -383.183128)
			(xy 116.090621 -383.183128) (xy 116.039286 -383.174998) (xy 115.989856 -383.158937) (xy 115.943546 -383.135341)
			(xy 115.901498 -383.104791) (xy 115.864747 -383.06804) (xy 115.834197 -383.025992) (xy 115.810601 -382.979682)
			(xy 115.79454 -382.930252) (xy 115.78641 -382.878917) (xy 115.7859 -382.85293) (xy 115.786381 -382.827228)
			(xy 115.794331 -382.776443) (xy 115.81006 -382.727504) (xy 115.821206 -382.70434) (xy 115.827302 -382.692402)
			(xy 115.826032 -382.66624) (xy 115.773708 -382.58115) (xy 115.768873 -382.573992) (xy 115.75543 -382.563165)
			(xy 115.739158 -382.557403) (xy 115.730528 -382.55702) (xy 115.302538 -382.55702) (xy 115.293901 -382.55736)
			(xy 115.277616 -382.563117) (xy 115.264189 -382.573982) (xy 115.259358 -382.58115) (xy 115.207034 -382.66624)
			(xy 115.205764 -382.692402) (xy 115.21186 -382.70434) (xy 115.222972 -382.727518) (xy 115.238694 -382.776454)
			(xy 115.246672 -382.827231) (xy 115.247166 -382.85293) (xy 115.246656 -382.878917) (xy 115.238526 -382.930252)
			(xy 115.222465 -382.979682) (xy 115.198869 -383.025992) (xy 115.168319 -383.06804) (xy 115.131568 -383.104791)
			(xy 115.08952 -383.135341) (xy 115.04321 -383.158937) (xy 114.99378 -383.174998) (xy 114.942445 -383.183128)
			(xy 114.890471 -383.183128) (xy 114.839136 -383.174998) (xy 114.789706 -383.158937) (xy 114.743396 -383.135341)
			(xy 114.701348 -383.104791) (xy 114.664597 -383.06804) (xy 114.634047 -383.025992) (xy 114.610451 -382.979682)
			(xy 114.59439 -382.930252) (xy 114.58626 -382.878917) (xy 114.58575 -382.85293) (xy 114.586231 -382.827228)
			(xy 114.594183 -382.776443) (xy 114.609914 -382.727506) (xy 114.621056 -382.70434) (xy 114.627152 -382.692402)
			(xy 114.625882 -382.66624) (xy 114.573558 -382.58115) (xy 114.568726 -382.573987) (xy 114.555284 -382.563146)
			(xy 114.539011 -382.557369) (xy 114.530378 -382.55702) (xy 113.92154 -382.55702) (xy 113.912247 -382.557434)
			(xy 113.894877 -382.56405) (xy 113.880984 -382.576399) (xy 113.876328 -382.584452) (xy 113.828322 -382.677416)
			(xy 113.830354 -382.705356) (xy 113.838482 -382.717294) (xy 113.852793 -382.738328) (xy 113.875468 -382.783867)
			(xy 113.890898 -382.832344) (xy 113.898716 -382.882612) (xy 113.899188 -382.908048) (xy 113.898675 -382.934032)
			(xy 113.890538 -382.98536) (xy 113.874473 -383.034782) (xy 113.850874 -383.081084) (xy 113.820323 -383.123124)
			(xy 113.783572 -383.159867) (xy 113.741526 -383.19041) (xy 113.69522 -383.213999) (xy 113.645793 -383.230054)
			(xy 113.594464 -383.23818) (xy 113.56848 -383.238756) (xy 113.539883 -383.238157) (xy 113.483541 -383.228327)
			(xy 113.429731 -383.208948) (xy 113.380059 -383.180598) (xy 113.35766 -383.16281) (xy 113.350802 -383.157222)
			(xy 113.334038 -383.151126) (xy 113.251742 -383.151126) (xy 113.234978 -383.156968) (xy 113.22812 -383.162556)
			(xy 113.205765 -383.180207) (xy 113.156254 -383.208359) (xy 113.10265 -383.227607) (xy 113.046539 -383.237381)
			(xy 113.018062 -383.237994) (xy 112.994829 -383.237598) (xy 112.948821 -383.23109) (xy 112.904177 -383.218208)
			(xy 112.861775 -383.199205) (xy 112.822449 -383.174455) (xy 112.804448 -383.159762) (xy 112.797336 -383.153666)
			(xy 112.780826 -383.14757) (xy 112.696498 -383.14757) (xy 112.679988 -383.153666) (xy 112.672876 -383.159762)
			(xy 112.654886 -383.174471) (xy 112.615561 -383.199228) (xy 112.573156 -383.218234) (xy 112.528508 -383.231114)
			(xy 112.482497 -383.237616) (xy 112.459262 -383.237994) (xy 112.433277 -383.237482) (xy 112.381948 -383.229346)
			(xy 112.332524 -383.213282) (xy 112.28622 -383.189684) (xy 112.244179 -383.159133) (xy 112.207433 -383.122382)
			(xy 112.176889 -383.080335) (xy 112.153298 -383.034028) (xy 112.137242 -382.984601) (xy 112.129114 -382.933271)
			(xy 112.128554 -382.907286) (xy 112.12904 -382.881936) (xy 112.13678 -382.831831) (xy 112.152076 -382.783493)
			(xy 112.174569 -382.738057) (xy 112.188752 -382.71704) (xy 112.19688 -382.705356) (xy 112.198912 -382.677162)
			(xy 112.150652 -382.584452) (xy 112.146049 -382.576408) (xy 112.132251 -382.564057) (xy 112.114953 -382.557446)
			(xy 112.105694 -382.55702) (xy 109.59973 -382.55702) (xy 109.571282 -382.581658) (xy 109.568488 -382.600454)
			(xy 109.564021 -382.627253) (xy 109.548493 -382.679314) (xy 109.525735 -382.728646) (xy 109.496207 -382.774249)
			(xy 109.460508 -382.815201) (xy 109.419359 -382.850674) (xy 109.373593 -382.879949) (xy 109.324136 -382.902433)
			(xy 109.27199 -382.917673) (xy 109.218208 -382.92536) (xy 109.191044 -382.925828) (xy 109.166971 -382.925481)
			(xy 109.119205 -382.919456) (xy 109.072578 -382.907458) (xy 109.050074 -382.898904) (xy 109.037628 -382.893824)
			(xy 109.01172 -382.897126) (xy 108.921042 -382.963928) (xy 108.91012 -382.98755) (xy 108.911136 -383.000758)
			(xy 108.912152 -383.02946) (xy 108.911707 -383.056167) (xy 108.904259 -383.109059) (xy 108.889503 -383.160395)
			(xy 108.867728 -383.209168) (xy 108.83936 -383.254427) (xy 108.804954 -383.295283) (xy 108.765183 -383.330939)
			(xy 108.720826 -383.360697) (xy 108.67275 -383.383973) (xy 108.621897 -383.400313) (xy 108.569261 -383.409397)
			(xy 108.542582 -383.410714) (xy 108.530136 -383.411222) (xy 108.509054 -383.422652) (xy 108.44911 -383.511298)
			(xy 108.446062 -383.535174) (xy 108.45038 -383.546858) (xy 108.459976 -383.574674) (xy 108.473434 -383.631957)
			(xy 108.48019 -383.69041) (xy 108.480606 -383.719832) (xy 108.480252 -383.7432) (xy 110.783876 -383.7432)
			(xy 110.787947 -383.687578) (xy 110.800073 -383.633141) (xy 110.819996 -383.58105) (xy 110.847292 -383.532415)
			(xy 110.881378 -383.488272) (xy 110.921527 -383.449563) (xy 110.966885 -383.417112) (xy 111.016485 -383.391611)
			(xy 111.069269 -383.373604) (xy 111.124112 -383.363474) (xy 111.179846 -383.361437) (xy 111.235283 -383.367537)
			(xy 111.28924 -383.381643) (xy 111.340569 -383.403455) (xy 111.388175 -383.432509) (xy 111.431043 -383.468184)
			(xy 111.46826 -383.509721) (xy 111.499033 -383.556234) (xy 111.522705 -383.606731) (xy 111.538773 -383.660138)
			(xy 111.546893 -383.715314) (xy 111.547402 -383.7432) (xy 111.546893 -383.771086) (xy 111.538773 -383.826262)
			(xy 111.522705 -383.879669) (xy 111.499033 -383.930166) (xy 111.46826 -383.976679) (xy 111.431043 -384.018216)
			(xy 111.388175 -384.053891) (xy 111.340569 -384.082945) (xy 111.28924 -384.104757) (xy 111.235283 -384.118863)
			(xy 111.179846 -384.124963) (xy 111.124112 -384.122926) (xy 111.069269 -384.112796) (xy 111.016485 -384.094789)
			(xy 110.966885 -384.069288) (xy 110.921527 -384.036837) (xy 110.881378 -383.998128) (xy 110.847292 -383.953985)
			(xy 110.819996 -383.90535) (xy 110.800073 -383.853259) (xy 110.787947 -383.798822) (xy 110.783876 -383.7432)
			(xy 108.480252 -383.7432) (xy 108.48014 -383.750562) (xy 108.472728 -383.811573) (xy 108.458017 -383.871245)
			(xy 108.43622 -383.92871) (xy 108.407656 -383.983128) (xy 108.372741 -384.033707) (xy 108.331984 -384.079709)
			(xy 108.28598 -384.120462) (xy 108.235399 -384.155374) (xy 108.180979 -384.183934) (xy 108.123513 -384.205727)
			(xy 108.063839 -384.220435) (xy 108.002828 -384.227842) (xy 107.972098 -384.22834) (xy 107.941403 -384.227861)
			(xy 107.880463 -384.22044) (xy 107.820858 -384.205742) (xy 107.763454 -384.18398) (xy 107.709084 -384.155471)
			(xy 107.683554 -384.138424) (xy 107.674802 -384.132953) (xy 107.654598 -384.128825) (xy 107.634394 -384.132953)
			(xy 107.625642 -384.138424) (xy 107.600115 -384.15548) (xy 107.545753 -384.18401) (xy 107.488349 -384.205783)
			(xy 107.42874 -384.220481) (xy 107.367795 -384.22789) (xy 107.337098 -384.22834) (xy 107.305135 -384.227838)
			(xy 107.241713 -384.219826) (xy 107.179796 -384.203928) (xy 107.120359 -384.180395) (xy 107.06434 -384.149598)
			(xy 107.012623 -384.112023) (xy 106.966023 -384.068263) (xy 106.925275 -384.019007) (xy 106.891022 -383.965033)
			(xy 106.863804 -383.907191) (xy 106.84405 -383.846393) (xy 106.832071 -383.7836) (xy 106.828057 -383.7198)
			(xy 106.832071 -383.656) (xy 106.84405 -383.593207) (xy 106.863804 -383.532409) (xy 106.891022 -383.474567)
			(xy 106.925275 -383.420593) (xy 106.966023 -383.371337) (xy 107.012623 -383.327577) (xy 107.06434 -383.290002)
			(xy 107.120359 -383.259205) (xy 107.179796 -383.235672) (xy 107.241713 -383.219774) (xy 107.305135 -383.211762)
			(xy 107.337098 -383.211324) (xy 107.367793 -383.211803) (xy 107.428734 -383.219223) (xy 107.48834 -383.23392)
			(xy 107.545745 -383.255679) (xy 107.600116 -383.284186) (xy 107.625642 -383.30124) (xy 107.634394 -383.306711)
			(xy 107.654598 -383.310839) (xy 107.674802 -383.306711) (xy 107.683554 -383.30124) (xy 107.709082 -383.284187)
			(xy 107.763445 -383.255663) (xy 107.820849 -383.233898) (xy 107.880458 -383.21921) (xy 107.941402 -383.211811)
			(xy 107.972098 -383.211324) (xy 107.989491 -383.211488) (xy 108.024192 -383.213906) (xy 108.04144 -383.21615)
			(xy 108.053632 -383.217674) (xy 108.076492 -383.2098) (xy 108.150406 -383.132584) (xy 108.157518 -383.10947)
			(xy 108.155232 -383.097278) (xy 108.152388 -383.080468) (xy 108.149333 -383.046508) (xy 108.149136 -383.02946)
			(xy 108.150152 -383.000758) (xy 108.151168 -382.98755) (xy 108.140246 -382.963928) (xy 108.049568 -382.897126)
			(xy 108.02366 -382.893824) (xy 108.011214 -382.898904) (xy 107.988704 -382.907442) (xy 107.942078 -382.919433)
			(xy 107.894316 -382.925473) (xy 107.870244 -382.925828) (xy 107.843083 -382.925345) (xy 107.78931 -382.917636)
			(xy 107.737172 -382.902382) (xy 107.687725 -382.87989) (xy 107.641965 -382.850615) (xy 107.600817 -382.815149)
			(xy 107.565113 -382.774208) (xy 107.535574 -382.728618) (xy 107.512796 -382.679301) (xy 107.497239 -382.627254)
			(xy 107.4928 -382.600454) (xy 107.490006 -382.581658) (xy 107.461558 -382.55702) (xy 107.018582 -382.55702)
			(xy 107.008514 -382.557447) (xy 106.989916 -382.565168) (xy 106.982514 -382.572006) (xy 105.123996 -384.430524)
			(xy 105.118662 -384.462782) (xy 105.125774 -384.47726) (xy 105.138327 -384.503574) (xy 105.158004 -384.558456)
			(xy 105.171263 -384.615232) (xy 105.176725 -384.66268) (xy 110.783876 -384.66268) (xy 110.787947 -384.607058)
			(xy 110.800073 -384.552621) (xy 110.819996 -384.50053) (xy 110.847292 -384.451895) (xy 110.881378 -384.407752)
			(xy 110.921527 -384.369043) (xy 110.966885 -384.336592) (xy 111.016485 -384.311091) (xy 111.069269 -384.293084)
			(xy 111.124112 -384.282954) (xy 111.179846 -384.280917) (xy 111.235283 -384.287017) (xy 111.28924 -384.301123)
			(xy 111.340569 -384.322935) (xy 111.388175 -384.351989) (xy 111.42587 -384.383359) (xy 112.170974 -384.383359)
			(xy 112.170974 -384.331385) (xy 112.179104 -384.28005) (xy 112.195165 -384.23062) (xy 112.218761 -384.18431)
			(xy 112.249311 -384.142262) (xy 112.286062 -384.105511) (xy 112.32811 -384.074961) (xy 112.37442 -384.051365)
			(xy 112.42385 -384.035304) (xy 112.475185 -384.027174) (xy 112.527159 -384.027174) (xy 112.578494 -384.035304)
			(xy 112.627924 -384.051365) (xy 112.674234 -384.074961) (xy 112.716282 -384.105511) (xy 112.753033 -384.142262)
			(xy 112.783583 -384.18431) (xy 112.807179 -384.23062) (xy 112.82324 -384.28005) (xy 112.83137 -384.331385)
			(xy 112.83188 -384.357372) (xy 112.83137 -384.383359) (xy 112.82324 -384.434694) (xy 112.807179 -384.484124)
			(xy 112.783583 -384.530434) (xy 112.753033 -384.572482) (xy 112.716282 -384.609233) (xy 112.674234 -384.639783)
			(xy 112.666529 -384.643709) (xy 114.232184 -384.643709) (xy 114.232184 -384.591735) (xy 114.240314 -384.5404)
			(xy 114.256375 -384.49097) (xy 114.279971 -384.44466) (xy 114.310521 -384.402612) (xy 114.347272 -384.365861)
			(xy 114.38932 -384.335311) (xy 114.43563 -384.311715) (xy 114.48506 -384.295654) (xy 114.536395 -384.287524)
			(xy 114.588369 -384.287524) (xy 114.639704 -384.295654) (xy 114.689134 -384.311715) (xy 114.735444 -384.335311)
			(xy 114.777492 -384.365861) (xy 114.814243 -384.402612) (xy 114.844793 -384.44466) (xy 114.868389 -384.49097)
			(xy 114.88445 -384.5404) (xy 114.89258 -384.591735) (xy 114.89309 -384.617722) (xy 114.89258 -384.643709)
			(xy 115.43208 -384.643709) (xy 115.43208 -384.591735) (xy 115.44021 -384.5404) (xy 115.456271 -384.49097)
			(xy 115.479867 -384.44466) (xy 115.510417 -384.402612) (xy 115.547168 -384.365861) (xy 115.589216 -384.335311)
			(xy 115.635526 -384.311715) (xy 115.684956 -384.295654) (xy 115.736291 -384.287524) (xy 115.788265 -384.287524)
			(xy 115.8396 -384.295654) (xy 115.88903 -384.311715) (xy 115.93534 -384.335311) (xy 115.977388 -384.365861)
			(xy 116.014139 -384.402612) (xy 116.044689 -384.44466) (xy 116.068285 -384.49097) (xy 116.084346 -384.5404)
			(xy 116.092476 -384.591735) (xy 116.092986 -384.617722) (xy 116.092476 -384.643709) (xy 116.63223 -384.643709)
			(xy 116.63223 -384.591735) (xy 116.64036 -384.5404) (xy 116.656421 -384.49097) (xy 116.680017 -384.44466)
			(xy 116.710567 -384.402612) (xy 116.747318 -384.365861) (xy 116.789366 -384.335311) (xy 116.835676 -384.311715)
			(xy 116.885106 -384.295654) (xy 116.936441 -384.287524) (xy 116.988415 -384.287524) (xy 117.03975 -384.295654)
			(xy 117.08918 -384.311715) (xy 117.13549 -384.335311) (xy 117.177538 -384.365861) (xy 117.214289 -384.402612)
			(xy 117.244839 -384.44466) (xy 117.268435 -384.49097) (xy 117.284496 -384.5404) (xy 117.292626 -384.591735)
			(xy 117.293136 -384.617722) (xy 117.292626 -384.643709) (xy 117.832126 -384.643709) (xy 117.832126 -384.591735)
			(xy 117.840256 -384.5404) (xy 117.856317 -384.49097) (xy 117.879913 -384.44466) (xy 117.910463 -384.402612)
			(xy 117.947214 -384.365861) (xy 117.989262 -384.335311) (xy 118.035572 -384.311715) (xy 118.085002 -384.295654)
			(xy 118.136337 -384.287524) (xy 118.188311 -384.287524) (xy 118.239646 -384.295654) (xy 118.289076 -384.311715)
			(xy 118.335386 -384.335311) (xy 118.377434 -384.365861) (xy 118.414185 -384.402612) (xy 118.444735 -384.44466)
			(xy 118.468331 -384.49097) (xy 118.484392 -384.5404) (xy 118.492522 -384.591735) (xy 118.493032 -384.617722)
			(xy 118.492522 -384.643709) (xy 119.032276 -384.643709) (xy 119.032276 -384.591735) (xy 119.040406 -384.5404)
			(xy 119.056467 -384.49097) (xy 119.080063 -384.44466) (xy 119.110613 -384.402612) (xy 119.147364 -384.365861)
			(xy 119.189412 -384.335311) (xy 119.235722 -384.311715) (xy 119.285152 -384.295654) (xy 119.336487 -384.287524)
			(xy 119.388461 -384.287524) (xy 119.439796 -384.295654) (xy 119.489226 -384.311715) (xy 119.535536 -384.335311)
			(xy 119.577584 -384.365861) (xy 119.614335 -384.402612) (xy 119.644885 -384.44466) (xy 119.668481 -384.49097)
			(xy 119.684542 -384.5404) (xy 119.692672 -384.591735) (xy 119.693182 -384.617722) (xy 119.692672 -384.643709)
			(xy 119.684542 -384.695044) (xy 119.668481 -384.744474) (xy 119.644885 -384.790784) (xy 119.614335 -384.832832)
			(xy 119.577584 -384.869583) (xy 119.535536 -384.900133) (xy 119.489226 -384.923729) (xy 119.439796 -384.93979)
			(xy 119.388461 -384.94792) (xy 119.336487 -384.94792) (xy 119.285152 -384.93979) (xy 119.235722 -384.923729)
			(xy 119.189412 -384.900133) (xy 119.147364 -384.869583) (xy 119.110613 -384.832832) (xy 119.080063 -384.790784)
			(xy 119.056467 -384.744474) (xy 119.040406 -384.695044) (xy 119.032276 -384.643709) (xy 118.492522 -384.643709)
			(xy 118.484392 -384.695044) (xy 118.468331 -384.744474) (xy 118.444735 -384.790784) (xy 118.414185 -384.832832)
			(xy 118.377434 -384.869583) (xy 118.335386 -384.900133) (xy 118.289076 -384.923729) (xy 118.239646 -384.93979)
			(xy 118.188311 -384.94792) (xy 118.136337 -384.94792) (xy 118.085002 -384.93979) (xy 118.035572 -384.923729)
			(xy 117.989262 -384.900133) (xy 117.947214 -384.869583) (xy 117.910463 -384.832832) (xy 117.879913 -384.790784)
			(xy 117.856317 -384.744474) (xy 117.840256 -384.695044) (xy 117.832126 -384.643709) (xy 117.292626 -384.643709)
			(xy 117.284496 -384.695044) (xy 117.268435 -384.744474) (xy 117.244839 -384.790784) (xy 117.214289 -384.832832)
			(xy 117.177538 -384.869583) (xy 117.13549 -384.900133) (xy 117.08918 -384.923729) (xy 117.03975 -384.93979)
			(xy 116.988415 -384.94792) (xy 116.936441 -384.94792) (xy 116.885106 -384.93979) (xy 116.835676 -384.923729)
			(xy 116.789366 -384.900133) (xy 116.747318 -384.869583) (xy 116.710567 -384.832832) (xy 116.680017 -384.790784)
			(xy 116.656421 -384.744474) (xy 116.64036 -384.695044) (xy 116.63223 -384.643709) (xy 116.092476 -384.643709)
			(xy 116.084346 -384.695044) (xy 116.068285 -384.744474) (xy 116.044689 -384.790784) (xy 116.014139 -384.832832)
			(xy 115.977388 -384.869583) (xy 115.93534 -384.900133) (xy 115.88903 -384.923729) (xy 115.8396 -384.93979)
			(xy 115.788265 -384.94792) (xy 115.736291 -384.94792) (xy 115.684956 -384.93979) (xy 115.635526 -384.923729)
			(xy 115.589216 -384.900133) (xy 115.547168 -384.869583) (xy 115.510417 -384.832832) (xy 115.479867 -384.790784)
			(xy 115.456271 -384.744474) (xy 115.44021 -384.695044) (xy 115.43208 -384.643709) (xy 114.89258 -384.643709)
			(xy 114.88445 -384.695044) (xy 114.868389 -384.744474) (xy 114.844793 -384.790784) (xy 114.814243 -384.832832)
			(xy 114.777492 -384.869583) (xy 114.735444 -384.900133) (xy 114.689134 -384.923729) (xy 114.639704 -384.93979)
			(xy 114.588369 -384.94792) (xy 114.536395 -384.94792) (xy 114.48506 -384.93979) (xy 114.43563 -384.923729)
			(xy 114.38932 -384.900133) (xy 114.347272 -384.869583) (xy 114.310521 -384.832832) (xy 114.279971 -384.790784)
			(xy 114.256375 -384.744474) (xy 114.240314 -384.695044) (xy 114.232184 -384.643709) (xy 112.666529 -384.643709)
			(xy 112.627924 -384.663379) (xy 112.578494 -384.67944) (xy 112.527159 -384.68757) (xy 112.475185 -384.68757)
			(xy 112.42385 -384.67944) (xy 112.37442 -384.663379) (xy 112.32811 -384.639783) (xy 112.286062 -384.609233)
			(xy 112.249311 -384.572482) (xy 112.218761 -384.530434) (xy 112.195165 -384.484124) (xy 112.179104 -384.434694)
			(xy 112.170974 -384.383359) (xy 111.42587 -384.383359) (xy 111.431043 -384.387664) (xy 111.46826 -384.429201)
			(xy 111.499033 -384.475714) (xy 111.522705 -384.526211) (xy 111.538773 -384.579618) (xy 111.546893 -384.634794)
			(xy 111.547402 -384.66268) (xy 111.546893 -384.690566) (xy 111.538773 -384.745742) (xy 111.522705 -384.799149)
			(xy 111.499033 -384.849646) (xy 111.46826 -384.896159) (xy 111.431043 -384.937696) (xy 111.388175 -384.973371)
			(xy 111.340569 -385.002425) (xy 111.28924 -385.024237) (xy 111.235283 -385.038343) (xy 111.179846 -385.044443)
			(xy 111.124112 -385.042406) (xy 111.069269 -385.032276) (xy 111.016485 -385.014269) (xy 110.966885 -384.988768)
			(xy 110.921527 -384.956317) (xy 110.881378 -384.917608) (xy 110.847292 -384.873465) (xy 110.819996 -384.82483)
			(xy 110.800073 -384.772739) (xy 110.787947 -384.718302) (xy 110.783876 -384.66268) (xy 105.176725 -384.66268)
			(xy 105.177931 -384.673152) (xy 105.178352 -384.702304) (xy 105.177888 -384.733036) (xy 105.17048 -384.794051)
			(xy 105.155771 -384.853729) (xy 105.133976 -384.911199) (xy 105.105414 -384.965623) (xy 105.0705 -385.016208)
			(xy 105.029744 -385.062215) (xy 104.983739 -385.102975) (xy 104.933157 -385.137893) (xy 104.878735 -385.16646)
			(xy 104.821267 -385.188259) (xy 104.761591 -385.202972) (xy 104.700576 -385.210386) (xy 104.669844 -385.210812)
			(xy 104.640694 -385.210389) (xy 104.582779 -385.203693) (xy 104.526007 -385.190429) (xy 104.47112 -385.17077)
			(xy 104.4448 -385.158234) (xy 104.430322 -385.151122) (xy 104.398064 -385.156456) (xy 104.20142 -385.3531)
			(xy 106.966241 -385.3531) (xy 106.970255 -385.2893) (xy 106.982233 -385.226506) (xy 107.001987 -385.165709)
			(xy 107.029204 -385.107866) (xy 107.063456 -385.053891) (xy 107.104203 -385.004634) (xy 107.150802 -384.960873)
			(xy 107.202518 -384.923296) (xy 107.258536 -384.892498) (xy 107.317972 -384.868963) (xy 107.379889 -384.853062)
			(xy 107.443311 -384.845047) (xy 107.475274 -384.844544) (xy 107.505971 -384.844991) (xy 107.566917 -384.852398)
			(xy 107.626527 -384.867096) (xy 107.68393 -384.88887) (xy 107.738292 -384.917403) (xy 107.763818 -384.93446)
			(xy 107.77257 -384.939931) (xy 107.792774 -384.944059) (xy 107.812978 -384.939931) (xy 107.82173 -384.93446)
			(xy 107.847266 -384.917421) (xy 107.901634 -384.888911) (xy 107.959036 -384.867148) (xy 108.01864 -384.852448)
			(xy 108.079579 -384.845024) (xy 108.110274 -384.844544) (xy 108.142234 -384.845119) (xy 108.205652 -384.853128)
			(xy 108.267565 -384.869021) (xy 108.326998 -384.89255) (xy 108.383013 -384.923342) (xy 108.434727 -384.960912)
			(xy 108.481324 -385.004668) (xy 108.52207 -385.053919) (xy 108.556322 -385.107888) (xy 108.583539 -385.165725)
			(xy 108.603292 -385.226517) (xy 108.61527 -385.289305) (xy 108.619284 -385.3531) (xy 108.61527 -385.416895)
			(xy 108.603292 -385.479683) (xy 108.583539 -385.540475) (xy 108.563923 -385.58216) (xy 110.783876 -385.58216)
			(xy 110.787947 -385.526538) (xy 110.800073 -385.472101) (xy 110.819996 -385.42001) (xy 110.847292 -385.371375)
			(xy 110.881378 -385.327232) (xy 110.921527 -385.288523) (xy 110.966885 -385.256072) (xy 111.016485 -385.230571)
			(xy 111.069269 -385.212564) (xy 111.124112 -385.202434) (xy 111.179846 -385.200397) (xy 111.235283 -385.206497)
			(xy 111.28924 -385.220603) (xy 111.340569 -385.242415) (xy 111.388175 -385.271469) (xy 111.431043 -385.307144)
			(xy 111.46826 -385.348681) (xy 111.499033 -385.395194) (xy 111.522705 -385.445691) (xy 111.538773 -385.499098)
			(xy 111.546893 -385.554274) (xy 111.547402 -385.58216) (xy 111.546893 -385.610046) (xy 111.544145 -385.628721)
			(xy 111.749588 -385.628721) (xy 111.749588 -385.576747) (xy 111.757718 -385.525412) (xy 111.773779 -385.475982)
			(xy 111.797375 -385.429672) (xy 111.827925 -385.387624) (xy 111.864676 -385.350873) (xy 111.906724 -385.320323)
			(xy 111.953034 -385.296727) (xy 112.002464 -385.280666) (xy 112.053799 -385.272536) (xy 112.105773 -385.272536)
			(xy 112.157108 -385.280666) (xy 112.206538 -385.296727) (xy 112.233334 -385.31038) (xy 114.560604 -385.31038)
			(xy 114.561083 -385.284392) (xy 114.569217 -385.233055) (xy 114.585282 -385.183623) (xy 114.608881 -385.137313)
			(xy 114.639434 -385.095265) (xy 114.676189 -385.058513) (xy 114.71824 -385.027964) (xy 114.764553 -385.004369)
			(xy 114.813987 -384.98831) (xy 114.865324 -384.980181) (xy 114.891312 -384.979672) (xy 114.917322 -384.980131)
			(xy 114.9687 -384.988291) (xy 115.018166 -385.004394) (xy 115.064502 -385.028041) (xy 115.106565 -385.05865)
			(xy 115.143318 -385.095466) (xy 115.173855 -385.137581) (xy 115.197423 -385.183958) (xy 115.213441 -385.233452)
			(xy 115.217956 -385.259072) (xy 115.21948 -385.26847) (xy 115.243706 -385.31038) (xy 115.7605 -385.31038)
			(xy 115.760983 -385.284392) (xy 115.769117 -385.233056) (xy 115.785181 -385.183624) (xy 115.80878 -385.137314)
			(xy 115.839333 -385.095266) (xy 115.876087 -385.058515) (xy 115.918138 -385.027966) (xy 115.96445 -385.00437)
			(xy 116.013883 -384.98831) (xy 116.06522 -384.980181) (xy 116.091208 -384.979672) (xy 116.117218 -384.980134)
			(xy 116.168595 -384.988294) (xy 116.218062 -385.004396) (xy 116.264398 -385.028043) (xy 116.306461 -385.058651)
			(xy 116.343214 -385.095467) (xy 116.373751 -385.137582) (xy 116.397319 -385.183958) (xy 116.413337 -385.233452)
			(xy 116.417852 -385.259072) (xy 116.419376 -385.26847) (xy 116.443602 -385.31038) (xy 116.96065 -385.31038)
			(xy 116.961183 -385.284394) (xy 116.969315 -385.233063) (xy 116.985376 -385.183636) (xy 117.008971 -385.137329)
			(xy 117.039518 -385.095283) (xy 117.076266 -385.058533) (xy 117.11831 -385.027983) (xy 117.164616 -385.004385)
			(xy 117.214042 -384.98832) (xy 117.265372 -384.980185) (xy 117.291358 -384.979672) (xy 117.317401 -384.980171)
			(xy 117.36884 -384.988353) (xy 117.418363 -385.004489) (xy 117.464748 -385.028181) (xy 117.506851 -385.058846)
			(xy 117.543631 -385.095725) (xy 117.574183 -385.13791) (xy 117.597751 -385.184358) (xy 117.613754 -385.233925)
			(xy 117.618256 -385.25958) (xy 117.619526 -385.268978) (xy 117.643462 -385.31038) (xy 118.160546 -385.31038)
			(xy 118.161083 -385.284395) (xy 118.169215 -385.233064) (xy 118.185276 -385.183637) (xy 118.20887 -385.13733)
			(xy 118.239417 -385.095285) (xy 118.276165 -385.058534) (xy 118.318208 -385.027984) (xy 118.364513 -385.004386)
			(xy 118.413939 -384.988321) (xy 118.465269 -384.980185) (xy 118.491254 -384.979672) (xy 118.517266 -384.980092)
			(xy 118.568645 -384.988259) (xy 118.618112 -385.004368) (xy 118.664448 -385.02802) (xy 118.706511 -385.058634)
			(xy 118.743263 -385.095455) (xy 118.773799 -385.137574) (xy 118.797366 -385.183953) (xy 118.813383 -385.23345)
			(xy 118.817898 -385.259072) (xy 118.819422 -385.26847) (xy 119.092218 -385.740402) (xy 119.099584 -385.746244)
			(xy 119.118362 -385.762046) (xy 119.15148 -385.798262) (xy 119.17889 -385.83897) (xy 119.199991 -385.883278)
			(xy 119.214321 -385.930216) (xy 119.221566 -385.978754) (xy 119.222012 -386.003292) (xy 119.221758 -386.015484)
			(xy 119.221504 -386.025136) (xy 119.2276 -386.04317) (xy 119.286274 -386.11048) (xy 119.303038 -386.119116)
			(xy 119.31269 -386.120132) (xy 119.339451 -386.1235) (xy 119.391474 -386.137721) (xy 119.440499 -386.160194)
			(xy 119.485229 -386.190325) (xy 119.524477 -386.227314) (xy 119.557203 -386.270182) (xy 119.582539 -386.317791)
			(xy 119.599815 -386.368881) (xy 119.608572 -386.422096) (xy 119.609108 -386.449062) (xy 119.608598 -386.475049)
			(xy 119.600468 -386.526384) (xy 119.584407 -386.575814) (xy 119.560811 -386.622124) (xy 119.530261 -386.664172)
			(xy 119.49351 -386.700923) (xy 119.451462 -386.731473) (xy 119.405152 -386.755069) (xy 119.355722 -386.77113)
			(xy 119.304387 -386.77926) (xy 119.252413 -386.77926) (xy 119.201078 -386.77113) (xy 119.151648 -386.755069)
			(xy 119.105338 -386.731473) (xy 119.06329 -386.700923) (xy 119.026539 -386.664172) (xy 118.995989 -386.622124)
			(xy 118.972393 -386.575814) (xy 118.956332 -386.526384) (xy 118.948202 -386.475049) (xy 118.947692 -386.449062)
			(xy 118.947946 -386.43687) (xy 118.9482 -386.427218) (xy 118.942104 -386.409184) (xy 118.88343 -386.341874)
			(xy 118.866666 -386.333238) (xy 118.857014 -386.332222) (xy 118.830113 -386.328808) (xy 118.777828 -386.314452)
			(xy 118.728585 -386.291761) (xy 118.683701 -386.261343) (xy 118.64438 -386.224011) (xy 118.611674 -386.180766)
			(xy 118.586459 -386.132766) (xy 118.56941 -386.081296) (xy 118.56466 -386.0546) (xy 118.563136 -386.045202)
			(xy 118.29034 -385.57327) (xy 118.282974 -385.567428) (xy 118.264222 -385.551598) (xy 118.231103 -385.515386)
			(xy 118.203691 -385.474683) (xy 118.182586 -385.430381) (xy 118.16825 -385.38345) (xy 118.160996 -385.334916)
			(xy 118.160546 -385.31038) (xy 117.643462 -385.31038) (xy 117.892068 -385.740402) (xy 117.899434 -385.746244)
			(xy 117.918223 -385.762033) (xy 117.951338 -385.798254) (xy 117.978745 -385.838965) (xy 117.999844 -385.883275)
			(xy 118.014173 -385.930214) (xy 118.021417 -385.978753) (xy 118.021862 -386.003292) (xy 118.021608 -386.015484)
			(xy 118.021354 -386.025136) (xy 118.02745 -386.04317) (xy 118.086124 -386.11048) (xy 118.102888 -386.119116)
			(xy 118.112794 -386.120132) (xy 118.139555 -386.123496) (xy 118.191578 -386.137718) (xy 118.240604 -386.160192)
			(xy 118.285333 -386.190323) (xy 118.324581 -386.227313) (xy 118.357307 -386.270181) (xy 118.382643 -386.31779)
			(xy 118.399919 -386.36888) (xy 118.408676 -386.422096) (xy 118.409212 -386.449062) (xy 118.408677 -386.476347)
			(xy 118.399723 -386.530177) (xy 118.38205 -386.581807) (xy 118.35614 -386.629833) (xy 118.322696 -386.672954)
			(xy 118.30304 -386.691886) (xy 118.295649 -386.699416) (xy 118.287117 -386.71869) (xy 118.28653 -386.729224)
			(xy 118.28653 -386.8039) (xy 118.287037 -386.814453) (xy 118.295587 -386.833748) (xy 118.30304 -386.841238)
			(xy 118.322681 -386.860183) (xy 118.356115 -386.903306) (xy 118.382019 -386.95133) (xy 118.39969 -387.002955)
			(xy 118.408651 -387.056779) (xy 118.409212 -387.084062) (xy 118.408768 -387.108178) (xy 118.401771 -387.155901)
			(xy 118.38792 -387.202102) (xy 118.367508 -387.245803) (xy 118.354602 -387.26618) (xy 118.34876 -387.27507)
			(xy 118.345204 -387.295136) (xy 118.366286 -387.387338) (xy 118.378478 -387.404102) (xy 118.387368 -387.409436)
			(xy 118.408177 -387.422279) (xy 118.44608 -387.453172) (xy 118.479021 -387.48931) (xy 118.506281 -387.529905)
			(xy 118.527265 -387.574072) (xy 118.541516 -387.620848) (xy 118.548723 -387.669213) (xy 118.549166 -387.693662)
			(xy 118.548757 -387.718036) (xy 118.541611 -387.766256) (xy 118.527467 -387.812907) (xy 118.506631 -387.856977)
			(xy 118.479555 -387.897513) (xy 118.446825 -387.933639) (xy 118.428262 -387.94944) (xy 118.419372 -387.956552)
			(xy 118.409974 -387.97611) (xy 118.40718 -388.075424) (xy 118.415816 -388.09549) (xy 118.424198 -388.10311)
			(xy 118.442636 -388.120583) (xy 118.473986 -388.16055) (xy 118.498287 -388.205155) (xy 118.514866 -388.253169)
			(xy 118.523266 -388.303264) (xy 118.523766 -388.328662) (xy 119.113046 -388.328662) (xy 119.113568 -388.303407)
			(xy 119.121881 -388.253585) (xy 119.138282 -388.205811) (xy 119.162323 -388.161388) (xy 119.193347 -388.121528)
			(xy 119.230509 -388.087318) (xy 119.272795 -388.059692) (xy 119.319051 -388.039402) (xy 119.368016 -388.027002)
			(xy 119.418354 -388.022831) (xy 119.468692 -388.027002) (xy 119.517657 -388.039402) (xy 119.563913 -388.059692)
			(xy 119.606199 -388.087318) (xy 119.643361 -388.121528) (xy 119.674385 -388.161388) (xy 119.698426 -388.205811)
			(xy 119.714827 -388.253585) (xy 119.72314 -388.303407) (xy 119.723662 -388.328662) (xy 119.723593 -388.338021)
			(xy 119.72245 -388.356703) (xy 119.721376 -388.366) (xy 119.72036 -388.37489) (xy 119.72417 -388.391654)
			(xy 119.768112 -388.461504) (xy 119.781828 -388.471918) (xy 119.79021 -388.474712) (xy 119.814232 -388.483196)
			(xy 119.859405 -388.506744) (xy 119.900211 -388.53724) (xy 119.935592 -388.573892) (xy 119.964629 -388.615749)
			(xy 119.986568 -388.661725) (xy 119.994172 -388.68604) (xy 119.995696 -388.691882) (xy 120.31599 -389.245602)
			(xy 120.320054 -389.24992) (xy 120.336251 -389.267621) (xy 120.363614 -389.307032) (xy 120.384697 -389.35013)
			(xy 120.399016 -389.395923) (xy 120.40624 -389.443354) (xy 120.406668 -389.467344) (xy 120.406223 -389.492135)
			(xy 120.39846 -389.541105) (xy 120.383133 -389.588259) (xy 120.360619 -389.632434) (xy 120.331473 -389.672544)
			(xy 120.296411 -389.707601) (xy 120.256296 -389.736742) (xy 120.212118 -389.75925) (xy 120.164962 -389.77457)
			(xy 120.115991 -389.782326) (xy 120.0912 -389.782812) (xy 120.065806 -389.782312) (xy 120.015672 -389.774181)
			(xy 119.967486 -389.758129) (xy 119.922492 -389.734571) (xy 119.881849 -389.704114) (xy 119.846607 -389.667543)
			(xy 119.817673 -389.625801) (xy 119.795795 -389.579967) (xy 119.788178 -389.555736) (xy 119.786654 -389.549894)
			(xy 119.46636 -388.996174) (xy 119.462296 -388.991856) (xy 119.446092 -388.974148) (xy 119.418668 -388.934757)
			(xy 119.397525 -388.891668) (xy 119.383152 -388.845873) (xy 119.375878 -388.79843) (xy 119.375428 -388.774432)
			(xy 119.37557 -388.76238) (xy 119.377476 -388.73835) (xy 119.379238 -388.726426) (xy 119.380508 -388.717536)
			(xy 119.37746 -388.700518) (xy 119.335296 -388.629652) (xy 119.322088 -388.618476) (xy 119.313706 -388.615428)
			(xy 119.291966 -388.607013) (xy 119.251106 -388.584577) (xy 119.214134 -388.556187) (xy 119.18191 -388.522505)
			(xy 119.155184 -388.484314) (xy 119.134576 -388.442502) (xy 119.120568 -388.398042) (xy 119.113484 -388.351969)
			(xy 119.113046 -388.328662) (xy 118.523766 -388.328662) (xy 118.523697 -388.338021) (xy 118.522554 -388.356703)
			(xy 118.52148 -388.366) (xy 118.520464 -388.37489) (xy 118.524274 -388.391654) (xy 118.568216 -388.461504)
			(xy 118.581932 -388.471918) (xy 118.590314 -388.474712) (xy 118.614337 -388.483194) (xy 118.65951 -388.506743)
			(xy 118.700316 -388.537239) (xy 118.735696 -388.573892) (xy 118.764733 -388.615749) (xy 118.786672 -388.661725)
			(xy 118.794276 -388.68604) (xy 118.7958 -388.691882) (xy 119.116094 -389.245602) (xy 119.120158 -389.24992)
			(xy 119.136356 -389.267621) (xy 119.163718 -389.307032) (xy 119.184801 -389.35013) (xy 119.19912 -389.395923)
			(xy 119.206344 -389.443354) (xy 119.206772 -389.467344) (xy 119.206323 -389.492135) (xy 119.19856 -389.541105)
			(xy 119.183234 -389.588258) (xy 119.16072 -389.632433) (xy 119.131574 -389.672543) (xy 119.096512 -389.7076)
			(xy 119.056399 -389.736741) (xy 119.012221 -389.759249) (xy 118.965066 -389.77457) (xy 118.916095 -389.782326)
			(xy 118.891304 -389.782812) (xy 118.86591 -389.782308) (xy 118.815776 -389.774178) (xy 118.767591 -389.758127)
			(xy 118.722596 -389.734569) (xy 118.681954 -389.704112) (xy 118.646711 -389.667542) (xy 118.617777 -389.625801)
			(xy 118.595899 -389.579966) (xy 118.588282 -389.555736) (xy 118.586758 -389.549894) (xy 118.266464 -388.996174)
			(xy 118.2624 -388.991856) (xy 118.246197 -388.974147) (xy 118.218772 -388.934757) (xy 118.19763 -388.891667)
			(xy 118.183256 -388.845873) (xy 118.175982 -388.79843) (xy 118.175532 -388.774432) (xy 118.175674 -388.76238)
			(xy 118.17758 -388.73835) (xy 118.179342 -388.726426) (xy 118.180612 -388.717536) (xy 118.177564 -388.700518)
			(xy 118.1354 -388.629652) (xy 118.122192 -388.618476) (xy 118.11381 -388.615428) (xy 118.092071 -388.607011)
			(xy 118.051211 -388.584575) (xy 118.014239 -388.556186) (xy 117.982015 -388.522504) (xy 117.955288 -388.484313)
			(xy 117.934681 -388.442501) (xy 117.920672 -388.398042) (xy 117.913588 -388.351969) (xy 117.91315 -388.328662)
			(xy 117.91366 -388.303266) (xy 117.92207 -388.253176) (xy 117.938653 -388.205167) (xy 117.962952 -388.160565)
			(xy 117.994295 -388.120597) (xy 118.012718 -388.10311) (xy 118.0211 -388.09549) (xy 118.029736 -388.075424)
			(xy 118.026942 -387.97611) (xy 118.017544 -387.956552) (xy 118.008654 -387.94944) (xy 117.990117 -387.933612)
			(xy 117.957396 -387.897486) (xy 117.930326 -387.856953) (xy 117.909492 -387.812889) (xy 117.895343 -387.766246)
			(xy 117.888188 -387.718033) (xy 117.88775 -387.693662) (xy 117.888164 -387.669544) (xy 117.895171 -387.621821)
			(xy 117.909031 -387.57562) (xy 117.929451 -387.53192) (xy 117.94236 -387.511544) (xy 117.948202 -387.502654)
			(xy 117.951758 -387.482588) (xy 117.930676 -387.390386) (xy 117.918484 -387.373622) (xy 117.909594 -387.368288)
			(xy 117.88881 -387.355406) (xy 117.850903 -387.324522) (xy 117.817959 -387.288392) (xy 117.790695 -387.247803)
			(xy 117.769707 -387.203642) (xy 117.755452 -387.15687) (xy 117.748241 -387.10851) (xy 117.747796 -387.084062)
			(xy 117.748344 -387.056777) (xy 117.757295 -387.002948) (xy 117.774964 -386.951318) (xy 117.800871 -386.903291)
			(xy 117.834313 -386.860171) (xy 117.853968 -386.841238) (xy 117.86135 -386.8337) (xy 117.869887 -386.814433)
			(xy 117.870478 -386.8039) (xy 117.870478 -386.729224) (xy 117.869956 -386.718673) (xy 117.861417 -386.699378)
			(xy 117.853968 -386.691886) (xy 117.83434 -386.672928) (xy 117.800904 -386.629809) (xy 117.774998 -386.581788)
			(xy 117.757323 -386.530166) (xy 117.748359 -386.476344) (xy 117.747796 -386.449062) (xy 117.74805 -386.43687)
			(xy 117.748304 -386.427218) (xy 117.742208 -386.409184) (xy 117.683534 -386.341874) (xy 117.66677 -386.333238)
			(xy 117.656864 -386.332222) (xy 117.629958 -386.328847) (xy 117.577672 -386.314484) (xy 117.528428 -386.291786)
			(xy 117.483546 -386.261361) (xy 117.444226 -386.224024) (xy 117.411521 -386.180775) (xy 117.386307 -386.132771)
			(xy 117.36926 -386.081298) (xy 117.36451 -386.0546) (xy 117.362986 -386.045202) (xy 117.089936 -385.572762)
			(xy 117.082824 -385.56692) (xy 117.064077 -385.551158) (xy 117.031026 -385.51501) (xy 117.003673 -385.474381)
			(xy 116.982617 -385.430158) (xy 116.968319 -385.383313) (xy 116.961092 -385.33487) (xy 116.96065 -385.31038)
			(xy 116.443602 -385.31038) (xy 116.692172 -385.740402) (xy 116.699538 -385.746244) (xy 116.718327 -385.762032)
			(xy 116.751443 -385.798253) (xy 116.77885 -385.838965) (xy 116.799948 -385.883275) (xy 116.814277 -385.930214)
			(xy 116.821521 -385.978753) (xy 116.821966 -386.003292) (xy 116.821712 -386.015484) (xy 116.821458 -386.025136)
			(xy 116.827554 -386.04317) (xy 116.886228 -386.11048) (xy 116.902992 -386.119116) (xy 116.912898 -386.120132)
			(xy 116.93966 -386.123493) (xy 116.991683 -386.137715) (xy 117.040708 -386.16019) (xy 117.085438 -386.190322)
			(xy 117.124685 -386.227312) (xy 117.157411 -386.27018) (xy 117.182748 -386.31779) (xy 117.200023 -386.36888)
			(xy 117.20878 -386.422096) (xy 117.209316 -386.449062) (xy 117.20878 -386.476347) (xy 117.199825 -386.530177)
			(xy 117.182154 -386.581807) (xy 117.156244 -386.629833) (xy 117.1228 -386.672954) (xy 117.103144 -386.691886)
			(xy 117.095753 -386.699417) (xy 117.087221 -386.71869) (xy 117.086634 -386.729224) (xy 117.086634 -386.8039)
			(xy 117.08714 -386.814453) (xy 117.09569 -386.833748) (xy 117.103144 -386.841238) (xy 117.122786 -386.860182)
			(xy 117.156219 -386.903305) (xy 117.182123 -386.95133) (xy 117.199794 -387.002955) (xy 117.208755 -387.056779)
			(xy 117.209316 -387.084062) (xy 117.208871 -387.108178) (xy 117.201875 -387.155901) (xy 117.188023 -387.202102)
			(xy 117.167612 -387.245803) (xy 117.154706 -387.26618) (xy 117.148864 -387.27507) (xy 117.145308 -387.295136)
			(xy 117.16639 -387.387338) (xy 117.178582 -387.404102) (xy 117.187472 -387.409436) (xy 117.208282 -387.422277)
			(xy 117.246185 -387.453171) (xy 117.279126 -387.489309) (xy 117.306385 -387.529905) (xy 117.327369 -387.574072)
			(xy 117.34162 -387.620848) (xy 117.348827 -387.669213) (xy 117.34927 -387.693662) (xy 117.34886 -387.718036)
			(xy 117.341713 -387.766256) (xy 117.327569 -387.812906) (xy 117.306734 -387.856977) (xy 117.279659 -387.897513)
			(xy 117.246929 -387.933639) (xy 117.228366 -387.94944) (xy 117.219476 -387.956552) (xy 117.210078 -387.97611)
			(xy 117.207284 -388.075424) (xy 117.21592 -388.09549) (xy 117.224302 -388.10311) (xy 117.242741 -388.120582)
			(xy 117.274091 -388.160549) (xy 117.298391 -388.205155) (xy 117.31497 -388.253168) (xy 117.32337 -388.303264)
			(xy 117.32387 -388.328662) (xy 117.323801 -388.338021) (xy 117.322658 -388.356703) (xy 117.321584 -388.366)
			(xy 117.320568 -388.37489) (xy 117.324378 -388.391654) (xy 117.36832 -388.461504) (xy 117.382036 -388.471918)
			(xy 117.390418 -388.474712) (xy 117.414519 -388.483182) (xy 117.45981 -388.50681) (xy 117.500704 -388.537423)
			(xy 117.536135 -388.574223) (xy 117.565177 -388.616247) (xy 117.587072 -388.6624) (xy 117.594634 -388.686802)
			(xy 117.596158 -388.692644) (xy 117.915944 -389.245602) (xy 117.920008 -389.24992) (xy 117.936201 -389.267637)
			(xy 117.963627 -389.307026) (xy 117.984771 -389.350113) (xy 117.999147 -389.395905) (xy 118.006424 -389.443346)
			(xy 118.006876 -389.467344) (xy 118.006447 -389.492149) (xy 117.998676 -389.541147) (xy 117.983333 -389.588325)
			(xy 117.960796 -389.632521) (xy 117.93162 -389.672645) (xy 117.896524 -389.707708) (xy 117.856373 -389.736847)
			(xy 117.812157 -389.759344) (xy 117.764964 -389.774644) (xy 117.715959 -389.782369) (xy 117.691154 -389.782812)
			(xy 117.665758 -389.782352) (xy 117.615623 -389.774214) (xy 117.567436 -389.758156) (xy 117.522442 -389.734592)
			(xy 117.4818 -389.704129) (xy 117.446558 -389.667553) (xy 117.417625 -389.625807) (xy 117.395748 -389.579968)
			(xy 117.388132 -389.555736) (xy 117.386608 -389.549894) (xy 117.06606 -388.995412) (xy 117.061996 -388.991094)
			(xy 117.0459 -388.973418) (xy 117.018649 -388.934141) (xy 116.997636 -388.891203) (xy 116.983343 -388.845586)
			(xy 116.976095 -388.798334) (xy 116.975636 -388.774432) (xy 116.975778 -388.76238) (xy 116.977684 -388.73835)
			(xy 116.979446 -388.726426) (xy 116.980716 -388.717536) (xy 116.977668 -388.700518) (xy 116.935504 -388.629652)
			(xy 116.922296 -388.618476) (xy 116.913914 -388.615428) (xy 116.892176 -388.607009) (xy 116.851316 -388.584573)
			(xy 116.814344 -388.556185) (xy 116.782119 -388.522503) (xy 116.755392 -388.484312) (xy 116.734785 -388.442501)
			(xy 116.720776 -388.398042) (xy 116.713692 -388.351969) (xy 116.713254 -388.328662) (xy 116.713762 -388.303266)
			(xy 116.722173 -388.253175) (xy 116.738756 -388.205167) (xy 116.763055 -388.160564) (xy 116.794399 -388.120597)
			(xy 116.812822 -388.10311) (xy 116.821204 -388.09549) (xy 116.82984 -388.075424) (xy 116.827046 -387.97611)
			(xy 116.817648 -387.956552) (xy 116.808758 -387.94944) (xy 116.790222 -387.933611) (xy 116.757501 -387.897485)
			(xy 116.73043 -387.856953) (xy 116.709596 -387.812889) (xy 116.695448 -387.766246) (xy 116.688292 -387.718033)
			(xy 116.687854 -387.693662) (xy 116.688267 -387.669544) (xy 116.695274 -387.621821) (xy 116.709135 -387.57562)
			(xy 116.729555 -387.53192) (xy 116.742464 -387.511544) (xy 116.748306 -387.502654) (xy 116.751862 -387.482588)
			(xy 116.73078 -387.390386) (xy 116.718588 -387.373622) (xy 116.709698 -387.368288) (xy 116.688915 -387.355405)
			(xy 116.651008 -387.324521) (xy 116.618063 -387.288391) (xy 116.590799 -387.247803) (xy 116.569811 -387.203641)
			(xy 116.555556 -387.15687) (xy 116.548345 -387.10851) (xy 116.5479 -387.084062) (xy 116.548447 -387.056777)
			(xy 116.557398 -387.002947) (xy 116.575067 -386.951318) (xy 116.600974 -386.903291) (xy 116.634417 -386.86017)
			(xy 116.654072 -386.841238) (xy 116.661455 -386.833701) (xy 116.669991 -386.814433) (xy 116.670582 -386.8039)
			(xy 116.670582 -386.729224) (xy 116.670059 -386.718673) (xy 116.66152 -386.699378) (xy 116.654072 -386.691886)
			(xy 116.634445 -386.672928) (xy 116.601009 -386.629809) (xy 116.575102 -386.581788) (xy 116.557427 -386.530166)
			(xy 116.548463 -386.476344) (xy 116.5479 -386.449062) (xy 116.548154 -386.43687) (xy 116.548408 -386.427218)
			(xy 116.542312 -386.409184) (xy 116.483638 -386.341874) (xy 116.466874 -386.333238) (xy 116.456968 -386.332222)
			(xy 116.430062 -386.328844) (xy 116.377776 -386.314481) (xy 116.328533 -386.291784) (xy 116.28365 -386.26136)
			(xy 116.24433 -386.224023) (xy 116.211625 -386.180774) (xy 116.186411 -386.132771) (xy 116.169364 -386.081298)
			(xy 116.164614 -386.0546) (xy 116.16309 -386.045202) (xy 115.890294 -385.57327) (xy 115.882928 -385.567428)
			(xy 115.864166 -385.551608) (xy 115.831051 -385.515393) (xy 115.803641 -385.474688) (xy 115.782538 -385.430384)
			(xy 115.768203 -385.383451) (xy 115.76095 -385.334917) (xy 115.7605 -385.31038) (xy 115.243706 -385.31038)
			(xy 115.492276 -385.740402) (xy 115.499642 -385.746244) (xy 115.518432 -385.762031) (xy 115.551547 -385.798252)
			(xy 115.578954 -385.838964) (xy 115.600053 -385.883275) (xy 115.614381 -385.930214) (xy 115.621625 -385.978753)
			(xy 115.62207 -386.003292) (xy 115.621816 -386.015484) (xy 115.621562 -386.025136) (xy 115.627658 -386.04317)
			(xy 115.686332 -386.11048) (xy 115.703096 -386.119116) (xy 115.712748 -386.120132) (xy 115.739515 -386.123452)
			(xy 115.791539 -386.137682) (xy 115.840564 -386.160164) (xy 115.885293 -386.190301) (xy 115.92454 -386.227296)
			(xy 115.957264 -386.270169) (xy 115.982599 -386.317783) (xy 115.999874 -386.368876) (xy 116.008631 -386.422095)
			(xy 116.009166 -386.449062) (xy 116.008614 -386.476346) (xy 115.999661 -386.530175) (xy 115.981992 -386.581803)
			(xy 115.956086 -386.62983) (xy 115.922647 -386.672952) (xy 115.902994 -386.691886) (xy 115.895596 -386.69941)
			(xy 115.88707 -386.718688) (xy 115.886484 -386.729224) (xy 115.886484 -386.8039) (xy 115.887004 -386.814451)
			(xy 115.895546 -386.833746) (xy 115.902994 -386.841238) (xy 115.922645 -386.860173) (xy 115.956075 -386.903299)
			(xy 115.981976 -386.951327) (xy 115.999646 -387.002953) (xy 116.008605 -387.056779) (xy 116.009166 -387.084062)
			(xy 116.008713 -387.108178) (xy 116.001718 -387.1559) (xy 115.987869 -387.202101) (xy 115.96746 -387.245802)
			(xy 115.954556 -387.26618) (xy 115.948714 -387.27507) (xy 115.945158 -387.295136) (xy 115.96624 -387.387338)
			(xy 115.978432 -387.404102) (xy 115.987322 -387.409436) (xy 116.00812 -387.422295) (xy 116.046026 -387.453184)
			(xy 116.07897 -387.489318) (xy 116.106231 -387.529911) (xy 116.127217 -387.574076) (xy 116.141469 -387.62085)
			(xy 116.148677 -387.669213) (xy 116.14912 -387.693662) (xy 116.148692 -387.718035) (xy 116.141546 -387.766254)
			(xy 116.127405 -387.812903) (xy 116.106573 -387.856973) (xy 116.079502 -387.89751) (xy 116.046776 -387.933637)
			(xy 116.028216 -387.94944) (xy 116.019326 -387.956552) (xy 116.009928 -387.97611) (xy 116.007134 -388.075424)
			(xy 116.01577 -388.09549) (xy 116.024152 -388.10311) (xy 116.042601 -388.120572) (xy 116.073947 -388.160543)
			(xy 116.098244 -388.205151) (xy 116.114821 -388.253167) (xy 116.123221 -388.303264) (xy 116.12372 -388.328662)
			(xy 116.123651 -388.338021) (xy 116.122508 -388.356703) (xy 116.121434 -388.366) (xy 116.120418 -388.37489)
			(xy 116.124228 -388.391654) (xy 116.16817 -388.461504) (xy 116.181886 -388.471918) (xy 116.190268 -388.474712)
			(xy 116.214282 -388.483218) (xy 116.259456 -388.506761) (xy 116.300264 -388.537252) (xy 116.335646 -388.5739)
			(xy 116.364684 -388.615753) (xy 116.386626 -388.661726) (xy 116.39423 -388.68604) (xy 116.395754 -388.691882)
			(xy 116.716048 -389.245602) (xy 116.720112 -389.24992) (xy 116.736306 -389.267637) (xy 116.763731 -389.307025)
			(xy 116.784875 -389.350113) (xy 116.799252 -389.395905) (xy 116.806528 -389.443346) (xy 116.80698 -389.467344)
			(xy 116.806547 -389.492149) (xy 116.798776 -389.541146) (xy 116.783433 -389.588324) (xy 116.760896 -389.632519)
			(xy 116.731721 -389.672643) (xy 116.696625 -389.707707) (xy 116.656475 -389.736846) (xy 116.612259 -389.759343)
			(xy 116.565068 -389.774643) (xy 116.516063 -389.782369) (xy 116.491258 -389.782812) (xy 116.465862 -389.782348)
			(xy 116.415727 -389.774211) (xy 116.367541 -389.758154) (xy 116.322546 -389.73459) (xy 116.281904 -389.704127)
			(xy 116.246662 -389.667552) (xy 116.217729 -389.625806) (xy 116.195852 -389.579968) (xy 116.188236 -389.555736)
			(xy 116.186712 -389.549894) (xy 115.866418 -388.996174) (xy 115.862354 -388.991856) (xy 115.846195 -388.974122)
			(xy 115.818826 -388.93472) (xy 115.797736 -388.89163) (xy 115.783408 -388.845845) (xy 115.776174 -388.798419)
			(xy 115.77574 -388.774432) (xy 115.775821 -388.762384) (xy 115.777603 -388.738355) (xy 115.779296 -388.726426)
			(xy 115.780566 -388.717536) (xy 115.777518 -388.700518) (xy 115.735354 -388.629652) (xy 115.722146 -388.618476)
			(xy 115.713764 -388.615428) (xy 115.692015 -388.607036) (xy 115.651157 -388.584594) (xy 115.614186 -388.5562)
			(xy 115.581964 -388.522514) (xy 115.555239 -388.48432) (xy 115.534633 -388.442506) (xy 115.520625 -388.398044)
			(xy 115.513542 -388.35197) (xy 115.513104 -388.328662) (xy 115.513629 -388.303267) (xy 115.522038 -388.253178)
			(xy 115.538618 -388.20517) (xy 115.562913 -388.160567) (xy 115.594252 -388.120599) (xy 115.612672 -388.10311)
			(xy 115.621054 -388.09549) (xy 115.62969 -388.075424) (xy 115.626896 -387.97611) (xy 115.617498 -387.956552)
			(xy 115.608608 -387.94944) (xy 115.590062 -387.933623) (xy 115.557343 -387.897493) (xy 115.530276 -387.856958)
			(xy 115.509443 -387.812892) (xy 115.495297 -387.766247) (xy 115.488141 -387.718033) (xy 115.487704 -387.693662)
			(xy 115.488109 -387.669544) (xy 115.495117 -387.62182) (xy 115.50898 -387.575619) (xy 115.529403 -387.53192)
			(xy 115.542314 -387.511544) (xy 115.548156 -387.502654) (xy 115.551712 -387.482588) (xy 115.53063 -387.390386)
			(xy 115.518438 -387.373622) (xy 115.509548 -387.368288) (xy 115.488754 -387.355423) (xy 115.450849 -387.324534)
			(xy 115.417907 -387.2884) (xy 115.390645 -387.247809) (xy 115.369659 -387.203645) (xy 115.355405 -387.156872)
			(xy 115.348195 -387.10851) (xy 115.34775 -387.084062) (xy 115.348313 -387.056778) (xy 115.357262 -387.00295)
			(xy 115.374928 -386.951321) (xy 115.400832 -386.903294) (xy 115.43427 -386.860172) (xy 115.453922 -386.841238)
			(xy 115.461312 -386.833707) (xy 115.469842 -386.814434) (xy 115.470432 -386.8039) (xy 115.470432 -386.729224)
			(xy 115.469894 -386.718676) (xy 115.461364 -386.699381) (xy 115.453922 -386.691886) (xy 115.434286 -386.672937)
			(xy 115.400853 -386.629814) (xy 115.374949 -386.581791) (xy 115.357276 -386.530168) (xy 115.348313 -386.476344)
			(xy 115.34775 -386.449062) (xy 115.348004 -386.43687) (xy 115.348258 -386.427218) (xy 115.342162 -386.409184)
			(xy 115.283488 -386.341874) (xy 115.266724 -386.333238) (xy 115.257072 -386.332222) (xy 115.230167 -386.328841)
			(xy 115.177881 -386.314479) (xy 115.128637 -386.291782) (xy 115.083755 -386.261358) (xy 115.044434 -386.224022)
			(xy 115.011729 -386.180774) (xy 114.986516 -386.13277) (xy 114.969468 -386.081297) (xy 114.964718 -386.0546)
			(xy 114.963194 -386.045202) (xy 114.690398 -385.57327) (xy 114.683032 -385.567428) (xy 114.664271 -385.551608)
			(xy 114.631155 -385.515393) (xy 114.603746 -385.474688) (xy 114.582642 -385.430384) (xy 114.568307 -385.383451)
			(xy 114.561054 -385.334917) (xy 114.560604 -385.31038) (xy 112.233334 -385.31038) (xy 112.252848 -385.320323)
			(xy 112.294896 -385.350873) (xy 112.331647 -385.387624) (xy 112.362197 -385.429672) (xy 112.385793 -385.475982)
			(xy 112.401854 -385.525412) (xy 112.409984 -385.576747) (xy 112.410494 -385.602734) (xy 112.409984 -385.628721)
			(xy 112.401854 -385.680056) (xy 112.385793 -385.729486) (xy 112.362197 -385.775796) (xy 112.331647 -385.817844)
			(xy 112.294896 -385.854595) (xy 112.266082 -385.87553) (xy 113.933986 -385.87553) (xy 113.934496 -385.849543)
			(xy 113.942626 -385.798208) (xy 113.958687 -385.748778) (xy 113.982283 -385.702468) (xy 114.012833 -385.66042)
			(xy 114.049584 -385.623669) (xy 114.091632 -385.593119) (xy 114.137942 -385.569523) (xy 114.187372 -385.553462)
			(xy 114.238707 -385.545332) (xy 114.290681 -385.545332) (xy 114.342016 -385.553462) (xy 114.391446 -385.569523)
			(xy 114.437756 -385.593119) (xy 114.479804 -385.623669) (xy 114.516555 -385.66042) (xy 114.547105 -385.702468)
			(xy 114.570701 -385.748778) (xy 114.586762 -385.798208) (xy 114.594892 -385.849543) (xy 114.595402 -385.87553)
			(xy 114.595014 -385.899206) (xy 114.588283 -385.946077) (xy 114.574919 -385.991503) (xy 114.56543 -386.013198)
			(xy 114.561112 -386.022596) (xy 114.56035 -386.042662) (xy 114.592608 -386.129022) (xy 114.606324 -386.143754)
			(xy 114.615722 -386.148072) (xy 114.640084 -386.159776) (xy 114.684956 -386.189899) (xy 114.724335 -386.226914)
			(xy 114.757175 -386.269837) (xy 114.782602 -386.317526) (xy 114.799941 -386.368714) (xy 114.80873 -386.42204)
			(xy 114.80927 -386.449062) (xy 114.808748 -386.476348) (xy 114.799793 -386.530179) (xy 114.782118 -386.58181)
			(xy 114.756205 -386.629836) (xy 114.722756 -386.672955) (xy 114.703098 -386.691886) (xy 114.6957 -386.699411)
			(xy 114.687174 -386.718688) (xy 114.686588 -386.729224) (xy 114.686588 -386.8039) (xy 114.687107 -386.814451)
			(xy 114.69565 -386.833746) (xy 114.703098 -386.841238) (xy 114.722731 -386.860191) (xy 114.756168 -386.90331)
			(xy 114.782074 -386.951333) (xy 114.799747 -387.002956) (xy 114.808709 -387.05678) (xy 114.80927 -387.084062)
			(xy 114.808817 -387.108178) (xy 114.801821 -387.1559) (xy 114.787972 -387.202101) (xy 114.767564 -387.245802)
			(xy 114.75466 -387.26618) (xy 114.748818 -387.27507) (xy 114.745262 -387.295136) (xy 114.766344 -387.387338)
			(xy 114.778536 -387.404102) (xy 114.787426 -387.409436) (xy 114.808225 -387.422294) (xy 114.846131 -387.453183)
			(xy 114.879074 -387.489317) (xy 114.906336 -387.52991) (xy 114.927321 -387.574075) (xy 114.941573 -387.62085)
			(xy 114.948781 -387.669213) (xy 114.949224 -387.693662) (xy 114.948794 -387.718035) (xy 114.941649 -387.766254)
			(xy 114.927508 -387.812903) (xy 114.906676 -387.856972) (xy 114.879605 -387.89751) (xy 114.84688 -387.933637)
			(xy 114.82832 -387.94944) (xy 114.81943 -387.956552) (xy 114.810032 -387.97611) (xy 114.807238 -388.075424)
			(xy 114.815874 -388.09549) (xy 114.824256 -388.10311) (xy 114.842705 -388.120572) (xy 114.874052 -388.160542)
			(xy 114.898349 -388.205151) (xy 114.914925 -388.253167) (xy 114.923325 -388.303264) (xy 114.923824 -388.328662)
			(xy 114.923755 -388.338021) (xy 114.922612 -388.356703) (xy 114.921538 -388.366) (xy 114.920522 -388.37489)
			(xy 114.924332 -388.391654) (xy 114.968274 -388.461504) (xy 114.98199 -388.471918) (xy 114.990372 -388.474712)
			(xy 115.014387 -388.483216) (xy 115.059561 -388.50676) (xy 115.100368 -388.537251) (xy 115.13575 -388.573899)
			(xy 115.164789 -388.615753) (xy 115.18673 -388.661726) (xy 115.194334 -388.68604) (xy 115.195858 -388.691882)
			(xy 115.516152 -389.245602) (xy 115.520216 -389.24992) (xy 115.53641 -389.267636) (xy 115.563835 -389.307025)
			(xy 115.58498 -389.350113) (xy 115.599356 -389.395905) (xy 115.606632 -389.443346) (xy 115.607084 -389.467344)
			(xy 115.606647 -389.492149) (xy 115.598876 -389.541146) (xy 115.583534 -389.588323) (xy 115.560997 -389.632518)
			(xy 115.531822 -389.672642) (xy 115.496727 -389.707705) (xy 115.456577 -389.736845) (xy 115.412362 -389.759342)
			(xy 115.365171 -389.774642) (xy 115.316167 -389.782369) (xy 115.291362 -389.782812) (xy 115.265966 -389.782345)
			(xy 115.215831 -389.774208) (xy 115.167645 -389.758151) (xy 115.122651 -389.734588) (xy 115.082008 -389.704126)
			(xy 115.046766 -389.667551) (xy 115.017833 -389.625806) (xy 114.995956 -389.579968) (xy 114.98834 -389.555736)
			(xy 114.986816 -389.549894) (xy 114.666522 -388.996174) (xy 114.662458 -388.991856) (xy 114.646299 -388.974121)
			(xy 114.618931 -388.93472) (xy 114.59784 -388.89163) (xy 114.583512 -388.845845) (xy 114.576278 -388.798419)
			(xy 114.575844 -388.774432) (xy 114.575925 -388.762384) (xy 114.577707 -388.738355) (xy 114.5794 -388.726426)
			(xy 114.58067 -388.717536) (xy 114.577622 -388.700518) (xy 114.535458 -388.629652) (xy 114.52225 -388.618476)
			(xy 114.513868 -388.615428) (xy 114.49212 -388.607034) (xy 114.451261 -388.584593) (xy 114.414291 -388.556199)
			(xy 114.382068 -388.522514) (xy 114.355343 -388.484319) (xy 114.334737 -388.442506) (xy 114.320729 -388.398044)
			(xy 114.313646 -388.35197) (xy 114.313208 -388.328662) (xy 114.313731 -388.303267) (xy 114.322141 -388.253178)
			(xy 114.338721 -388.20517) (xy 114.363016 -388.160567) (xy 114.394355 -388.120599) (xy 114.412776 -388.10311)
			(xy 114.421158 -388.09549) (xy 114.429794 -388.075424) (xy 114.427 -387.97611) (xy 114.417602 -387.956552)
			(xy 114.408712 -387.94944) (xy 114.390167 -387.933622) (xy 114.357448 -387.897493) (xy 114.33038 -387.856957)
			(xy 114.309547 -387.812891) (xy 114.295401 -387.766247) (xy 114.288245 -387.718033) (xy 114.287808 -387.693662)
			(xy 114.288229 -387.669545) (xy 114.295235 -387.621822) (xy 114.309093 -387.575621) (xy 114.32951 -387.531921)
			(xy 114.342418 -387.511544) (xy 114.34826 -387.502654) (xy 114.351816 -387.482588) (xy 114.330734 -387.390386)
			(xy 114.318542 -387.373622) (xy 114.309652 -387.368288) (xy 114.288859 -387.355422) (xy 114.250954 -387.324533)
			(xy 114.218011 -387.288399) (xy 114.190749 -387.247808) (xy 114.169763 -387.203645) (xy 114.155509 -387.156872)
			(xy 114.148299 -387.10851) (xy 114.147854 -387.084062) (xy 114.148415 -387.056778) (xy 114.157365 -387.00295)
			(xy 114.175031 -386.951321) (xy 114.200935 -386.903294) (xy 114.234373 -386.860172) (xy 114.254026 -386.841238)
			(xy 114.261402 -386.833694) (xy 114.269944 -386.814432) (xy 114.270536 -386.8039) (xy 114.270536 -386.729224)
			(xy 114.269997 -386.718676) (xy 114.261468 -386.699381) (xy 114.254026 -386.691886) (xy 114.23439 -386.672936)
			(xy 114.200958 -386.629814) (xy 114.175053 -386.58179) (xy 114.15738 -386.530167) (xy 114.148417 -386.476344)
			(xy 114.147854 -386.449062) (xy 114.148234 -386.425386) (xy 114.154968 -386.378515) (xy 114.168335 -386.333088)
			(xy 114.177826 -386.311394) (xy 114.182144 -386.301996) (xy 114.182906 -386.28193) (xy 114.150648 -386.19557)
			(xy 114.136932 -386.180838) (xy 114.127534 -386.17652) (xy 114.103158 -386.164843) (xy 114.058289 -386.134713)
			(xy 114.018912 -386.097693) (xy 113.986074 -386.054765) (xy 113.960649 -386.007072) (xy 113.943312 -385.955881)
			(xy 113.934525 -385.902553) (xy 113.933986 -385.87553) (xy 112.266082 -385.87553) (xy 112.252848 -385.885145)
			(xy 112.206538 -385.908741) (xy 112.157108 -385.924802) (xy 112.105773 -385.932932) (xy 112.053799 -385.932932)
			(xy 112.002464 -385.924802) (xy 111.953034 -385.908741) (xy 111.906724 -385.885145) (xy 111.864676 -385.854595)
			(xy 111.827925 -385.817844) (xy 111.797375 -385.775796) (xy 111.773779 -385.729486) (xy 111.757718 -385.680056)
			(xy 111.749588 -385.628721) (xy 111.544145 -385.628721) (xy 111.538773 -385.665222) (xy 111.522705 -385.718629)
			(xy 111.499033 -385.769126) (xy 111.46826 -385.815639) (xy 111.431043 -385.857176) (xy 111.388175 -385.892851)
			(xy 111.340569 -385.921905) (xy 111.28924 -385.943717) (xy 111.235283 -385.957823) (xy 111.179846 -385.963923)
			(xy 111.124112 -385.961886) (xy 111.069269 -385.951756) (xy 111.016485 -385.933749) (xy 110.966885 -385.908248)
			(xy 110.921527 -385.875797) (xy 110.881378 -385.837088) (xy 110.847292 -385.792945) (xy 110.819996 -385.74431)
			(xy 110.800073 -385.692219) (xy 110.787947 -385.637782) (xy 110.783876 -385.58216) (xy 108.563923 -385.58216)
			(xy 108.556322 -385.598312) (xy 108.52207 -385.652281) (xy 108.481324 -385.701532) (xy 108.434727 -385.745288)
			(xy 108.383013 -385.782858) (xy 108.326998 -385.81365) (xy 108.267565 -385.837179) (xy 108.205651 -385.853072)
			(xy 108.142234 -385.861081) (xy 108.110274 -385.86156) (xy 108.079578 -385.861088) (xy 108.018633 -385.853686)
			(xy 107.959024 -385.838994) (xy 107.901619 -385.817226) (xy 107.847257 -385.788698) (xy 107.82173 -385.771644)
			(xy 107.812978 -385.766173) (xy 107.792774 -385.762045) (xy 107.77257 -385.766173) (xy 107.763818 -385.771644)
			(xy 107.738269 -385.788663) (xy 107.683905 -385.817176) (xy 107.626506 -385.838943) (xy 107.566905 -385.853648)
			(xy 107.505968 -385.861077) (xy 107.475274 -385.86156) (xy 107.443311 -385.861153) (xy 107.379889 -385.853138)
			(xy 107.317972 -385.837237) (xy 107.258536 -385.813702) (xy 107.202518 -385.782904) (xy 107.150802 -385.745327)
			(xy 107.104203 -385.701566) (xy 107.063456 -385.652309) (xy 107.029204 -385.598334) (xy 107.001987 -385.540491)
			(xy 106.982233 -385.479694) (xy 106.970255 -385.4169) (xy 106.966241 -385.3531) (xy 104.20142 -385.3531)
			(xy 103.897176 -385.657344) (xy 103.895652 -385.696714) (xy 103.908606 -385.711954) (xy 103.927529 -385.734964)
			(xy 103.960447 -385.78462) (xy 103.987339 -385.837782) (xy 104.007836 -385.893721) (xy 104.021658 -385.951673)
			(xy 104.028614 -386.010842) (xy 104.029002 -386.04063) (xy 104.028536 -386.07136) (xy 104.021125 -386.132371)
			(xy 104.006413 -386.192043) (xy 103.984617 -386.249508) (xy 103.956053 -386.303926) (xy 103.921138 -386.354505)
			(xy 103.880381 -386.400506) (xy 103.834377 -386.44126) (xy 103.783795 -386.476171) (xy 103.729375 -386.504732)
			(xy 103.671909 -386.526524) (xy 103.612235 -386.541231) (xy 103.551224 -386.548638) (xy 103.520494 -386.549138)
			(xy 103.51389 -386.549138) (xy 103.50373 -386.548884) (xy 103.484934 -386.556504) (xy 103.426006 -386.614416)
			(xy 103.419126 -386.621869) (xy 103.411395 -386.640602) (xy 103.41102 -386.650738) (xy 103.41102 -387.7945)
			(xy 104.48493 -387.7945) (xy 104.489001 -387.738878) (xy 104.501127 -387.684441) (xy 104.52105 -387.63235)
			(xy 104.548346 -387.583715) (xy 104.582432 -387.539572) (xy 104.622581 -387.500863) (xy 104.667939 -387.468412)
			(xy 104.717539 -387.442911) (xy 104.770323 -387.424904) (xy 104.825166 -387.414774) (xy 104.8809 -387.412737)
			(xy 104.936337 -387.418837) (xy 104.990294 -387.432943) (xy 105.041623 -387.454755) (xy 105.089229 -387.483809)
			(xy 105.132097 -387.519484) (xy 105.169314 -387.561021) (xy 105.200087 -387.607534) (xy 105.223759 -387.658031)
			(xy 105.239827 -387.711438) (xy 105.247947 -387.766614) (xy 105.248368 -387.789674) (xy 108.001308 -387.789674)
			(xy 108.001308 -386.926074) (xy 108.001799 -386.898817) (xy 108.009557 -386.844857) (xy 108.024911 -386.79255)
			(xy 108.04755 -386.742959) (xy 108.077012 -386.697092) (xy 108.112699 -386.655882) (xy 108.153885 -386.620167)
			(xy 108.199732 -386.590674) (xy 108.249308 -386.568002) (xy 108.301605 -386.552612) (xy 108.355559 -386.544818)
			(xy 108.382816 -386.544312) (xy 108.415328 -386.545836) (xy 108.425234 -386.546598) (xy 108.443268 -386.541264)
			(xy 108.513372 -386.486146) (xy 108.523024 -386.46989) (xy 108.524548 -386.460238) (xy 108.529125 -386.433582)
			(xy 108.544858 -386.381836) (xy 108.567744 -386.332831) (xy 108.597324 -386.287552) (xy 108.633004 -386.246906)
			(xy 108.67407 -386.211709) (xy 108.719696 -386.182668) (xy 108.768968 -386.160364) (xy 108.820897 -386.145246)
			(xy 108.874441 -386.137616) (xy 108.901484 -386.13715) (xy 108.928735 -386.137696) (xy 108.982681 -386.14545)
			(xy 109.034975 -386.160803) (xy 109.084552 -386.183442) (xy 109.130402 -386.212907) (xy 109.171592 -386.248597)
			(xy 109.207284 -386.289785) (xy 109.23675 -386.335634) (xy 109.259391 -386.38521) (xy 109.274746 -386.437503)
			(xy 109.282215 -386.489448) (xy 111.850932 -386.489448) (xy 111.851442 -386.463461) (xy 111.859572 -386.412126)
			(xy 111.875633 -386.362696) (xy 111.899229 -386.316386) (xy 111.929779 -386.274338) (xy 111.96653 -386.237587)
			(xy 112.008578 -386.207037) (xy 112.054888 -386.183441) (xy 112.104318 -386.16738) (xy 112.155653 -386.15925)
			(xy 112.207627 -386.15925) (xy 112.258962 -386.16738) (xy 112.308392 -386.183441) (xy 112.354702 -386.207037)
			(xy 112.39675 -386.237587) (xy 112.433501 -386.274338) (xy 112.464051 -386.316386) (xy 112.487647 -386.362696)
			(xy 112.503708 -386.412126) (xy 112.511838 -386.463461) (xy 112.512348 -386.489448) (xy 112.511801 -386.516777)
			(xy 112.502808 -386.57069) (xy 112.485073 -386.62239) (xy 112.45908 -386.670472) (xy 112.442752 -386.692394)
			(xy 112.437164 -386.69976) (xy 112.431576 -386.716524) (xy 112.435132 -386.800598) (xy 112.44199 -386.816854)
			(xy 112.448086 -386.823712) (xy 112.464463 -386.842117) (xy 112.492116 -386.882887) (xy 112.513419 -386.927307)
			(xy 112.527902 -386.974394) (xy 112.535244 -387.023108) (xy 112.535716 -387.04774) (xy 112.535206 -387.073727)
			(xy 112.527076 -387.125062) (xy 112.511015 -387.174492) (xy 112.487419 -387.220802) (xy 112.456869 -387.26285)
			(xy 112.420118 -387.299601) (xy 112.37807 -387.330151) (xy 112.33176 -387.353747) (xy 112.28233 -387.369808)
			(xy 112.230995 -387.377938) (xy 112.179021 -387.377938) (xy 112.127686 -387.369808) (xy 112.078256 -387.353747)
			(xy 112.031946 -387.330151) (xy 111.989898 -387.299601) (xy 111.953147 -387.26285) (xy 111.922597 -387.220802)
			(xy 111.899001 -387.174492) (xy 111.88294 -387.125062) (xy 111.87481 -387.073727) (xy 111.8743 -387.04774)
			(xy 111.874884 -387.020413) (xy 111.883865 -386.966501) (xy 111.901588 -386.9148) (xy 111.927572 -386.866717)
			(xy 111.943896 -386.844794) (xy 111.949484 -386.837428) (xy 111.955072 -386.820664) (xy 111.951516 -386.73659)
			(xy 111.944658 -386.720334) (xy 111.938562 -386.713476) (xy 111.922218 -386.695044) (xy 111.894562 -386.65428)
			(xy 111.873253 -386.609867) (xy 111.858763 -386.562786) (xy 111.85141 -386.514078) (xy 111.850932 -386.489448)
			(xy 109.282215 -386.489448) (xy 109.282503 -386.491449) (xy 109.282503 -386.545951) (xy 109.274746 -386.599897)
			(xy 109.259391 -386.65219) (xy 109.23675 -386.701766) (xy 109.207284 -386.747615) (xy 109.171592 -386.788803)
			(xy 109.130402 -386.824493) (xy 109.084552 -386.853958) (xy 109.034975 -386.876597) (xy 108.982681 -386.89195)
			(xy 108.928735 -386.899704) (xy 108.901484 -386.900166) (xy 108.873544 -386.89915) (xy 108.862876 -386.898388)
			(xy 108.843064 -386.905246) (xy 108.78058 -386.963158) (xy 108.773254 -386.970715) (xy 108.764853 -386.989986)
			(xy 108.764324 -387.000496) (xy 108.764324 -387.789674) (xy 108.763751 -387.820807) (xy 108.753667 -387.88225)
			(xy 108.733715 -387.941232) (xy 108.71962 -387.968998) (xy 108.71454 -387.978904) (xy 108.713016 -388.000494)
			(xy 108.74756 -388.092442) (xy 108.7628 -388.107936) (xy 108.77296 -388.111746) (xy 108.79964 -388.122516)
			(xy 108.849698 -388.150878) (xy 108.894928 -388.186437) (xy 108.934304 -388.228385) (xy 108.966934 -388.275771)
			(xy 108.977575 -388.297674) (xy 110.908844 -388.297674) (xy 110.912915 -388.242052) (xy 110.925041 -388.187615)
			(xy 110.944964 -388.135524) (xy 110.97226 -388.086889) (xy 111.006346 -388.042746) (xy 111.046495 -388.004037)
			(xy 111.091853 -387.971586) (xy 111.141453 -387.946085) (xy 111.194237 -387.928078) (xy 111.24908 -387.917948)
			(xy 111.304814 -387.915911) (xy 111.360251 -387.922011) (xy 111.414208 -387.936117) (xy 111.465537 -387.957929)
			(xy 111.513143 -387.986983) (xy 111.556011 -388.022658) (xy 111.593228 -388.064195) (xy 111.624001 -388.110708)
			(xy 111.647673 -388.161205) (xy 111.663741 -388.214612) (xy 111.671861 -388.269788) (xy 111.67237 -388.297674)
			(xy 111.671923 -388.322137) (xy 111.87481 -388.322137) (xy 111.87481 -388.270163) (xy 111.88294 -388.218828)
			(xy 111.899001 -388.169398) (xy 111.922597 -388.123088) (xy 111.953147 -388.08104) (xy 111.989898 -388.044289)
			(xy 112.031946 -388.013739) (xy 112.078256 -387.990143) (xy 112.127686 -387.974082) (xy 112.179021 -387.965952)
			(xy 112.230995 -387.965952) (xy 112.28233 -387.974082) (xy 112.33176 -387.990143) (xy 112.37807 -388.013739)
			(xy 112.420118 -388.044289) (xy 112.456869 -388.08104) (xy 112.487419 -388.123088) (xy 112.511015 -388.169398)
			(xy 112.527076 -388.218828) (xy 112.535206 -388.270163) (xy 112.535716 -388.29615) (xy 112.535206 -388.322137)
			(xy 112.527076 -388.373472) (xy 112.511015 -388.422902) (xy 112.487419 -388.469212) (xy 112.456869 -388.51126)
			(xy 112.420118 -388.548011) (xy 112.37807 -388.578561) (xy 112.33176 -388.602157) (xy 112.28233 -388.618218)
			(xy 112.230995 -388.626348) (xy 112.179021 -388.626348) (xy 112.127686 -388.618218) (xy 112.078256 -388.602157)
			(xy 112.031946 -388.578561) (xy 111.989898 -388.548011) (xy 111.953147 -388.51126) (xy 111.922597 -388.469212)
			(xy 111.899001 -388.422902) (xy 111.88294 -388.373472) (xy 111.87481 -388.322137) (xy 111.671923 -388.322137)
			(xy 111.671861 -388.32556) (xy 111.663741 -388.380736) (xy 111.647673 -388.434143) (xy 111.624001 -388.48464)
			(xy 111.593228 -388.531153) (xy 111.556011 -388.57269) (xy 111.513143 -388.608365) (xy 111.465537 -388.637419)
			(xy 111.414208 -388.659231) (xy 111.360251 -388.673337) (xy 111.304814 -388.679437) (xy 111.24908 -388.6774)
			(xy 111.194237 -388.66727) (xy 111.141453 -388.649263) (xy 111.091853 -388.623762) (xy 111.046495 -388.591311)
			(xy 111.006346 -388.552602) (xy 110.97226 -388.508459) (xy 110.944964 -388.459824) (xy 110.925041 -388.407733)
			(xy 110.912915 -388.353296) (xy 110.908844 -388.297674) (xy 108.977575 -388.297674) (xy 108.992076 -388.327521)
			(xy 109.009161 -388.38246) (xy 109.017801 -388.439341) (xy 109.018324 -388.468108) (xy 109.017881 -388.495479)
			(xy 109.010061 -388.54966) (xy 108.994567 -388.602164) (xy 108.97172 -388.651911) (xy 108.941989 -388.697876)
			(xy 108.924344 -388.718806) (xy 108.918248 -388.725918) (xy 108.911898 -388.742936) (xy 108.911898 -388.82828)
			(xy 108.918248 -388.845298) (xy 108.924344 -388.85241) (xy 108.942008 -388.873322) (xy 108.971715 -388.919301)
			(xy 108.994546 -388.969053) (xy 109.010031 -389.021558) (xy 109.017853 -389.075738) (xy 109.018324 -389.103108)
			(xy 109.017838 -389.130359) (xy 109.010082 -389.184307) (xy 108.994727 -389.236602) (xy 108.974724 -389.2804)
			(xy 111.361472 -389.2804) (xy 111.365543 -389.224778) (xy 111.377669 -389.170341) (xy 111.397592 -389.11825)
			(xy 111.424888 -389.069615) (xy 111.458974 -389.025472) (xy 111.499123 -388.986763) (xy 111.544481 -388.954312)
			(xy 111.594081 -388.928811) (xy 111.646865 -388.910804) (xy 111.701708 -388.900674) (xy 111.757442 -388.898637)
			(xy 111.812879 -388.904737) (xy 111.866836 -388.918843) (xy 111.918165 -388.940655) (xy 111.965771 -388.969709)
			(xy 112.008639 -389.005384) (xy 112.045856 -389.046921) (xy 112.076629 -389.093434) (xy 112.100301 -389.143931)
			(xy 112.116369 -389.197338) (xy 112.124489 -389.252514) (xy 112.124998 -389.2804) (xy 112.124489 -389.308286)
			(xy 112.116369 -389.363462) (xy 112.100301 -389.416869) (xy 112.076629 -389.467366) (xy 112.045856 -389.513879)
			(xy 112.008639 -389.555416) (xy 111.965771 -389.591091) (xy 111.918165 -389.620145) (xy 111.866836 -389.641957)
			(xy 111.812879 -389.656063) (xy 111.757442 -389.662163) (xy 111.701708 -389.660126) (xy 111.646865 -389.649996)
			(xy 111.594081 -389.631989) (xy 111.544481 -389.606488) (xy 111.499123 -389.574037) (xy 111.458974 -389.535328)
			(xy 111.424888 -389.491185) (xy 111.397592 -389.44255) (xy 111.377669 -389.390459) (xy 111.365543 -389.336022)
			(xy 111.361472 -389.2804) (xy 108.974724 -389.2804) (xy 108.972085 -389.286179) (xy 108.942619 -389.332029)
			(xy 108.906928 -389.37322) (xy 108.865737 -389.408911) (xy 108.819887 -389.438377) (xy 108.77031 -389.461019)
			(xy 108.718015 -389.476374) (xy 108.664067 -389.48413) (xy 108.609565 -389.48413) (xy 108.555617 -389.476374)
			(xy 108.503322 -389.461019) (xy 108.453745 -389.438377) (xy 108.407895 -389.408911) (xy 108.366704 -389.37322)
			(xy 108.331013 -389.332029) (xy 108.301547 -389.286179) (xy 108.278905 -389.236602) (xy 108.26355 -389.184307)
			(xy 108.255794 -389.130359) (xy 108.255308 -389.103108) (xy 108.255777 -389.075738) (xy 108.263594 -389.021559)
			(xy 108.279082 -388.969056) (xy 108.301923 -388.919309) (xy 108.331647 -388.873342) (xy 108.349288 -388.85241)
			(xy 108.355384 -388.845298) (xy 108.361734 -388.82828) (xy 108.361734 -388.742936) (xy 108.355384 -388.725918)
			(xy 108.349288 -388.718806) (xy 108.331636 -388.697884) (xy 108.301927 -388.651908) (xy 108.279094 -388.602158)
			(xy 108.263605 -388.549655) (xy 108.25578 -388.495478) (xy 108.255308 -388.468108) (xy 108.25592 -388.436977)
			(xy 108.265989 -388.375535) (xy 108.285925 -388.316552) (xy 108.300012 -388.288784) (xy 108.305092 -388.279132)
			(xy 108.306616 -388.257542) (xy 108.272326 -388.165594) (xy 108.256832 -388.1501) (xy 108.246672 -388.14629)
			(xy 108.219995 -388.135483) (xy 108.169939 -388.107076) (xy 108.124713 -388.071479) (xy 108.085341 -388.029498)
			(xy 108.052714 -387.982085) (xy 108.027572 -387.930312) (xy 108.010484 -387.875353) (xy 108.001836 -387.818451)
			(xy 108.001308 -387.789674) (xy 105.248368 -387.789674) (xy 105.248456 -387.7945) (xy 105.247947 -387.822386)
			(xy 105.239827 -387.877562) (xy 105.223759 -387.930969) (xy 105.200087 -387.981466) (xy 105.169314 -388.027979)
			(xy 105.132097 -388.069516) (xy 105.089229 -388.105191) (xy 105.041623 -388.134245) (xy 104.990294 -388.156057)
			(xy 104.936337 -388.170163) (xy 104.8809 -388.176263) (xy 104.825166 -388.174226) (xy 104.770323 -388.164096)
			(xy 104.717539 -388.146089) (xy 104.667939 -388.120588) (xy 104.622581 -388.088137) (xy 104.582432 -388.049428)
			(xy 104.548346 -388.005285) (xy 104.52105 -387.95665) (xy 104.501127 -387.904559) (xy 104.489001 -387.850122)
			(xy 104.48493 -387.7945) (xy 103.41102 -387.7945) (xy 103.41102 -390.094681) (xy 103.659426 -390.094681)
			(xy 103.659426 -390.030759) (xy 103.667437 -389.967341) (xy 103.683334 -389.905427) (xy 103.706866 -389.845994)
			(xy 103.73766 -389.789979) (xy 103.775233 -389.738264) (xy 103.81899 -389.691667) (xy 103.868243 -389.650922)
			(xy 103.922214 -389.616671) (xy 103.980053 -389.589454) (xy 104.040846 -389.569701) (xy 104.103636 -389.557723)
			(xy 104.167432 -389.55371) (xy 104.231228 -389.557723) (xy 104.294018 -389.569701) (xy 104.354811 -389.589454)
			(xy 104.41265 -389.616671) (xy 104.466621 -389.650922) (xy 104.515874 -389.691667) (xy 104.559631 -389.738264)
			(xy 104.597204 -389.789979) (xy 104.627998 -389.845994) (xy 104.65153 -389.905427) (xy 104.667427 -389.967341)
			(xy 104.675438 -390.030759) (xy 104.67594 -390.06272) (xy 104.675438 -390.094681) (xy 104.667427 -390.158099)
			(xy 104.65153 -390.220013) (xy 104.627998 -390.279446) (xy 104.597204 -390.335461) (xy 104.559631 -390.387176)
			(xy 104.515874 -390.433773) (xy 104.466621 -390.474518) (xy 104.41265 -390.508769) (xy 104.354811 -390.535986)
			(xy 104.294018 -390.555739) (xy 104.231228 -390.567717) (xy 104.167432 -390.571731) (xy 104.103636 -390.567717)
			(xy 104.040846 -390.555739) (xy 103.980053 -390.535986) (xy 103.922214 -390.508769) (xy 103.868243 -390.474518)
			(xy 103.81899 -390.433773) (xy 103.775233 -390.387176) (xy 103.73766 -390.335461) (xy 103.706866 -390.279446)
			(xy 103.683334 -390.220013) (xy 103.667437 -390.158099) (xy 103.659426 -390.094681) (xy 103.41102 -390.094681)
			(xy 103.41102 -393.193524) (xy 103.411137 -393.199029) (xy 103.413435 -393.209795) (xy 103.415592 -393.21486)
			(xy 103.428317 -393.243555) (xy 103.447393 -393.303359) (xy 103.458956 -393.365058) (xy 103.462829 -393.427711)
			(xy 103.458953 -393.490364) (xy 103.453224 -393.52093) (xy 105.06837 -393.52093) (xy 105.068832 -393.490233)
			(xy 105.076238 -393.429288) (xy 105.090933 -393.36968) (xy 105.112703 -393.312276) (xy 105.141232 -393.257913)
			(xy 105.158286 -393.232386) (xy 105.163734 -393.223621) (xy 105.167872 -393.203425) (xy 105.163753 -393.183225)
			(xy 105.158286 -393.174474) (xy 105.141252 -393.148935) (xy 105.11274 -393.094568) (xy 105.090976 -393.037166)
			(xy 105.076275 -392.977563) (xy 105.068851 -392.916624) (xy 105.06837 -392.88593) (xy 105.068832 -392.855233)
			(xy 105.076238 -392.794288) (xy 105.090933 -392.73468) (xy 105.112703 -392.677276) (xy 105.141232 -392.622913)
			(xy 105.158286 -392.597386) (xy 105.163734 -392.588621) (xy 105.167872 -392.568425) (xy 105.163753 -392.548225)
			(xy 105.158286 -392.539474) (xy 105.141252 -392.513935) (xy 105.11274 -392.459568) (xy 105.090976 -392.402166)
			(xy 105.076275 -392.342563) (xy 105.068851 -392.281624) (xy 105.06837 -392.25093) (xy 105.068832 -392.220233)
			(xy 105.076238 -392.159288) (xy 105.090933 -392.09968) (xy 105.112703 -392.042276) (xy 105.141232 -391.987913)
			(xy 105.158286 -391.962386) (xy 105.163734 -391.953621) (xy 105.167872 -391.933425) (xy 105.163753 -391.913225)
			(xy 105.158286 -391.904474) (xy 105.141252 -391.878935) (xy 105.11274 -391.824568) (xy 105.090976 -391.767166)
			(xy 105.076275 -391.707563) (xy 105.068851 -391.646624) (xy 105.06837 -391.61593) (xy 105.068828 -391.585437)
			(xy 105.076141 -391.524889) (xy 105.090642 -391.465651) (xy 105.112122 -391.408572) (xy 105.140274 -391.354471)
			(xy 105.174693 -391.304125) (xy 105.214886 -391.258256) (xy 105.260275 -391.217522) (xy 105.31021 -391.182508)
			(xy 105.363973 -391.153716) (xy 105.39222 -391.14222) (xy 105.40111 -391.138664) (xy 105.414826 -391.126218)
			(xy 105.453942 -391.047986) (xy 105.45572 -391.029444) (xy 105.45318 -391.020046) (xy 105.444416 -390.986564)
			(xy 105.434984 -390.917999) (xy 105.434384 -390.883394) (xy 105.434876 -390.852698) (xy 105.442274 -390.791754)
			(xy 105.456962 -390.732146) (xy 105.478726 -390.674742) (xy 105.507248 -390.620378) (xy 105.5243 -390.59485)
			(xy 105.529777 -390.586101) (xy 105.533904 -390.565895) (xy 105.529773 -390.54569) (xy 105.5243 -390.536938)
			(xy 105.50724 -390.511416) (xy 105.478735 -390.457044) (xy 105.456977 -390.399637) (xy 105.442282 -390.340031)
			(xy 105.434862 -390.279089) (xy 105.434384 -390.248394) (xy 105.434853 -390.217842) (xy 105.442166 -390.157177)
			(xy 105.456698 -390.097825) (xy 105.478239 -390.040644) (xy 105.506479 -389.986457) (xy 105.541011 -389.936045)
			(xy 105.581336 -389.890136) (xy 105.603802 -389.869426) (xy 105.61025 -389.863229) (xy 105.618716 -389.847491)
			(xy 105.620312 -389.838692) (xy 105.624376 -389.80872) (xy 105.625278 -389.800006) (xy 105.621762 -389.782856)
			(xy 105.617518 -389.775192) (xy 105.604224 -389.75261) (xy 105.583229 -389.704598) (xy 105.569006 -389.654164)
			(xy 105.561822 -389.602257) (xy 105.561384 -389.576056) (xy 105.561862 -389.548686) (xy 105.569674 -389.494507)
			(xy 105.585159 -389.442003) (xy 105.607999 -389.392256) (xy 105.637723 -389.346289) (xy 105.655364 -389.325358)
			(xy 105.66146 -389.318246) (xy 105.66781 -389.301228) (xy 105.66781 -389.215884) (xy 105.66146 -389.198866)
			(xy 105.655364 -389.191754) (xy 105.637731 -389.170817) (xy 105.60802 -389.124845) (xy 105.585183 -389.075099)
			(xy 105.56969 -389.022599) (xy 105.56186 -388.968425) (xy 105.561384 -388.941056) (xy 105.561837 -388.913804)
			(xy 105.569599 -388.859856) (xy 105.584959 -388.807561) (xy 105.607605 -388.757984) (xy 105.637075 -388.712134)
			(xy 105.67277 -388.670945) (xy 105.713963 -388.635254) (xy 105.759815 -388.605788) (xy 105.809394 -388.583147)
			(xy 105.861691 -388.567791) (xy 105.91564 -388.560034) (xy 105.942892 -388.559548) (xy 105.969653 -388.559964)
			(xy 106.02265 -388.56744) (xy 106.074084 -388.582247) (xy 106.122944 -388.604094) (xy 106.168273 -388.632552)
			(xy 106.189018 -388.649464) (xy 106.198162 -388.657338) (xy 106.221022 -388.662926) (xy 106.323638 -388.639558)
			(xy 106.341926 -388.624826) (xy 106.347006 -388.61365) (xy 106.358728 -388.588968) (xy 106.388149 -388.542925)
			(xy 106.423838 -388.50155) (xy 106.465065 -388.465691) (xy 106.510986 -388.436081) (xy 106.560663 -388.413326)
			(xy 106.613077 -388.397891) (xy 106.667158 -388.390092) (xy 106.694478 -388.389622) (xy 106.721848 -388.390096)
			(xy 106.776027 -388.397911) (xy 106.82853 -388.413398) (xy 106.878277 -388.436238) (xy 106.924244 -388.465961)
			(xy 106.945176 -388.483602) (xy 106.952288 -388.489698) (xy 106.969306 -388.496048) (xy 107.05465 -388.496048)
			(xy 107.071668 -388.489698) (xy 107.07878 -388.483602) (xy 107.099709 -388.465959) (xy 107.145683 -388.436248)
			(xy 107.195431 -388.413413) (xy 107.247932 -388.397922) (xy 107.302109 -388.390095) (xy 107.329478 -388.389622)
			(xy 107.356734 -388.390023) (xy 107.410692 -388.397778) (xy 107.462996 -388.413134) (xy 107.512583 -388.435777)
			(xy 107.558443 -388.465247) (xy 107.599641 -388.500943) (xy 107.63534 -388.54214) (xy 107.664813 -388.587997)
			(xy 107.687458 -388.637583) (xy 107.702817 -388.689887) (xy 107.710575 -388.743844) (xy 107.710575 -388.798356)
			(xy 107.702817 -388.852313) (xy 107.687458 -388.904617) (xy 107.664813 -388.954203) (xy 107.63534 -389.00006)
			(xy 107.599641 -389.041257) (xy 107.558443 -389.076953) (xy 107.512583 -389.106423) (xy 107.462996 -389.129066)
			(xy 107.410692 -389.144422) (xy 107.356734 -389.152177) (xy 107.329478 -389.152638) (xy 107.302107 -389.1522)
			(xy 107.247926 -389.144378) (xy 107.195422 -389.128883) (xy 107.145675 -389.106035) (xy 107.09971 -389.076303)
			(xy 107.07878 -389.058658) (xy 107.071668 -389.052562) (xy 107.05465 -389.046212) (xy 106.969306 -389.046212)
			(xy 106.952288 -389.052562) (xy 106.945176 -389.058658) (xy 106.924221 -389.076268) (xy 106.878255 -389.105986)
			(xy 106.828513 -389.128828) (xy 106.776018 -389.144326) (xy 106.721846 -389.152161) (xy 106.694478 -389.152638)
			(xy 106.667718 -389.152185) (xy 106.614722 -389.144718) (xy 106.563289 -389.12992) (xy 106.514428 -389.108081)
			(xy 106.469098 -389.07963) (xy 106.448352 -389.062722) (xy 106.439208 -389.054848) (xy 106.416348 -389.04926)
			(xy 106.313732 -389.072628) (xy 106.295444 -389.08736) (xy 106.290364 -389.098536) (xy 106.278417 -389.123663)
			(xy 106.248322 -389.170456) (xy 106.23042 -389.191754) (xy 106.224324 -389.198866) (xy 106.217974 -389.215884)
			(xy 106.217974 -389.301228) (xy 106.224324 -389.318246) (xy 106.23042 -389.325358) (xy 106.248056 -389.346293)
			(xy 106.277768 -389.392265) (xy 106.300604 -389.442012) (xy 106.316096 -389.494512) (xy 106.323925 -389.548687)
			(xy 106.3244 -389.576056) (xy 106.323958 -389.602258) (xy 106.316785 -389.654167) (xy 106.30257 -389.704606)
			(xy 106.28158 -389.752621) (xy 106.268266 -389.775192) (xy 106.26404 -389.782861) (xy 106.26054 -389.800006)
			(xy 106.261408 -389.80872) (xy 106.265472 -389.838692) (xy 106.26717 -389.847459) (xy 106.275598 -389.863184)
			(xy 106.281982 -389.869426) (xy 106.305439 -389.891063) (xy 106.347308 -389.939224) (xy 106.382814 -389.992251)
			(xy 106.397552 -390.020556) (xy 106.401616 -390.028938) (xy 106.415332 -390.041384) (xy 106.495342 -390.073388)
			(xy 106.513884 -390.073642) (xy 106.52252 -390.070594) (xy 106.550182 -390.061092) (xy 106.60713 -390.047751)
			(xy 106.665233 -390.041034) (xy 106.694478 -390.040622) (xy 106.725175 -390.041071) (xy 106.786121 -390.048478)
			(xy 106.84573 -390.063176) (xy 106.903134 -390.084949) (xy 106.957495 -390.113481) (xy 106.983022 -390.130538)
			(xy 106.991774 -390.136009) (xy 107.011978 -390.140137) (xy 107.032182 -390.136009) (xy 107.040934 -390.130538)
			(xy 107.066467 -390.113495) (xy 107.120836 -390.084986) (xy 107.178239 -390.063224) (xy 107.237844 -390.048525)
			(xy 107.298783 -390.041102) (xy 107.329478 -390.040622) (xy 107.360211 -390.041058) (xy 107.421228 -390.048465)
			(xy 107.480908 -390.063173) (xy 107.53838 -390.084968) (xy 107.592805 -390.113532) (xy 107.643391 -390.148448)
			(xy 107.689398 -390.189207) (xy 107.730157 -390.235216) (xy 107.765072 -390.285801) (xy 107.793635 -390.340227)
			(xy 107.815429 -390.397699) (xy 107.830136 -390.457379) (xy 107.837542 -390.518397) (xy 107.837986 -390.54913)
			(xy 107.83742 -390.583316) (xy 107.828282 -390.651074) (xy 107.810149 -390.716997) (xy 107.783346 -390.779896)
			(xy 107.748358 -390.838637) (xy 107.705815 -390.89216) (xy 107.656485 -390.939501) (xy 107.629198 -390.960102)
			(xy 107.617514 -390.968484) (xy 107.606846 -390.994138) (xy 107.623356 -391.111232) (xy 107.641136 -391.132822)
			(xy 107.654598 -391.137648) (xy 107.683728 -391.148658) (xy 107.73928 -391.176804) (xy 107.790979 -391.211524)
			(xy 107.83805 -391.252298) (xy 107.87979 -391.298515) (xy 107.915572 -391.349484) (xy 107.944863 -391.404441)
			(xy 107.967222 -391.462564) (xy 107.982316 -391.522983) (xy 107.989917 -391.584792) (xy 107.990386 -391.61593)
			(xy 107.989911 -391.646626) (xy 107.98251 -391.707571) (xy 107.967818 -391.76718) (xy 107.94605 -391.824584)
			(xy 107.917524 -391.878947) (xy 107.90047 -391.904474) (xy 107.894975 -391.913213) (xy 107.890857 -391.933425)
			(xy 107.894994 -391.953633) (xy 107.90047 -391.962386) (xy 107.917493 -391.987931) (xy 107.946005 -392.042297)
			(xy 107.967771 -392.099697) (xy 107.982475 -392.159299) (xy 107.989903 -392.220236) (xy 107.990386 -392.25093)
			(xy 107.989972 -392.281662) (xy 107.98256 -392.342679) (xy 107.967847 -392.402357) (xy 107.946048 -392.459827)
			(xy 107.917481 -392.51425) (xy 107.882562 -392.564832) (xy 107.841801 -392.610838) (xy 107.795791 -392.651594)
			(xy 107.745205 -392.686508) (xy 107.690779 -392.715069) (xy 107.633307 -392.736862) (xy 107.573628 -392.751569)
			(xy 107.512611 -392.758975) (xy 107.481878 -392.759438) (xy 107.460796 -392.75893) (xy 107.449874 -392.758422)
			(xy 107.430316 -392.766042) (xy 107.36199 -392.834368) (xy 107.35437 -392.853926) (xy 107.354878 -392.864848)
			(xy 107.355386 -392.88593) (xy 107.354911 -392.916626) (xy 107.34751 -392.977571) (xy 107.332818 -393.03718)
			(xy 107.31105 -393.094584) (xy 107.282524 -393.148947) (xy 107.26547 -393.174474) (xy 107.259975 -393.183213)
			(xy 107.255857 -393.203425) (xy 107.259994 -393.223633) (xy 107.26547 -393.232386) (xy 107.282493 -393.257931)
			(xy 107.311005 -393.312297) (xy 107.332771 -393.369697) (xy 107.347475 -393.429299) (xy 107.354903 -393.490236)
			(xy 107.355386 -393.52093) (xy 108.21035 -393.52093) (xy 108.210821 -393.49356) (xy 108.218636 -393.43938)
			(xy 108.234123 -393.386877) (xy 108.256964 -393.33713) (xy 108.286689 -393.291163) (xy 108.30433 -393.270232)
			(xy 108.310426 -393.26312) (xy 108.316776 -393.246102) (xy 108.316776 -393.160758) (xy 108.310426 -393.14374)
			(xy 108.30433 -393.136628) (xy 108.286719 -393.115672) (xy 108.256992 -393.069708) (xy 108.234145 -393.019966)
			(xy 108.218646 -392.967467) (xy 108.210815 -392.913292) (xy 108.210812 -392.858553) (xy 108.218637 -392.804377)
			(xy 108.234129 -392.751877) (xy 108.256971 -392.702132) (xy 108.286691 -392.656165) (xy 108.30433 -392.635232)
			(xy 108.310426 -392.62812) (xy 108.316776 -392.611102) (xy 108.316776 -392.525758) (xy 108.310426 -392.50874)
			(xy 108.30433 -392.501628) (xy 108.286719 -392.480672) (xy 108.256992 -392.434708) (xy 108.234145 -392.384966)
			(xy 108.218646 -392.332467) (xy 108.210815 -392.278292) (xy 108.210812 -392.223553) (xy 108.218637 -392.169377)
			(xy 108.234129 -392.116877) (xy 108.256971 -392.067132) (xy 108.286691 -392.021165) (xy 108.30433 -392.000232)
			(xy 108.310426 -391.99312) (xy 108.316776 -391.976102) (xy 108.316776 -391.890758) (xy 108.310426 -391.87374)
			(xy 108.30433 -391.866628) (xy 108.286695 -391.845692) (xy 108.256982 -391.799721) (xy 108.234144 -391.749974)
			(xy 108.218652 -391.697474) (xy 108.210824 -391.643299) (xy 108.21035 -391.61593) (xy 108.210837 -391.58846)
			(xy 108.218721 -391.534089) (xy 108.234315 -391.481409) (xy 108.257299 -391.431507) (xy 108.287197 -391.385415)
			(xy 108.323392 -391.344084) (xy 108.343954 -391.325862) (xy 108.351574 -391.319258) (xy 108.360718 -391.301478)
			(xy 108.36783 -391.209276) (xy 108.36148 -391.189972) (xy 108.354622 -391.182352) (xy 108.337237 -391.16144)
			(xy 108.307926 -391.115633) (xy 108.285404 -391.066135) (xy 108.270126 -391.013944) (xy 108.2624 -390.960114)
			(xy 108.261912 -390.932924) (xy 108.262389 -390.905554) (xy 108.270204 -390.851375) (xy 108.28569 -390.798872)
			(xy 108.30853 -390.749125) (xy 108.338252 -390.703158) (xy 108.355892 -390.682226) (xy 108.361988 -390.675114)
			(xy 108.368338 -390.658096) (xy 108.368338 -390.572752) (xy 108.361988 -390.555734) (xy 108.355892 -390.548622)
			(xy 108.338249 -390.527693) (xy 108.308538 -390.48172) (xy 108.285703 -390.431971) (xy 108.270213 -390.37947)
			(xy 108.262385 -390.325293) (xy 108.261912 -390.297924) (xy 108.262398 -390.270673) (xy 108.270154 -390.216725)
			(xy 108.285509 -390.16443) (xy 108.308151 -390.114853) (xy 108.337617 -390.069003) (xy 108.373308 -390.027812)
			(xy 108.414499 -389.992121) (xy 108.460349 -389.962655) (xy 108.509926 -389.940013) (xy 108.562221 -389.924658)
			(xy 108.616169 -389.916902) (xy 108.670671 -389.916902) (xy 108.724619 -389.924658) (xy 108.776914 -389.940013)
			(xy 108.826491 -389.962655) (xy 108.872341 -389.992121) (xy 108.913532 -390.027812) (xy 108.949223 -390.069003)
			(xy 108.978689 -390.114853) (xy 109.001331 -390.16443) (xy 109.016686 -390.216725) (xy 109.024442 -390.270673)
			(xy 109.024928 -390.297924) (xy 109.024494 -390.325296) (xy 109.016671 -390.379477) (xy 109.001175 -390.431981)
			(xy 108.978326 -390.481727) (xy 108.948593 -390.527692) (xy 108.930948 -390.548622) (xy 108.924852 -390.555734)
			(xy 108.918502 -390.572752) (xy 108.918502 -390.626092) (xy 111.862616 -390.626092) (xy 111.863023 -390.602859)
			(xy 111.869518 -390.556848) (xy 111.882391 -390.5122) (xy 111.901391 -390.469795) (xy 111.926142 -390.430469)
			(xy 111.940848 -390.412478) (xy 111.946944 -390.405366) (xy 111.95304 -390.388856) (xy 111.95304 -390.304528)
			(xy 111.946944 -390.288018) (xy 111.940848 -390.280906) (xy 111.926135 -390.26292) (xy 111.901388 -390.22359)
			(xy 111.882389 -390.181184) (xy 111.869511 -390.136537) (xy 111.863009 -390.090526) (xy 111.862616 -390.067292)
			(xy 111.863126 -390.041305) (xy 111.871256 -389.98997) (xy 111.887317 -389.94054) (xy 111.910913 -389.89423)
			(xy 111.941463 -389.852182) (xy 111.978214 -389.815431) (xy 112.020262 -389.784881) (xy 112.066572 -389.761285)
			(xy 112.116002 -389.745224) (xy 112.167337 -389.737094) (xy 112.219311 -389.737094) (xy 112.270646 -389.745224)
			(xy 112.320076 -389.761285) (xy 112.366386 -389.784881) (xy 112.408434 -389.815431) (xy 112.445185 -389.852182)
			(xy 112.475735 -389.89423) (xy 112.499331 -389.94054) (xy 112.515392 -389.98997) (xy 112.523522 -390.041305)
			(xy 112.524032 -390.067292) (xy 112.523663 -390.090527) (xy 112.517157 -390.136539) (xy 112.510387 -390.160002)
			(xy 114.185204 -390.160002) (xy 114.189164 -390.110948) (xy 114.200941 -390.063164) (xy 114.220232 -390.017888)
			(xy 114.246535 -389.976292) (xy 114.27917 -389.939455) (xy 114.317291 -389.90833) (xy 114.359912 -389.883723)
			(xy 114.405928 -389.866271) (xy 114.454147 -389.856427) (xy 114.503322 -389.854446) (xy 114.552177 -389.860378)
			(xy 114.599448 -389.87407) (xy 114.64391 -389.895168) (xy 114.684413 -389.923124) (xy 114.719906 -389.957216)
			(xy 114.749471 -389.99656) (xy 114.772342 -390.040137) (xy 114.787926 -390.086818) (xy 114.795821 -390.135395)
			(xy 114.796316 -390.160002) (xy 115.385354 -390.160002) (xy 115.389314 -390.110948) (xy 115.401091 -390.063164)
			(xy 115.420382 -390.017888) (xy 115.446685 -389.976292) (xy 115.47932 -389.939455) (xy 115.517441 -389.90833)
			(xy 115.560062 -389.883723) (xy 115.606078 -389.866271) (xy 115.654297 -389.856427) (xy 115.703472 -389.854446)
			(xy 115.752327 -389.860378) (xy 115.799598 -389.87407) (xy 115.84406 -389.895168) (xy 115.884563 -389.923124)
			(xy 115.920056 -389.957216) (xy 115.949621 -389.99656) (xy 115.972492 -390.040137) (xy 115.988076 -390.086818)
			(xy 115.995971 -390.135395) (xy 115.996466 -390.160002) (xy 116.585504 -390.160002) (xy 116.589464 -390.110948)
			(xy 116.601241 -390.063164) (xy 116.620532 -390.017888) (xy 116.646835 -389.976292) (xy 116.67947 -389.939455)
			(xy 116.717591 -389.90833) (xy 116.760212 -389.883723) (xy 116.806228 -389.866271) (xy 116.854447 -389.856427)
			(xy 116.903622 -389.854446) (xy 116.952477 -389.860378) (xy 116.999748 -389.87407) (xy 117.04421 -389.895168)
			(xy 117.084713 -389.923124) (xy 117.120206 -389.957216) (xy 117.149771 -389.99656) (xy 117.172642 -390.040137)
			(xy 117.188226 -390.086818) (xy 117.196121 -390.135395) (xy 117.196616 -390.160002) (xy 117.7854 -390.160002)
			(xy 117.78936 -390.110948) (xy 117.801137 -390.063164) (xy 117.820428 -390.017888) (xy 117.846731 -389.976292)
			(xy 117.879366 -389.939455) (xy 117.917487 -389.90833) (xy 117.960108 -389.883723) (xy 118.006124 -389.866271)
			(xy 118.054343 -389.856427) (xy 118.103518 -389.854446) (xy 118.152373 -389.860378) (xy 118.199644 -389.87407)
			(xy 118.244106 -389.895168) (xy 118.284609 -389.923124) (xy 118.320102 -389.957216) (xy 118.349667 -389.99656)
			(xy 118.372538 -390.040137) (xy 118.388122 -390.086818) (xy 118.396017 -390.135395) (xy 118.396512 -390.160002)
			(xy 118.98555 -390.160002) (xy 118.98951 -390.110948) (xy 119.001287 -390.063164) (xy 119.020578 -390.017888)
			(xy 119.046881 -389.976292) (xy 119.079516 -389.939455) (xy 119.117637 -389.90833) (xy 119.160258 -389.883723)
			(xy 119.206274 -389.866271) (xy 119.254493 -389.856427) (xy 119.303668 -389.854446) (xy 119.352523 -389.860378)
			(xy 119.399794 -389.87407) (xy 119.444256 -389.895168) (xy 119.484759 -389.923124) (xy 119.520252 -389.957216)
			(xy 119.549817 -389.99656) (xy 119.572688 -390.040137) (xy 119.588272 -390.086818) (xy 119.596167 -390.135395)
			(xy 119.596662 -390.160002) (xy 120.185446 -390.160002) (xy 120.189406 -390.110948) (xy 120.201183 -390.063164)
			(xy 120.220474 -390.017888) (xy 120.246777 -389.976292) (xy 120.279412 -389.939455) (xy 120.317533 -389.90833)
			(xy 120.360154 -389.883723) (xy 120.40617 -389.866271) (xy 120.454389 -389.856427) (xy 120.503564 -389.854446)
			(xy 120.552419 -389.860378) (xy 120.59969 -389.87407) (xy 120.644152 -389.895168) (xy 120.684655 -389.923124)
			(xy 120.720148 -389.957216) (xy 120.749713 -389.99656) (xy 120.772584 -390.040137) (xy 120.788168 -390.086818)
			(xy 120.796063 -390.135395) (xy 120.796558 -390.160002) (xy 121.385342 -390.160002) (xy 121.389302 -390.110948)
			(xy 121.401079 -390.063164) (xy 121.42037 -390.017888) (xy 121.446673 -389.976292) (xy 121.479308 -389.939455)
			(xy 121.517429 -389.90833) (xy 121.56005 -389.883723) (xy 121.606066 -389.866271) (xy 121.654285 -389.856427)
			(xy 121.70346 -389.854446) (xy 121.752315 -389.860378) (xy 121.799586 -389.87407) (xy 121.844048 -389.895168)
			(xy 121.884551 -389.923124) (xy 121.920044 -389.957216) (xy 121.949609 -389.99656) (xy 121.97248 -390.040137)
			(xy 121.988064 -390.086818) (xy 121.995959 -390.135395) (xy 121.996454 -390.160002) (xy 122.585492 -390.160002)
			(xy 122.589452 -390.110948) (xy 122.601229 -390.063164) (xy 122.62052 -390.017888) (xy 122.646823 -389.976292)
			(xy 122.679458 -389.939455) (xy 122.717579 -389.90833) (xy 122.7602 -389.883723) (xy 122.806216 -389.866271)
			(xy 122.854435 -389.856427) (xy 122.90361 -389.854446) (xy 122.952465 -389.860378) (xy 122.999736 -389.87407)
			(xy 123.044198 -389.895168) (xy 123.084701 -389.923124) (xy 123.120194 -389.957216) (xy 123.149759 -389.99656)
			(xy 123.17263 -390.040137) (xy 123.188214 -390.086818) (xy 123.196109 -390.135395) (xy 123.196604 -390.160002)
			(xy 123.785388 -390.160002) (xy 123.789348 -390.110948) (xy 123.801125 -390.063164) (xy 123.820416 -390.017888)
			(xy 123.846719 -389.976292) (xy 123.879354 -389.939455) (xy 123.917475 -389.90833) (xy 123.960096 -389.883723)
			(xy 124.006112 -389.866271) (xy 124.054331 -389.856427) (xy 124.103506 -389.854446) (xy 124.152361 -389.860378)
			(xy 124.199632 -389.87407) (xy 124.244094 -389.895168) (xy 124.284597 -389.923124) (xy 124.32009 -389.957216)
			(xy 124.349655 -389.99656) (xy 124.372526 -390.040137) (xy 124.38811 -390.086818) (xy 124.396005 -390.135395)
			(xy 124.3965 -390.160002) (xy 124.985538 -390.160002) (xy 124.989498 -390.110948) (xy 125.001275 -390.063164)
			(xy 125.020566 -390.017888) (xy 125.046869 -389.976292) (xy 125.079504 -389.939455) (xy 125.117625 -389.90833)
			(xy 125.160246 -389.883723) (xy 125.206262 -389.866271) (xy 125.254481 -389.856427) (xy 125.303656 -389.854446)
			(xy 125.352511 -389.860378) (xy 125.399782 -389.87407) (xy 125.444244 -389.895168) (xy 125.484747 -389.923124)
			(xy 125.52024 -389.957216) (xy 125.549805 -389.99656) (xy 125.572676 -390.040137) (xy 125.58826 -390.086818)
			(xy 125.596155 -390.135395) (xy 125.59665 -390.160002) (xy 126.185434 -390.160002) (xy 126.189394 -390.110948)
			(xy 126.201171 -390.063164) (xy 126.220462 -390.017888) (xy 126.246765 -389.976292) (xy 126.2794 -389.939455)
			(xy 126.317521 -389.90833) (xy 126.360142 -389.883723) (xy 126.406158 -389.866271) (xy 126.454377 -389.856427)
			(xy 126.503552 -389.854446) (xy 126.552407 -389.860378) (xy 126.599678 -389.87407) (xy 126.64414 -389.895168)
			(xy 126.684643 -389.923124) (xy 126.720136 -389.957216) (xy 126.749701 -389.99656) (xy 126.772572 -390.040137)
			(xy 126.788156 -390.086818) (xy 126.796051 -390.135395) (xy 126.796546 -390.160002) (xy 127.38533 -390.160002)
			(xy 127.38929 -390.110948) (xy 127.401067 -390.063164) (xy 127.420358 -390.017888) (xy 127.446661 -389.976292)
			(xy 127.479296 -389.939455) (xy 127.517417 -389.90833) (xy 127.560038 -389.883723) (xy 127.606054 -389.866271)
			(xy 127.654273 -389.856427) (xy 127.703448 -389.854446) (xy 127.752303 -389.860378) (xy 127.799574 -389.87407)
			(xy 127.844036 -389.895168) (xy 127.884539 -389.923124) (xy 127.920032 -389.957216) (xy 127.949597 -389.99656)
			(xy 127.972468 -390.040137) (xy 127.988052 -390.086818) (xy 127.995947 -390.135395) (xy 127.996442 -390.160002)
			(xy 128.58548 -390.160002) (xy 128.58944 -390.110948) (xy 128.601217 -390.063164) (xy 128.620508 -390.017888)
			(xy 128.646811 -389.976292) (xy 128.679446 -389.939455) (xy 128.717567 -389.90833) (xy 128.760188 -389.883723)
			(xy 128.806204 -389.866271) (xy 128.854423 -389.856427) (xy 128.903598 -389.854446) (xy 128.952453 -389.860378)
			(xy 128.999724 -389.87407) (xy 129.044186 -389.895168) (xy 129.084689 -389.923124) (xy 129.120182 -389.957216)
			(xy 129.149747 -389.99656) (xy 129.172618 -390.040137) (xy 129.188202 -390.086818) (xy 129.196097 -390.135395)
			(xy 129.196592 -390.160002) (xy 129.785376 -390.160002) (xy 129.789336 -390.110948) (xy 129.801113 -390.063164)
			(xy 129.820404 -390.017888) (xy 129.846707 -389.976292) (xy 129.879342 -389.939455) (xy 129.917463 -389.90833)
			(xy 129.960084 -389.883723) (xy 130.0061 -389.866271) (xy 130.054319 -389.856427) (xy 130.103494 -389.854446)
			(xy 130.152349 -389.860378) (xy 130.19962 -389.87407) (xy 130.244082 -389.895168) (xy 130.284585 -389.923124)
			(xy 130.320078 -389.957216) (xy 130.349643 -389.99656) (xy 130.372514 -390.040137) (xy 130.388098 -390.086818)
			(xy 130.395993 -390.135395) (xy 130.396488 -390.160002) (xy 130.985526 -390.160002) (xy 130.989486 -390.110948)
			(xy 131.001263 -390.063164) (xy 131.020554 -390.017888) (xy 131.046857 -389.976292) (xy 131.079492 -389.939455)
			(xy 131.117613 -389.90833) (xy 131.160234 -389.883723) (xy 131.20625 -389.866271) (xy 131.254469 -389.856427)
			(xy 131.303644 -389.854446) (xy 131.352499 -389.860378) (xy 131.39977 -389.87407) (xy 131.444232 -389.895168)
			(xy 131.484735 -389.923124) (xy 131.520228 -389.957216) (xy 131.549793 -389.99656) (xy 131.572664 -390.040137)
			(xy 131.588248 -390.086818) (xy 131.596143 -390.135395) (xy 131.596638 -390.160002) (xy 132.185422 -390.160002)
			(xy 132.189382 -390.110948) (xy 132.201159 -390.063164) (xy 132.22045 -390.017888) (xy 132.246753 -389.976292)
			(xy 132.279388 -389.939455) (xy 132.317509 -389.90833) (xy 132.36013 -389.883723) (xy 132.406146 -389.866271)
			(xy 132.454365 -389.856427) (xy 132.50354 -389.854446) (xy 132.552395 -389.860378) (xy 132.599666 -389.87407)
			(xy 132.644128 -389.895168) (xy 132.684631 -389.923124) (xy 132.720124 -389.957216) (xy 132.749689 -389.99656)
			(xy 132.77256 -390.040137) (xy 132.788144 -390.086818) (xy 132.796039 -390.135395) (xy 132.796534 -390.160002)
			(xy 132.796039 -390.184609) (xy 132.788144 -390.233186) (xy 132.77256 -390.279867) (xy 132.749689 -390.323444)
			(xy 132.720124 -390.362788) (xy 132.684631 -390.39688) (xy 132.644128 -390.424836) (xy 132.599666 -390.445934)
			(xy 132.552395 -390.459626) (xy 132.50354 -390.465558) (xy 132.454365 -390.463577) (xy 132.406146 -390.453733)
			(xy 132.36013 -390.436281) (xy 132.317509 -390.411674) (xy 132.279388 -390.380549) (xy 132.246753 -390.343712)
			(xy 132.22045 -390.302116) (xy 132.201159 -390.25684) (xy 132.189382 -390.209056) (xy 132.185422 -390.160002)
			(xy 131.596638 -390.160002) (xy 131.596143 -390.184609) (xy 131.588248 -390.233186) (xy 131.572664 -390.279867)
			(xy 131.549793 -390.323444) (xy 131.520228 -390.362788) (xy 131.484735 -390.39688) (xy 131.444232 -390.424836)
			(xy 131.39977 -390.445934) (xy 131.352499 -390.459626) (xy 131.303644 -390.465558) (xy 131.254469 -390.463577)
			(xy 131.20625 -390.453733) (xy 131.160234 -390.436281) (xy 131.117613 -390.411674) (xy 131.079492 -390.380549)
			(xy 131.046857 -390.343712) (xy 131.020554 -390.302116) (xy 131.001263 -390.25684) (xy 130.989486 -390.209056)
			(xy 130.985526 -390.160002) (xy 130.396488 -390.160002) (xy 130.395993 -390.184609) (xy 130.388098 -390.233186)
			(xy 130.372514 -390.279867) (xy 130.349643 -390.323444) (xy 130.320078 -390.362788) (xy 130.284585 -390.39688)
			(xy 130.244082 -390.424836) (xy 130.19962 -390.445934) (xy 130.152349 -390.459626) (xy 130.103494 -390.465558)
			(xy 130.054319 -390.463577) (xy 130.0061 -390.453733) (xy 129.960084 -390.436281) (xy 129.917463 -390.411674)
			(xy 129.879342 -390.380549) (xy 129.846707 -390.343712) (xy 129.820404 -390.302116) (xy 129.801113 -390.25684)
			(xy 129.789336 -390.209056) (xy 129.785376 -390.160002) (xy 129.196592 -390.160002) (xy 129.196097 -390.184609)
			(xy 129.188202 -390.233186) (xy 129.172618 -390.279867) (xy 129.149747 -390.323444) (xy 129.120182 -390.362788)
			(xy 129.084689 -390.39688) (xy 129.044186 -390.424836) (xy 128.999724 -390.445934) (xy 128.952453 -390.459626)
			(xy 128.903598 -390.465558) (xy 128.854423 -390.463577) (xy 128.806204 -390.453733) (xy 128.760188 -390.436281)
			(xy 128.717567 -390.411674) (xy 128.679446 -390.380549) (xy 128.646811 -390.343712) (xy 128.620508 -390.302116)
			(xy 128.601217 -390.25684) (xy 128.58944 -390.209056) (xy 128.58548 -390.160002) (xy 127.996442 -390.160002)
			(xy 127.995947 -390.184609) (xy 127.988052 -390.233186) (xy 127.972468 -390.279867) (xy 127.949597 -390.323444)
			(xy 127.920032 -390.362788) (xy 127.884539 -390.39688) (xy 127.844036 -390.424836) (xy 127.799574 -390.445934)
			(xy 127.752303 -390.459626) (xy 127.703448 -390.465558) (xy 127.654273 -390.463577) (xy 127.606054 -390.453733)
			(xy 127.560038 -390.436281) (xy 127.517417 -390.411674) (xy 127.479296 -390.380549) (xy 127.446661 -390.343712)
			(xy 127.420358 -390.302116) (xy 127.401067 -390.25684) (xy 127.38929 -390.209056) (xy 127.38533 -390.160002)
			(xy 126.796546 -390.160002) (xy 126.796051 -390.184609) (xy 126.788156 -390.233186) (xy 126.772572 -390.279867)
			(xy 126.749701 -390.323444) (xy 126.720136 -390.362788) (xy 126.684643 -390.39688) (xy 126.64414 -390.424836)
			(xy 126.599678 -390.445934) (xy 126.552407 -390.459626) (xy 126.503552 -390.465558) (xy 126.454377 -390.463577)
			(xy 126.406158 -390.453733) (xy 126.360142 -390.436281) (xy 126.317521 -390.411674) (xy 126.2794 -390.380549)
			(xy 126.246765 -390.343712) (xy 126.220462 -390.302116) (xy 126.201171 -390.25684) (xy 126.189394 -390.209056)
			(xy 126.185434 -390.160002) (xy 125.59665 -390.160002) (xy 125.596155 -390.184609) (xy 125.58826 -390.233186)
			(xy 125.572676 -390.279867) (xy 125.549805 -390.323444) (xy 125.52024 -390.362788) (xy 125.484747 -390.39688)
			(xy 125.444244 -390.424836) (xy 125.399782 -390.445934) (xy 125.352511 -390.459626) (xy 125.303656 -390.465558)
			(xy 125.254481 -390.463577) (xy 125.206262 -390.453733) (xy 125.160246 -390.436281) (xy 125.117625 -390.411674)
			(xy 125.079504 -390.380549) (xy 125.046869 -390.343712) (xy 125.020566 -390.302116) (xy 125.001275 -390.25684)
			(xy 124.989498 -390.209056) (xy 124.985538 -390.160002) (xy 124.3965 -390.160002) (xy 124.396005 -390.184609)
			(xy 124.38811 -390.233186) (xy 124.372526 -390.279867) (xy 124.349655 -390.323444) (xy 124.32009 -390.362788)
			(xy 124.284597 -390.39688) (xy 124.244094 -390.424836) (xy 124.199632 -390.445934) (xy 124.152361 -390.459626)
			(xy 124.103506 -390.465558) (xy 124.054331 -390.463577) (xy 124.006112 -390.453733) (xy 123.960096 -390.436281)
			(xy 123.917475 -390.411674) (xy 123.879354 -390.380549) (xy 123.846719 -390.343712) (xy 123.820416 -390.302116)
			(xy 123.801125 -390.25684) (xy 123.789348 -390.209056) (xy 123.785388 -390.160002) (xy 123.196604 -390.160002)
			(xy 123.196109 -390.184609) (xy 123.188214 -390.233186) (xy 123.17263 -390.279867) (xy 123.149759 -390.323444)
			(xy 123.120194 -390.362788) (xy 123.084701 -390.39688) (xy 123.044198 -390.424836) (xy 122.999736 -390.445934)
			(xy 122.952465 -390.459626) (xy 122.90361 -390.465558) (xy 122.854435 -390.463577) (xy 122.806216 -390.453733)
			(xy 122.7602 -390.436281) (xy 122.717579 -390.411674) (xy 122.679458 -390.380549) (xy 122.646823 -390.343712)
			(xy 122.62052 -390.302116) (xy 122.601229 -390.25684) (xy 122.589452 -390.209056) (xy 122.585492 -390.160002)
			(xy 121.996454 -390.160002) (xy 121.995959 -390.184609) (xy 121.988064 -390.233186) (xy 121.97248 -390.279867)
			(xy 121.949609 -390.323444) (xy 121.920044 -390.362788) (xy 121.884551 -390.39688) (xy 121.844048 -390.424836)
			(xy 121.799586 -390.445934) (xy 121.752315 -390.459626) (xy 121.70346 -390.465558) (xy 121.654285 -390.463577)
			(xy 121.606066 -390.453733) (xy 121.56005 -390.436281) (xy 121.517429 -390.411674) (xy 121.479308 -390.380549)
			(xy 121.446673 -390.343712) (xy 121.42037 -390.302116) (xy 121.401079 -390.25684) (xy 121.389302 -390.209056)
			(xy 121.385342 -390.160002) (xy 120.796558 -390.160002) (xy 120.796063 -390.184609) (xy 120.788168 -390.233186)
			(xy 120.772584 -390.279867) (xy 120.749713 -390.323444) (xy 120.720148 -390.362788) (xy 120.684655 -390.39688)
			(xy 120.644152 -390.424836) (xy 120.59969 -390.445934) (xy 120.552419 -390.459626) (xy 120.503564 -390.465558)
			(xy 120.454389 -390.463577) (xy 120.40617 -390.453733) (xy 120.360154 -390.436281) (xy 120.317533 -390.411674)
			(xy 120.279412 -390.380549) (xy 120.246777 -390.343712) (xy 120.220474 -390.302116) (xy 120.201183 -390.25684)
			(xy 120.189406 -390.209056) (xy 120.185446 -390.160002) (xy 119.596662 -390.160002) (xy 119.596167 -390.184609)
			(xy 119.588272 -390.233186) (xy 119.572688 -390.279867) (xy 119.549817 -390.323444) (xy 119.520252 -390.362788)
			(xy 119.484759 -390.39688) (xy 119.444256 -390.424836) (xy 119.399794 -390.445934) (xy 119.352523 -390.459626)
			(xy 119.303668 -390.465558) (xy 119.254493 -390.463577) (xy 119.206274 -390.453733) (xy 119.160258 -390.436281)
			(xy 119.117637 -390.411674) (xy 119.079516 -390.380549) (xy 119.046881 -390.343712) (xy 119.020578 -390.302116)
			(xy 119.001287 -390.25684) (xy 118.98951 -390.209056) (xy 118.98555 -390.160002) (xy 118.396512 -390.160002)
			(xy 118.396017 -390.184609) (xy 118.388122 -390.233186) (xy 118.372538 -390.279867) (xy 118.349667 -390.323444)
			(xy 118.320102 -390.362788) (xy 118.284609 -390.39688) (xy 118.244106 -390.424836) (xy 118.199644 -390.445934)
			(xy 118.152373 -390.459626) (xy 118.103518 -390.465558) (xy 118.054343 -390.463577) (xy 118.006124 -390.453733)
			(xy 117.960108 -390.436281) (xy 117.917487 -390.411674) (xy 117.879366 -390.380549) (xy 117.846731 -390.343712)
			(xy 117.820428 -390.302116) (xy 117.801137 -390.25684) (xy 117.78936 -390.209056) (xy 117.7854 -390.160002)
			(xy 117.196616 -390.160002) (xy 117.196121 -390.184609) (xy 117.188226 -390.233186) (xy 117.172642 -390.279867)
			(xy 117.149771 -390.323444) (xy 117.120206 -390.362788) (xy 117.084713 -390.39688) (xy 117.04421 -390.424836)
			(xy 116.999748 -390.445934) (xy 116.952477 -390.459626) (xy 116.903622 -390.465558) (xy 116.854447 -390.463577)
			(xy 116.806228 -390.453733) (xy 116.760212 -390.436281) (xy 116.717591 -390.411674) (xy 116.67947 -390.380549)
			(xy 116.646835 -390.343712) (xy 116.620532 -390.302116) (xy 116.601241 -390.25684) (xy 116.589464 -390.209056)
			(xy 116.585504 -390.160002) (xy 115.996466 -390.160002) (xy 115.995971 -390.184609) (xy 115.988076 -390.233186)
			(xy 115.972492 -390.279867) (xy 115.949621 -390.323444) (xy 115.920056 -390.362788) (xy 115.884563 -390.39688)
			(xy 115.84406 -390.424836) (xy 115.799598 -390.445934) (xy 115.752327 -390.459626) (xy 115.703472 -390.465558)
			(xy 115.654297 -390.463577) (xy 115.606078 -390.453733) (xy 115.560062 -390.436281) (xy 115.517441 -390.411674)
			(xy 115.47932 -390.380549) (xy 115.446685 -390.343712) (xy 115.420382 -390.302116) (xy 115.401091 -390.25684)
			(xy 115.389314 -390.209056) (xy 115.385354 -390.160002) (xy 114.796316 -390.160002) (xy 114.795821 -390.184609)
			(xy 114.787926 -390.233186) (xy 114.772342 -390.279867) (xy 114.749471 -390.323444) (xy 114.719906 -390.362788)
			(xy 114.684413 -390.39688) (xy 114.64391 -390.424836) (xy 114.599448 -390.445934) (xy 114.552177 -390.459626)
			(xy 114.503322 -390.465558) (xy 114.454147 -390.463577) (xy 114.405928 -390.453733) (xy 114.359912 -390.436281)
			(xy 114.317291 -390.411674) (xy 114.27917 -390.380549) (xy 114.246535 -390.343712) (xy 114.220232 -390.302116)
			(xy 114.200941 -390.25684) (xy 114.189164 -390.209056) (xy 114.185204 -390.160002) (xy 112.510387 -390.160002)
			(xy 112.504274 -390.181186) (xy 112.485267 -390.223591) (xy 112.460509 -390.262916) (xy 112.4458 -390.280906)
			(xy 112.439704 -390.288018) (xy 112.433608 -390.304528) (xy 112.433608 -390.388856) (xy 112.439704 -390.405366)
			(xy 112.4458 -390.412478) (xy 112.460513 -390.430464) (xy 112.485258 -390.469794) (xy 112.504257 -390.512201)
			(xy 112.517135 -390.556848) (xy 112.523638 -390.602858) (xy 112.524032 -390.626092) (xy 112.523616 -390.650184)
			(xy 112.516637 -390.697862) (xy 112.502827 -390.744025) (xy 112.493044 -390.766046) (xy 112.48771 -390.777476)
			(xy 112.48898 -390.802622) (xy 112.545114 -390.896602) (xy 112.566704 -390.909556) (xy 112.579404 -390.910318)
			(xy 112.604403 -390.912126) (xy 112.653449 -390.922464) (xy 112.700373 -390.940083) (xy 112.744101 -390.964581)
			(xy 112.783633 -390.995396) (xy 112.818063 -391.031822) (xy 112.846603 -391.073026) (xy 112.8686 -391.118065)
			(xy 112.883549 -391.165907) (xy 112.891108 -391.215456) (xy 112.89157 -391.240518) (xy 112.89106 -391.266505)
			(xy 112.88293 -391.31784) (xy 112.866869 -391.36727) (xy 112.843273 -391.41358) (xy 112.812723 -391.455628)
			(xy 112.775972 -391.492379) (xy 112.733924 -391.522929) (xy 112.687614 -391.546525) (xy 112.638184 -391.562586)
			(xy 112.586849 -391.570716) (xy 112.534875 -391.570716) (xy 112.48354 -391.562586) (xy 112.43411 -391.546525)
			(xy 112.3878 -391.522929) (xy 112.345752 -391.492379) (xy 112.309001 -391.455628) (xy 112.278451 -391.41358)
			(xy 112.254855 -391.36727) (xy 112.238794 -391.31784) (xy 112.230664 -391.266505) (xy 112.230154 -391.240518)
			(xy 112.230575 -391.216426) (xy 112.237552 -391.168749) (xy 112.25136 -391.122585) (xy 112.261142 -391.100564)
			(xy 112.266476 -391.089134) (xy 112.265206 -391.063988) (xy 112.209072 -390.970008) (xy 112.187482 -390.957054)
			(xy 112.174782 -390.956292) (xy 112.14979 -390.9544) (xy 112.100747 -390.944075) (xy 112.053825 -390.926467)
			(xy 112.010096 -390.901981) (xy 111.970563 -390.871176) (xy 111.936132 -390.834758) (xy 111.90759 -390.793562)
			(xy 111.885591 -390.74853) (xy 111.87064 -390.700695) (xy 111.863078 -390.651151) (xy 111.862616 -390.626092)
			(xy 108.918502 -390.626092) (xy 108.918502 -390.658096) (xy 108.924852 -390.675114) (xy 108.930948 -390.682226)
			(xy 108.948558 -390.703182) (xy 108.978276 -390.749147) (xy 109.001118 -390.798889) (xy 109.016616 -390.851384)
			(xy 109.024451 -390.905556) (xy 109.024928 -390.932924) (xy 109.024345 -390.962534) (xy 109.015184 -391.021042)
			(xy 108.997103 -391.077435) (xy 108.970533 -391.130361) (xy 108.936112 -391.178551) (xy 108.894665 -391.22085)
			(xy 108.871258 -391.238994) (xy 108.862812 -391.245906) (xy 108.852277 -391.264993) (xy 108.850938 -391.275824)
			(xy 108.846874 -391.331958) (xy 108.85805 -391.342626) (xy 108.865404 -391.349136) (xy 108.88355 -391.356595)
			(xy 108.893356 -391.357104) (xy 108.92536 -391.357104) (xy 108.935177 -391.356638) (xy 108.953341 -391.349179)
			(xy 108.960666 -391.342626) (xy 108.982177 -391.322465) (xy 109.030233 -391.288319) (xy 109.08297 -391.261971)
			(xy 109.139132 -391.244047) (xy 109.197382 -391.234974) (xy 109.226858 -391.234422) (xy 109.254228 -391.234907)
			(xy 109.308406 -391.24272) (xy 109.360909 -391.258204) (xy 109.410656 -391.281042) (xy 109.456624 -391.310762)
			(xy 109.477556 -391.328402) (xy 109.484668 -391.334498) (xy 109.501686 -391.340848) (xy 109.58703 -391.340848)
			(xy 109.604048 -391.334498) (xy 109.61116 -391.328402) (xy 109.632093 -391.310761) (xy 109.678061 -391.281037)
			(xy 109.727807 -391.258191) (xy 109.780309 -391.242695) (xy 109.834487 -391.234866) (xy 109.889229 -391.234866)
			(xy 109.943407 -391.242695) (xy 109.995909 -391.258191) (xy 110.045655 -391.281037) (xy 110.091623 -391.310761)
			(xy 110.112556 -391.328402) (xy 110.119668 -391.334498) (xy 110.136686 -391.340848) (xy 110.22203 -391.340848)
			(xy 110.239048 -391.334498) (xy 110.24616 -391.328402) (xy 110.267097 -391.310769) (xy 110.313068 -391.281056)
			(xy 110.362814 -391.258219) (xy 110.415314 -391.242726) (xy 110.469489 -391.234897) (xy 110.496858 -391.234422)
			(xy 110.524111 -391.234894) (xy 110.578063 -391.242646) (xy 110.630363 -391.257999) (xy 110.679945 -391.280639)
			(xy 110.7258 -391.310105) (xy 110.766994 -391.345798) (xy 110.802688 -391.386991) (xy 110.832156 -391.432845)
			(xy 110.854797 -391.482426) (xy 110.870151 -391.534725) (xy 110.877905 -391.588677) (xy 110.878366 -391.61593)
			(xy 110.877792 -391.645406) (xy 110.868732 -391.703658) (xy 110.850818 -391.759823) (xy 110.824476 -391.812563)
			(xy 110.790334 -391.860622) (xy 110.770162 -391.882122) (xy 110.76362 -391.889451) (xy 110.75618 -391.907616)
			(xy 110.755684 -391.917428) (xy 110.755684 -391.949432) (xy 110.756167 -391.959247) (xy 110.763615 -391.977411)
			(xy 110.770162 -391.984738) (xy 110.778036 -391.99312) (xy 110.785148 -392.00074) (xy 110.803436 -392.009376)
			(xy 110.8964 -392.012678) (xy 110.915196 -392.005566) (xy 110.922816 -391.998454) (xy 110.9442 -391.978982)
			(xy 110.991719 -391.946021) (xy 111.04367 -391.920613) (xy 111.098861 -391.90334) (xy 111.156028 -391.894599)
			(xy 111.184944 -391.89406) (xy 111.212195 -391.894537) (xy 111.266141 -391.902298) (xy 111.318434 -391.917658)
			(xy 111.368009 -391.940301) (xy 111.413858 -391.969769) (xy 111.455047 -392.005462) (xy 111.490738 -392.046652)
			(xy 111.520204 -392.092501) (xy 111.542847 -392.142077) (xy 111.558204 -392.19437) (xy 111.565964 -392.248317)
			(xy 111.566452 -392.275568) (xy 111.565945 -392.304082) (xy 111.561342 -392.33475) (xy 113.264188 -392.33475)
			(xy 113.264577 -392.311516) (xy 113.271077 -392.265505) (xy 113.283955 -392.220857) (xy 113.302958 -392.178452)
			(xy 113.327712 -392.139127) (xy 113.34242 -392.121136) (xy 113.348516 -392.114024) (xy 113.354612 -392.097514)
			(xy 113.354612 -392.013186) (xy 113.348516 -391.996676) (xy 113.34242 -391.989564) (xy 113.32773 -391.97156)
			(xy 113.30298 -391.932235) (xy 113.283977 -391.889833) (xy 113.271094 -391.84519) (xy 113.264585 -391.799183)
			(xy 113.264188 -391.77595) (xy 113.264698 -391.749963) (xy 113.272828 -391.698628) (xy 113.288889 -391.649198)
			(xy 113.312485 -391.602888) (xy 113.343035 -391.56084) (xy 113.379786 -391.524089) (xy 113.421834 -391.493539)
			(xy 113.468144 -391.469943) (xy 113.517574 -391.453882) (xy 113.568909 -391.445752) (xy 113.620883 -391.445752)
			(xy 113.672218 -391.453882) (xy 113.721648 -391.469943) (xy 113.767958 -391.493539) (xy 113.810006 -391.524089)
			(xy 113.846757 -391.56084) (xy 113.877307 -391.602888) (xy 113.900903 -391.649198) (xy 113.916964 -391.698628)
			(xy 113.925094 -391.749963) (xy 113.925604 -391.77595) (xy 113.925217 -391.799184) (xy 113.918717 -391.845196)
			(xy 113.905838 -391.889843) (xy 113.886834 -391.932248) (xy 113.86208 -391.971574) (xy 113.847372 -391.989564)
			(xy 113.841276 -391.996676) (xy 113.83518 -392.013186) (xy 113.83518 -392.097514) (xy 113.841276 -392.114024)
			(xy 113.847372 -392.121136) (xy 113.862061 -392.139141) (xy 113.886811 -392.178465) (xy 113.905815 -392.220867)
			(xy 113.918698 -392.26551) (xy 113.925207 -392.311517) (xy 113.925604 -392.33475) (xy 113.925094 -392.360737)
			(xy 113.916964 -392.412072) (xy 113.900903 -392.461502) (xy 113.877307 -392.507812) (xy 113.846757 -392.54986)
			(xy 113.810006 -392.586611) (xy 113.767958 -392.617161) (xy 113.721648 -392.640757) (xy 113.672218 -392.656818)
			(xy 113.620883 -392.664948) (xy 113.568909 -392.664948) (xy 113.517574 -392.656818) (xy 113.468144 -392.640757)
			(xy 113.421834 -392.617161) (xy 113.379786 -392.586611) (xy 113.343035 -392.54986) (xy 113.312485 -392.507812)
			(xy 113.288889 -392.461502) (xy 113.272828 -392.412072) (xy 113.264698 -392.360737) (xy 113.264188 -392.33475)
			(xy 111.561342 -392.33475) (xy 111.557481 -392.360478) (xy 111.540723 -392.414988) (xy 111.52886 -392.440922)
			(xy 111.524288 -392.45032) (xy 111.523526 -392.471148) (xy 111.557562 -392.560048) (xy 111.572294 -392.575034)
			(xy 111.581946 -392.578844) (xy 111.607905 -392.589973) (xy 111.656485 -392.618781) (xy 111.700289 -392.654433)
			(xy 111.73836 -392.696153) (xy 111.769867 -392.743027) (xy 111.794121 -392.794033) (xy 111.810593 -392.848057)
			(xy 111.818923 -392.903918) (xy 111.819436 -392.932158) (xy 111.81895 -392.959409) (xy 111.811194 -393.013357)
			(xy 111.795839 -393.065652) (xy 111.773197 -393.115229) (xy 111.743731 -393.161079) (xy 111.70804 -393.20227)
			(xy 111.666849 -393.237961) (xy 111.620999 -393.267427) (xy 111.571422 -393.290069) (xy 111.519127 -393.305424)
			(xy 111.465179 -393.31318) (xy 111.410677 -393.31318) (xy 111.356729 -393.305424) (xy 111.304434 -393.290069)
			(xy 111.254857 -393.267427) (xy 111.209007 -393.237961) (xy 111.167816 -393.20227) (xy 111.132125 -393.161079)
			(xy 111.102659 -393.115229) (xy 111.080017 -393.065652) (xy 111.064662 -393.013357) (xy 111.056906 -392.959409)
			(xy 111.05642 -392.932158) (xy 111.056939 -392.903645) (xy 111.065398 -392.847249) (xy 111.082151 -392.792739)
			(xy 111.094012 -392.766804) (xy 111.098584 -392.757406) (xy 111.099346 -392.736578) (xy 111.06531 -392.647678)
			(xy 111.050578 -392.632692) (xy 111.040926 -392.628882) (xy 111.018523 -392.619363) (xy 110.976156 -392.595393)
			(xy 110.93718 -392.566232) (xy 110.902228 -392.532352) (xy 110.886748 -392.513566) (xy 110.879483 -392.505309)
			(xy 110.859862 -392.495429) (xy 110.848902 -392.494516) (xy 110.79226 -392.492484) (xy 110.784386 -392.501628)
			(xy 110.77829 -392.50874) (xy 110.77194 -392.525758) (xy 110.77194 -392.611102) (xy 110.77829 -392.62812)
			(xy 110.784386 -392.635232) (xy 110.802056 -392.656141) (xy 110.831778 -392.702113) (xy 110.854621 -392.751864)
			(xy 110.870114 -392.804369) (xy 110.87794 -392.858551) (xy 110.877937 -392.913294) (xy 110.870105 -392.967475)
			(xy 110.854605 -393.019979) (xy 110.831756 -393.069726) (xy 110.802028 -393.115695) (xy 110.784386 -393.136628)
			(xy 110.77829 -393.14374) (xy 110.77194 -393.160758) (xy 110.77194 -393.246102) (xy 110.77829 -393.26312)
			(xy 110.784386 -393.270232) (xy 110.802004 -393.291181) (xy 110.83172 -393.337149) (xy 110.85456 -393.386892)
			(xy 110.870056 -393.439389) (xy 110.877889 -393.493562) (xy 110.878366 -393.52093) (xy 110.877973 -393.548186)
			(xy 110.870211 -393.602141) (xy 110.854849 -393.654443) (xy 110.8322 -393.704026) (xy 110.802725 -393.749881)
			(xy 110.767024 -393.791075) (xy 110.725823 -393.826768) (xy 110.679963 -393.856234) (xy 110.630375 -393.878874)
			(xy 110.578071 -393.894226) (xy 110.524114 -393.901978) (xy 110.496858 -393.902438) (xy 114.530632 -393.902438)
			(xy 114.531101 -393.874162) (xy 114.539388 -393.81822) (xy 114.555788 -393.764098) (xy 114.579947 -393.712965)
			(xy 114.611342 -393.665928) (xy 114.629946 -393.644628) (xy 114.635872 -393.637454) (xy 114.642643 -393.620137)
			(xy 114.643154 -393.610846) (xy 114.643408 -393.579604) (xy 114.642971 -393.57027) (xy 114.636346 -393.552818)
			(xy 114.630454 -393.545568) (xy 114.612492 -393.524554) (xy 114.582211 -393.478303) (xy 114.558932 -393.428162)
			(xy 114.543143 -393.375183) (xy 114.535177 -393.320479) (xy 114.534696 -393.292838) (xy 114.534696 -392.429238)
			(xy 114.535158 -392.402882) (xy 114.542422 -392.350671) (xy 114.556803 -392.299958) (xy 114.578028 -392.251707)
			(xy 114.605692 -392.206837) (xy 114.639269 -392.166201) (xy 114.658394 -392.14806) (xy 114.665506 -392.14171)
			(xy 114.673634 -392.124946) (xy 114.682016 -392.038332) (xy 114.676936 -392.020552) (xy 114.671348 -392.012678)
			(xy 114.657197 -391.992832) (xy 114.63474 -391.949573) (xy 114.619428 -391.9033) (xy 114.611648 -391.855184)
			(xy 114.61115 -391.830814) (xy 114.611672 -391.805559) (xy 114.619985 -391.755737) (xy 114.636386 -391.707963)
			(xy 114.660427 -391.66354) (xy 114.691451 -391.62368) (xy 114.728613 -391.58947) (xy 114.770899 -391.561844)
			(xy 114.817155 -391.541554) (xy 114.86612 -391.529154) (xy 114.916458 -391.524983) (xy 114.966796 -391.529154)
			(xy 115.015761 -391.541554) (xy 115.062017 -391.561844) (xy 115.104303 -391.58947) (xy 115.141465 -391.62368)
			(xy 115.172489 -391.66354) (xy 115.19653 -391.707963) (xy 115.212931 -391.755737) (xy 115.221244 -391.805559)
			(xy 115.221766 -391.830814) (xy 115.221285 -391.855186) (xy 115.213526 -391.903309) (xy 115.198209 -391.949584)
			(xy 115.175724 -391.992833) (xy 115.161568 -392.012678) (xy 115.15598 -392.020552) (xy 115.1509 -392.038332)
			(xy 115.159282 -392.124946) (xy 115.16741 -392.14171) (xy 115.174522 -392.14806) (xy 115.193651 -392.166199)
			(xy 115.22724 -392.206828) (xy 115.254913 -392.251697) (xy 115.276141 -392.299949) (xy 115.290521 -392.350666)
			(xy 115.297777 -392.40288) (xy 115.29822 -392.429238) (xy 115.29822 -393.292838) (xy 115.297748 -393.32075)
			(xy 115.289608 -393.375976) (xy 115.273507 -393.429427) (xy 115.24979 -393.479961) (xy 115.218962 -393.5265)
			(xy 115.200684 -393.5476) (xy 115.194785 -393.554776) (xy 115.188136 -393.572102) (xy 115.18773 -393.581382)
			(xy 115.18773 -393.612624) (xy 115.188157 -393.621898) (xy 115.194811 -393.639215) (xy 115.200684 -393.646406)
			(xy 115.218971 -393.667652) (xy 115.249817 -393.714457) (xy 115.273533 -393.765247) (xy 115.289618 -393.818945)
			(xy 115.297729 -393.87441) (xy 115.29822 -393.902438) (xy 115.730528 -393.902438) (xy 115.730999 -393.874162)
			(xy 115.739285 -393.81822) (xy 115.755685 -393.764098) (xy 115.779843 -393.712965) (xy 115.811238 -393.665928)
			(xy 115.829842 -393.644628) (xy 115.835768 -393.637454) (xy 115.842539 -393.620137) (xy 115.84305 -393.610846)
			(xy 115.843304 -393.579604) (xy 115.842868 -393.57027) (xy 115.836242 -393.552818) (xy 115.83035 -393.545568)
			(xy 115.812387 -393.524554) (xy 115.782106 -393.478304) (xy 115.758827 -393.428163) (xy 115.743039 -393.375184)
			(xy 115.735073 -393.320479) (xy 115.734592 -393.292838) (xy 115.734592 -392.429238) (xy 115.735055 -392.402882)
			(xy 115.742319 -392.350672) (xy 115.7567 -392.299958) (xy 115.777925 -392.251707) (xy 115.805589 -392.206837)
			(xy 115.839165 -392.166201) (xy 115.85829 -392.14806) (xy 115.865402 -392.141456) (xy 115.873784 -392.124946)
			(xy 115.881912 -392.038078) (xy 115.877086 -392.020298) (xy 115.871244 -392.012678) (xy 115.857133 -391.992814)
			(xy 115.834713 -391.949557) (xy 115.819457 -391.903285) (xy 115.811754 -391.855175) (xy 115.8113 -391.830814)
			(xy 115.811822 -391.805559) (xy 115.820135 -391.755737) (xy 115.836536 -391.707963) (xy 115.860577 -391.66354)
			(xy 115.891601 -391.62368) (xy 115.928763 -391.58947) (xy 115.971049 -391.561844) (xy 116.017305 -391.541554)
			(xy 116.06627 -391.529154) (xy 116.116608 -391.524983) (xy 116.166946 -391.529154) (xy 116.215911 -391.541554)
			(xy 116.262167 -391.561844) (xy 116.304453 -391.58947) (xy 116.341615 -391.62368) (xy 116.372639 -391.66354)
			(xy 116.39668 -391.707963) (xy 116.413081 -391.755737) (xy 116.421394 -391.805559) (xy 116.421916 -391.830814)
			(xy 116.421459 -391.855217) (xy 116.413698 -391.903402) (xy 116.398375 -391.949741) (xy 116.375881 -391.993054)
			(xy 116.361718 -392.012932) (xy 116.35613 -392.020552) (xy 116.35105 -392.038332) (xy 116.359178 -392.1252)
			(xy 116.36756 -392.14171) (xy 116.374672 -392.148314) (xy 116.393732 -392.166476) (xy 116.427225 -392.207095)
			(xy 116.454824 -392.251928) (xy 116.476008 -392.300125) (xy 116.490374 -392.350773) (xy 116.497651 -392.402915)
			(xy 116.498116 -392.429238) (xy 116.498116 -393.292838) (xy 116.497645 -393.32075) (xy 116.489505 -393.375976)
			(xy 116.473404 -393.429427) (xy 116.449687 -393.479962) (xy 116.418859 -393.526501) (xy 116.40058 -393.5476)
			(xy 116.394681 -393.554776) (xy 116.388032 -393.572102) (xy 116.387626 -393.581382) (xy 116.387626 -393.612624)
			(xy 116.388054 -393.621897) (xy 116.394707 -393.639215) (xy 116.40058 -393.646406) (xy 116.418866 -393.667652)
			(xy 116.449712 -393.714457) (xy 116.473429 -393.765247) (xy 116.489514 -393.818945) (xy 116.497625 -393.87441)
			(xy 116.498116 -393.902438) (xy 116.497663 -393.927838) (xy 116.930424 -393.927838) (xy 116.930918 -393.900141)
			(xy 116.938861 -393.845319) (xy 116.954601 -393.792208) (xy 116.977812 -393.741912) (xy 117.008012 -393.695474)
			(xy 117.025928 -393.674346) (xy 117.032278 -393.667488) (xy 117.038628 -393.65047) (xy 117.039136 -393.56538)
			(xy 117.032786 -393.548362) (xy 117.02669 -393.54125) (xy 117.009477 -393.520375) (xy 116.980456 -393.474712)
			(xy 116.958172 -393.42541) (xy 116.943071 -393.373456) (xy 116.935455 -393.31989) (xy 116.934996 -393.292838)
			(xy 116.934996 -392.429238) (xy 116.935451 -392.402891) (xy 116.942681 -392.350697) (xy 116.957021 -392.299992)
			(xy 116.9782 -392.251743) (xy 117.005815 -392.206866) (xy 117.039341 -392.166213) (xy 117.05844 -392.14806)
			(xy 117.065552 -392.14171) (xy 117.07368 -392.124946) (xy 117.082062 -392.038332) (xy 117.076982 -392.020552)
			(xy 117.071394 -392.012678) (xy 117.057249 -391.992828) (xy 117.034789 -391.949571) (xy 117.019475 -391.903299)
			(xy 117.011695 -391.855184) (xy 117.011196 -391.830814) (xy 117.011718 -391.805559) (xy 117.020031 -391.755737)
			(xy 117.036432 -391.707963) (xy 117.060473 -391.66354) (xy 117.091497 -391.62368) (xy 117.128659 -391.58947)
			(xy 117.170945 -391.561844) (xy 117.217201 -391.541554) (xy 117.266166 -391.529154) (xy 117.316504 -391.524983)
			(xy 117.366842 -391.529154) (xy 117.415807 -391.541554) (xy 117.462063 -391.561844) (xy 117.504349 -391.58947)
			(xy 117.541511 -391.62368) (xy 117.572535 -391.66354) (xy 117.596576 -391.707963) (xy 117.612977 -391.755737)
			(xy 117.62129 -391.805559) (xy 117.621812 -391.830814) (xy 117.621341 -391.855187) (xy 117.613581 -391.903311)
			(xy 117.598262 -391.949586) (xy 117.575773 -391.992834) (xy 117.561614 -392.012678) (xy 117.556026 -392.020552)
			(xy 117.550946 -392.038332) (xy 117.559328 -392.124946) (xy 117.567456 -392.14171) (xy 117.574568 -392.14806)
			(xy 117.593686 -392.166198) (xy 117.627232 -392.206842) (xy 117.65486 -392.251718) (xy 117.676043 -392.299972)
			(xy 117.690378 -392.350685) (xy 117.69759 -392.402888) (xy 117.698012 -392.429238) (xy 117.698012 -393.292838)
			(xy 117.697547 -393.320137) (xy 117.689771 -393.374179) (xy 117.674368 -393.42656) (xy 117.651653 -393.47621)
			(xy 117.62209 -393.522113) (xy 117.60454 -393.543028) (xy 117.598444 -393.55014) (xy 117.592094 -393.567158)
			(xy 117.592094 -393.652248) (xy 117.598444 -393.669266) (xy 117.60454 -393.676378) (xy 117.622153 -393.697419)
			(xy 117.651847 -393.743561) (xy 117.674673 -393.793458) (xy 117.690167 -393.846096) (xy 117.694637 -393.877038)
			(xy 118.13032 -393.877038) (xy 118.130736 -393.850172) (xy 118.138239 -393.796967) (xy 118.153089 -393.745328)
			(xy 118.174995 -393.696265) (xy 118.203531 -393.650737) (xy 118.22049 -393.629896) (xy 118.225868 -393.622927)
			(xy 118.231971 -393.606429) (xy 118.232428 -393.597638) (xy 118.232682 -393.567158) (xy 118.232403 -393.558308)
			(xy 118.22641 -393.541656) (xy 118.220998 -393.534646) (xy 118.204759 -393.514095) (xy 118.177494 -393.469374)
			(xy 118.156591 -393.421348) (xy 118.142442 -393.370917) (xy 118.135312 -393.319027) (xy 118.134892 -393.292838)
			(xy 118.134892 -392.429238) (xy 118.135348 -392.402891) (xy 118.142578 -392.350697) (xy 118.156918 -392.299993)
			(xy 118.178097 -392.251743) (xy 118.205711 -392.206866) (xy 118.239237 -392.166213) (xy 118.258336 -392.14806)
			(xy 118.265448 -392.14171) (xy 118.273576 -392.124946) (xy 118.281958 -392.038332) (xy 118.276878 -392.020552)
			(xy 118.27129 -392.012678) (xy 118.257145 -391.992828) (xy 118.234685 -391.949571) (xy 118.219371 -391.903299)
			(xy 118.211591 -391.855184) (xy 118.211092 -391.830814) (xy 118.211614 -391.805559) (xy 118.219927 -391.755737)
			(xy 118.236328 -391.707963) (xy 118.260369 -391.66354) (xy 118.291393 -391.62368) (xy 118.328555 -391.58947)
			(xy 118.370841 -391.561844) (xy 118.417097 -391.541554) (xy 118.466062 -391.529154) (xy 118.5164 -391.524983)
			(xy 118.566738 -391.529154) (xy 118.615703 -391.541554) (xy 118.661959 -391.561844) (xy 118.704245 -391.58947)
			(xy 118.741407 -391.62368) (xy 118.772431 -391.66354) (xy 118.796472 -391.707963) (xy 118.812873 -391.755737)
			(xy 118.821186 -391.805559) (xy 118.821708 -391.830814) (xy 118.821238 -391.855187) (xy 118.813478 -391.903311)
			(xy 118.798158 -391.949586) (xy 118.775669 -391.992834) (xy 118.76151 -392.012678) (xy 118.755922 -392.020552)
			(xy 118.750842 -392.038332) (xy 118.759224 -392.124946) (xy 118.767352 -392.14171) (xy 118.774464 -392.14806)
			(xy 118.793581 -392.166199) (xy 118.827127 -392.206842) (xy 118.854755 -392.251719) (xy 118.875939 -392.299973)
			(xy 118.890273 -392.350685) (xy 118.897486 -392.402888) (xy 118.897908 -392.429238) (xy 118.897908 -393.292838)
			(xy 118.897471 -393.319295) (xy 118.890194 -393.371706) (xy 118.875745 -393.422608) (xy 118.8544 -393.471025)
			(xy 118.826568 -393.516027) (xy 118.810024 -393.536678) (xy 118.804699 -393.543735) (xy 118.798722 -393.560358)
			(xy 118.79834 -393.56919) (xy 118.79834 -393.59967) (xy 118.798727 -393.608444) (xy 118.804696 -393.624947)
			(xy 118.810024 -393.631928) (xy 118.826664 -393.652679) (xy 118.854635 -393.697922) (xy 118.876094 -393.746593)
			(xy 118.890631 -393.797759) (xy 118.897967 -393.850442) (xy 118.898416 -393.877038) (xy 118.897927 -393.904471)
			(xy 118.894567 -393.927838) (xy 119.330724 -393.927838) (xy 119.331154 -393.900148) (xy 119.339053 -393.845335)
			(xy 119.35475 -393.792227) (xy 119.377919 -393.741927) (xy 119.408078 -393.695481) (xy 119.425974 -393.674346)
			(xy 119.432324 -393.667488) (xy 119.438674 -393.65047) (xy 119.439182 -393.56538) (xy 119.432832 -393.548362)
			(xy 119.426736 -393.54125) (xy 119.40948 -393.520397) (xy 119.380401 -393.474746) (xy 119.358063 -393.425445)
			(xy 119.342916 -393.373482) (xy 119.335263 -393.319901) (xy 119.334788 -393.292838) (xy 119.334788 -392.429238)
			(xy 119.335252 -392.402882) (xy 119.342516 -392.350672) (xy 119.356897 -392.299959) (xy 119.378121 -392.251708)
			(xy 119.405785 -392.206837) (xy 119.439361 -392.166201) (xy 119.458486 -392.14806) (xy 119.465598 -392.14171)
			(xy 119.473726 -392.124946) (xy 119.482108 -392.038332) (xy 119.477028 -392.020552) (xy 119.47144 -392.012678)
			(xy 119.457288 -391.992832) (xy 119.434832 -391.949573) (xy 119.41952 -391.9033) (xy 119.41174 -391.855184)
			(xy 119.411242 -391.830814) (xy 119.411764 -391.805559) (xy 119.420077 -391.755737) (xy 119.436478 -391.707963)
			(xy 119.460519 -391.66354) (xy 119.491543 -391.62368) (xy 119.528705 -391.58947) (xy 119.570991 -391.561844)
			(xy 119.617247 -391.541554) (xy 119.666212 -391.529154) (xy 119.71655 -391.524983) (xy 119.766888 -391.529154)
			(xy 119.815853 -391.541554) (xy 119.862109 -391.561844) (xy 119.904395 -391.58947) (xy 119.941557 -391.62368)
			(xy 119.972581 -391.66354) (xy 119.996622 -391.707963) (xy 120.013023 -391.755737) (xy 120.021336 -391.805559)
			(xy 120.021858 -391.830814) (xy 120.021378 -391.855186) (xy 120.01362 -391.903309) (xy 119.998302 -391.949585)
			(xy 119.975817 -391.992833) (xy 119.96166 -392.012678) (xy 119.956072 -392.020552) (xy 119.950992 -392.038332)
			(xy 119.959374 -392.124946) (xy 119.967502 -392.14171) (xy 119.974614 -392.14806) (xy 119.993741 -392.166201)
			(xy 120.027331 -392.206829) (xy 120.055004 -392.251697) (xy 120.076233 -392.29995) (xy 120.090613 -392.350666)
			(xy 120.097869 -392.40288) (xy 120.098312 -392.429238) (xy 120.098312 -393.292838) (xy 120.097812 -393.320144)
			(xy 120.089963 -393.37419) (xy 120.074501 -393.426569) (xy 120.051742 -393.476213) (xy 120.022148 -393.522113)
			(xy 120.004586 -393.543028) (xy 119.99849 -393.55014) (xy 119.99214 -393.567158) (xy 119.99214 -393.652248)
			(xy 119.99849 -393.669266) (xy 120.004586 -393.676378) (xy 120.022193 -393.697416) (xy 120.051864 -393.743559)
			(xy 120.074653 -393.793461) (xy 120.090092 -393.846103) (xy 120.097867 -393.900408) (xy 120.098312 -393.927838)
			(xy 120.53062 -393.927838) (xy 120.531051 -393.900148) (xy 120.53895 -393.845335) (xy 120.554647 -393.792227)
			(xy 120.577815 -393.741927) (xy 120.607974 -393.695481) (xy 120.62587 -393.674346) (xy 120.63222 -393.667488)
			(xy 120.63857 -393.65047) (xy 120.639078 -393.56538) (xy 120.632728 -393.548362) (xy 120.626632 -393.54125)
			(xy 120.609391 -393.520385) (xy 120.580306 -393.474739) (xy 120.557964 -393.425441) (xy 120.542814 -393.373481)
			(xy 120.535159 -393.3199) (xy 120.534684 -393.292838) (xy 120.534684 -392.429238) (xy 120.53515 -392.402882)
			(xy 120.542413 -392.350672) (xy 120.556794 -392.299959) (xy 120.578018 -392.251708) (xy 120.605682 -392.206837)
			(xy 120.639257 -392.166201) (xy 120.658382 -392.14806) (xy 120.665494 -392.14171) (xy 120.673622 -392.124946)
			(xy 120.682004 -392.038332) (xy 120.676924 -392.020552) (xy 120.671336 -392.012678) (xy 120.657184 -391.992833)
			(xy 120.634727 -391.949573) (xy 120.619416 -391.9033) (xy 120.611636 -391.855184) (xy 120.611138 -391.830814)
			(xy 120.61166 -391.805559) (xy 120.619973 -391.755737) (xy 120.636374 -391.707963) (xy 120.660415 -391.66354)
			(xy 120.691439 -391.62368) (xy 120.728601 -391.58947) (xy 120.770887 -391.561844) (xy 120.817143 -391.541554)
			(xy 120.866108 -391.529154) (xy 120.916446 -391.524983) (xy 120.966784 -391.529154) (xy 121.015749 -391.541554)
			(xy 121.062005 -391.561844) (xy 121.104291 -391.58947) (xy 121.141453 -391.62368) (xy 121.172477 -391.66354)
			(xy 121.196518 -391.707963) (xy 121.212919 -391.755737) (xy 121.221232 -391.805559) (xy 121.221754 -391.830814)
			(xy 121.221275 -391.855186) (xy 121.213516 -391.903309) (xy 121.198199 -391.949585) (xy 121.175713 -391.992833)
			(xy 121.161556 -392.012678) (xy 121.155968 -392.020552) (xy 121.150888 -392.038332) (xy 121.15927 -392.124946)
			(xy 121.167398 -392.14171) (xy 121.17451 -392.14806) (xy 121.193636 -392.166202) (xy 121.227226 -392.20683)
			(xy 121.2549 -392.251698) (xy 121.276129 -392.29995) (xy 121.290509 -392.350666) (xy 121.297765 -392.40288)
			(xy 121.298208 -392.429238) (xy 121.298208 -393.292838) (xy 121.297663 -393.320141) (xy 121.289816 -393.374182)
			(xy 121.274359 -393.426557) (xy 121.251607 -393.476199) (xy 121.222022 -393.522098) (xy 121.204482 -393.543028)
			(xy 121.198386 -393.55014) (xy 121.192036 -393.567158) (xy 121.192036 -393.652248) (xy 121.198386 -393.669266)
			(xy 121.204482 -393.676378) (xy 121.222088 -393.697417) (xy 121.25176 -393.743559) (xy 121.274548 -393.793461)
			(xy 121.289988 -393.846103) (xy 121.294417 -393.877038) (xy 121.730516 -393.877038) (xy 121.730933 -393.850172)
			(xy 121.738435 -393.796967) (xy 121.753285 -393.745329) (xy 121.775192 -393.696266) (xy 121.803727 -393.650738)
			(xy 121.820686 -393.629896) (xy 121.826064 -393.622927) (xy 121.832167 -393.606429) (xy 121.832624 -393.597638)
			(xy 121.832878 -393.567158) (xy 121.8326 -393.558307) (xy 121.826606 -393.541655) (xy 121.821194 -393.534646)
			(xy 121.804955 -393.514096) (xy 121.77769 -393.469374) (xy 121.756787 -393.421348) (xy 121.742638 -393.370917)
			(xy 121.735508 -393.319027) (xy 121.735088 -393.292838) (xy 121.735088 -392.429238) (xy 121.735546 -392.402891)
			(xy 121.742775 -392.350697) (xy 121.757115 -392.299993) (xy 121.778294 -392.251744) (xy 121.805908 -392.206866)
			(xy 121.839433 -392.166214) (xy 121.858532 -392.14806) (xy 121.865644 -392.14171) (xy 121.873772 -392.124946)
			(xy 121.882154 -392.038332) (xy 121.877074 -392.020552) (xy 121.871486 -392.012678) (xy 121.85734 -391.992828)
			(xy 121.834881 -391.949571) (xy 121.819567 -391.903299) (xy 121.811787 -391.855184) (xy 121.811288 -391.830814)
			(xy 121.81181 -391.805559) (xy 121.820123 -391.755737) (xy 121.836524 -391.707963) (xy 121.860565 -391.66354)
			(xy 121.891589 -391.62368) (xy 121.928751 -391.58947) (xy 121.971037 -391.561844) (xy 122.017293 -391.541554)
			(xy 122.066258 -391.529154) (xy 122.116596 -391.524983) (xy 122.166934 -391.529154) (xy 122.215899 -391.541554)
			(xy 122.262155 -391.561844) (xy 122.304441 -391.58947) (xy 122.341603 -391.62368) (xy 122.372627 -391.66354)
			(xy 122.396668 -391.707963) (xy 122.413069 -391.755737) (xy 122.421382 -391.805559) (xy 122.421904 -391.830814)
			(xy 122.421435 -391.855187) (xy 122.413675 -391.903311) (xy 122.398355 -391.949586) (xy 122.375865 -391.992834)
			(xy 122.361706 -392.012678) (xy 122.356118 -392.020552) (xy 122.351038 -392.038332) (xy 122.35942 -392.124946)
			(xy 122.367548 -392.14171) (xy 122.37466 -392.14806) (xy 122.393795 -392.16618) (xy 122.427336 -392.20683)
			(xy 122.45496 -392.25171) (xy 122.476139 -392.299968) (xy 122.490471 -392.350682) (xy 122.497682 -392.402887)
			(xy 122.498104 -392.429238) (xy 122.498104 -393.292838) (xy 122.497668 -393.319295) (xy 122.490391 -393.371706)
			(xy 122.475942 -393.422608) (xy 122.454596 -393.471025) (xy 122.426765 -393.516028) (xy 122.41022 -393.536678)
			(xy 122.404894 -393.543734) (xy 122.398918 -393.560358) (xy 122.398536 -393.56919) (xy 122.398536 -393.59967)
			(xy 122.398924 -393.608444) (xy 122.404892 -393.624946) (xy 122.41022 -393.631928) (xy 122.42686 -393.65268)
			(xy 122.454831 -393.697923) (xy 122.47629 -393.746593) (xy 122.490827 -393.797759) (xy 122.498163 -393.850442)
			(xy 122.498612 -393.877038) (xy 122.498159 -393.902438) (xy 122.930412 -393.902438) (xy 122.930939 -393.874153)
			(xy 122.939253 -393.818197) (xy 122.955691 -393.764067) (xy 122.979897 -393.712937) (xy 123.011347 -393.665915)
			(xy 123.02998 -393.644628) (xy 123.035898 -393.637448) (xy 123.042676 -393.620136) (xy 123.043188 -393.610846)
			(xy 123.043442 -393.579604) (xy 123.04302 -393.570268) (xy 123.036386 -393.552816) (xy 123.030488 -393.545568)
			(xy 123.012575 -393.524526) (xy 122.98236 -393.478261) (xy 122.959137 -393.42812) (xy 122.943392 -393.375152)
			(xy 122.935456 -393.320467) (xy 122.934984 -393.292838) (xy 122.934984 -392.429238) (xy 122.935443 -392.402891)
			(xy 122.942672 -392.350697) (xy 122.957012 -392.299993) (xy 122.978191 -392.251744) (xy 123.005805 -392.206866)
			(xy 123.039329 -392.166214) (xy 123.058428 -392.14806) (xy 123.06554 -392.14171) (xy 123.073668 -392.124946)
			(xy 123.08205 -392.038332) (xy 123.07697 -392.020552) (xy 123.071382 -392.012678) (xy 123.057236 -391.992829)
			(xy 123.034776 -391.949571) (xy 123.019463 -391.903299) (xy 123.011682 -391.855184) (xy 123.011184 -391.830814)
			(xy 123.011706 -391.805559) (xy 123.020019 -391.755737) (xy 123.03642 -391.707963) (xy 123.060461 -391.66354)
			(xy 123.091485 -391.62368) (xy 123.128647 -391.58947) (xy 123.170933 -391.561844) (xy 123.217189 -391.541554)
			(xy 123.266154 -391.529154) (xy 123.316492 -391.524983) (xy 123.36683 -391.529154) (xy 123.415795 -391.541554)
			(xy 123.462051 -391.561844) (xy 123.504337 -391.58947) (xy 123.541499 -391.62368) (xy 123.572523 -391.66354)
			(xy 123.596564 -391.707963) (xy 123.612965 -391.755737) (xy 123.621278 -391.805559) (xy 123.6218 -391.830814)
			(xy 123.621331 -391.855187) (xy 123.613571 -391.903311) (xy 123.598251 -391.949586) (xy 123.575761 -391.992834)
			(xy 123.561602 -392.012678) (xy 123.556014 -392.020552) (xy 123.550934 -392.038332) (xy 123.559316 -392.124946)
			(xy 123.567444 -392.14171) (xy 123.574556 -392.14806) (xy 123.593691 -392.166181) (xy 123.627232 -392.20683)
			(xy 123.654855 -392.251711) (xy 123.676035 -392.299968) (xy 123.690367 -392.350682) (xy 123.697578 -392.402887)
			(xy 123.698 -392.429238) (xy 123.698 -393.292838) (xy 123.697569 -393.320741) (xy 123.689476 -393.375957)
			(xy 123.673423 -393.429405) (xy 123.649754 -393.479942) (xy 123.618974 -393.526492) (xy 123.600718 -393.5476)
			(xy 123.594824 -393.554779) (xy 123.588171 -393.572103) (xy 123.587764 -393.581382) (xy 123.587764 -393.612624)
			(xy 123.588183 -393.621899) (xy 123.594842 -393.639217) (xy 123.600718 -393.646406) (xy 123.619054 -393.667624)
			(xy 123.649954 -393.714419) (xy 123.673722 -393.76521) (xy 123.689852 -393.818917) (xy 123.698001 -393.874399)
			(xy 123.698508 -393.902438) (xy 123.698055 -393.927838) (xy 124.130816 -393.927838) (xy 124.131248 -393.900148)
			(xy 124.139147 -393.845335) (xy 124.154844 -393.792227) (xy 124.178012 -393.741928) (xy 124.20817 -393.695481)
			(xy 124.226066 -393.674346) (xy 124.232416 -393.667488) (xy 124.238766 -393.65047) (xy 124.239274 -393.56538)
			(xy 124.232924 -393.548362) (xy 124.226828 -393.54125) (xy 124.209586 -393.520385) (xy 124.180502 -393.474739)
			(xy 124.15816 -393.425441) (xy 124.14301 -393.373481) (xy 124.135355 -393.3199) (xy 124.13488 -393.292838)
			(xy 124.13488 -392.429238) (xy 124.135297 -392.40291) (xy 124.142548 -392.350755) (xy 124.156904 -392.300093)
			(xy 124.178092 -392.251888) (xy 124.205709 -392.207055) (xy 124.23923 -392.166446) (xy 124.258324 -392.148314)
			(xy 124.265436 -392.14171) (xy 124.273818 -392.1252) (xy 124.281946 -392.038332) (xy 124.276866 -392.020552)
			(xy 124.271278 -392.012932) (xy 124.25712 -391.993052) (xy 124.234633 -391.949737) (xy 124.219316 -391.903399)
			(xy 124.211558 -391.855216) (xy 124.21108 -391.830814) (xy 124.211602 -391.805559) (xy 124.219915 -391.755737)
			(xy 124.236316 -391.707963) (xy 124.260357 -391.66354) (xy 124.291381 -391.62368) (xy 124.328543 -391.58947)
			(xy 124.370829 -391.561844) (xy 124.417085 -391.541554) (xy 124.46605 -391.529154) (xy 124.516388 -391.524983)
			(xy 124.566726 -391.529154) (xy 124.615691 -391.541554) (xy 124.661947 -391.561844) (xy 124.704233 -391.58947)
			(xy 124.741395 -391.62368) (xy 124.772419 -391.66354) (xy 124.79646 -391.707963) (xy 124.812861 -391.755737)
			(xy 124.821174 -391.805559) (xy 124.821696 -391.830814) (xy 124.821208 -391.855173) (xy 124.813495 -391.903276)
			(xy 124.798249 -391.949546) (xy 124.775857 -391.992813) (xy 124.761752 -392.012678) (xy 124.75591 -392.020298)
			(xy 124.751084 -392.038078) (xy 124.759212 -392.124946) (xy 124.767594 -392.141456) (xy 124.774706 -392.14806)
			(xy 124.793832 -392.166203) (xy 124.827422 -392.20683) (xy 124.855096 -392.251698) (xy 124.876325 -392.29995)
			(xy 124.890705 -392.350666) (xy 124.897961 -392.40288) (xy 124.898404 -392.429238) (xy 124.898404 -393.292838)
			(xy 124.89786 -393.320141) (xy 124.890013 -393.374182) (xy 124.874556 -393.426557) (xy 124.851803 -393.476199)
			(xy 124.822218 -393.522098) (xy 124.804678 -393.543028) (xy 124.798582 -393.55014) (xy 124.792232 -393.567158)
			(xy 124.792232 -393.652248) (xy 124.798582 -393.669266) (xy 124.804678 -393.676378) (xy 124.822284 -393.697417)
			(xy 124.851956 -393.743559) (xy 124.874744 -393.793461) (xy 124.890184 -393.846103) (xy 124.897959 -393.900408)
			(xy 124.898404 -393.927838) (xy 125.330712 -393.927838) (xy 125.331145 -393.900148) (xy 125.339044 -393.845335)
			(xy 125.35474 -393.792227) (xy 125.377908 -393.741928) (xy 125.408066 -393.695481) (xy 125.425962 -393.674346)
			(xy 125.432312 -393.667488) (xy 125.438662 -393.65047) (xy 125.43917 -393.56538) (xy 125.43282 -393.548362)
			(xy 125.426724 -393.54125) (xy 125.409482 -393.520386) (xy 125.380397 -393.47474) (xy 125.358056 -393.425442)
			(xy 125.342906 -393.373481) (xy 125.335251 -393.3199) (xy 125.334776 -393.292838) (xy 125.334776 -392.429238)
			(xy 125.335244 -392.402882) (xy 125.342508 -392.350672) (xy 125.356888 -392.299959) (xy 125.378112 -392.251708)
			(xy 125.405775 -392.206838) (xy 125.43935 -392.166201) (xy 125.458474 -392.14806) (xy 125.465586 -392.14171)
			(xy 125.473714 -392.124946) (xy 125.482096 -392.038332) (xy 125.477016 -392.020552) (xy 125.471428 -392.012678)
			(xy 125.457275 -391.992833) (xy 125.434819 -391.949574) (xy 125.419508 -391.9033) (xy 125.411728 -391.855184)
			(xy 125.41123 -391.830814) (xy 125.411752 -391.805559) (xy 125.420065 -391.755737) (xy 125.436466 -391.707963)
			(xy 125.460507 -391.66354) (xy 125.491531 -391.62368) (xy 125.528693 -391.58947) (xy 125.570979 -391.561844)
			(xy 125.617235 -391.541554) (xy 125.6662 -391.529154) (xy 125.716538 -391.524983) (xy 125.766876 -391.529154)
			(xy 125.815841 -391.541554) (xy 125.862097 -391.561844) (xy 125.904383 -391.58947) (xy 125.941545 -391.62368)
			(xy 125.972569 -391.66354) (xy 125.99661 -391.707963) (xy 126.013011 -391.755737) (xy 126.021324 -391.805559)
			(xy 126.021846 -391.830814) (xy 126.021369 -391.855186) (xy 126.01361 -391.90331) (xy 125.998292 -391.949585)
			(xy 125.975805 -391.992833) (xy 125.961648 -392.012678) (xy 125.95606 -392.020552) (xy 125.95098 -392.038332)
			(xy 125.959362 -392.124946) (xy 125.96749 -392.14171) (xy 125.974602 -392.14806) (xy 125.993727 -392.166203)
			(xy 126.027317 -392.206831) (xy 126.054991 -392.251698) (xy 126.076221 -392.29995) (xy 126.090601 -392.350667)
			(xy 126.097857 -392.40288) (xy 126.0983 -392.429238) (xy 126.0983 -393.292838) (xy 126.097756 -393.320141)
			(xy 126.089909 -393.374182) (xy 126.074452 -393.426557) (xy 126.051699 -393.476199) (xy 126.022114 -393.522098)
			(xy 126.004574 -393.543028) (xy 125.998478 -393.55014) (xy 125.992128 -393.567158) (xy 125.992128 -393.652248)
			(xy 125.998478 -393.669266) (xy 126.004574 -393.676378) (xy 126.022179 -393.697418) (xy 126.051851 -393.74356)
			(xy 126.07464 -393.793461) (xy 126.09008 -393.846103) (xy 126.097855 -393.900408) (xy 126.0983 -393.927838)
			(xy 126.530608 -393.927838) (xy 126.531106 -393.900141) (xy 126.539048 -393.84532) (xy 126.554788 -393.792209)
			(xy 126.577998 -393.741912) (xy 126.608197 -393.695474) (xy 126.626112 -393.674346) (xy 126.632462 -393.667488)
			(xy 126.638812 -393.65047) (xy 126.63932 -393.56538) (xy 126.63297 -393.548362) (xy 126.626874 -393.54125)
			(xy 126.609658 -393.520377) (xy 126.580638 -393.474714) (xy 126.558355 -393.425411) (xy 126.543254 -393.373456)
			(xy 126.535639 -393.31989) (xy 126.53518 -393.292838) (xy 126.53518 -392.429238) (xy 126.535618 -392.402922)
			(xy 126.542842 -392.350787) (xy 126.557159 -392.300139) (xy 126.578296 -392.251937) (xy 126.605854 -392.207096)
			(xy 126.639309 -392.166464) (xy 126.65837 -392.148314) (xy 126.665482 -392.14171) (xy 126.673864 -392.1252)
			(xy 126.681992 -392.038332) (xy 126.676912 -392.020552) (xy 126.671324 -392.012932) (xy 126.657171 -391.993048)
			(xy 126.634682 -391.949735) (xy 126.619364 -391.903398) (xy 126.611604 -391.855216) (xy 126.611126 -391.830814)
			(xy 126.611648 -391.805559) (xy 126.619961 -391.755737) (xy 126.636362 -391.707963) (xy 126.660403 -391.66354)
			(xy 126.691427 -391.62368) (xy 126.728589 -391.58947) (xy 126.770875 -391.561844) (xy 126.817131 -391.541554)
			(xy 126.866096 -391.529154) (xy 126.916434 -391.524983) (xy 126.966772 -391.529154) (xy 127.015737 -391.541554)
			(xy 127.061993 -391.561844) (xy 127.104279 -391.58947) (xy 127.141441 -391.62368) (xy 127.172465 -391.66354)
			(xy 127.196506 -391.707963) (xy 127.212907 -391.755737) (xy 127.22122 -391.805559) (xy 127.221742 -391.830814)
			(xy 127.221246 -391.855172) (xy 127.213534 -391.903275) (xy 127.19829 -391.949545) (xy 127.175901 -391.992812)
			(xy 127.161798 -392.012678) (xy 127.155956 -392.020298) (xy 127.15113 -392.038078) (xy 127.159258 -392.124946)
			(xy 127.16764 -392.141456) (xy 127.174752 -392.14806) (xy 127.193886 -392.166182) (xy 127.227427 -392.206831)
			(xy 127.255051 -392.251711) (xy 127.276231 -392.299968) (xy 127.290563 -392.350683) (xy 127.297774 -392.402887)
			(xy 127.298196 -392.429238) (xy 127.298196 -393.292838) (xy 127.297735 -393.320138) (xy 127.289958 -393.37418)
			(xy 127.274554 -393.426561) (xy 127.251839 -393.47621) (xy 127.222275 -393.522113) (xy 127.204724 -393.543028)
			(xy 127.198628 -393.55014) (xy 127.192278 -393.567158) (xy 127.192278 -393.652248) (xy 127.198628 -393.669266)
			(xy 127.204724 -393.676378) (xy 127.222334 -393.697421) (xy 127.25203 -393.743562) (xy 127.274856 -393.793459)
			(xy 127.29035 -393.846096) (xy 127.298196 -393.900403) (xy 127.298704 -393.927838) (xy 127.730504 -393.927838)
			(xy 127.730978 -393.90014) (xy 127.738923 -393.845316) (xy 127.754667 -393.792205) (xy 127.777883 -393.741908)
			(xy 127.808089 -393.695472) (xy 127.826008 -393.674346) (xy 127.832358 -393.667488) (xy 127.838708 -393.65047)
			(xy 127.839216 -393.56538) (xy 127.832866 -393.548362) (xy 127.82677 -393.54125) (xy 127.809554 -393.520377)
			(xy 127.780534 -393.474714) (xy 127.758251 -393.425411) (xy 127.74315 -393.373457) (xy 127.735535 -393.31989)
			(xy 127.735076 -393.292838) (xy 127.735076 -392.429238) (xy 127.735537 -392.402892) (xy 127.742767 -392.350697)
			(xy 127.757106 -392.299994) (xy 127.778284 -392.251744) (xy 127.805898 -392.206867) (xy 127.839421 -392.166214)
			(xy 127.85852 -392.14806) (xy 127.865632 -392.14171) (xy 127.87376 -392.124946) (xy 127.882142 -392.038332)
			(xy 127.877062 -392.020552) (xy 127.871474 -392.012678) (xy 127.857327 -391.992829) (xy 127.834868 -391.949572)
			(xy 127.819555 -391.903299) (xy 127.811774 -391.855184) (xy 127.811276 -391.830814) (xy 127.811798 -391.805559)
			(xy 127.820111 -391.755737) (xy 127.836512 -391.707963) (xy 127.860553 -391.66354) (xy 127.891577 -391.62368)
			(xy 127.928739 -391.58947) (xy 127.971025 -391.561844) (xy 128.017281 -391.541554) (xy 128.066246 -391.529154)
			(xy 128.116584 -391.524983) (xy 128.166922 -391.529154) (xy 128.215887 -391.541554) (xy 128.262143 -391.561844)
			(xy 128.304429 -391.58947) (xy 128.341591 -391.62368) (xy 128.372615 -391.66354) (xy 128.396656 -391.707963)
			(xy 128.413057 -391.755737) (xy 128.42137 -391.805559) (xy 128.421892 -391.830814) (xy 128.421425 -391.855187)
			(xy 128.413665 -391.903311) (xy 128.398344 -391.949587) (xy 128.375853 -391.992834) (xy 128.361694 -392.012678)
			(xy 128.356106 -392.020552) (xy 128.351026 -392.038332) (xy 128.359408 -392.124946) (xy 128.367536 -392.14171)
			(xy 128.374648 -392.14806) (xy 128.393781 -392.166183) (xy 128.427323 -392.206831) (xy 128.454947 -392.251711)
			(xy 128.476127 -392.299969) (xy 128.490459 -392.350683) (xy 128.49767 -392.402887) (xy 128.498092 -392.429238)
			(xy 128.498092 -393.292838) (xy 128.497632 -393.320138) (xy 128.489855 -393.37418) (xy 128.474451 -393.426561)
			(xy 128.451735 -393.47621) (xy 128.422171 -393.522113) (xy 128.40462 -393.543028) (xy 128.398524 -393.55014)
			(xy 128.392174 -393.567158) (xy 128.392174 -393.652248) (xy 128.398524 -393.669266) (xy 128.40462 -393.676378)
			(xy 128.42223 -393.697422) (xy 128.451925 -393.743562) (xy 128.474752 -393.793459) (xy 128.490246 -393.846096)
			(xy 128.494716 -393.877038) (xy 128.9304 -393.877038) (xy 128.930821 -393.850173) (xy 128.938323 -393.796968)
			(xy 128.953172 -393.745329) (xy 128.975078 -393.696266) (xy 129.003612 -393.650738) (xy 129.02057 -393.629896)
			(xy 129.025946 -393.622926) (xy 129.032051 -393.606429) (xy 129.032508 -393.597638) (xy 129.032762 -393.567158)
			(xy 129.032466 -393.55831) (xy 129.026483 -393.541658) (xy 129.021078 -393.534646) (xy 129.004836 -393.514098)
			(xy 128.977572 -393.469375) (xy 128.95667 -393.421348) (xy 128.942522 -393.370918) (xy 128.935392 -393.319027)
			(xy 128.934972 -393.292838) (xy 128.934972 -392.429238) (xy 128.935435 -392.402892) (xy 128.942664 -392.350698)
			(xy 128.957003 -392.299994) (xy 128.978181 -392.251745) (xy 129.005794 -392.206867) (xy 129.039318 -392.166214)
			(xy 129.058416 -392.14806) (xy 129.065528 -392.14171) (xy 129.073656 -392.124946) (xy 129.082038 -392.038332)
			(xy 129.076958 -392.020552) (xy 129.07137 -392.012678) (xy 129.057222 -391.99283) (xy 129.034764 -391.949572)
			(xy 129.019451 -391.903299) (xy 129.01167 -391.855184) (xy 129.011172 -391.830814) (xy 129.011694 -391.805559)
			(xy 129.020007 -391.755737) (xy 129.036408 -391.707963) (xy 129.060449 -391.66354) (xy 129.091473 -391.62368)
			(xy 129.128635 -391.58947) (xy 129.170921 -391.561844) (xy 129.217177 -391.541554) (xy 129.266142 -391.529154)
			(xy 129.31648 -391.524983) (xy 129.366818 -391.529154) (xy 129.415783 -391.541554) (xy 129.462039 -391.561844)
			(xy 129.504325 -391.58947) (xy 129.541487 -391.62368) (xy 129.572511 -391.66354) (xy 129.596552 -391.707963)
			(xy 129.612953 -391.755737) (xy 129.621266 -391.805559) (xy 129.621788 -391.830814) (xy 129.621322 -391.855187)
			(xy 129.613561 -391.903311) (xy 129.59824 -391.949587) (xy 129.57575 -391.992834) (xy 129.56159 -392.012678)
			(xy 129.556002 -392.020552) (xy 129.550922 -392.038332) (xy 129.559304 -392.124946) (xy 129.567432 -392.14171)
			(xy 129.574544 -392.14806) (xy 129.593676 -392.166183) (xy 129.627218 -392.206832) (xy 129.654842 -392.251712)
			(xy 129.676022 -392.299969) (xy 129.690355 -392.350683) (xy 129.697566 -392.402887) (xy 129.697988 -392.429238)
			(xy 129.697988 -393.292838) (xy 129.697555 -393.319295) (xy 129.690279 -393.371706) (xy 129.675828 -393.422609)
			(xy 129.654482 -393.471026) (xy 129.626649 -393.516028) (xy 129.610104 -393.536678) (xy 129.604776 -393.543733)
			(xy 129.598801 -393.560358) (xy 129.59842 -393.56919) (xy 129.59842 -393.59967) (xy 129.598812 -393.608444)
			(xy 129.604778 -393.624946) (xy 129.610104 -393.631928) (xy 129.626741 -393.652682) (xy 129.654713 -393.697924)
			(xy 129.676173 -393.746594) (xy 129.69071 -393.79776) (xy 129.698047 -393.850442) (xy 129.698496 -393.877038)
			(xy 129.698007 -393.904471) (xy 129.694647 -393.927838) (xy 130.130296 -393.927838) (xy 130.130772 -393.90014)
			(xy 130.138717 -393.845317) (xy 130.15446 -393.792205) (xy 130.177676 -393.741909) (xy 130.207881 -393.695472)
			(xy 130.2258 -393.674346) (xy 130.23215 -393.667488) (xy 130.2385 -393.65047) (xy 130.239008 -393.56538)
			(xy 130.232658 -393.548362) (xy 130.226562 -393.54125) (xy 130.209345 -393.520378) (xy 130.180325 -393.474714)
			(xy 130.158042 -393.425411) (xy 130.142942 -393.373457) (xy 130.135327 -393.319891) (xy 130.134868 -393.292838)
			(xy 130.134868 -392.429238) (xy 130.135332 -392.402892) (xy 130.142561 -392.350698) (xy 130.1569 -392.299994)
			(xy 130.178078 -392.251745) (xy 130.205691 -392.206867) (xy 130.239214 -392.166214) (xy 130.258312 -392.14806)
			(xy 130.265424 -392.14171) (xy 130.273552 -392.124946) (xy 130.281934 -392.038332) (xy 130.276854 -392.020552)
			(xy 130.271266 -392.012678) (xy 130.257118 -391.99283) (xy 130.234659 -391.949572) (xy 130.219346 -391.903299)
			(xy 130.211566 -391.855184) (xy 130.211068 -391.830814) (xy 130.21159 -391.805559) (xy 130.219903 -391.755737)
			(xy 130.236304 -391.707963) (xy 130.260345 -391.66354) (xy 130.291369 -391.62368) (xy 130.328531 -391.58947)
			(xy 130.370817 -391.561844) (xy 130.417073 -391.541554) (xy 130.466038 -391.529154) (xy 130.516376 -391.524983)
			(xy 130.566714 -391.529154) (xy 130.615679 -391.541554) (xy 130.661935 -391.561844) (xy 130.704221 -391.58947)
			(xy 130.741383 -391.62368) (xy 130.772407 -391.66354) (xy 130.796448 -391.707963) (xy 130.812849 -391.755737)
			(xy 130.821162 -391.805559) (xy 130.821684 -391.830814) (xy 130.821219 -391.855187) (xy 130.813458 -391.903311)
			(xy 130.798137 -391.949587) (xy 130.775646 -391.992834) (xy 130.761486 -392.012678) (xy 130.755898 -392.020552)
			(xy 130.750818 -392.038332) (xy 130.7592 -392.124946) (xy 130.767328 -392.14171) (xy 130.77444 -392.14806)
			(xy 130.793571 -392.166184) (xy 130.827114 -392.206832) (xy 130.854738 -392.251712) (xy 130.875918 -392.299969)
			(xy 130.890251 -392.350683) (xy 130.897462 -392.402887) (xy 130.897884 -392.429238) (xy 130.897884 -393.292838)
			(xy 130.897426 -393.320138) (xy 130.889649 -393.37418) (xy 130.874245 -393.426562) (xy 130.851528 -393.476211)
			(xy 130.821964 -393.522113) (xy 130.804412 -393.543028) (xy 130.798316 -393.55014) (xy 130.791966 -393.567158)
			(xy 130.791966 -393.652248) (xy 130.798316 -393.669266) (xy 130.804412 -393.676378) (xy 130.82202 -393.697423)
			(xy 130.851716 -393.743563) (xy 130.874544 -393.793459) (xy 130.890038 -393.846097) (xy 130.897884 -393.900403)
			(xy 130.898392 -393.927838) (xy 131.3307 -393.927838) (xy 131.331136 -393.900148) (xy 131.339035 -393.845336)
			(xy 131.35473 -393.792228) (xy 131.377898 -393.741928) (xy 131.408055 -393.695481) (xy 131.42595 -393.674346)
			(xy 131.4323 -393.667488) (xy 131.43865 -393.65047) (xy 131.439158 -393.56538) (xy 131.432808 -393.548362)
			(xy 131.426712 -393.54125) (xy 131.409468 -393.520387) (xy 131.380384 -393.474741) (xy 131.358043 -393.425442)
			(xy 131.342893 -393.373481) (xy 131.335239 -393.3199) (xy 131.334764 -393.292838) (xy 131.334764 -392.429238)
			(xy 131.335236 -392.402882) (xy 131.342499 -392.350673) (xy 131.356879 -392.29996) (xy 131.378102 -392.251709)
			(xy 131.405764 -392.206838) (xy 131.439338 -392.166202) (xy 131.458462 -392.14806) (xy 131.465574 -392.14171)
			(xy 131.473702 -392.124946) (xy 131.482084 -392.038332) (xy 131.477004 -392.020552) (xy 131.471416 -392.012678)
			(xy 131.457261 -391.992834) (xy 131.434806 -391.949574) (xy 131.419495 -391.9033) (xy 131.411716 -391.855184)
			(xy 131.411218 -391.830814) (xy 131.41174 -391.805559) (xy 131.420053 -391.755737) (xy 131.436454 -391.707963)
			(xy 131.460495 -391.66354) (xy 131.491519 -391.62368) (xy 131.528681 -391.58947) (xy 131.570967 -391.561844)
			(xy 131.617223 -391.541554) (xy 131.666188 -391.529154) (xy 131.716526 -391.524983) (xy 131.766864 -391.529154)
			(xy 131.815829 -391.541554) (xy 131.862085 -391.561844) (xy 131.904371 -391.58947) (xy 131.941533 -391.62368)
			(xy 131.972557 -391.66354) (xy 131.996598 -391.707963) (xy 132.012999 -391.755737) (xy 132.021312 -391.805559)
			(xy 132.021834 -391.830814) (xy 132.021359 -391.855186) (xy 132.0136 -391.90331) (xy 131.998281 -391.949585)
			(xy 131.975794 -391.992833) (xy 131.961636 -392.012678) (xy 131.956048 -392.020552) (xy 131.950968 -392.038332)
			(xy 131.95935 -392.124946) (xy 131.967478 -392.14171) (xy 131.97459 -392.14806) (xy 131.993732 -392.166186)
			(xy 132.027317 -392.206819) (xy 132.054987 -392.251691) (xy 132.076213 -392.299946) (xy 132.09059 -392.350664)
			(xy 132.097845 -392.40288) (xy 132.098288 -392.429238) (xy 132.098288 -393.292838) (xy 132.097747 -393.320141)
			(xy 132.0899 -393.374183) (xy 132.074442 -393.426557) (xy 132.051689 -393.476199) (xy 132.022103 -393.522098)
			(xy 132.004562 -393.543028) (xy 131.998466 -393.55014) (xy 131.992116 -393.567158) (xy 131.992116 -393.652248)
			(xy 131.998466 -393.669266) (xy 132.004562 -393.676378) (xy 132.022165 -393.697419) (xy 132.051838 -393.743561)
			(xy 132.074627 -393.793462) (xy 132.090068 -393.846103) (xy 132.097843 -393.900408) (xy 132.097876 -393.902438)
			(xy 132.530596 -393.902438) (xy 132.531075 -393.874162) (xy 132.539361 -393.818221) (xy 132.555759 -393.764099)
			(xy 132.579915 -393.712967) (xy 132.611307 -393.665929) (xy 132.62991 -393.644628) (xy 132.635832 -393.637451)
			(xy 132.642607 -393.620137) (xy 132.643118 -393.610846) (xy 132.643372 -393.579604) (xy 132.642944 -393.570269)
			(xy 132.636313 -393.552817) (xy 132.630418 -393.545568) (xy 132.61245 -393.524559) (xy 132.582171 -393.478306)
			(xy 132.558894 -393.428164) (xy 132.543107 -393.375184) (xy 132.535141 -393.320479) (xy 132.53466 -393.292838)
			(xy 132.53466 -392.429238) (xy 132.535133 -392.402882) (xy 132.542397 -392.350673) (xy 132.556777 -392.29996)
			(xy 132.577999 -392.251709) (xy 132.605661 -392.206839) (xy 132.639235 -392.166202) (xy 132.658358 -392.14806)
			(xy 132.66547 -392.14171) (xy 132.673598 -392.124946) (xy 132.68198 -392.038332) (xy 132.6769 -392.020552)
			(xy 132.671312 -392.012678) (xy 132.657157 -391.992835) (xy 132.634702 -391.949574) (xy 132.619391 -391.9033)
			(xy 132.611612 -391.855184) (xy 132.611114 -391.830814) (xy 132.611636 -391.805559) (xy 132.619949 -391.755737)
			(xy 132.63635 -391.707963) (xy 132.660391 -391.66354) (xy 132.691415 -391.62368) (xy 132.728577 -391.58947)
			(xy 132.770863 -391.561844) (xy 132.817119 -391.541554) (xy 132.866084 -391.529154) (xy 132.916422 -391.524983)
			(xy 132.96676 -391.529154) (xy 133.015725 -391.541554) (xy 133.061981 -391.561844) (xy 133.104267 -391.58947)
			(xy 133.141429 -391.62368) (xy 133.172453 -391.66354) (xy 133.196494 -391.707963) (xy 133.212895 -391.755737)
			(xy 133.221208 -391.805559) (xy 133.22173 -391.830814) (xy 133.221256 -391.855187) (xy 133.213496 -391.90331)
			(xy 133.198178 -391.949586) (xy 133.17569 -391.992834) (xy 133.161532 -392.012678) (xy 133.155944 -392.020552)
			(xy 133.150864 -392.038332) (xy 133.159246 -392.124946) (xy 133.167374 -392.14171) (xy 133.174486 -392.14806)
			(xy 133.193627 -392.166187) (xy 133.227213 -392.20682) (xy 133.254882 -392.251691) (xy 133.276108 -392.299946)
			(xy 133.290486 -392.350664) (xy 133.297741 -392.40288) (xy 133.298184 -392.429238) (xy 133.298184 -393.292838)
			(xy 133.297695 -393.320749) (xy 133.289557 -393.375974) (xy 133.27346 -393.429424) (xy 133.249746 -393.479959)
			(xy 133.218924 -393.526499) (xy 133.200648 -393.5476) (xy 133.194745 -393.554773) (xy 133.188099 -393.572102)
			(xy 133.187694 -393.581382) (xy 133.187694 -393.612624) (xy 133.188129 -393.621896) (xy 133.194778 -393.639214)
			(xy 133.200648 -393.646406) (xy 133.218929 -393.667656) (xy 133.249777 -393.71446) (xy 133.273495 -393.765249)
			(xy 133.289581 -393.818946) (xy 133.297693 -393.87441) (xy 133.298184 -393.902438) (xy 133.297695 -393.929853)
			(xy 133.289892 -393.984123) (xy 133.274445 -394.036731) (xy 133.251668 -394.086606) (xy 133.222025 -394.132731)
			(xy 133.18612 -394.174168) (xy 133.144683 -394.210073) (xy 133.098558 -394.239716) (xy 133.048683 -394.262493)
			(xy 132.996075 -394.27794) (xy 132.941805 -394.285743) (xy 132.886975 -394.285743) (xy 132.832705 -394.27794)
			(xy 132.780097 -394.262493) (xy 132.730222 -394.239716) (xy 132.684097 -394.210073) (xy 132.64266 -394.174168)
			(xy 132.606755 -394.132731) (xy 132.577112 -394.086606) (xy 132.554335 -394.036731) (xy 132.538888 -393.984123)
			(xy 132.531085 -393.929853) (xy 132.530596 -393.902438) (xy 132.097876 -393.902438) (xy 132.098288 -393.927838)
			(xy 132.097799 -393.955253) (xy 132.089996 -394.009523) (xy 132.074549 -394.062131) (xy 132.051772 -394.112006)
			(xy 132.022129 -394.158131) (xy 131.986224 -394.199568) (xy 131.944787 -394.235473) (xy 131.898662 -394.265116)
			(xy 131.848787 -394.287893) (xy 131.796179 -394.30334) (xy 131.741909 -394.311143) (xy 131.687079 -394.311143)
			(xy 131.632809 -394.30334) (xy 131.580201 -394.287893) (xy 131.530326 -394.265116) (xy 131.484201 -394.235473)
			(xy 131.442764 -394.199568) (xy 131.406859 -394.158131) (xy 131.377216 -394.112006) (xy 131.354439 -394.062131)
			(xy 131.338992 -394.009523) (xy 131.331189 -393.955253) (xy 131.3307 -393.927838) (xy 130.898392 -393.927838)
			(xy 130.897903 -393.955271) (xy 130.890095 -394.009578) (xy 130.874637 -394.06222) (xy 130.851845 -394.112128)
			(xy 130.822183 -394.158283) (xy 130.786254 -394.199748) (xy 130.744789 -394.235677) (xy 130.698634 -394.265339)
			(xy 130.648726 -394.288131) (xy 130.596084 -394.303589) (xy 130.541777 -394.311397) (xy 130.486911 -394.311397)
			(xy 130.432604 -394.303589) (xy 130.379962 -394.288131) (xy 130.330054 -394.265339) (xy 130.283899 -394.235677)
			(xy 130.242434 -394.199748) (xy 130.206505 -394.158283) (xy 130.176843 -394.112128) (xy 130.154051 -394.06222)
			(xy 130.138593 -394.009578) (xy 130.130785 -393.955271) (xy 130.130296 -393.927838) (xy 129.694647 -393.927838)
			(xy 129.690199 -393.958778) (xy 129.674741 -394.01142) (xy 129.651949 -394.061328) (xy 129.622287 -394.107483)
			(xy 129.586358 -394.148948) (xy 129.544893 -394.184877) (xy 129.498738 -394.214539) (xy 129.44883 -394.237331)
			(xy 129.396188 -394.252789) (xy 129.341881 -394.260597) (xy 129.287015 -394.260597) (xy 129.232708 -394.252789)
			(xy 129.180066 -394.237331) (xy 129.130158 -394.214539) (xy 129.084003 -394.184877) (xy 129.042538 -394.148948)
			(xy 129.006609 -394.107483) (xy 128.976947 -394.061328) (xy 128.954155 -394.01142) (xy 128.938697 -393.958778)
			(xy 128.930889 -393.904471) (xy 128.9304 -393.877038) (xy 128.494716 -393.877038) (xy 128.498092 -393.900403)
			(xy 128.4986 -393.927838) (xy 128.498111 -393.955271) (xy 128.490303 -394.009578) (xy 128.474845 -394.06222)
			(xy 128.452053 -394.112128) (xy 128.422391 -394.158283) (xy 128.386462 -394.199748) (xy 128.344997 -394.235677)
			(xy 128.298842 -394.265339) (xy 128.248934 -394.288131) (xy 128.196292 -394.303589) (xy 128.141985 -394.311397)
			(xy 128.087119 -394.311397) (xy 128.032812 -394.303589) (xy 127.98017 -394.288131) (xy 127.930262 -394.265339)
			(xy 127.884107 -394.235677) (xy 127.842642 -394.199748) (xy 127.806713 -394.158283) (xy 127.777051 -394.112128)
			(xy 127.754259 -394.06222) (xy 127.738801 -394.009578) (xy 127.730993 -393.955271) (xy 127.730504 -393.927838)
			(xy 127.298704 -393.927838) (xy 127.298215 -393.955271) (xy 127.290407 -394.009578) (xy 127.274949 -394.06222)
			(xy 127.252157 -394.112128) (xy 127.222495 -394.158283) (xy 127.186566 -394.199748) (xy 127.145101 -394.235677)
			(xy 127.098946 -394.265339) (xy 127.049038 -394.288131) (xy 126.996396 -394.303589) (xy 126.942089 -394.311397)
			(xy 126.887223 -394.311397) (xy 126.832916 -394.303589) (xy 126.780274 -394.288131) (xy 126.730366 -394.265339)
			(xy 126.684211 -394.235677) (xy 126.642746 -394.199748) (xy 126.606817 -394.158283) (xy 126.577155 -394.112128)
			(xy 126.554363 -394.06222) (xy 126.538905 -394.009578) (xy 126.531097 -393.955271) (xy 126.530608 -393.927838)
			(xy 126.0983 -393.927838) (xy 126.097811 -393.955253) (xy 126.090008 -394.009523) (xy 126.074561 -394.062131)
			(xy 126.051784 -394.112006) (xy 126.022141 -394.158131) (xy 125.986236 -394.199568) (xy 125.944799 -394.235473)
			(xy 125.898674 -394.265116) (xy 125.848799 -394.287893) (xy 125.796191 -394.30334) (xy 125.741921 -394.311143)
			(xy 125.687091 -394.311143) (xy 125.632821 -394.30334) (xy 125.580213 -394.287893) (xy 125.530338 -394.265116)
			(xy 125.484213 -394.235473) (xy 125.442776 -394.199568) (xy 125.406871 -394.158131) (xy 125.377228 -394.112006)
			(xy 125.354451 -394.062131) (xy 125.339004 -394.009523) (xy 125.331201 -393.955253) (xy 125.330712 -393.927838)
			(xy 124.898404 -393.927838) (xy 124.897915 -393.955253) (xy 124.890112 -394.009523) (xy 124.874665 -394.062131)
			(xy 124.851888 -394.112006) (xy 124.822245 -394.158131) (xy 124.78634 -394.199568) (xy 124.744903 -394.235473)
			(xy 124.698778 -394.265116) (xy 124.648903 -394.287893) (xy 124.596295 -394.30334) (xy 124.542025 -394.311143)
			(xy 124.487195 -394.311143) (xy 124.432925 -394.30334) (xy 124.380317 -394.287893) (xy 124.330442 -394.265116)
			(xy 124.284317 -394.235473) (xy 124.24288 -394.199568) (xy 124.206975 -394.158131) (xy 124.177332 -394.112006)
			(xy 124.154555 -394.062131) (xy 124.139108 -394.009523) (xy 124.131305 -393.955253) (xy 124.130816 -393.927838)
			(xy 123.698055 -393.927838) (xy 123.698019 -393.929871) (xy 123.690211 -393.984178) (xy 123.674753 -394.03682)
			(xy 123.651961 -394.086728) (xy 123.622299 -394.132883) (xy 123.58637 -394.174348) (xy 123.544905 -394.210277)
			(xy 123.49875 -394.239939) (xy 123.448842 -394.262731) (xy 123.3962 -394.278189) (xy 123.341893 -394.285997)
			(xy 123.287027 -394.285997) (xy 123.23272 -394.278189) (xy 123.180078 -394.262731) (xy 123.13017 -394.239939)
			(xy 123.084015 -394.210277) (xy 123.04255 -394.174348) (xy 123.006621 -394.132883) (xy 122.976959 -394.086728)
			(xy 122.954167 -394.03682) (xy 122.938709 -393.984178) (xy 122.930901 -393.929871) (xy 122.930412 -393.902438)
			(xy 122.498159 -393.902438) (xy 122.498123 -393.904471) (xy 122.490315 -393.958778) (xy 122.474857 -394.01142)
			(xy 122.452065 -394.061328) (xy 122.422403 -394.107483) (xy 122.386474 -394.148948) (xy 122.345009 -394.184877)
			(xy 122.298854 -394.214539) (xy 122.248946 -394.237331) (xy 122.196304 -394.252789) (xy 122.141997 -394.260597)
			(xy 122.087131 -394.260597) (xy 122.032824 -394.252789) (xy 121.980182 -394.237331) (xy 121.930274 -394.214539)
			(xy 121.884119 -394.184877) (xy 121.842654 -394.148948) (xy 121.806725 -394.107483) (xy 121.777063 -394.061328)
			(xy 121.754271 -394.01142) (xy 121.738813 -393.958778) (xy 121.731005 -393.904471) (xy 121.730516 -393.877038)
			(xy 121.294417 -393.877038) (xy 121.297763 -393.900408) (xy 121.298208 -393.927838) (xy 121.297719 -393.955253)
			(xy 121.289916 -394.009523) (xy 121.274469 -394.062131) (xy 121.251692 -394.112006) (xy 121.222049 -394.158131)
			(xy 121.186144 -394.199568) (xy 121.144707 -394.235473) (xy 121.098582 -394.265116) (xy 121.048707 -394.287893)
			(xy 120.996099 -394.30334) (xy 120.941829 -394.311143) (xy 120.886999 -394.311143) (xy 120.832729 -394.30334)
			(xy 120.780121 -394.287893) (xy 120.730246 -394.265116) (xy 120.684121 -394.235473) (xy 120.642684 -394.199568)
			(xy 120.606779 -394.158131) (xy 120.577136 -394.112006) (xy 120.554359 -394.062131) (xy 120.538912 -394.009523)
			(xy 120.531109 -393.955253) (xy 120.53062 -393.927838) (xy 120.098312 -393.927838) (xy 120.097823 -393.955253)
			(xy 120.09002 -394.009523) (xy 120.074573 -394.062131) (xy 120.051796 -394.112006) (xy 120.022153 -394.158131)
			(xy 119.986248 -394.199568) (xy 119.944811 -394.235473) (xy 119.898686 -394.265116) (xy 119.848811 -394.287893)
			(xy 119.796203 -394.30334) (xy 119.741933 -394.311143) (xy 119.687103 -394.311143) (xy 119.632833 -394.30334)
			(xy 119.580225 -394.287893) (xy 119.53035 -394.265116) (xy 119.484225 -394.235473) (xy 119.442788 -394.199568)
			(xy 119.406883 -394.158131) (xy 119.37724 -394.112006) (xy 119.354463 -394.062131) (xy 119.339016 -394.009523)
			(xy 119.331213 -393.955253) (xy 119.330724 -393.927838) (xy 118.894567 -393.927838) (xy 118.890119 -393.958778)
			(xy 118.874661 -394.01142) (xy 118.851869 -394.061328) (xy 118.822207 -394.107483) (xy 118.786278 -394.148948)
			(xy 118.744813 -394.184877) (xy 118.698658 -394.214539) (xy 118.64875 -394.237331) (xy 118.596108 -394.252789)
			(xy 118.541801 -394.260597) (xy 118.486935 -394.260597) (xy 118.432628 -394.252789) (xy 118.379986 -394.237331)
			(xy 118.330078 -394.214539) (xy 118.283923 -394.184877) (xy 118.242458 -394.148948) (xy 118.206529 -394.107483)
			(xy 118.176867 -394.061328) (xy 118.154075 -394.01142) (xy 118.138617 -393.958778) (xy 118.130809 -393.904471)
			(xy 118.13032 -393.877038) (xy 117.694637 -393.877038) (xy 117.698012 -393.900403) (xy 117.69852 -393.927838)
			(xy 117.698031 -393.955271) (xy 117.690223 -394.009578) (xy 117.674765 -394.06222) (xy 117.651973 -394.112128)
			(xy 117.622311 -394.158283) (xy 117.586382 -394.199748) (xy 117.544917 -394.235677) (xy 117.498762 -394.265339)
			(xy 117.448854 -394.288131) (xy 117.396212 -394.303589) (xy 117.341905 -394.311397) (xy 117.287039 -394.311397)
			(xy 117.232732 -394.303589) (xy 117.18009 -394.288131) (xy 117.130182 -394.265339) (xy 117.084027 -394.235677)
			(xy 117.042562 -394.199748) (xy 117.006633 -394.158283) (xy 116.976971 -394.112128) (xy 116.954179 -394.06222)
			(xy 116.938721 -394.009578) (xy 116.930913 -393.955271) (xy 116.930424 -393.927838) (xy 116.497663 -393.927838)
			(xy 116.497627 -393.929853) (xy 116.489824 -393.984123) (xy 116.474377 -394.036731) (xy 116.4516 -394.086606)
			(xy 116.421957 -394.132731) (xy 116.386052 -394.174168) (xy 116.344615 -394.210073) (xy 116.29849 -394.239716)
			(xy 116.248615 -394.262493) (xy 116.196007 -394.27794) (xy 116.141737 -394.285743) (xy 116.086907 -394.285743)
			(xy 116.032637 -394.27794) (xy 115.980029 -394.262493) (xy 115.930154 -394.239716) (xy 115.884029 -394.210073)
			(xy 115.842592 -394.174168) (xy 115.806687 -394.132731) (xy 115.777044 -394.086606) (xy 115.754267 -394.036731)
			(xy 115.73882 -393.984123) (xy 115.731017 -393.929853) (xy 115.730528 -393.902438) (xy 115.29822 -393.902438)
			(xy 115.297731 -393.929853) (xy 115.289928 -393.984123) (xy 115.274481 -394.036731) (xy 115.251704 -394.086606)
			(xy 115.222061 -394.132731) (xy 115.186156 -394.174168) (xy 115.144719 -394.210073) (xy 115.098594 -394.239716)
			(xy 115.048719 -394.262493) (xy 114.996111 -394.27794) (xy 114.941841 -394.285743) (xy 114.887011 -394.285743)
			(xy 114.832741 -394.27794) (xy 114.780133 -394.262493) (xy 114.730258 -394.239716) (xy 114.684133 -394.210073)
			(xy 114.642696 -394.174168) (xy 114.606791 -394.132731) (xy 114.577148 -394.086606) (xy 114.554371 -394.036731)
			(xy 114.538924 -393.984123) (xy 114.531121 -393.929853) (xy 114.530632 -393.902438) (xy 110.496858 -393.902438)
			(xy 110.469488 -393.901953) (xy 110.415309 -393.894142) (xy 110.362806 -393.878658) (xy 110.313059 -393.85582)
			(xy 110.267092 -393.826098) (xy 110.24616 -393.808458) (xy 110.239048 -393.802362) (xy 110.22203 -393.796012)
			(xy 110.136686 -393.796012) (xy 110.119668 -393.802362) (xy 110.112556 -393.808458) (xy 110.091623 -393.826099)
			(xy 110.045655 -393.855823) (xy 109.995909 -393.878669) (xy 109.943407 -393.894165) (xy 109.889229 -393.901994)
			(xy 109.834487 -393.901994) (xy 109.780309 -393.894165) (xy 109.727807 -393.878669) (xy 109.678061 -393.855823)
			(xy 109.632093 -393.826099) (xy 109.61116 -393.808458) (xy 109.604048 -393.802362) (xy 109.58703 -393.796012)
			(xy 109.501686 -393.796012) (xy 109.484668 -393.802362) (xy 109.477556 -393.808458) (xy 109.456623 -393.826099)
			(xy 109.410655 -393.855823) (xy 109.360909 -393.878669) (xy 109.308407 -393.894165) (xy 109.254229 -393.901994)
			(xy 109.199487 -393.901994) (xy 109.145309 -393.894165) (xy 109.092807 -393.878669) (xy 109.043061 -393.855823)
			(xy 108.997093 -393.826099) (xy 108.97616 -393.808458) (xy 108.969048 -393.802362) (xy 108.95203 -393.796012)
			(xy 108.866686 -393.796012) (xy 108.849668 -393.802362) (xy 108.842556 -393.808458) (xy 108.821608 -393.826078)
			(xy 108.77564 -393.855794) (xy 108.725897 -393.878634) (xy 108.6734 -393.89413) (xy 108.619226 -393.901962)
			(xy 108.591858 -393.902438) (xy 108.564607 -393.901961) (xy 108.510661 -393.8942) (xy 108.458368 -393.878841)
			(xy 108.408792 -393.856197) (xy 108.362943 -393.826729) (xy 108.321754 -393.791037) (xy 108.286064 -393.749847)
			(xy 108.256597 -393.703997) (xy 108.233955 -393.654421) (xy 108.218598 -393.602128) (xy 108.210838 -393.548181)
			(xy 108.21035 -393.52093) (xy 107.355386 -393.52093) (xy 107.354972 -393.551662) (xy 107.34756 -393.612679)
			(xy 107.332847 -393.672357) (xy 107.311048 -393.729827) (xy 107.282481 -393.78425) (xy 107.247562 -393.834832)
			(xy 107.206801 -393.880838) (xy 107.160791 -393.921594) (xy 107.110205 -393.956508) (xy 107.055779 -393.985069)
			(xy 106.998307 -394.006862) (xy 106.938628 -394.021569) (xy 106.877611 -394.028975) (xy 106.846878 -394.029438)
			(xy 106.816182 -394.02895) (xy 106.755238 -394.02155) (xy 106.69563 -394.006861) (xy 106.638226 -393.985097)
			(xy 106.583862 -393.956574) (xy 106.558334 -393.939522) (xy 106.549582 -393.934051) (xy 106.529378 -393.929923)
			(xy 106.509174 -393.934051) (xy 106.500422 -393.939522) (xy 106.474898 -393.95658) (xy 106.420527 -393.985087)
			(xy 106.363121 -394.006846) (xy 106.303515 -394.021542) (xy 106.242573 -394.028961) (xy 106.211878 -394.029438)
			(xy 106.181182 -394.02895) (xy 106.120238 -394.02155) (xy 106.06063 -394.006861) (xy 106.003226 -393.985097)
			(xy 105.948862 -393.956574) (xy 105.923334 -393.939522) (xy 105.914582 -393.934051) (xy 105.894378 -393.929923)
			(xy 105.874174 -393.934051) (xy 105.865422 -393.939522) (xy 105.839898 -393.95658) (xy 105.785527 -393.985087)
			(xy 105.728121 -394.006846) (xy 105.668515 -394.021542) (xy 105.607573 -394.028961) (xy 105.576878 -394.029438)
			(xy 105.546148 -394.028965) (xy 105.485135 -394.021554) (xy 105.425461 -394.006844) (xy 105.367995 -393.985049)
			(xy 105.313574 -393.956486) (xy 105.262993 -393.921572) (xy 105.216989 -393.880816) (xy 105.176233 -393.834813)
			(xy 105.141318 -393.784232) (xy 105.112755 -393.729812) (xy 105.090958 -393.672347) (xy 105.076247 -393.612672)
			(xy 105.068836 -393.55166) (xy 105.06837 -393.52093) (xy 103.453224 -393.52093) (xy 103.447388 -393.552062)
			(xy 103.428309 -393.611865) (xy 103.415592 -393.640564) (xy 103.413433 -393.64563) (xy 103.411127 -393.656395)
			(xy 103.41102 -393.6619) (xy 103.41102 -394.349478) (xy 103.411458 -394.359541) (xy 103.419194 -394.378123)
			(xy 103.426006 -394.385546) (xy 103.46309 -394.42263) (xy 103.470456 -394.42947) (xy 103.488989 -394.437212)
			(xy 103.509073 -394.437212) (xy 103.527606 -394.42947) (xy 103.534972 -394.42263) (xy 103.538528 -394.419074)
			(xy 103.541322 -394.414756) (xy 103.556549 -394.392619) (xy 103.592229 -394.352447) (xy 103.633195 -394.317681)
			(xy 103.678634 -394.289008) (xy 103.727647 -394.266996) (xy 103.779265 -394.252081) (xy 103.832465 -394.244559)
			(xy 103.85933 -394.244068) (xy 103.88658 -394.244556) (xy 103.940526 -394.252316) (xy 103.992819 -394.267673)
			(xy 104.042394 -394.290316) (xy 104.088242 -394.319782) (xy 104.129431 -394.355474) (xy 104.165121 -394.396663)
			(xy 104.194587 -394.442512) (xy 104.217229 -394.492087) (xy 104.232586 -394.54438) (xy 104.240345 -394.598326)
			(xy 104.240838 -394.625576) (xy 104.240373 -394.652865) (xy 104.232594 -394.706885) (xy 104.227235 -394.725101)
			(xy 110.721134 -394.725101) (xy 110.721134 -394.661179) (xy 110.729145 -394.597761) (xy 110.745042 -394.535847)
			(xy 110.768574 -394.476414) (xy 110.799368 -394.420399) (xy 110.836941 -394.368684) (xy 110.880698 -394.322087)
			(xy 110.929951 -394.281342) (xy 110.983922 -394.247091) (xy 111.041761 -394.219874) (xy 111.102554 -394.200121)
			(xy 111.165344 -394.188143) (xy 111.22914 -394.18413) (xy 111.292936 -394.188143) (xy 111.355726 -394.200121)
			(xy 111.416519 -394.219874) (xy 111.474358 -394.247091) (xy 111.528329 -394.281342) (xy 111.577582 -394.322087)
			(xy 111.621339 -394.368684) (xy 111.658912 -394.420399) (xy 111.689706 -394.476414) (xy 111.713238 -394.535847)
			(xy 111.729135 -394.597761) (xy 111.737146 -394.661179) (xy 111.737648 -394.69314) (xy 111.737146 -394.725101)
			(xy 111.729135 -394.788519) (xy 111.713238 -394.850433) (xy 111.689706 -394.909866) (xy 111.658912 -394.965881)
			(xy 111.621339 -395.017596) (xy 111.577582 -395.064193) (xy 111.528329 -395.104938) (xy 111.474358 -395.139189)
			(xy 111.416519 -395.166406) (xy 111.355726 -395.186159) (xy 111.292936 -395.198137) (xy 111.22914 -395.202151)
			(xy 111.165344 -395.198137) (xy 111.102554 -395.186159) (xy 111.041761 -395.166406) (xy 110.983922 -395.139189)
			(xy 110.929951 -395.104938) (xy 110.880698 -395.064193) (xy 110.836941 -395.017596) (xy 110.799368 -394.965881)
			(xy 110.768574 -394.909866) (xy 110.745042 -394.850433) (xy 110.729145 -394.788519) (xy 110.721134 -394.725101)
			(xy 104.227235 -394.725101) (xy 104.21719 -394.759244) (xy 104.194478 -394.808871) (xy 104.164921 -394.854752)
			(xy 104.129123 -394.89595) (xy 104.108758 -394.91412) (xy 104.10063 -394.921232) (xy 104.09174 -394.940028)
			(xy 104.088438 -395.025118) (xy 104.088589 -395.035642) (xy 104.096331 -395.055188) (xy 104.103424 -395.062964)
			(xy 104.248712 -395.208252) (xy 104.272842 -395.215618) (xy 104.285288 -395.213332) (xy 104.302841 -395.210237)
			(xy 104.338332 -395.20693) (xy 104.356154 -395.206728) (xy 104.382057 -395.207159) (xy 104.433386 -395.214164)
			(xy 104.483296 -395.22805) (xy 104.530866 -395.248564) (xy 104.553258 -395.261592) (xy 104.562656 -395.26718)
			(xy 104.583484 -395.269974) (xy 104.676194 -395.242796) (xy 104.692196 -395.229334) (xy 104.697022 -395.219428)
			(xy 104.70917 -395.195825) (xy 104.739018 -395.151927) (xy 104.774662 -395.11259) (xy 104.815413 -395.078573)
			(xy 104.860486 -395.050532) (xy 104.909011 -395.029008) (xy 104.96005 -395.014417) (xy 105.012618 -395.007041)
			(xy 105.03916 -395.006576) (xy 105.066415 -395.007036) (xy 105.120371 -395.014788) (xy 105.172675 -395.030141)
			(xy 105.222261 -395.052781) (xy 105.268121 -395.082248) (xy 105.309319 -395.117941) (xy 105.345019 -395.159135)
			(xy 105.374492 -395.20499) (xy 105.39714 -395.254572) (xy 105.4125 -395.306874) (xy 105.42026 -395.360829)
			(xy 105.420668 -395.388084) (xy 105.420014 -395.420402) (xy 105.409165 -395.48412) (xy 105.399078 -395.51483)
			(xy 105.39603 -395.523466) (xy 105.396284 -395.5415) (xy 105.426764 -395.62024) (xy 105.438956 -395.633702)
			(xy 105.447084 -395.63802) (xy 105.478148 -395.655318) (xy 105.535545 -395.697281) (xy 105.586524 -395.746843)
			(xy 105.630088 -395.803035) (xy 105.648252 -395.8336) (xy 105.653021 -395.841157) (xy 105.666722 -395.852612)
			(xy 105.683518 -395.858681) (xy 105.692448 -395.859)
		)
		(stroke
			(width 0)
			(type solid)
		)
		(fill yes)
		(layer "In15.Cu")
		(net "P0V9_CPU1_RT3_2A_2D")
	)
	(gr_poly
		(pts
			(xy 30.404308 -417.010342) (xy 30.414376 -417.009916) (xy 30.432973 -417.002193) (xy 30.440376 -416.995356)
			(xy 31.798006 -415.637726) (xy 31.806485 -415.628371) (xy 31.813815 -415.604244) (xy 31.811976 -415.591752)
			(xy 31.808538 -415.573403) (xy 31.804851 -415.536251) (xy 31.80461 -415.517584) (xy 31.80461 -415.516822)
			(xy 31.805238 -415.48618) (xy 31.815056 -415.425688) (xy 31.824168 -415.396426) (xy 31.82874 -415.38271)
			(xy 31.822136 -415.35477) (xy 31.7373 -415.269934) (xy 31.70936 -415.26333) (xy 31.695644 -415.267902)
			(xy 31.666381 -415.277013) (xy 31.60589 -415.286837) (xy 31.575248 -415.28746) (xy 31.547995 -415.286997)
			(xy 31.494044 -415.279239) (xy 31.441746 -415.263883) (xy 31.392166 -415.24124) (xy 31.346312 -415.211772)
			(xy 31.30512 -415.176078) (xy 31.269426 -415.134884) (xy 31.239958 -415.089031) (xy 31.217316 -415.03945)
			(xy 31.20196 -414.987152) (xy 31.194203 -414.933201) (xy 31.194203 -414.878695) (xy 31.201961 -414.824744)
			(xy 31.217317 -414.772446) (xy 31.23996 -414.722866) (xy 31.269428 -414.677012) (xy 31.305122 -414.63582)
			(xy 31.346316 -414.600126) (xy 31.392169 -414.570658) (xy 31.44175 -414.548016) (xy 31.494048 -414.53266)
			(xy 31.547999 -414.524903) (xy 31.602505 -414.524903) (xy 31.656456 -414.532661) (xy 31.708754 -414.548017)
			(xy 31.758334 -414.57066) (xy 31.804188 -414.600128) (xy 31.84538 -414.635822) (xy 31.881074 -414.677016)
			(xy 31.910542 -414.722869) (xy 31.933184 -414.77245) (xy 31.94854 -414.824748) (xy 31.956297 -414.878699)
			(xy 31.956756 -414.905952) (xy 31.956122 -414.936592) (xy 31.946292 -414.997081) (xy 31.937198 -415.026348)
			(xy 31.932626 -415.040064) (xy 31.93923 -415.068004) (xy 32.024066 -415.15284) (xy 32.052006 -415.159444)
			(xy 32.065722 -415.154872) (xy 32.094984 -415.145757) (xy 32.155476 -415.135926) (xy 32.186118 -415.135314)
			(xy 32.18688 -415.135314) (xy 32.205546 -415.135566) (xy 32.242697 -415.139256) (xy 32.261048 -415.14268)
			(xy 32.273533 -415.144473) (xy 32.297631 -415.137133) (xy 32.307022 -415.12871) (xy 33.549082 -413.88665)
			(xy 33.555923 -413.87925) (xy 33.563642 -413.860651) (xy 33.564068 -413.850582) (xy 33.564068 -395.581124)
			(xy 33.56363 -395.571061) (xy 33.555893 -395.552479) (xy 33.549082 -395.545056) (xy 30.803342 -392.799062)
			(xy 30.780663 -392.775752) (xy 30.740096 -392.724916) (xy 30.705472 -392.669861) (xy 30.677224 -392.611277)
			(xy 30.655709 -392.549901) (xy 30.641197 -392.486503) (xy 30.633868 -392.421879) (xy 30.633416 -392.38936)
			(xy 30.633416 -388.071868) (xy 30.632988 -388.0618) (xy 30.625267 -388.043202) (xy 30.61843 -388.0358)
			(xy 30.318456 -387.735572) (xy 30.311608 -387.728175) (xy 30.303875 -387.709576) (xy 30.30347 -387.699504)
			(xy 30.30347 -384.751072) (xy 30.30338 -384.746052) (xy 30.301463 -384.736199) (xy 30.29966 -384.731514)
			(xy 30.108906 -384.27152) (xy 30.106895 -384.266959) (xy 30.101388 -384.258652) (xy 30.097984 -384.25501)
			(xy 29.577538 -383.734564) (xy 29.56687 -383.730754) (xy 29.540299 -383.720818) (xy 29.4902 -383.694213)
			(xy 29.444593 -383.660482) (xy 29.404485 -383.620368) (xy 29.370759 -383.574757) (xy 29.344161 -383.524654)
			(xy 29.334206 -383.49809) (xy 29.330396 -383.487422) (xy 28.482798 -382.639824) (xy 28.475964 -382.632421)
			(xy 28.468258 -382.613823) (xy 28.467812 -382.603756) (xy 28.467812 -380.31928) (xy 28.467723 -380.31426)
			(xy 28.465809 -380.304406) (xy 28.464002 -380.299722) (xy 28.430982 -380.220474) (xy 28.426505 -380.210947)
			(xy 28.411406 -380.196312) (xy 28.391722 -380.188917) (xy 28.381198 -380.188978) (xy 28.26893 -380.195582)
			(xy 28.243784 -380.215902) (xy 28.239466 -380.23165) (xy 28.230241 -380.261857) (xy 28.20328 -380.318968)
			(xy 28.167287 -380.370862) (xy 28.14574 -380.393956) (xy 28.138882 -380.400814) (xy 28.131516 -380.419102)
			(xy 28.131008 -380.499112) (xy 28.131339 -380.508761) (xy 28.138263 -380.526768) (xy 28.14447 -380.534164)
			(xy 28.144724 -380.534418) (xy 28.164079 -380.555764) (xy 28.196796 -380.603194) (xy 28.222012 -380.655002)
			(xy 28.239155 -380.710013) (xy 28.247833 -380.766975) (xy 28.248356 -380.795784) (xy 28.247868 -380.823388)
			(xy 28.239912 -380.87802) (xy 28.224163 -380.930934) (xy 28.20095 -380.981025) (xy 28.170759 -381.027247)
			(xy 28.152852 -381.04826) (xy 28.146248 -381.05588) (xy 28.139644 -381.07493) (xy 28.144724 -381.156718)
			(xy 28.145846 -381.166634) (xy 28.154604 -381.184543) (xy 28.161742 -381.191516) (xy 28.181607 -381.209702)
			(xy 28.216532 -381.250699) (xy 28.245348 -381.296198) (xy 28.26748 -381.345297) (xy 28.282491 -381.397019)
			(xy 28.290081 -381.450338) (xy 28.29052 -381.477266) (xy 28.290059 -381.504521) (xy 28.282307 -381.558476)
			(xy 28.266954 -381.610779) (xy 28.244313 -381.660364) (xy 28.214846 -381.706222) (xy 28.179153 -381.74742)
			(xy 28.137959 -381.783119) (xy 28.092104 -381.812591) (xy 28.042522 -381.835237) (xy 27.990221 -381.850597)
			(xy 27.936267 -381.858356) (xy 27.909012 -381.858774) (xy 27.882654 -381.85833) (xy 27.830441 -381.851071)
			(xy 27.779725 -381.83669) (xy 27.731473 -381.815462) (xy 27.686605 -381.78779) (xy 27.645975 -381.754202)
			(xy 27.627834 -381.735076) (xy 27.62076 -381.728032) (xy 27.602718 -381.719534) (xy 27.592782 -381.718566)
			(xy 27.510994 -381.714756) (xy 27.491944 -381.721614) (xy 27.484578 -381.728472) (xy 27.463397 -381.747014)
			(xy 27.416606 -381.77831) (xy 27.365728 -381.802397) (xy 27.311865 -381.818753) (xy 27.256184 -381.827023)
			(xy 27.228038 -381.827532) (xy 27.227784 -381.827532) (xy 27.200144 -381.827046) (xy 27.145441 -381.819074)
			(xy 27.092464 -381.803285) (xy 27.042322 -381.780009) (xy 26.996068 -381.749736) (xy 26.975054 -381.731774)
			(xy 26.967942 -381.725424) (xy 26.950162 -381.71882) (xy 26.86177 -381.720598) (xy 26.844244 -381.727964)
			(xy 26.837386 -381.734568) (xy 26.815931 -381.754529) (xy 26.768036 -381.788292) (xy 26.715539 -381.81433)
			(xy 26.659677 -381.832029) (xy 26.601764 -381.840974) (xy 26.572464 -381.841502) (xy 26.546976 -381.841075)
			(xy 26.496455 -381.834284) (xy 26.447288 -381.820827) (xy 26.40035 -381.800943) (xy 26.356477 -381.774988)
			(xy 26.31645 -381.743422) (xy 26.298398 -381.725424) (xy 26.291032 -381.717804) (xy 26.271728 -381.709676)
			(xy 26.17597 -381.711454) (xy 26.15692 -381.720344) (xy 26.149808 -381.728218) (xy 26.131646 -381.747757)
			(xy 26.090805 -381.782077) (xy 26.045583 -381.810375) (xy 25.996861 -381.832099) (xy 25.945587 -381.846825)
			(xy 25.892763 -381.854267) (xy 25.86609 -381.85471) (xy 25.838839 -381.854224) (xy 25.784892 -381.846466)
			(xy 25.732599 -381.83111) (xy 25.683023 -381.808468) (xy 25.637173 -381.779002) (xy 25.595984 -381.74331)
			(xy 25.560294 -381.70212) (xy 25.530828 -381.65627) (xy 25.508187 -381.606694) (xy 25.492832 -381.5544)
			(xy 25.485076 -381.500453) (xy 25.484582 -381.473202) (xy 25.485191 -381.442146) (xy 25.49525 -381.380853)
			(xy 25.515102 -381.321998) (xy 25.544223 -381.267134) (xy 25.56256 -381.242062) (xy 25.562814 -381.241808)
			(xy 25.568267 -381.233811) (xy 25.573342 -381.215147) (xy 25.57272 -381.205486) (xy 25.563576 -381.125476)
			(xy 25.554178 -381.108458) (xy 25.546558 -381.102108) (xy 25.525301 -381.083882) (xy 25.487836 -381.042268)
			(xy 25.45685 -380.99563) (xy 25.433006 -380.944967) (xy 25.416817 -380.891364) (xy 25.408629 -380.835973)
			(xy 25.408128 -380.807976) (xy 25.408591 -380.781078) (xy 25.416152 -380.727816) (xy 25.431121 -380.676145)
			(xy 25.453201 -380.627089) (xy 25.481954 -380.581622) (xy 25.51681 -380.540646) (xy 25.536652 -380.52248)
			(xy 25.544005 -380.515273) (xy 25.552791 -380.49667) (xy 25.55367 -380.486412) (xy 25.556718 -380.402084)
			(xy 25.549352 -380.383034) (xy 25.541986 -380.375414) (xy 25.521769 -380.353906) (xy 25.487545 -380.305816)
			(xy 25.461136 -380.253028) (xy 25.443174 -380.196802) (xy 25.434087 -380.138481) (xy 25.433528 -380.108968)
			(xy 25.434002 -380.081599) (xy 25.44183 -380.027423) (xy 25.457322 -379.974923) (xy 25.480158 -379.925176)
			(xy 25.509871 -379.879204) (xy 25.527508 -379.85827) (xy 25.527508 -379.858016) (xy 25.527762 -379.858016)
			(xy 25.533353 -379.850931) (xy 25.539605 -379.834014) (xy 25.539954 -379.824996) (xy 25.539954 -379.75794)
			(xy 25.539602 -379.74892) (xy 25.53337 -379.731991) (xy 25.527762 -379.72492) (xy 25.527508 -379.724666)
			(xy 25.509868 -379.703734) (xy 25.480145 -379.657767) (xy 25.457306 -379.60802) (xy 25.44182 -379.555517)
			(xy 25.434006 -379.501338) (xy 25.433528 -379.473968) (xy 25.434076 -379.444527) (xy 25.443126 -379.386346)
			(xy 25.461006 -379.330245) (xy 25.487292 -379.277557) (xy 25.52136 -379.229532) (xy 25.541478 -379.20803)
			(xy 25.54859 -379.200918) (xy 25.555956 -379.182122) (xy 25.554178 -379.089412) (xy 25.54605 -379.07087)
			(xy 25.538684 -379.064012) (xy 25.520401 -379.045944) (xy 25.488358 -379.005751) (xy 25.461998 -378.961622)
			(xy 25.441796 -378.914355) (xy 25.428119 -378.864806) (xy 25.421213 -378.813869) (xy 25.420828 -378.788168)
			(xy 25.421294 -378.760918) (xy 25.429054 -378.706972) (xy 25.444414 -378.65468) (xy 25.467058 -378.605106)
			(xy 25.496528 -378.55926) (xy 25.532222 -378.518074) (xy 25.573414 -378.482387) (xy 25.619266 -378.452926)
			(xy 25.668844 -378.43029) (xy 25.721139 -378.41494) (xy 25.775085 -378.407189) (xy 25.802336 -378.40666)
			(xy 25.831074 -378.407184) (xy 25.887898 -378.415812) (xy 25.942784 -378.432869) (xy 25.99449 -378.457967)
			(xy 26.041845 -378.490538) (xy 26.063194 -378.509784) (xy 26.070052 -378.516388) (xy 26.088086 -378.5235)
			(xy 26.176986 -378.5235) (xy 26.19502 -378.516388) (xy 26.201878 -378.509784) (xy 26.223205 -378.490514)
			(xy 26.270568 -378.457949) (xy 26.322279 -378.432858) (xy 26.37717 -378.415808) (xy 26.433997 -378.407186)
			(xy 26.491475 -378.407186) (xy 26.548302 -378.415808) (xy 26.603193 -378.432858) (xy 26.654904 -378.457949)
			(xy 26.702267 -378.490514) (xy 26.723594 -378.509784) (xy 26.730452 -378.516388) (xy 26.748486 -378.5235)
			(xy 26.837386 -378.5235) (xy 26.85542 -378.516388) (xy 26.862278 -378.509784) (xy 26.883604 -378.490511)
			(xy 26.930966 -378.457941) (xy 26.982677 -378.432844) (xy 27.037568 -378.415787) (xy 27.094396 -378.407155)
			(xy 27.123136 -378.40666) (xy 27.152188 -378.407207) (xy 27.209621 -378.416018) (xy 27.265055 -378.433431)
			(xy 27.31721 -378.459043) (xy 27.364881 -378.492264) (xy 27.406967 -378.532325) (xy 27.425142 -378.554996)
			(xy 27.432254 -378.56414) (xy 27.45232 -378.5743) (xy 27.54249 -378.57684) (xy 27.553921 -378.576484)
			(xy 27.574745 -378.567102) (xy 27.582622 -378.558806) (xy 27.600829 -378.53831) (xy 27.64211 -378.502236)
			(xy 27.688129 -378.472443) (xy 27.737939 -378.449543) (xy 27.790514 -378.434009) (xy 27.844771 -378.426159)
			(xy 27.872182 -378.42571) (xy 27.897635 -378.426132) (xy 27.948089 -378.432903) (xy 27.997194 -378.446328)
			(xy 28.044075 -378.466168) (xy 28.0879 -378.49207) (xy 28.108148 -378.507498) (xy 28.108402 -378.507752)
			(xy 28.116095 -378.513263) (xy 28.134215 -378.51867) (xy 28.153061 -378.51711) (xy 28.161742 -378.51334)
			(xy 28.244038 -378.473462) (xy 28.252438 -378.468962) (xy 28.265378 -378.45499) (xy 28.272335 -378.437263)
			(xy 28.27274 -378.427742) (xy 28.27274 -378.402342) (xy 28.272209 -378.391319) (xy 28.263006 -378.371285)
			(xy 28.25496 -378.363734) (xy 28.195778 -378.313696) (xy 28.187032 -378.307001) (xy 28.165837 -378.301093)
			(xy 28.154884 -378.302266) (xy 28.15463 -378.302266) (xy 28.139493 -378.304539) (xy 28.108976 -378.306951)
			(xy 28.09367 -378.307092) (xy 28.06556 -378.30659) (xy 28.009947 -378.298341) (xy 27.956146 -378.282026)
			(xy 27.905319 -378.257997) (xy 27.858566 -378.226773) (xy 27.837384 -378.208286) (xy 27.830272 -378.201682)
			(xy 27.813 -378.195078) (xy 27.735276 -378.194824) (xy 27.725918 -378.195131) (xy 27.708427 -378.201778)
			(xy 27.70124 -378.207778) (xy 27.700986 -378.208032) (xy 27.679861 -378.226441) (xy 27.633224 -378.257502)
			(xy 27.582543 -378.281401) (xy 27.528909 -378.297624) (xy 27.473479 -378.305821) (xy 27.445462 -378.30633)
			(xy 27.416724 -378.305806) (xy 27.359901 -378.297177) (xy 27.305015 -378.28012) (xy 27.25331 -378.255021)
			(xy 27.205955 -378.222449) (xy 27.184604 -378.203206) (xy 27.177746 -378.196602) (xy 27.159712 -378.18949)
			(xy 27.070812 -378.18949) (xy 27.052778 -378.196602) (xy 27.04592 -378.203206) (xy 27.024594 -378.222479)
			(xy 26.977232 -378.25505) (xy 26.925521 -378.280147) (xy 26.87063 -378.297205) (xy 26.813802 -378.305836)
			(xy 26.785062 -378.30633) (xy 26.754241 -378.305714) (xy 26.693405 -378.295763) (xy 26.634957 -378.276173)
			(xy 26.580412 -378.247452) (xy 26.555446 -378.229368) (xy 26.554938 -378.22886) (xy 26.547572 -378.223526)
			(xy 26.530046 -378.218446) (xy 26.453084 -378.224542) (xy 26.443841 -378.225644) (xy 26.427022 -378.23358)
			(xy 26.420318 -378.240036) (xy 26.402266 -378.258348) (xy 26.362093 -378.290446) (xy 26.317971 -378.316855)
			(xy 26.2707 -378.337095) (xy 26.221138 -378.350799) (xy 26.170185 -378.357719) (xy 26.144474 -378.358146)
			(xy 26.117223 -378.357658) (xy 26.063276 -378.349899) (xy 26.010982 -378.334542) (xy 25.961406 -378.3119)
			(xy 25.915556 -378.282434) (xy 25.874366 -378.246743) (xy 25.838674 -378.205554) (xy 25.809206 -378.159705)
			(xy 25.786562 -378.110129) (xy 25.771203 -378.057836) (xy 25.763442 -378.003889) (xy 25.762966 -377.976638)
			(xy 25.763436 -377.949667) (xy 25.771041 -377.896262) (xy 25.78609 -377.844461) (xy 25.808283 -377.795295)
			(xy 25.837179 -377.749744) (xy 25.872201 -377.708716) (xy 25.912651 -377.673028) (xy 25.957724 -377.643392)
			(xy 25.981914 -377.631452) (xy 25.992836 -377.626372) (xy 26.007568 -377.60783) (xy 26.026618 -377.516644)
			(xy 26.028452 -377.504996) (xy 26.022494 -377.482211) (xy 26.015188 -377.472956) (xy 25.997598 -377.452029)
			(xy 25.967965 -377.40609) (xy 25.945192 -377.356392) (xy 25.929745 -377.303953) (xy 25.921941 -377.249846)
			(xy 25.921462 -377.222512) (xy 25.921995 -377.193596) (xy 25.930722 -377.136425) (xy 25.947977 -377.081226)
			(xy 25.973364 -377.029263) (xy 26.006304 -376.981728) (xy 26.04604 -376.939708) (xy 26.068528 -376.921522)
			(xy 26.077354 -376.91393) (xy 26.087532 -376.89302) (xy 26.088086 -376.88139) (xy 26.088086 -376.801634)
			(xy 26.087516 -376.790011) (xy 26.077331 -376.769113) (xy 26.068528 -376.761502) (xy 26.047746 -376.744748)
			(xy 26.010616 -376.706393) (xy 25.979196 -376.663237) (xy 25.954098 -376.616123) (xy 25.935811 -376.565971)
			(xy 25.924695 -376.513759) (xy 25.920964 -376.460507) (xy 25.924692 -376.407256) (xy 25.935807 -376.355043)
			(xy 25.954092 -376.30489) (xy 25.979188 -376.257775) (xy 26.010607 -376.214618) (xy 26.047735 -376.176262)
			(xy 26.068528 -376.159522) (xy 26.077354 -376.15193) (xy 26.087532 -376.13102) (xy 26.088086 -376.11939)
			(xy 26.088086 -376.039634) (xy 26.087516 -376.028011) (xy 26.077331 -376.007113) (xy 26.068528 -375.999502)
			(xy 26.046045 -375.981312) (xy 26.006308 -375.939294) (xy 25.97337 -375.89176) (xy 25.947986 -375.839797)
			(xy 25.930738 -375.784598) (xy 25.92202 -375.727428) (xy 25.921462 -375.698512) (xy 25.922015 -375.668963)
			(xy 25.931126 -375.610571) (xy 25.949131 -375.554282) (xy 25.975601 -375.501443) (xy 26.009901 -375.453317)
			(xy 26.030174 -375.431812) (xy 26.036714 -375.424482) (xy 26.044146 -375.406318) (xy 26.044652 -375.396506)
			(xy 26.04516 -375.325894) (xy 26.04472 -375.316201) (xy 26.037522 -375.298198) (xy 26.03119 -375.290842)
			(xy 26.030936 -375.290588) (xy 26.011263 -375.269161) (xy 25.977977 -375.221458) (xy 25.952315 -375.169258)
			(xy 25.93487 -375.113768) (xy 25.926046 -375.056274) (xy 25.925526 -375.02719) (xy 25.925943 -375.001821)
			(xy 25.932668 -374.951532) (xy 25.945999 -374.902577) (xy 25.9657 -374.855821) (xy 25.991424 -374.812088)
			(xy 26.022716 -374.772149) (xy 26.040588 -374.75414) (xy 26.041096 -374.753632) (xy 26.041604 -374.753124)
			(xy 26.048286 -374.74571) (xy 26.055881 -374.727276) (xy 26.055884 -374.707338) (xy 26.048294 -374.688902)
			(xy 26.041604 -374.681496) (xy 25.081484 -373.72163) (xy 25.074086 -373.714783) (xy 25.055488 -373.707049)
			(xy 25.045416 -373.706644) (xy 20.319746 -373.706644) (xy 20.309681 -373.706209) (xy 20.291097 -373.698475)
			(xy 20.283678 -373.691658) (xy 19.330162 -372.738142) (xy 19.323318 -372.730743) (xy 19.315595 -372.712144)
			(xy 19.315176 -372.702074) (xy 19.315176 -370.66855) (xy 19.314743 -370.658484) (xy 19.307013 -370.639895)
			(xy 19.30019 -370.632482) (xy 18.265394 -369.597686) (xy 18.257999 -369.590831) (xy 18.2394 -369.583085)
			(xy 18.229326 -369.5827) (xy 5.259324 -369.5827) (xy 5.24926 -369.583137) (xy 5.230676 -369.590871)
			(xy 5.223256 -369.597686) (xy 4.491482 -370.329714) (xy 4.484629 -370.337109) (xy 4.476887 -370.355708)
			(xy 4.476496 -370.365782) (xy 4.476496 -376.70105) (xy 8.208781 -376.70105) (xy 8.21251 -376.647799)
			(xy 8.223627 -376.595587) (xy 8.241913 -376.545435) (xy 8.267012 -376.498321) (xy 8.298433 -376.455167)
			(xy 8.335563 -376.416813) (xy 8.356346 -376.40006) (xy 8.365169 -376.392468) (xy 8.375342 -376.371556)
			(xy 8.375904 -376.359928) (xy 8.375904 -376.280172) (xy 8.375365 -376.26854) (xy 8.365176 -376.247631)
			(xy 8.356346 -376.24004) (xy 8.335563 -376.223287) (xy 8.298433 -376.184933) (xy 8.267012 -376.141779)
			(xy 8.241913 -376.094665) (xy 8.223627 -376.044513) (xy 8.21251 -375.992301) (xy 8.208781 -375.93905)
			(xy 8.21251 -375.885799) (xy 8.223627 -375.833587) (xy 8.241913 -375.783435) (xy 8.267012 -375.736321)
			(xy 8.298433 -375.693167) (xy 8.335563 -375.654813) (xy 8.356346 -375.63806) (xy 8.365169 -375.630468)
			(xy 8.375342 -375.609556) (xy 8.375904 -375.597928) (xy 8.375904 -375.518172) (xy 8.375365 -375.50654)
			(xy 8.365176 -375.485631) (xy 8.356346 -375.47804) (xy 8.33387 -375.45984) (xy 8.294137 -375.417821)
			(xy 8.261199 -375.370287) (xy 8.23581 -375.318328) (xy 8.218551 -375.263133) (xy 8.209818 -375.205965)
			(xy 8.20928 -375.17705) (xy 8.209766 -375.149799) (xy 8.217522 -375.095851) (xy 8.232877 -375.043556)
			(xy 8.255519 -374.993979) (xy 8.284985 -374.948129) (xy 8.320676 -374.906938) (xy 8.361867 -374.871247)
			(xy 8.407717 -374.841781) (xy 8.457294 -374.819139) (xy 8.509589 -374.803784) (xy 8.563537 -374.796028)
			(xy 8.618039 -374.796028) (xy 8.671987 -374.803784) (xy 8.724282 -374.819139) (xy 8.773859 -374.841781)
			(xy 8.819709 -374.871247) (xy 8.8609 -374.906938) (xy 8.896591 -374.948129) (xy 8.926057 -374.993979)
			(xy 8.948699 -375.043556) (xy 8.964054 -375.095851) (xy 8.97181 -375.149799) (xy 8.972296 -375.17705)
			(xy 8.971743 -375.205966) (xy 8.963022 -375.263135) (xy 8.945771 -375.318334) (xy 8.920385 -375.370295)
			(xy 8.887448 -375.41783) (xy 8.847713 -375.459849) (xy 8.82523 -375.47804) (xy 8.816403 -375.485628)
			(xy 8.806233 -375.506544) (xy 8.805672 -375.518172) (xy 8.805672 -375.597928) (xy 8.806184 -375.609564)
			(xy 8.816389 -375.630475) (xy 8.82523 -375.63806) (xy 8.846013 -375.654813) (xy 8.883144 -375.693166)
			(xy 8.914565 -375.736321) (xy 8.939664 -375.783435) (xy 8.95795 -375.833587) (xy 8.969067 -375.885798)
			(xy 8.972797 -375.93905) (xy 8.969067 -375.992302) (xy 8.95795 -376.044513) (xy 8.939664 -376.094665)
			(xy 8.914565 -376.141779) (xy 8.883144 -376.184934) (xy 8.846013 -376.223287) (xy 8.82523 -376.24004)
			(xy 8.816403 -376.247628) (xy 8.806233 -376.268544) (xy 8.805672 -376.280172) (xy 8.805672 -376.359928)
			(xy 8.806184 -376.371564) (xy 8.816389 -376.392475) (xy 8.82523 -376.40006) (xy 8.846013 -376.416813)
			(xy 8.883144 -376.455166) (xy 8.914565 -376.498321) (xy 8.939664 -376.545435) (xy 8.95795 -376.595587)
			(xy 8.969067 -376.647798) (xy 8.972797 -376.70105) (xy 10.494781 -376.70105) (xy 10.49851 -376.647799)
			(xy 10.509627 -376.595587) (xy 10.527913 -376.545435) (xy 10.553012 -376.498321) (xy 10.584433 -376.455167)
			(xy 10.621563 -376.416813) (xy 10.642346 -376.40006) (xy 10.651169 -376.392468) (xy 10.661342 -376.371556)
			(xy 10.661904 -376.359928) (xy 10.661904 -376.280172) (xy 10.661365 -376.26854) (xy 10.651176 -376.247631)
			(xy 10.642346 -376.24004) (xy 10.621563 -376.223287) (xy 10.584433 -376.184933) (xy 10.553012 -376.141779)
			(xy 10.527913 -376.094665) (xy 10.509627 -376.044513) (xy 10.49851 -375.992301) (xy 10.494781 -375.93905)
			(xy 10.49851 -375.885799) (xy 10.509627 -375.833587) (xy 10.527913 -375.783435) (xy 10.553012 -375.736321)
			(xy 10.584433 -375.693167) (xy 10.621563 -375.654813) (xy 10.642346 -375.63806) (xy 10.651169 -375.630468)
			(xy 10.661342 -375.609556) (xy 10.661904 -375.597928) (xy 10.661904 -375.518172) (xy 10.661365 -375.50654)
			(xy 10.651176 -375.485631) (xy 10.642346 -375.47804) (xy 10.61987 -375.45984) (xy 10.580137 -375.417821)
			(xy 10.547199 -375.370287) (xy 10.52181 -375.318328) (xy 10.504551 -375.263133) (xy 10.495818 -375.205965)
			(xy 10.49528 -375.17705) (xy 10.495766 -375.149799) (xy 10.503522 -375.095851) (xy 10.518877 -375.043556)
			(xy 10.541519 -374.993979) (xy 10.570985 -374.948129) (xy 10.606676 -374.906938) (xy 10.647867 -374.871247)
			(xy 10.693717 -374.841781) (xy 10.743294 -374.819139) (xy 10.795589 -374.803784) (xy 10.849537 -374.796028)
			(xy 10.904039 -374.796028) (xy 10.957987 -374.803784) (xy 11.010282 -374.819139) (xy 11.059859 -374.841781)
			(xy 11.105709 -374.871247) (xy 11.1469 -374.906938) (xy 11.182591 -374.948129) (xy 11.212057 -374.993979)
			(xy 11.234699 -375.043556) (xy 11.250054 -375.095851) (xy 11.25781 -375.149799) (xy 11.258296 -375.17705)
			(xy 11.257743 -375.205966) (xy 11.249022 -375.263135) (xy 11.231771 -375.318334) (xy 11.206385 -375.370295)
			(xy 11.173448 -375.41783) (xy 11.133713 -375.459849) (xy 11.11123 -375.47804) (xy 11.102403 -375.485628)
			(xy 11.092233 -375.506544) (xy 11.091672 -375.518172) (xy 11.091672 -375.597928) (xy 11.092184 -375.609564)
			(xy 11.102389 -375.630475) (xy 11.11123 -375.63806) (xy 11.132013 -375.654813) (xy 11.169144 -375.693166)
			(xy 11.200565 -375.736321) (xy 11.225664 -375.783435) (xy 11.24395 -375.833587) (xy 11.255067 -375.885798)
			(xy 11.258797 -375.93905) (xy 11.255067 -375.992302) (xy 11.24395 -376.044513) (xy 11.225664 -376.094665)
			(xy 11.200565 -376.141779) (xy 11.169144 -376.184934) (xy 11.132013 -376.223287) (xy 11.11123 -376.24004)
			(xy 11.102403 -376.247628) (xy 11.092233 -376.268544) (xy 11.091672 -376.280172) (xy 11.091672 -376.359928)
			(xy 11.092184 -376.371564) (xy 11.102389 -376.392475) (xy 11.11123 -376.40006) (xy 11.132013 -376.416813)
			(xy 11.169144 -376.455166) (xy 11.200565 -376.498321) (xy 11.225664 -376.545435) (xy 11.24395 -376.595587)
			(xy 11.255067 -376.647798) (xy 11.258797 -376.70105) (xy 11.255067 -376.754302) (xy 11.24395 -376.806513)
			(xy 11.225664 -376.856665) (xy 11.200565 -376.903779) (xy 11.169144 -376.946934) (xy 11.132013 -376.985287)
			(xy 11.11123 -377.00204) (xy 11.102403 -377.009628) (xy 11.092233 -377.030544) (xy 11.091672 -377.042172)
			(xy 11.091672 -377.121928) (xy 11.092184 -377.133564) (xy 11.102389 -377.154475) (xy 11.11123 -377.16206)
			(xy 11.133701 -377.180266) (xy 11.173435 -377.222284) (xy 11.206375 -377.269816) (xy 11.231765 -377.321774)
			(xy 11.249025 -377.376968) (xy 11.257758 -377.434135) (xy 11.258296 -377.46305) (xy 11.25781 -377.490301)
			(xy 11.250054 -377.544249) (xy 11.234699 -377.596544) (xy 11.212057 -377.646121) (xy 11.182591 -377.691971)
			(xy 11.1469 -377.733162) (xy 11.105709 -377.768853) (xy 11.059859 -377.798319) (xy 11.010282 -377.820961)
			(xy 10.957987 -377.836316) (xy 10.904039 -377.844072) (xy 10.849537 -377.844072) (xy 10.795589 -377.836316)
			(xy 10.743294 -377.820961) (xy 10.693717 -377.798319) (xy 10.647867 -377.768853) (xy 10.606676 -377.733162)
			(xy 10.570985 -377.691971) (xy 10.541519 -377.646121) (xy 10.518877 -377.596544) (xy 10.503522 -377.544249)
			(xy 10.495766 -377.490301) (xy 10.49528 -377.46305) (xy 10.495804 -377.434133) (xy 10.504528 -377.376961)
			(xy 10.521783 -377.321761) (xy 10.547173 -377.269798) (xy 10.580117 -377.222265) (xy 10.61986 -377.180249)
			(xy 10.642346 -377.16206) (xy 10.651169 -377.154468) (xy 10.661342 -377.133556) (xy 10.661904 -377.121928)
			(xy 10.661904 -377.042172) (xy 10.661365 -377.03054) (xy 10.651176 -377.009631) (xy 10.642346 -377.00204)
			(xy 10.621563 -376.985287) (xy 10.584433 -376.946933) (xy 10.553012 -376.903779) (xy 10.527913 -376.856665)
			(xy 10.509627 -376.806513) (xy 10.49851 -376.754301) (xy 10.494781 -376.70105) (xy 8.972797 -376.70105)
			(xy 8.969067 -376.754302) (xy 8.95795 -376.806513) (xy 8.939664 -376.856665) (xy 8.914565 -376.903779)
			(xy 8.883144 -376.946934) (xy 8.846013 -376.985287) (xy 8.82523 -377.00204) (xy 8.816403 -377.009628)
			(xy 8.806233 -377.030544) (xy 8.805672 -377.042172) (xy 8.805672 -377.121928) (xy 8.806184 -377.133564)
			(xy 8.816389 -377.154475) (xy 8.82523 -377.16206) (xy 8.847701 -377.180266) (xy 8.887435 -377.222284)
			(xy 8.920375 -377.269816) (xy 8.945765 -377.321774) (xy 8.963025 -377.376968) (xy 8.971758 -377.434135)
			(xy 8.972296 -377.46305) (xy 8.97181 -377.490301) (xy 8.964054 -377.544249) (xy 8.948699 -377.596544)
			(xy 8.926057 -377.646121) (xy 8.896591 -377.691971) (xy 8.8609 -377.733162) (xy 8.819709 -377.768853)
			(xy 8.773859 -377.798319) (xy 8.724282 -377.820961) (xy 8.671987 -377.836316) (xy 8.618039 -377.844072)
			(xy 8.563537 -377.844072) (xy 8.509589 -377.836316) (xy 8.457294 -377.820961) (xy 8.407717 -377.798319)
			(xy 8.361867 -377.768853) (xy 8.320676 -377.733162) (xy 8.284985 -377.691971) (xy 8.255519 -377.646121)
			(xy 8.232877 -377.596544) (xy 8.217522 -377.544249) (xy 8.209766 -377.490301) (xy 8.20928 -377.46305)
			(xy 8.209804 -377.434133) (xy 8.218528 -377.376961) (xy 8.235783 -377.321761) (xy 8.261173 -377.269798)
			(xy 8.294117 -377.222265) (xy 8.33386 -377.180249) (xy 8.356346 -377.16206) (xy 8.365169 -377.154468)
			(xy 8.375342 -377.133556) (xy 8.375904 -377.121928) (xy 8.375904 -377.042172) (xy 8.375365 -377.03054)
			(xy 8.365176 -377.009631) (xy 8.356346 -377.00204) (xy 8.335563 -376.985287) (xy 8.298433 -376.946933)
			(xy 8.267012 -376.903779) (xy 8.241913 -376.856665) (xy 8.223627 -376.806513) (xy 8.21251 -376.754301)
			(xy 8.208781 -376.70105) (xy 4.476496 -376.70105) (xy 4.476496 -377.963938) (xy 14.292072 -377.963938)
			(xy 14.292072 -377.963684) (xy 14.292551 -377.937359) (xy 14.299803 -377.885211) (xy 14.314154 -377.834554)
			(xy 14.33533 -377.786351) (xy 14.362931 -377.741515) (xy 14.396432 -377.700899) (xy 14.415516 -377.68276)
			(xy 14.42339 -377.675648) (xy 14.432026 -377.656598) (xy 14.43355 -377.572778) (xy 14.433238 -377.562513)
			(xy 14.425514 -377.543508) (xy 14.418564 -377.535948) (xy 14.41831 -377.535694) (xy 14.397291 -377.514057)
			(xy 14.361641 -377.465399) (xy 14.334096 -377.411735) (xy 14.315343 -377.354404) (xy 14.30585 -377.294836)
			(xy 14.30528 -377.264676) (xy 14.305729 -377.23727) (xy 14.313582 -377.183025) (xy 14.329122 -377.130463)
			(xy 14.352029 -377.080668) (xy 14.38183 -377.034666) (xy 14.399514 -377.013724) (xy 14.399768 -377.01347)
			(xy 14.405339 -377.006373) (xy 14.411593 -376.989464) (xy 14.41196 -376.98045) (xy 14.41196 -376.91314)
			(xy 14.411592 -376.904124) (xy 14.405353 -376.887207) (xy 14.399768 -376.88012) (xy 14.39926 -376.879612)
			(xy 14.381606 -376.858692) (xy 14.351898 -376.812715) (xy 14.329065 -376.762964) (xy 14.313578 -376.710461)
			(xy 14.305752 -376.656284) (xy 14.30528 -376.628914) (xy 14.305825 -376.598573) (xy 14.315443 -376.538657)
			(xy 14.334423 -376.481018) (xy 14.362287 -376.427111) (xy 14.398332 -376.378293) (xy 14.41958 -376.356626)
			(xy 14.426531 -376.349206) (xy 14.434379 -376.330463) (xy 14.43482 -376.320304) (xy 14.43482 -376.24766)
			(xy 14.434369 -376.237502) (xy 14.426523 -376.218765) (xy 14.41958 -376.211338) (xy 14.39832 -376.189683)
			(xy 14.362282 -376.140862) (xy 14.334429 -376.08695) (xy 14.315462 -376.029309) (xy 14.305862 -375.969391)
			(xy 14.30528 -375.93905) (xy 14.305804 -375.910133) (xy 14.314528 -375.852961) (xy 14.331783 -375.797761)
			(xy 14.357173 -375.745798) (xy 14.390117 -375.698265) (xy 14.42986 -375.656249) (xy 14.452346 -375.63806)
			(xy 14.461169 -375.630468) (xy 14.471342 -375.609556) (xy 14.471904 -375.597928) (xy 14.471904 -375.518172)
			(xy 14.471365 -375.50654) (xy 14.461176 -375.485631) (xy 14.452346 -375.47804) (xy 14.42987 -375.45984)
			(xy 14.390137 -375.417821) (xy 14.357199 -375.370287) (xy 14.33181 -375.318328) (xy 14.314551 -375.263133)
			(xy 14.305818 -375.205965) (xy 14.30528 -375.17705) (xy 14.305766 -375.149799) (xy 14.313522 -375.095851)
			(xy 14.328877 -375.043556) (xy 14.351519 -374.993979) (xy 14.380985 -374.948129) (xy 14.416676 -374.906938)
			(xy 14.457867 -374.871247) (xy 14.503717 -374.841781) (xy 14.553294 -374.819139) (xy 14.605589 -374.803784)
			(xy 14.659537 -374.796028) (xy 14.714039 -374.796028) (xy 14.767987 -374.803784) (xy 14.820282 -374.819139)
			(xy 14.869859 -374.841781) (xy 14.915709 -374.871247) (xy 14.9569 -374.906938) (xy 14.992591 -374.948129)
			(xy 15.022057 -374.993979) (xy 15.044699 -375.043556) (xy 15.060054 -375.095851) (xy 15.06781 -375.149799)
			(xy 15.068296 -375.17705) (xy 15.067743 -375.205966) (xy 15.059022 -375.263135) (xy 15.041771 -375.318334)
			(xy 15.016385 -375.370295) (xy 14.983448 -375.41783) (xy 14.943713 -375.459849) (xy 14.92123 -375.47804)
			(xy 14.912403 -375.485628) (xy 14.902233 -375.506544) (xy 14.901672 -375.518172) (xy 14.901672 -375.597928)
			(xy 14.902184 -375.609564) (xy 14.912389 -375.630475) (xy 14.92123 -375.63806) (xy 14.943701 -375.656266)
			(xy 14.983435 -375.698284) (xy 15.016375 -375.745816) (xy 15.041765 -375.797774) (xy 15.059025 -375.852968)
			(xy 15.067758 -375.910135) (xy 15.068296 -375.93905) (xy 15.067706 -375.969389) (xy 15.058096 -376.029302)
			(xy 15.039125 -376.086939) (xy 15.011272 -376.140847) (xy 14.975238 -376.189668) (xy 14.953996 -376.211338)
			(xy 14.947057 -376.218768) (xy 14.939203 -376.237503) (xy 14.938756 -376.24766) (xy 14.938756 -376.320304)
			(xy 14.939179 -376.330465) (xy 14.947045 -376.349201) (xy 14.953996 -376.356626) (xy 14.975234 -376.378301)
			(xy 15.011276 -376.427116) (xy 15.039134 -376.481023) (xy 15.058105 -376.53866) (xy 15.067711 -376.598574)
			(xy 15.068296 -376.628914) (xy 15.067847 -376.65632) (xy 15.059995 -376.710566) (xy 15.044456 -376.763128)
			(xy 15.021548 -376.812923) (xy 14.991746 -376.858924) (xy 14.974062 -376.879866) (xy 14.973808 -376.88012)
			(xy 14.968208 -376.887197) (xy 14.961969 -376.904121) (xy 14.961616 -376.91314) (xy 14.961616 -376.98045)
			(xy 14.961994 -376.989465) (xy 14.968227 -377.006382) (xy 14.973808 -377.01347) (xy 14.974316 -377.013978)
			(xy 14.991961 -377.034905) (xy 15.021671 -377.08088) (xy 15.044506 -377.130629) (xy 15.059996 -377.18313)
			(xy 15.067823 -377.237307) (xy 15.068296 -377.264676) (xy 15.068296 -377.26493) (xy 15.067837 -377.291256)
			(xy 15.060582 -377.343405) (xy 15.046228 -377.394063) (xy 15.025048 -377.442266) (xy 14.997443 -377.487101)
			(xy 14.963938 -377.527716) (xy 14.944852 -377.545854) (xy 14.936978 -377.552966) (xy 14.928342 -377.572016)
			(xy 14.926818 -377.655836) (xy 14.927131 -377.6661) (xy 14.934855 -377.685106) (xy 14.941804 -377.692666)
			(xy 14.942058 -377.69292) (xy 14.963096 -377.71454) (xy 14.998741 -377.763204) (xy 15.026281 -377.816872)
			(xy 15.045029 -377.874206) (xy 15.054519 -377.933777) (xy 15.054911 -377.95454) (xy 16.559276 -377.95454)
			(xy 16.559865 -377.924417) (xy 16.56934 -377.864921) (xy 16.588047 -377.807653) (xy 16.615519 -377.754036)
			(xy 16.651074 -377.705401) (xy 16.672052 -377.683776) (xy 16.679164 -377.676664) (xy 16.687038 -377.658122)
			(xy 16.687546 -377.57608) (xy 16.687094 -377.56611) (xy 16.679502 -377.547674) (xy 16.672814 -377.540266)
			(xy 16.652346 -377.5187) (xy 16.617644 -377.470424) (xy 16.590855 -377.417347) (xy 16.572626 -377.360757)
			(xy 16.563401 -377.302023) (xy 16.562832 -377.272296) (xy 16.563335 -377.243378) (xy 16.572066 -377.186206)
			(xy 16.589326 -377.131006) (xy 16.61472 -377.079044) (xy 16.647667 -377.031511) (xy 16.687411 -376.989495)
			(xy 16.709898 -376.971306) (xy 16.718692 -376.963686) (xy 16.728883 -376.942795) (xy 16.729456 -376.931174)
			(xy 16.729456 -376.851418) (xy 16.728907 -376.839787) (xy 16.718727 -376.818876) (xy 16.709898 -376.811286)
			(xy 16.687407 -376.793103) (xy 16.647673 -376.751082) (xy 16.614735 -376.703545) (xy 16.589347 -376.651582)
			(xy 16.572093 -376.596383) (xy 16.563366 -376.539212) (xy 16.562832 -376.510296) (xy 16.563308 -376.483052)
			(xy 16.571066 -376.429118) (xy 16.586423 -376.376839) (xy 16.609066 -376.327278) (xy 16.638534 -376.281445)
			(xy 16.674227 -376.240275) (xy 16.715418 -376.204605) (xy 16.738092 -376.189494) (xy 16.738346 -376.18924)
			(xy 16.748264 -376.18188) (xy 16.760349 -376.160391) (xy 16.76146 -376.148092) (xy 16.763746 -376.05081)
			(xy 16.75257 -376.028712) (xy 16.74241 -376.021092) (xy 16.742156 -376.021092) (xy 16.721253 -376.00571)
			(xy 16.68343 -375.970175) (xy 16.650778 -375.929836) (xy 16.623903 -375.885439) (xy 16.6033 -375.837806)
			(xy 16.589352 -375.787818) (xy 16.582316 -375.736399) (xy 16.581882 -375.71045) (xy 16.582315 -375.684786)
			(xy 16.589185 -375.633921) (xy 16.602819 -375.584437) (xy 16.622972 -375.537232) (xy 16.649278 -375.493158)
			(xy 16.681262 -375.453015) (xy 16.718345 -375.417527) (xy 16.738854 -375.402094) (xy 16.739108 -375.40184)
			(xy 16.747575 -375.394949) (xy 16.7581 -375.375847) (xy 16.759428 -375.36501) (xy 16.765524 -375.287794)
			(xy 16.76584 -375.276857) (xy 16.758341 -375.256325) (xy 16.751046 -375.24817) (xy 16.750538 -375.247662)
			(xy 16.72979 -375.226065) (xy 16.694619 -375.177595) (xy 16.667457 -375.124223) (xy 16.648971 -375.067262)
			(xy 16.639615 -375.008111) (xy 16.639032 -374.978168) (xy 16.639518 -374.950917) (xy 16.647274 -374.896969)
			(xy 16.662629 -374.844674) (xy 16.685271 -374.795097) (xy 16.714737 -374.749247) (xy 16.750428 -374.708056)
			(xy 16.791619 -374.672365) (xy 16.837469 -374.642899) (xy 16.887046 -374.620257) (xy 16.939341 -374.604902)
			(xy 16.993289 -374.597146) (xy 17.047791 -374.597146) (xy 17.101739 -374.604902) (xy 17.154034 -374.620257)
			(xy 17.203611 -374.642899) (xy 17.249461 -374.672365) (xy 17.290652 -374.708056) (xy 17.326343 -374.749247)
			(xy 17.355809 -374.795097) (xy 17.378451 -374.844674) (xy 17.393806 -374.896969) (xy 17.401562 -374.950917)
			(xy 17.402048 -374.978168) (xy 17.401616 -375.003832) (xy 17.394745 -375.054697) (xy 17.38111 -375.10418)
			(xy 17.360956 -375.151385) (xy 17.33465 -375.195458) (xy 17.302666 -375.235602) (xy 17.265584 -375.27109)
			(xy 17.245076 -375.286524) (xy 17.244822 -375.286778) (xy 17.236394 -375.293709) (xy 17.225847 -375.312781)
			(xy 17.224502 -375.323608) (xy 17.218406 -375.400824) (xy 17.218072 -375.411762) (xy 17.225583 -375.432295)
			(xy 17.232884 -375.440448) (xy 17.233392 -375.440956) (xy 17.254137 -375.462556) (xy 17.289311 -375.511024)
			(xy 17.316475 -375.564395) (xy 17.334961 -375.621356) (xy 17.344316 -375.680507) (xy 17.344898 -375.71045)
			(xy 17.344444 -375.737695) (xy 17.33668 -375.791629) (xy 17.321318 -375.843908) (xy 17.298671 -375.893469)
			(xy 17.2692 -375.939301) (xy 17.233505 -375.980471) (xy 17.192313 -376.016141) (xy 17.169638 -376.031252)
			(xy 17.169384 -376.031506) (xy 17.159434 -376.038828) (xy 17.147369 -376.060347) (xy 17.14627 -376.072654)
			(xy 17.143984 -376.169936) (xy 17.15516 -376.192034) (xy 17.16532 -376.199654) (xy 17.165574 -376.199654)
			(xy 17.186458 -376.21506) (xy 17.224281 -376.250592) (xy 17.256933 -376.290928) (xy 17.28381 -376.33532)
			(xy 17.304416 -376.382949) (xy 17.318368 -376.432933) (xy 17.32541 -376.484348) (xy 17.325848 -376.510296)
			(xy 17.325346 -376.539214) (xy 17.316617 -376.596387) (xy 17.299357 -376.651587) (xy 17.273962 -376.703549)
			(xy 17.241015 -376.751082) (xy 17.20127 -376.793097) (xy 17.178782 -376.811286) (xy 17.169988 -376.818906)
			(xy 17.159798 -376.839797) (xy 17.159224 -376.851418) (xy 17.159224 -376.931174) (xy 17.159784 -376.942804)
			(xy 17.169957 -376.963714) (xy 17.178782 -376.971306) (xy 17.201265 -376.989498) (xy 17.241001 -377.031517)
			(xy 17.27394 -377.079052) (xy 17.299329 -377.131013) (xy 17.316585 -377.18621) (xy 17.325314 -377.24338)
			(xy 17.325848 -377.272296) (xy 17.325275 -377.302419) (xy 17.315795 -377.361916) (xy 17.297085 -377.419184)
			(xy 17.269609 -377.472801) (xy 17.234051 -377.521435) (xy 17.213072 -377.54306) (xy 17.20596 -377.550172)
			(xy 17.198086 -377.568714) (xy 17.197578 -377.650756) (xy 17.198057 -377.660723) (xy 17.20563 -377.679159)
			(xy 17.21231 -377.68657) (xy 17.232799 -377.708117) (xy 17.267497 -377.756399) (xy 17.294282 -377.80948)
			(xy 17.312506 -377.866075) (xy 17.321726 -377.924812) (xy 17.322292 -377.95454) (xy 17.321806 -377.981791)
			(xy 17.31405 -378.035739) (xy 17.298695 -378.088034) (xy 17.276053 -378.137611) (xy 17.246587 -378.183461)
			(xy 17.210896 -378.224652) (xy 17.169705 -378.260343) (xy 17.123855 -378.289809) (xy 17.074278 -378.312451)
			(xy 17.021983 -378.327806) (xy 16.968035 -378.335562) (xy 16.913533 -378.335562) (xy 16.859585 -378.327806)
			(xy 16.80729 -378.312451) (xy 16.757713 -378.289809) (xy 16.711863 -378.260343) (xy 16.670672 -378.224652)
			(xy 16.634981 -378.183461) (xy 16.605515 -378.137611) (xy 16.582873 -378.088034) (xy 16.567518 -378.035739)
			(xy 16.559762 -377.981791) (xy 16.559276 -377.95454) (xy 15.054911 -377.95454) (xy 15.055088 -377.963938)
			(xy 15.054596 -377.991648) (xy 15.046568 -378.046482) (xy 15.030685 -378.099577) (xy 15.007284 -378.149813)
			(xy 14.976857 -378.196133) (xy 14.958822 -378.217176) (xy 14.952967 -378.224358) (xy 14.946468 -378.241697)
			(xy 14.946122 -378.250958) (xy 14.946376 -378.318776) (xy 14.946816 -378.328048) (xy 14.95346 -378.345367)
			(xy 14.95933 -378.352558) (xy 14.977614 -378.373652) (xy 15.00844 -378.420193) (xy 15.032153 -378.470729)
			(xy 15.048248 -378.524181) (xy 15.056381 -378.579408) (xy 15.056866 -378.60732) (xy 15.05638 -378.634571)
			(xy 15.048624 -378.688519) (xy 15.033269 -378.740814) (xy 15.010627 -378.790391) (xy 14.981161 -378.836241)
			(xy 14.94547 -378.877432) (xy 14.904279 -378.913123) (xy 14.858429 -378.942589) (xy 14.808852 -378.965231)
			(xy 14.756557 -378.980586) (xy 14.702609 -378.988342) (xy 14.648107 -378.988342) (xy 14.594159 -378.980586)
			(xy 14.541864 -378.965231) (xy 14.492287 -378.942589) (xy 14.446437 -378.913123) (xy 14.405246 -378.877432)
			(xy 14.369555 -378.836241) (xy 14.340089 -378.790391) (xy 14.317447 -378.740814) (xy 14.302092 -378.688519)
			(xy 14.294336 -378.634571) (xy 14.29385 -378.60732) (xy 14.294333 -378.57961) (xy 14.302366 -378.524776)
			(xy 14.318251 -378.471681) (xy 14.341654 -378.421445) (xy 14.372081 -378.375126) (xy 14.390116 -378.354082)
			(xy 14.395938 -378.346877) (xy 14.402459 -378.329556) (xy 14.402816 -378.3203) (xy 14.402562 -378.252482)
			(xy 14.402134 -378.243209) (xy 14.395481 -378.225891) (xy 14.389608 -378.2187) (xy 14.371357 -378.197578)
			(xy 14.340525 -378.151046) (xy 14.316805 -378.100517) (xy 14.300702 -378.047071) (xy 14.292561 -377.991848)
			(xy 14.292072 -377.963938) (xy 4.476496 -377.963938) (xy 4.476496 -381.324104) (xy 4.47692 -381.334174)
			(xy 4.484635 -381.352778) (xy 4.491482 -381.360172) (xy 4.545328 -381.41402) (xy 6.528562 -381.41402)
			(xy 6.528988 -381.38764) (xy 6.536251 -381.335383) (xy 6.55064 -381.284623) (xy 6.571882 -381.236329)
			(xy 6.599573 -381.19142) (xy 6.633183 -381.150752) (xy 6.672074 -381.115099) (xy 6.715503 -381.085142)
			(xy 6.738874 -381.072898) (xy 6.751214 -381.066166) (xy 6.77194 -381.047195) (xy 6.786699 -381.023287)
			(xy 6.794371 -380.996257) (xy 6.794374 -380.96816) (xy 6.786706 -380.94113) (xy 6.771951 -380.917219)
			(xy 6.751229 -380.898244) (xy 6.738874 -380.891542) (xy 6.715506 -380.879296) (xy 6.672083 -380.849334)
			(xy 6.633198 -380.813679) (xy 6.599593 -380.77301) (xy 6.571906 -380.728102) (xy 6.550665 -380.679809)
			(xy 6.536274 -380.629053) (xy 6.529009 -380.576799) (xy 6.528562 -380.55042) (xy 6.529048 -380.523169)
			(xy 6.536804 -380.469221) (xy 6.552159 -380.416926) (xy 6.574801 -380.367349) (xy 6.604267 -380.321499)
			(xy 6.639958 -380.280308) (xy 6.681149 -380.244617) (xy 6.726999 -380.215151) (xy 6.776576 -380.192509)
			(xy 6.828871 -380.177154) (xy 6.882819 -380.169398) (xy 6.937321 -380.169398) (xy 6.991269 -380.177154)
			(xy 7.043564 -380.192509) (xy 7.093141 -380.215151) (xy 7.138991 -380.244617) (xy 7.180182 -380.280308)
			(xy 7.215873 -380.321499) (xy 7.245339 -380.367349) (xy 7.267981 -380.416926) (xy 7.283336 -380.469221)
			(xy 7.291092 -380.523169) (xy 7.291578 -380.55042) (xy 7.291135 -380.5768) (xy 7.283879 -380.629058)
			(xy 7.269495 -380.679818) (xy 7.248257 -380.728114) (xy 7.220568 -380.773024) (xy 7.186959 -380.813693)
			(xy 7.170475 -380.828804) (xy 9.435592 -380.828804) (xy 9.436059 -380.801551) (xy 9.443815 -380.7476)
			(xy 9.459171 -380.695303) (xy 9.481813 -380.645723) (xy 9.511281 -380.599869) (xy 9.546974 -380.558677)
			(xy 9.588166 -380.522983) (xy 9.634019 -380.493515) (xy 9.683599 -380.470872) (xy 9.735897 -380.455516)
			(xy 9.789847 -380.447759) (xy 9.8171 -380.447296) (xy 9.842716 -380.447723) (xy 9.893486 -380.454584)
			(xy 9.942881 -380.46818) (xy 9.990009 -380.488269) (xy 10.034024 -380.514487) (xy 10.054336 -380.5301)
			(xy 10.05459 -380.5301) (xy 10.062868 -380.536078) (xy 10.082512 -380.541582) (xy 10.09269 -380.540768)
			(xy 10.17524 -380.529846) (xy 10.19302 -380.519432) (xy 10.199116 -380.51105) (xy 10.208935 -380.498203)
			(xy 10.230428 -380.474041) (xy 10.242042 -380.46279) (xy 10.242296 -380.462536) (xy 10.249432 -380.454907)
			(xy 10.257437 -380.435637) (xy 10.25779 -380.425198) (xy 10.256266 -380.350268) (xy 10.255566 -380.339836)
			(xy 10.246903 -380.320826) (xy 10.239502 -380.313438) (xy 10.239248 -380.313184) (xy 10.219468 -380.294997)
			(xy 10.184674 -380.254051) (xy 10.155972 -380.208626) (xy 10.133932 -380.159621) (xy 10.118989 -380.108008)
			(xy 10.11144 -380.054808) (xy 10.110978 -380.027942) (xy 10.111464 -380.000691) (xy 10.11922 -379.946743)
			(xy 10.134575 -379.894448) (xy 10.157217 -379.844871) (xy 10.186683 -379.799021) (xy 10.222374 -379.75783)
			(xy 10.263565 -379.722139) (xy 10.309415 -379.692673) (xy 10.358992 -379.670031) (xy 10.411287 -379.654676)
			(xy 10.465235 -379.64692) (xy 10.519737 -379.64692) (xy 10.573685 -379.654676) (xy 10.62598 -379.670031)
			(xy 10.675557 -379.692673) (xy 10.721407 -379.722139) (xy 10.762598 -379.75783) (xy 10.798289 -379.799021)
			(xy 10.827755 -379.844871) (xy 10.850397 -379.894448) (xy 10.865752 -379.946743) (xy 10.873508 -380.000691)
			(xy 10.873994 -380.027942) (xy 10.873606 -380.053088) (xy 12.10945 -380.053088) (xy 12.109966 -380.025484)
			(xy 12.117913 -379.97085) (xy 12.133654 -379.917933) (xy 12.15686 -379.867839) (xy 12.187045 -379.821613)
			(xy 12.22358 -379.780222) (xy 12.244324 -379.762004) (xy 12.252452 -379.755146) (xy 12.261596 -379.735842)
			(xy 12.264898 -379.63856) (xy 12.25677 -379.618748) (xy 12.248896 -379.611382) (xy 12.230736 -379.593319)
			(xy 12.198897 -379.553199) (xy 12.17271 -379.50918) (xy 12.152646 -379.462055) (xy 12.139067 -379.412668)
			(xy 12.132215 -379.36191) (xy 12.131802 -379.3363) (xy 12.132268 -379.30893) (xy 12.140085 -379.254751)
			(xy 12.155575 -379.202247) (xy 12.178416 -379.152501) (xy 12.208141 -379.106534) (xy 12.225782 -379.085602)
			(xy 12.226036 -379.085348) (xy 12.231613 -379.078255) (xy 12.237864 -379.061343) (xy 12.238228 -379.052328)
			(xy 12.238228 -378.985272) (xy 12.237878 -378.976254) (xy 12.231625 -378.959338) (xy 12.226036 -378.952252)
			(xy 12.225782 -378.952252) (xy 12.225782 -378.951998) (xy 12.208126 -378.93108) (xy 12.178417 -378.885103)
			(xy 12.155585 -378.835352) (xy 12.140098 -378.782848) (xy 12.132274 -378.72867) (xy 12.131802 -378.7013)
			(xy 12.132288 -378.674049) (xy 12.140044 -378.620101) (xy 12.155399 -378.567806) (xy 12.178041 -378.518229)
			(xy 12.207507 -378.472379) (xy 12.243198 -378.431188) (xy 12.284389 -378.395497) (xy 12.330239 -378.366031)
			(xy 12.379816 -378.343389) (xy 12.432111 -378.328034) (xy 12.486059 -378.320278) (xy 12.540561 -378.320278)
			(xy 12.594509 -378.328034) (xy 12.646804 -378.343389) (xy 12.696381 -378.366031) (xy 12.742231 -378.395497)
			(xy 12.783422 -378.431188) (xy 12.819113 -378.472379) (xy 12.848579 -378.518229) (xy 12.871221 -378.567806)
			(xy 12.886576 -378.620101) (xy 12.894332 -378.674049) (xy 12.894818 -378.7013) (xy 12.894372 -378.728671)
			(xy 12.886552 -378.782852) (xy 12.87106 -378.835356) (xy 12.848213 -378.885103) (xy 12.818482 -378.931068)
			(xy 12.800838 -378.951998) (xy 12.800584 -378.952252) (xy 12.79501 -378.959347) (xy 12.788756 -378.976257)
			(xy 12.788392 -378.985272) (xy 12.788392 -379.052328) (xy 12.788738 -379.061346) (xy 12.794993 -379.078263)
			(xy 12.800584 -379.085348) (xy 12.800838 -379.085348) (xy 12.800838 -379.085602) (xy 12.818498 -379.106517)
			(xy 12.848205 -379.152495) (xy 12.871037 -379.202247) (xy 12.886523 -379.254751) (xy 12.894347 -379.30893)
			(xy 12.894818 -379.3363) (xy 12.894374 -379.363907) (xy 12.886414 -379.418544) (xy 12.870659 -379.471463)
			(xy 12.84744 -379.521558) (xy 12.817241 -379.567781) (xy 12.780694 -379.609168) (xy 12.759944 -379.627384)
			(xy 12.751816 -379.634242) (xy 12.742672 -379.653546) (xy 12.73937 -379.750828) (xy 12.747498 -379.77064)
			(xy 12.755372 -379.778006) (xy 12.773568 -379.796033) (xy 12.805406 -379.836161) (xy 12.831589 -379.880187)
			(xy 12.851646 -379.927319) (xy 12.865217 -379.976712) (xy 12.872058 -380.027476) (xy 12.872466 -380.053088)
			(xy 12.872004 -380.080663) (xy 12.864052 -380.135236) (xy 12.848327 -380.188097) (xy 12.825157 -380.238143)
			(xy 12.795023 -380.284332) (xy 12.758554 -380.325703) (xy 12.737846 -380.343918) (xy 12.72921 -380.351284)
			(xy 12.719812 -380.37135) (xy 12.72032 -380.460758) (xy 12.720905 -380.471805) (xy 12.730258 -380.491827)
			(xy 12.738354 -380.499366) (xy 12.759369 -380.517586) (xy 12.796408 -380.559077) (xy 12.827037 -380.605502)
			(xy 12.850607 -380.655879) (xy 12.866619 -380.709142) (xy 12.874734 -380.764165) (xy 12.87526 -380.791974)
			(xy 12.874774 -380.819225) (xy 12.867018 -380.873173) (xy 12.851663 -380.925468) (xy 12.829021 -380.975045)
			(xy 12.799555 -381.020895) (xy 12.763864 -381.062086) (xy 12.722673 -381.097777) (xy 12.676823 -381.127243)
			(xy 12.627246 -381.149885) (xy 12.574951 -381.16524) (xy 12.521003 -381.172996) (xy 12.466501 -381.172996)
			(xy 12.412553 -381.16524) (xy 12.360258 -381.149885) (xy 12.310681 -381.127243) (xy 12.264831 -381.097777)
			(xy 12.22364 -381.062086) (xy 12.187949 -381.020895) (xy 12.158483 -380.975045) (xy 12.135841 -380.925468)
			(xy 12.120486 -380.873173) (xy 12.11273 -380.819225) (xy 12.112244 -380.791974) (xy 12.112745 -380.764401)
			(xy 12.120688 -380.709829) (xy 12.136405 -380.656969) (xy 12.159569 -380.606922) (xy 12.189696 -380.560732)
			(xy 12.226159 -380.51936) (xy 12.246864 -380.501144) (xy 12.2555 -380.493778) (xy 12.264898 -380.473712)
			(xy 12.26439 -380.384304) (xy 12.263822 -380.373255) (xy 12.254457 -380.353234) (xy 12.246356 -380.345696)
			(xy 12.225325 -380.327494) (xy 12.188286 -380.286) (xy 12.157659 -380.239571) (xy 12.134092 -380.18919)
			(xy 12.118084 -380.135924) (xy 12.109973 -380.080898) (xy 12.10945 -380.053088) (xy 10.873606 -380.053088)
			(xy 10.873597 -380.053653) (xy 10.866669 -380.104608) (xy 10.852958 -380.154169) (xy 10.832712 -380.20144)
			(xy 10.806299 -380.245561) (xy 10.774197 -380.285734) (xy 10.755884 -380.303786) (xy 10.75563 -380.30404)
			(xy 10.748508 -380.311681) (xy 10.740494 -380.330941) (xy 10.740136 -380.341378) (xy 10.74166 -380.416308)
			(xy 10.742365 -380.42674) (xy 10.751024 -380.44575) (xy 10.758424 -380.453138) (xy 10.758678 -380.453392)
			(xy 10.7785 -380.471535) (xy 10.81329 -380.512491) (xy 10.841985 -380.557926) (xy 10.864018 -380.606939)
			(xy 10.878952 -380.658559) (xy 10.886491 -380.711765) (xy 10.886948 -380.738634) (xy 10.886454 -380.765884)
			(xy 10.878694 -380.81983) (xy 10.863336 -380.872122) (xy 10.840694 -380.921696) (xy 10.811228 -380.967545)
			(xy 10.775538 -381.008734) (xy 10.73435 -381.044425) (xy 10.688502 -381.073891) (xy 10.638927 -381.096534)
			(xy 10.586635 -381.111893) (xy 10.53269 -381.119654) (xy 10.50544 -381.120142) (xy 10.479824 -381.119706)
			(xy 10.429054 -381.11285) (xy 10.379659 -381.099256) (xy 10.33253 -381.079169) (xy 10.288516 -381.052951)
			(xy 10.268204 -381.037338) (xy 10.26795 -381.037338) (xy 10.259688 -381.031334) (xy 10.240031 -381.025845)
			(xy 10.22985 -381.02667) (xy 10.1473 -381.037592) (xy 10.12952 -381.048006) (xy 10.123424 -381.056388)
			(xy 10.114912 -381.067578) (xy 10.096477 -381.088807) (xy 10.086594 -381.098806) (xy 10.079758 -381.106209)
			(xy 10.072036 -381.124806) (xy 10.071608 -381.134874) (xy 10.071608 -381.40513) (xy 15.882112 -381.40513)
			(xy 15.882593 -381.37776) (xy 15.890407 -381.323582) (xy 15.905892 -381.271079) (xy 15.928731 -381.221332)
			(xy 15.958452 -381.175364) (xy 15.976092 -381.154432) (xy 15.976346 -381.154178) (xy 15.981953 -381.147106)
			(xy 15.988186 -381.130178) (xy 15.988538 -381.121158) (xy 15.988538 -381.054102) (xy 15.988172 -381.045086)
			(xy 15.981929 -381.02817) (xy 15.976346 -381.021082) (xy 15.976092 -381.021082) (xy 15.976092 -381.020828)
			(xy 15.958482 -380.999871) (xy 15.928759 -380.953906) (xy 15.905914 -380.904164) (xy 15.890417 -380.851666)
			(xy 15.882586 -380.797491) (xy 15.882583 -380.742754) (xy 15.890407 -380.688578) (xy 15.905898 -380.636078)
			(xy 15.928737 -380.586333) (xy 15.958455 -380.540365) (xy 15.976092 -380.519432) (xy 15.976346 -380.519178)
			(xy 15.981953 -380.512106) (xy 15.988186 -380.495178) (xy 15.988538 -380.486158) (xy 15.988538 -380.419102)
			(xy 15.988172 -380.410086) (xy 15.981929 -380.39317) (xy 15.976346 -380.386082) (xy 15.976092 -380.386082)
			(xy 15.976092 -380.385828) (xy 15.958482 -380.364871) (xy 15.928759 -380.318906) (xy 15.905914 -380.269164)
			(xy 15.890417 -380.216666) (xy 15.882586 -380.162491) (xy 15.882583 -380.107754) (xy 15.890407 -380.053578)
			(xy 15.905898 -380.001078) (xy 15.928737 -379.951333) (xy 15.958455 -379.905365) (xy 15.976092 -379.884432)
			(xy 15.976346 -379.884178) (xy 15.981953 -379.877106) (xy 15.988186 -379.860178) (xy 15.988538 -379.851158)
			(xy 15.988538 -379.784102) (xy 15.988172 -379.775086) (xy 15.981929 -379.75817) (xy 15.976346 -379.751082)
			(xy 15.976092 -379.751082) (xy 15.976092 -379.750828) (xy 15.958482 -379.729871) (xy 15.928759 -379.683906)
			(xy 15.905914 -379.634164) (xy 15.890417 -379.581666) (xy 15.882586 -379.527491) (xy 15.882583 -379.472754)
			(xy 15.890407 -379.418578) (xy 15.905898 -379.366078) (xy 15.928737 -379.316333) (xy 15.958455 -379.270365)
			(xy 15.976092 -379.249432) (xy 15.976346 -379.249178) (xy 15.981953 -379.242106) (xy 15.988186 -379.225178)
			(xy 15.988538 -379.216158) (xy 15.988538 -379.149102) (xy 15.988172 -379.140086) (xy 15.981929 -379.12317)
			(xy 15.976346 -379.116082) (xy 15.976092 -379.116082) (xy 15.976092 -379.115828) (xy 15.958451 -379.094897)
			(xy 15.92874 -379.048924) (xy 15.905904 -378.999176) (xy 15.890414 -378.946675) (xy 15.882586 -378.892499)
			(xy 15.882112 -378.86513) (xy 15.882598 -378.837879) (xy 15.890354 -378.783931) (xy 15.905709 -378.731636)
			(xy 15.928351 -378.682059) (xy 15.957817 -378.636209) (xy 15.993508 -378.595018) (xy 16.034699 -378.559327)
			(xy 16.080549 -378.529861) (xy 16.130126 -378.507219) (xy 16.182421 -378.491864) (xy 16.236369 -378.484108)
			(xy 16.290871 -378.484108) (xy 16.344819 -378.491864) (xy 16.397114 -378.507219) (xy 16.446691 -378.529861)
			(xy 16.492541 -378.559327) (xy 16.533732 -378.595018) (xy 16.569423 -378.636209) (xy 16.598889 -378.682059)
			(xy 16.621531 -378.731636) (xy 16.636886 -378.783931) (xy 16.644642 -378.837879) (xy 16.645128 -378.86513)
			(xy 16.644697 -378.892502) (xy 16.636873 -378.946683) (xy 16.621377 -378.999187) (xy 16.598527 -379.048934)
			(xy 16.568794 -379.094898) (xy 16.551148 -379.115828) (xy 16.550894 -379.116082) (xy 16.545308 -379.123169)
			(xy 16.539061 -379.140085) (xy 16.538702 -379.149102) (xy 16.538702 -379.216158) (xy 16.539079 -379.225173)
			(xy 16.545313 -379.24209) (xy 16.550894 -379.249178) (xy 16.551148 -379.249178) (xy 16.551148 -379.249432)
			(xy 16.568819 -379.27034) (xy 16.598545 -379.316312) (xy 16.62139 -379.366062) (xy 16.636885 -379.418568)
			(xy 16.644711 -379.47275) (xy 16.644708 -379.527495) (xy 16.636875 -379.581676) (xy 16.621374 -379.63418)
			(xy 16.598523 -379.683928) (xy 16.568792 -379.729896) (xy 16.551148 -379.750828) (xy 16.550894 -379.751082)
			(xy 16.545308 -379.758169) (xy 16.539061 -379.775085) (xy 16.538702 -379.784102) (xy 16.538702 -379.851158)
			(xy 16.539079 -379.860173) (xy 16.545313 -379.87709) (xy 16.550894 -379.884178) (xy 16.551148 -379.884178)
			(xy 16.551148 -379.884432) (xy 16.568819 -379.90534) (xy 16.598545 -379.951312) (xy 16.62139 -380.001062)
			(xy 16.636885 -380.053568) (xy 16.644711 -380.10775) (xy 16.644708 -380.162495) (xy 16.636875 -380.216676)
			(xy 16.621374 -380.26918) (xy 16.598523 -380.318928) (xy 16.568792 -380.364896) (xy 16.551148 -380.385828)
			(xy 16.550894 -380.386082) (xy 16.545308 -380.393169) (xy 16.539061 -380.410085) (xy 16.538702 -380.419102)
			(xy 16.538702 -380.486158) (xy 16.539079 -380.495173) (xy 16.545313 -380.51209) (xy 16.550894 -380.519178)
			(xy 16.551148 -380.519178) (xy 16.551148 -380.519432) (xy 16.568819 -380.54034) (xy 16.598545 -380.586312)
			(xy 16.62139 -380.636062) (xy 16.636885 -380.688568) (xy 16.644711 -380.74275) (xy 16.644708 -380.797495)
			(xy 16.644405 -380.799594) (xy 18.005552 -380.799594) (xy 18.005939 -380.774164) (xy 18.012698 -380.723755)
			(xy 18.026095 -380.674691) (xy 18.045893 -380.627843) (xy 18.071741 -380.584041) (xy 18.103179 -380.544061)
			(xy 18.121122 -380.526036) (xy 18.128234 -380.519178) (xy 18.136362 -380.500128) (xy 18.136616 -380.406656)
			(xy 18.128742 -380.388114) (xy 18.121376 -380.380748) (xy 18.10012 -380.35909) (xy 18.064082 -380.310269)
			(xy 18.036228 -380.256358) (xy 18.01726 -380.198718) (xy 18.007659 -380.138801) (xy 18.007076 -380.10846)
			(xy 18.007582 -380.079721) (xy 18.01621 -380.022893) (xy 18.033264 -379.968002) (xy 18.05836 -379.916291)
			(xy 18.090928 -379.868929) (xy 18.1102 -379.847602) (xy 18.116804 -379.840744) (xy 18.123916 -379.82271)
			(xy 18.123916 -379.73381) (xy 18.116804 -379.715776) (xy 18.1102 -379.708918) (xy 18.090929 -379.687591)
			(xy 18.058364 -379.640229) (xy 18.033273 -379.588517) (xy 18.016223 -379.533626) (xy 18.007601 -379.476799)
			(xy 18.007601 -379.419321) (xy 18.016223 -379.362494) (xy 18.033273 -379.307603) (xy 18.058364 -379.255891)
			(xy 18.090929 -379.208529) (xy 18.1102 -379.187202) (xy 18.116804 -379.180344) (xy 18.123916 -379.16231)
			(xy 18.123916 -379.07341) (xy 18.116804 -379.055376) (xy 18.1102 -379.048518) (xy 18.090921 -379.027198)
			(xy 18.058354 -378.979835) (xy 18.033262 -378.928122) (xy 18.016213 -378.873229) (xy 18.007595 -378.8164)
			(xy 18.007076 -378.78766) (xy 18.007541 -378.760408) (xy 18.015302 -378.706461) (xy 18.030661 -378.654167)
			(xy 18.053306 -378.60459) (xy 18.082775 -378.558741) (xy 18.118469 -378.517552) (xy 18.15966 -378.481861)
			(xy 18.205511 -378.452395) (xy 18.255089 -378.429753) (xy 18.307384 -378.414397) (xy 18.361332 -378.406639)
			(xy 18.388584 -378.406152) (xy 18.417229 -378.406637) (xy 18.473874 -378.415214) (xy 18.528601 -378.432164)
			(xy 18.580178 -378.457104) (xy 18.627447 -378.489474) (xy 18.669346 -378.528548) (xy 18.687542 -378.550678)
			(xy 18.6944 -378.559314) (xy 18.713704 -378.56922) (xy 18.811748 -378.574554) (xy 18.832068 -378.56668)
			(xy 18.839688 -378.558806) (xy 18.861356 -378.537509) (xy 18.910208 -378.501392) (xy 18.964166 -378.473475)
			(xy 19.021868 -378.454464) (xy 19.081854 -378.444839) (xy 19.11223 -378.444252) (xy 19.14149 -378.444813)
			(xy 19.199321 -378.453759) (xy 19.255112 -378.471422) (xy 19.307555 -378.497388) (xy 19.355424 -378.53105)
			(xy 19.376898 -378.550932) (xy 19.384264 -378.558044) (xy 19.402044 -378.565156) (xy 19.492468 -378.565156)
			(xy 19.510248 -378.558044) (xy 19.517614 -378.550932) (xy 19.539048 -378.531001) (xy 19.586919 -378.497327)
			(xy 19.639371 -378.471358) (xy 19.695174 -378.453703) (xy 19.753018 -378.444778) (xy 19.782282 -378.444252)
			(xy 19.811862 -378.444836) (xy 19.870315 -378.453966) (xy 19.926657 -378.472009) (xy 19.979539 -378.498533)
			(xy 20.027693 -378.532901) (xy 20.069964 -378.574291) (xy 20.088098 -378.597668) (xy 20.095686 -378.606789)
			(xy 20.116888 -378.617376) (xy 20.128738 -378.617988) (xy 20.210272 -378.617988) (xy 20.222117 -378.617357)
			(xy 20.243308 -378.60677) (xy 20.250912 -378.597668) (xy 20.260074 -378.585618) (xy 20.280037 -378.562857)
			(xy 20.29079 -378.552202) (xy 20.291044 -378.551948) (xy 20.2982 -378.544197) (xy 20.306073 -378.524649)
			(xy 20.306284 -378.514102) (xy 20.304252 -378.439172) (xy 20.303415 -378.428753) (xy 20.294485 -378.409873)
			(xy 20.28698 -378.402596) (xy 20.28698 -378.402342) (xy 20.286472 -378.402342) (xy 20.266219 -378.384114)
			(xy 20.230556 -378.34292) (xy 20.201114 -378.297074) (xy 20.178489 -378.247507) (xy 20.163144 -378.195227)
			(xy 20.155388 -378.141295) (xy 20.1549 -378.114052) (xy 20.155347 -378.086223) (xy 20.163428 -378.031153)
			(xy 20.179427 -377.977844) (xy 20.203003 -377.927425) (xy 20.233657 -377.880968) (xy 20.270736 -377.839458)
			(xy 20.313455 -377.803779) (xy 20.360905 -377.774686) (xy 20.386294 -377.763278) (xy 20.395692 -377.759214)
			(xy 20.41017 -377.744482) (xy 20.439634 -377.665996) (xy 20.442814 -377.65633) (xy 20.442028 -377.636016)
			(xy 20.43811 -377.626626) (xy 20.43811 -377.626372) (xy 20.42649 -377.600731) (xy 20.410102 -377.546875)
			(xy 20.4018 -377.491197) (xy 20.40128 -377.46305) (xy 20.401804 -377.434133) (xy 20.410528 -377.376961)
			(xy 20.427783 -377.321761) (xy 20.453173 -377.269798) (xy 20.486117 -377.222265) (xy 20.52586 -377.180249)
			(xy 20.548346 -377.16206) (xy 20.557169 -377.154468) (xy 20.567342 -377.133556) (xy 20.567904 -377.121928)
			(xy 20.567904 -377.042172) (xy 20.567365 -377.03054) (xy 20.557176 -377.009631) (xy 20.548346 -377.00204)
			(xy 20.527563 -376.985287) (xy 20.490433 -376.946933) (xy 20.459012 -376.903779) (xy 20.433913 -376.856665)
			(xy 20.415627 -376.806513) (xy 20.40451 -376.754301) (xy 20.400781 -376.70105) (xy 20.40451 -376.647799)
			(xy 20.415627 -376.595587) (xy 20.433913 -376.545435) (xy 20.459012 -376.498321) (xy 20.490433 -376.455167)
			(xy 20.527563 -376.416813) (xy 20.548346 -376.40006) (xy 20.557169 -376.392468) (xy 20.567342 -376.371556)
			(xy 20.567904 -376.359928) (xy 20.567904 -376.280172) (xy 20.567365 -376.26854) (xy 20.557176 -376.247631)
			(xy 20.548346 -376.24004) (xy 20.527563 -376.223287) (xy 20.490433 -376.184933) (xy 20.459012 -376.141779)
			(xy 20.433913 -376.094665) (xy 20.415627 -376.044513) (xy 20.40451 -375.992301) (xy 20.400781 -375.93905)
			(xy 20.40451 -375.885799) (xy 20.415627 -375.833587) (xy 20.433913 -375.783435) (xy 20.459012 -375.736321)
			(xy 20.490433 -375.693167) (xy 20.527563 -375.654813) (xy 20.548346 -375.63806) (xy 20.557169 -375.630468)
			(xy 20.567342 -375.609556) (xy 20.567904 -375.597928) (xy 20.567904 -375.518172) (xy 20.567365 -375.50654)
			(xy 20.557176 -375.485631) (xy 20.548346 -375.47804) (xy 20.52587 -375.45984) (xy 20.486137 -375.417821)
			(xy 20.453199 -375.370287) (xy 20.42781 -375.318328) (xy 20.410551 -375.263133) (xy 20.401818 -375.205965)
			(xy 20.40128 -375.17705) (xy 20.401766 -375.149799) (xy 20.409522 -375.095851) (xy 20.424877 -375.043556)
			(xy 20.447519 -374.993979) (xy 20.476985 -374.948129) (xy 20.512676 -374.906938) (xy 20.553867 -374.871247)
			(xy 20.599717 -374.841781) (xy 20.649294 -374.819139) (xy 20.701589 -374.803784) (xy 20.755537 -374.796028)
			(xy 20.810039 -374.796028) (xy 20.863987 -374.803784) (xy 20.916282 -374.819139) (xy 20.965859 -374.841781)
			(xy 21.011709 -374.871247) (xy 21.0529 -374.906938) (xy 21.088591 -374.948129) (xy 21.118057 -374.993979)
			(xy 21.140699 -375.043556) (xy 21.156054 -375.095851) (xy 21.16381 -375.149799) (xy 21.164296 -375.17705)
			(xy 21.163743 -375.205966) (xy 21.155022 -375.263135) (xy 21.137771 -375.318334) (xy 21.112385 -375.370295)
			(xy 21.079448 -375.41783) (xy 21.039713 -375.459849) (xy 21.01723 -375.47804) (xy 21.008403 -375.485628)
			(xy 20.998233 -375.506544) (xy 20.997672 -375.518172) (xy 20.997672 -375.597928) (xy 20.998184 -375.609564)
			(xy 21.008389 -375.630475) (xy 21.01723 -375.63806) (xy 21.038013 -375.654813) (xy 21.075144 -375.693166)
			(xy 21.106565 -375.736321) (xy 21.131664 -375.783435) (xy 21.14995 -375.833587) (xy 21.161067 -375.885798)
			(xy 21.164797 -375.93905) (xy 21.161067 -375.992302) (xy 21.14995 -376.044513) (xy 21.131664 -376.094665)
			(xy 21.106565 -376.141779) (xy 21.075144 -376.184934) (xy 21.038013 -376.223287) (xy 21.01723 -376.24004)
			(xy 21.008403 -376.247628) (xy 20.998233 -376.268544) (xy 20.997672 -376.280172) (xy 20.997672 -376.359928)
			(xy 20.998184 -376.371564) (xy 21.008389 -376.392475) (xy 21.01723 -376.40006) (xy 21.038013 -376.416813)
			(xy 21.075144 -376.455166) (xy 21.106565 -376.498321) (xy 21.131664 -376.545435) (xy 21.14995 -376.595587)
			(xy 21.154341 -376.616209) (xy 22.153395 -376.616209) (xy 22.157124 -376.562959) (xy 22.168239 -376.510749)
			(xy 22.186523 -376.460598) (xy 22.211619 -376.413485) (xy 22.243037 -376.370331) (xy 22.280165 -376.331978)
			(xy 22.300946 -376.315224) (xy 22.30974 -376.307604) (xy 22.319929 -376.286713) (xy 22.320504 -376.275092)
			(xy 22.320504 -376.195336) (xy 22.319986 -376.183702) (xy 22.309782 -376.162793) (xy 22.300946 -376.155204)
			(xy 22.280177 -376.138434) (xy 22.243048 -376.100082) (xy 22.211628 -376.056929) (xy 22.18653 -376.009818)
			(xy 22.168243 -375.959668) (xy 22.157126 -375.907458) (xy 22.153395 -375.854209) (xy 22.157124 -375.800959)
			(xy 22.168239 -375.748749) (xy 22.186523 -375.698598) (xy 22.211619 -375.651485) (xy 22.243037 -375.608331)
			(xy 22.280165 -375.569978) (xy 22.300946 -375.553224) (xy 22.30974 -375.545604) (xy 22.319929 -375.524713)
			(xy 22.320504 -375.513092) (xy 22.320504 -375.433336) (xy 22.319986 -375.421702) (xy 22.309782 -375.400793)
			(xy 22.300946 -375.393204) (xy 22.278453 -375.375024) (xy 22.238721 -375.333001) (xy 22.205785 -375.285463)
			(xy 22.180398 -375.2335) (xy 22.163144 -375.178301) (xy 22.154415 -375.12113) (xy 22.15388 -375.092214)
			(xy 22.154366 -375.064963) (xy 22.162122 -375.011015) (xy 22.177477 -374.95872) (xy 22.200119 -374.909143)
			(xy 22.229585 -374.863293) (xy 22.265276 -374.822102) (xy 22.306467 -374.786411) (xy 22.352317 -374.756945)
			(xy 22.401894 -374.734303) (xy 22.454189 -374.718948) (xy 22.508137 -374.711192) (xy 22.562639 -374.711192)
			(xy 22.616587 -374.718948) (xy 22.668882 -374.734303) (xy 22.718459 -374.756945) (xy 22.764309 -374.786411)
			(xy 22.8055 -374.822102) (xy 22.841191 -374.863293) (xy 22.870657 -374.909143) (xy 22.893299 -374.95872)
			(xy 22.908654 -375.011015) (xy 22.91641 -375.064963) (xy 22.916896 -375.092214) (xy 22.916318 -375.121129)
			(xy 22.907601 -375.178297) (xy 22.890355 -375.233495) (xy 22.864975 -375.285457) (xy 22.832042 -375.332992)
			(xy 22.792311 -375.375012) (xy 22.76983 -375.393204) (xy 22.761019 -375.400807) (xy 22.75084 -375.421711)
			(xy 22.750272 -375.433336) (xy 22.750272 -375.513092) (xy 22.750805 -375.524725) (xy 22.760996 -375.545636)
			(xy 22.76983 -375.553224) (xy 22.790627 -375.569961) (xy 22.827759 -375.608315) (xy 22.859181 -375.651472)
			(xy 22.884281 -375.698587) (xy 22.902567 -375.748741) (xy 22.913683 -375.800955) (xy 22.917412 -375.854209)
			(xy 22.913681 -375.907462) (xy 22.902562 -375.959675) (xy 22.884274 -376.009829) (xy 22.859172 -376.056943)
			(xy 22.827748 -376.100098) (xy 22.790614 -376.138451) (xy 22.76983 -376.155204) (xy 22.761019 -376.162807)
			(xy 22.75084 -376.183711) (xy 22.750272 -376.195336) (xy 22.750272 -376.275092) (xy 22.750805 -376.286725)
			(xy 22.760996 -376.307636) (xy 22.76983 -376.315224) (xy 22.790627 -376.331961) (xy 22.827759 -376.370315)
			(xy 22.859181 -376.413472) (xy 22.884281 -376.460587) (xy 22.902567 -376.510741) (xy 22.913683 -376.562955)
			(xy 22.917412 -376.616209) (xy 22.913681 -376.669462) (xy 22.902562 -376.721675) (xy 22.884274 -376.771829)
			(xy 22.859172 -376.818943) (xy 22.827748 -376.862098) (xy 22.790614 -376.900451) (xy 22.76983 -376.917204)
			(xy 22.761019 -376.924807) (xy 22.75084 -376.945711) (xy 22.750272 -376.957336) (xy 22.750272 -377.037092)
			(xy 22.750805 -377.048725) (xy 22.760996 -377.069636) (xy 22.76983 -377.077224) (xy 22.792331 -377.095394)
			(xy 22.832064 -377.137419) (xy 22.865 -377.184958) (xy 22.890385 -377.236924) (xy 22.907638 -377.292125)
			(xy 22.916363 -377.349297) (xy 22.916896 -377.378214) (xy 22.916393 -377.405147) (xy 22.908811 -377.458476)
			(xy 22.8938 -377.510208) (xy 22.87166 -377.559313) (xy 22.84283 -377.604813) (xy 22.82571 -377.62561)
			(xy 22.818852 -377.633738) (xy 22.812756 -377.653804) (xy 22.822662 -377.738386) (xy 22.824359 -377.748681)
			(xy 22.8347 -377.766776) (xy 22.842728 -377.773438) (xy 22.842982 -377.773438) (xy 22.866608 -377.791547)
			(xy 22.908468 -377.833868) (xy 22.943245 -377.882178) (xy 22.970093 -377.935305) (xy 22.988361 -377.991958)
			(xy 22.997606 -378.050761) (xy 22.998176 -378.080524) (xy 22.998176 -378.080778) (xy 22.997679 -378.108758)
			(xy 22.989484 -378.164116) (xy 22.973296 -378.217685) (xy 22.949461 -378.268316) (xy 22.91849 -378.314926)
			(xy 22.900132 -378.336048) (xy 22.893782 -378.34316) (xy 22.886924 -378.361194) (xy 22.888448 -378.450094)
			(xy 22.896068 -378.467874) (xy 22.902672 -378.474732) (xy 22.922864 -378.496215) (xy 22.957006 -378.544279)
			(xy 22.983348 -378.597023) (xy 23.001265 -378.653191) (xy 23.010329 -378.711446) (xy 23.010876 -378.740924)
			(xy 23.01039 -378.768175) (xy 23.002634 -378.822123) (xy 22.987279 -378.874418) (xy 22.964637 -378.923995)
			(xy 22.935171 -378.969845) (xy 22.89948 -379.011036) (xy 22.858289 -379.046727) (xy 22.812439 -379.076193)
			(xy 22.762862 -379.098835) (xy 22.710567 -379.11419) (xy 22.656619 -379.121946) (xy 22.602117 -379.121946)
			(xy 22.548169 -379.11419) (xy 22.495874 -379.098835) (xy 22.446297 -379.076193) (xy 22.400447 -379.046727)
			(xy 22.359256 -379.011036) (xy 22.323565 -378.969845) (xy 22.294099 -378.923995) (xy 22.271457 -378.874418)
			(xy 22.256102 -378.822123) (xy 22.248346 -378.768175) (xy 22.24786 -378.740924) (xy 22.24786 -378.74067)
			(xy 22.248402 -378.712692) (xy 22.256588 -378.657336) (xy 22.272767 -378.603769) (xy 22.296592 -378.553137)
			(xy 22.327552 -378.506524) (xy 22.345904 -378.4854) (xy 22.352254 -378.478288) (xy 22.359112 -378.460254)
			(xy 22.357588 -378.371354) (xy 22.349968 -378.353574) (xy 22.343364 -378.346716) (xy 22.323201 -378.325207)
			(xy 22.289054 -378.277151) (xy 22.262705 -378.224414) (xy 22.244782 -378.168251) (xy 22.23571 -378.11)
			(xy 22.23516 -378.080524) (xy 22.235614 -378.053589) (xy 22.243206 -378.000258) (xy 22.258227 -377.948525)
			(xy 22.280379 -377.899421) (xy 22.30922 -377.853922) (xy 22.326346 -377.833128) (xy 22.333204 -377.825)
			(xy 22.3393 -377.804934) (xy 22.329394 -377.720352) (xy 22.327741 -377.710047) (xy 22.31737 -377.691955)
			(xy 22.309328 -377.6853) (xy 22.309074 -377.6853) (xy 22.28543 -377.667212) (xy 22.243569 -377.624889)
			(xy 22.208792 -377.576575) (xy 22.181946 -377.523443) (xy 22.163683 -377.466786) (xy 22.154445 -377.407978)
			(xy 22.15388 -377.378214) (xy 22.154378 -377.349296) (xy 22.163107 -377.292122) (xy 22.180367 -377.236922)
			(xy 22.205762 -377.18496) (xy 22.238711 -377.137426) (xy 22.278458 -377.095412) (xy 22.300946 -377.077224)
			(xy 22.30974 -377.069604) (xy 22.319929 -377.048713) (xy 22.320504 -377.037092) (xy 22.320504 -376.957336)
			(xy 22.319986 -376.945702) (xy 22.309782 -376.924793) (xy 22.300946 -376.917204) (xy 22.280177 -376.900434)
			(xy 22.243048 -376.862082) (xy 22.211628 -376.818929) (xy 22.18653 -376.771818) (xy 22.168243 -376.721668)
			(xy 22.157126 -376.669458) (xy 22.153395 -376.616209) (xy 21.154341 -376.616209) (xy 21.161067 -376.647798)
			(xy 21.164797 -376.70105) (xy 21.161067 -376.754302) (xy 21.14995 -376.806513) (xy 21.131664 -376.856665)
			(xy 21.106565 -376.903779) (xy 21.075144 -376.946934) (xy 21.038013 -376.985287) (xy 21.01723 -377.00204)
			(xy 21.008403 -377.009628) (xy 20.998233 -377.030544) (xy 20.997672 -377.042172) (xy 20.997672 -377.121928)
			(xy 20.998184 -377.133564) (xy 21.008389 -377.154475) (xy 21.01723 -377.16206) (xy 21.039701 -377.180266)
			(xy 21.079435 -377.222284) (xy 21.112375 -377.269816) (xy 21.137765 -377.321774) (xy 21.155025 -377.376968)
			(xy 21.163758 -377.434135) (xy 21.164296 -377.46305) (xy 21.163853 -377.49088) (xy 21.155772 -377.545949)
			(xy 21.139772 -377.599259) (xy 21.116195 -377.649678) (xy 21.085541 -377.696135) (xy 21.048461 -377.737644)
			(xy 21.005742 -377.773324) (xy 20.958291 -377.802416) (xy 20.932902 -377.813824) (xy 20.923504 -377.817888)
			(xy 20.909026 -377.83262) (xy 20.875752 -377.921012) (xy 20.876514 -377.941078) (xy 20.881086 -377.950476)
			(xy 20.881086 -377.950984) (xy 20.888452 -377.966986) (xy 20.892425 -377.975526) (xy 20.905503 -377.989068)
			(xy 20.922589 -377.996973) (xy 20.941376 -377.998175) (xy 20.959329 -377.992513) (xy 20.974027 -377.980749)
			(xy 20.97913 -377.972828) (xy 20.993908 -377.94856) (xy 21.029543 -377.904305) (xy 21.071346 -377.865824)
			(xy 21.118394 -377.833968) (xy 21.169645 -377.809441) (xy 21.223967 -377.792785) (xy 21.280159 -377.78437)
			(xy 21.308568 -377.783852) (xy 21.335817 -377.784408) (xy 21.38976 -377.792159) (xy 21.442051 -377.807508)
			(xy 21.491625 -377.830143) (xy 21.537474 -377.859602) (xy 21.578663 -377.895286) (xy 21.614355 -377.936469)
			(xy 21.643823 -377.982312) (xy 21.666467 -378.031882) (xy 21.681826 -378.08417) (xy 21.689587 -378.138111)
			(xy 21.690076 -378.16536) (xy 21.689633 -378.19266) (xy 21.681852 -378.246704) (xy 21.666445 -378.299085)
			(xy 21.643725 -378.348734) (xy 21.614157 -378.394636) (xy 21.596604 -378.41555) (xy 21.590601 -378.423083)
			(xy 21.58419 -378.441225) (xy 21.584158 -378.450856) (xy 21.586952 -378.520452) (xy 21.587727 -378.529893)
			(xy 21.595288 -378.547247) (xy 21.601684 -378.554234) (xy 21.601938 -378.554488) (xy 21.623017 -378.576118)
			(xy 21.658744 -378.624811) (xy 21.686349 -378.678527) (xy 21.705141 -378.735923) (xy 21.714652 -378.795563)
			(xy 21.715222 -378.82576) (xy 21.714729 -378.8545) (xy 21.706098 -378.911328) (xy 21.68904 -378.966219)
			(xy 21.663942 -379.01793) (xy 21.631371 -379.065292) (xy 21.612098 -379.086618) (xy 21.605494 -379.093476)
			(xy 21.598382 -379.11151) (xy 21.598382 -379.20041) (xy 21.605494 -379.218444) (xy 21.612098 -379.225302)
			(xy 21.631339 -379.246655) (xy 21.663911 -379.294009) (xy 21.689011 -379.345714) (xy 21.706068 -379.400599)
			(xy 21.714697 -379.457423) (xy 21.715222 -379.48616) (xy 21.714752 -379.51353) (xy 21.706938 -379.56771)
			(xy 21.691451 -379.620214) (xy 21.668609 -379.669961) (xy 21.638884 -379.715927) (xy 21.621242 -379.736858)
			(xy 21.620988 -379.737112) (xy 21.615389 -379.74419) (xy 21.60915 -379.761113) (xy 21.608796 -379.770132)
			(xy 21.608796 -379.837188) (xy 21.60916 -379.846204) (xy 21.615403 -379.863121) (xy 21.620988 -379.870208)
			(xy 21.621242 -379.870208) (xy 21.621242 -379.870462) (xy 21.638884 -379.891392) (xy 21.668594 -379.937366)
			(xy 21.691429 -379.987114) (xy 21.706919 -380.039615) (xy 21.714748 -380.093791) (xy 21.715222 -380.12116)
			(xy 21.714631 -380.151355) (xy 21.705111 -380.210989) (xy 21.686316 -380.26838) (xy 21.658718 -380.322094)
			(xy 21.623003 -380.370792) (xy 21.601938 -380.392432) (xy 21.601684 -380.392686) (xy 21.595283 -380.399671)
			(xy 21.587714 -380.417025) (xy 21.586952 -380.426468) (xy 21.584158 -380.496064) (xy 21.584249 -380.505688)
			(xy 21.590626 -380.523829) (xy 21.596604 -380.53137) (xy 21.614134 -380.552301) (xy 21.643695 -380.598202)
			(xy 21.666411 -380.647848) (xy 21.68182 -380.700224) (xy 21.689607 -380.754262) (xy 21.690076 -380.78156)
			(xy 21.689631 -380.807303) (xy 21.682701 -380.85832) (xy 21.668976 -380.907942) (xy 21.648705 -380.955269)
			(xy 21.622254 -380.999441) (xy 21.60651 -381.019812) (xy 21.600668 -381.027178) (xy 21.59508 -381.045212)
			(xy 21.599906 -381.122936) (xy 21.60097 -381.132206) (xy 21.60878 -381.149135) (xy 21.615146 -381.155956)
			(xy 21.618956 -381.159766) (xy 21.626381 -381.166574) (xy 21.644961 -381.174314) (xy 21.655024 -381.174752)
			(xy 21.839682 -381.174752) (xy 21.864678 -381.175391) (xy 21.913701 -381.185193) (xy 21.959872 -381.204366)
			(xy 22.001418 -381.232173) (xy 22.019514 -381.249428) (xy 23.320756 -382.55067) (xy 23.338031 -382.568749)
			(xy 23.36584 -382.610299) (xy 23.385008 -382.656475) (xy 23.3948 -382.705504) (xy 23.395432 -382.730502)
			(xy 23.395432 -385.217924) (xy 23.394824 -385.242922) (xy 23.385013 -385.291946) (xy 23.365831 -385.338117)
			(xy 23.338015 -385.379662) (xy 23.320756 -385.397756) (xy 22.19579 -386.522722) (xy 22.188947 -386.530119)
			(xy 22.181229 -386.548721) (xy 22.180804 -386.55879) (xy 22.180804 -388.574026) (xy 22.181188 -388.5841)
			(xy 22.188935 -388.602699) (xy 22.19579 -388.610094) (xy 22.45106 -388.865364) (xy 22.468333 -388.883445)
			(xy 22.496142 -388.924994) (xy 22.515311 -388.97117) (xy 22.525103 -389.020198) (xy 22.525736 -389.045196)
			(xy 22.525736 -390.824466) (xy 22.525091 -390.849462) (xy 22.516528 -390.8923) (xy 25.924276 -390.8923)
			(xy 25.928259 -390.839151) (xy 25.940119 -390.787188) (xy 25.95959 -390.737574) (xy 25.986238 -390.691416)
			(xy 26.019467 -390.649744) (xy 26.058536 -390.613491) (xy 26.102572 -390.583464) (xy 26.150591 -390.560336)
			(xy 26.20152 -390.544623) (xy 26.254223 -390.536676) (xy 26.280872 -390.536176) (xy 26.307232 -390.536658)
			(xy 26.359374 -390.544448) (xy 26.409796 -390.559846) (xy 26.457393 -390.582515) (xy 26.501125 -390.611959)
			(xy 26.520902 -390.629394) (xy 26.521156 -390.629648) (xy 26.528336 -390.635658) (xy 26.545832 -390.642298)
			(xy 26.555192 -390.642602) (xy 26.623772 -390.642602) (xy 26.63311 -390.642204) (xy 26.650561 -390.635552)
			(xy 26.657808 -390.629648) (xy 26.658316 -390.62914) (xy 26.678074 -390.611741) (xy 26.721789 -390.582403)
			(xy 26.769343 -390.559811) (xy 26.819701 -390.544455) (xy 26.871769 -390.53667) (xy 26.898092 -390.536176)
			(xy 26.924453 -390.536646) (xy 26.976595 -390.544439) (xy 27.027017 -390.55984) (xy 27.074614 -390.582511)
			(xy 27.118346 -390.611958) (xy 27.138122 -390.629394) (xy 27.138376 -390.629648) (xy 27.145581 -390.635623)
			(xy 27.163058 -390.642284) (xy 27.172412 -390.642602) (xy 27.240992 -390.642602) (xy 27.250326 -390.642165)
			(xy 27.267778 -390.63554) (xy 27.275028 -390.629648) (xy 27.275536 -390.62914) (xy 27.295326 -390.611779)
			(xy 27.339032 -390.582435) (xy 27.386578 -390.559836) (xy 27.436929 -390.544471) (xy 27.488991 -390.536676)
			(xy 27.515312 -390.536176) (xy 27.540308 -390.536589) (xy 27.589808 -390.543588) (xy 27.637846 -390.557433)
			(xy 27.683478 -390.577853) (xy 27.72581 -390.604448) (xy 27.745182 -390.62025) (xy 27.75204 -390.626092)
			(xy 27.769058 -390.632442) (xy 27.852624 -390.632442) (xy 27.869642 -390.626092) (xy 27.8765 -390.62025)
			(xy 27.895852 -390.604422) (xy 27.938186 -390.577825) (xy 27.983823 -390.557409) (xy 28.031866 -390.543574)
			(xy 28.081372 -390.536593) (xy 28.10637 -390.536176) (xy 28.133805 -390.53668) (xy 28.188024 -390.545101)
			(xy 28.21432 -390.55294) (xy 28.225496 -390.556496) (xy 28.24861 -390.553194) (xy 28.334462 -390.49452)
			(xy 28.345892 -390.4742) (xy 28.346654 -390.462516) (xy 28.348971 -390.433797) (xy 28.361097 -390.377473)
			(xy 28.381556 -390.323614) (xy 28.409882 -390.273444) (xy 28.445432 -390.228105) (xy 28.487397 -390.188628)
			(xy 28.534821 -390.155912) (xy 28.586626 -390.130701) (xy 28.641634 -390.113568) (xy 28.698593 -390.104903)
			(xy 28.7274 -390.104376) (xy 28.75465 -390.104894) (xy 28.808595 -390.11265) (xy 28.860888 -390.128005)
			(xy 28.910463 -390.150645) (xy 28.956311 -390.18011) (xy 28.9975 -390.2158) (xy 29.03319 -390.256989)
			(xy 29.062655 -390.302837) (xy 29.085295 -390.352412) (xy 29.10065 -390.404705) (xy 29.108406 -390.45865)
			(xy 29.108406 -390.51315) (xy 29.10065 -390.567095) (xy 29.085295 -390.619388) (xy 29.062655 -390.668963)
			(xy 29.03319 -390.714811) (xy 28.9975 -390.756) (xy 28.956311 -390.79169) (xy 28.910463 -390.821155)
			(xy 28.860888 -390.843795) (xy 28.808595 -390.85915) (xy 28.75465 -390.866906) (xy 28.7274 -390.867392)
			(xy 28.693996 -390.866697) (xy 28.628208 -390.855075) (xy 28.59659 -390.844278) (xy 28.585414 -390.840214)
			(xy 28.5623 -390.8425) (xy 28.484068 -390.891522) (xy 28.474593 -390.898061) (xy 28.462297 -390.917498)
			(xy 28.460446 -390.92886) (xy 28.460446 -390.929368) (xy 28.457216 -390.955293) (xy 28.444267 -391.005903)
			(xy 28.42406 -391.054076) (xy 28.397027 -391.098778) (xy 28.36375 -391.139047) (xy 28.324943 -391.17402)
			(xy 28.281441 -391.202944) (xy 28.234178 -391.225197) (xy 28.184169 -391.240302) (xy 28.13249 -391.247935)
			(xy 28.10637 -391.248392) (xy 28.081375 -391.24794) (xy 28.031876 -391.240951) (xy 27.983839 -391.227115)
			(xy 27.938206 -391.206704) (xy 27.895873 -391.180117) (xy 27.8765 -391.164318) (xy 27.869642 -391.158476)
			(xy 27.852624 -391.152126) (xy 27.769058 -391.152126) (xy 27.75204 -391.158476) (xy 27.745182 -391.164318)
			(xy 27.725796 -391.180103) (xy 27.683472 -391.206708) (xy 27.637844 -391.227133) (xy 27.589808 -391.240977)
			(xy 27.540308 -391.247969) (xy 27.515312 -391.248392) (xy 27.488951 -391.247927) (xy 27.436808 -391.240135)
			(xy 27.386386 -391.224733) (xy 27.338788 -391.20206) (xy 27.295058 -391.172611) (xy 27.275282 -391.155174)
			(xy 27.275028 -391.15492) (xy 27.267816 -391.148955) (xy 27.250344 -391.142286) (xy 27.240992 -391.141966)
			(xy 27.172412 -391.141966) (xy 27.163077 -391.14239) (xy 27.145624 -391.149022) (xy 27.138376 -391.15492)
			(xy 27.137868 -391.155428) (xy 27.118072 -391.172782) (xy 27.074368 -391.202128) (xy 27.026824 -391.224729)
			(xy 26.976474 -391.240095) (xy 26.924413 -391.247892) (xy 26.898092 -391.248392) (xy 26.871731 -391.247939)
			(xy 26.819587 -391.240144) (xy 26.769165 -391.22474) (xy 26.721567 -391.202064) (xy 26.677837 -391.172612)
			(xy 26.658062 -391.155174) (xy 26.657808 -391.15492) (xy 26.650602 -391.148946) (xy 26.633126 -391.142282)
			(xy 26.623772 -391.141966) (xy 26.555192 -391.141966) (xy 26.545856 -391.14238) (xy 26.528403 -391.14902)
			(xy 26.521156 -391.15492) (xy 26.520648 -391.155428) (xy 26.50086 -391.172792) (xy 26.457154 -391.202136)
			(xy 26.409608 -391.224735) (xy 26.359256 -391.240099) (xy 26.307193 -391.247893) (xy 26.280872 -391.248392)
			(xy 26.254223 -391.247924) (xy 26.20152 -391.239977) (xy 26.150591 -391.224264) (xy 26.102572 -391.201136)
			(xy 26.058536 -391.171109) (xy 26.019467 -391.134856) (xy 25.986238 -391.093184) (xy 25.95959 -391.047026)
			(xy 25.940119 -390.997412) (xy 25.928259 -390.945449) (xy 25.924276 -390.8923) (xy 22.516528 -390.8923)
			(xy 22.515292 -390.898485) (xy 22.496121 -390.944656) (xy 22.468315 -390.986202) (xy 22.45106 -391.004298)
			(xy 21.642832 -391.812526) (xy 27.862276 -391.812526) (xy 27.862779 -391.785275) (xy 27.870532 -391.731326)
			(xy 27.885884 -391.67903) (xy 27.908523 -391.629451) (xy 27.937987 -391.583598) (xy 27.973676 -391.542406)
			(xy 28.014865 -391.506712) (xy 28.060714 -391.477243) (xy 28.11029 -391.454599) (xy 28.162585 -391.439241)
			(xy 28.216533 -391.431482) (xy 28.243784 -391.431018) (xy 28.273907 -391.431608) (xy 28.333402 -391.441086)
			(xy 28.390669 -391.459793) (xy 28.444286 -391.487264) (xy 28.492922 -391.522818) (xy 28.514548 -391.543794)
			(xy 28.522168 -391.551668) (xy 28.542488 -391.559288) (xy 28.629102 -391.554716) (xy 28.639766 -391.553542)
			(xy 28.658795 -391.543679) (xy 28.665932 -391.535666) (xy 28.68415 -391.513789) (xy 28.725992 -391.475185)
			(xy 28.773102 -391.443223) (xy 28.824436 -391.41861) (xy 28.878856 -391.401893) (xy 28.935155 -391.393442)
			(xy 28.96362 -391.392918) (xy 28.990875 -391.393336) (xy 29.044828 -391.401097) (xy 29.097129 -391.416457)
			(xy 29.146711 -391.439103) (xy 29.192565 -391.468576) (xy 29.233758 -391.504274) (xy 29.269452 -391.545472)
			(xy 29.298919 -391.59133) (xy 29.321559 -391.640914) (xy 29.336913 -391.693217) (xy 29.344667 -391.747171)
			(xy 29.345128 -391.774426) (xy 29.344717 -391.800035) (xy 29.337855 -391.850792) (xy 29.324271 -391.900177)
			(xy 29.304209 -391.947303) (xy 29.278029 -391.991325) (xy 29.246201 -392.031453) (xy 29.228034 -392.049508)
			(xy 29.218636 -392.058398) (xy 29.210762 -392.082528) (xy 29.231336 -392.191494) (xy 29.247084 -392.211306)
			(xy 29.259022 -392.216386) (xy 29.284595 -392.227703) (xy 29.332418 -392.256689) (xy 29.375495 -392.292347)
			(xy 29.412903 -392.333914) (xy 29.443839 -392.380499) (xy 29.46764 -392.431103) (xy 29.483795 -392.484639)
			(xy 29.491959 -392.539961) (xy 29.492448 -392.567922) (xy 29.491943 -392.595172) (xy 29.484184 -392.649117)
			(xy 29.468828 -392.701409) (xy 29.446188 -392.750983) (xy 29.416723 -392.796832) (xy 29.381034 -392.838021)
			(xy 29.339846 -392.873712) (xy 29.293999 -392.903179) (xy 29.244426 -392.925822) (xy 29.192135 -392.94118)
			(xy 29.13819 -392.948942) (xy 29.11094 -392.94943) (xy 29.080673 -392.948837) (xy 29.0209 -392.939271)
			(xy 28.963386 -392.920389) (xy 28.909575 -392.892664) (xy 28.860815 -392.856792) (xy 28.83916 -392.835638)
			(xy 28.832048 -392.828526) (xy 28.813506 -392.820652) (xy 28.720288 -392.820652) (xy 28.701746 -392.828526)
			(xy 28.694634 -392.835638) (xy 28.672998 -392.856814) (xy 28.624238 -392.892693) (xy 28.570422 -392.92042)
			(xy 28.512903 -392.939298) (xy 28.453123 -392.948853) (xy 28.422854 -392.94943) (xy 28.395603 -392.948965)
			(xy 28.341655 -392.941203) (xy 28.289362 -392.925843) (xy 28.239786 -392.903198) (xy 28.193936 -392.873729)
			(xy 28.152747 -392.838036) (xy 28.117057 -392.796844) (xy 28.08759 -392.750993) (xy 28.064949 -392.701416)
			(xy 28.049592 -392.649121) (xy 28.041833 -392.595173) (xy 28.041346 -392.567922) (xy 28.041819 -392.541189)
			(xy 28.049324 -392.488253) (xy 28.064134 -392.436879) (xy 28.085961 -392.38807) (xy 28.114378 -392.342781)
			(xy 28.131262 -392.32205) (xy 28.138344 -392.312547) (xy 28.14379 -392.289514) (xy 28.141676 -392.277854)
			(xy 28.120086 -392.186414) (xy 28.104592 -392.168126) (xy 28.093416 -392.1633) (xy 28.068068 -392.151839)
			(xy 28.020679 -392.122711) (xy 27.978019 -392.087013) (xy 27.940992 -392.045501) (xy 27.910382 -391.999054)
			(xy 27.886838 -391.948656) (xy 27.870858 -391.895375) (xy 27.862781 -391.840339) (xy 27.862276 -391.812526)
			(xy 21.642832 -391.812526) (xy 21.53285 -391.922508) (xy 21.516378 -391.938241) (xy 21.478932 -391.964168)
			(xy 21.43746 -391.982998) (xy 21.415502 -391.989056) (xy 21.408514 -391.991037) (xy 21.395997 -391.998395)
			(xy 21.390864 -392.003534) (xy 21.37278 -392.022208) (xy 21.332413 -392.054963) (xy 21.287973 -392.081934)
			(xy 21.240282 -392.102619) (xy 21.190224 -392.116637) (xy 21.138726 -392.123728) (xy 21.112734 -392.124184)
			(xy 21.085478 -392.123771) (xy 21.03152 -392.116018) (xy 20.979214 -392.100664) (xy 20.929627 -392.078022)
			(xy 20.883767 -392.048553) (xy 20.842567 -392.012857) (xy 20.806868 -391.971661) (xy 20.777395 -391.925803)
			(xy 20.754748 -391.876217) (xy 20.739389 -391.823914) (xy 20.731631 -391.769956) (xy 20.731631 -391.715444)
			(xy 20.739389 -391.661486) (xy 20.754748 -391.609183) (xy 20.777395 -391.559597) (xy 20.806868 -391.513739)
			(xy 20.842567 -391.472543) (xy 20.883767 -391.436847) (xy 20.929627 -391.407378) (xy 20.979214 -391.384736)
			(xy 21.03152 -391.369382) (xy 21.085478 -391.361629) (xy 21.112734 -391.361168) (xy 21.142438 -391.361732)
			(xy 21.201126 -391.370952) (xy 21.257668 -391.389177) (xy 21.284438 -391.402062) (xy 21.284692 -391.402316)
			(xy 21.294456 -391.406554) (xy 21.315688 -391.407541) (xy 21.335493 -391.399824) (xy 21.343366 -391.392664)
			(xy 22.001734 -390.734042) (xy 22.008553 -390.726626) (xy 22.016284 -390.708039) (xy 22.01672 -390.697974)
			(xy 22.01672 -389.171688) (xy 22.016322 -389.161615) (xy 22.008584 -389.143016) (xy 22.001734 -389.13562)
			(xy 21.746718 -388.88035) (xy 21.7295 -388.862237) (xy 21.701759 -388.820678) (xy 21.682651 -388.774509)
			(xy 21.672909 -388.725501) (xy 21.672296 -388.700518) (xy 21.672296 -386.432298) (xy 21.672912 -386.407315)
			(xy 21.682652 -386.358306) (xy 21.701758 -386.312136) (xy 21.729496 -386.270576) (xy 21.746718 -386.252466)
			(xy 22.87143 -385.1275) (xy 22.878267 -385.120098) (xy 22.885988 -385.1015) (xy 22.886416 -385.091432)
			(xy 22.886416 -382.856994) (xy 22.886016 -382.846921) (xy 22.87828 -382.828323) (xy 22.87143 -382.820926)
			(xy 21.749258 -381.698754) (xy 21.741872 -381.691897) (xy 21.723262 -381.684188) (xy 21.71319 -381.683768)
			(xy 21.644864 -381.683768) (xy 21.626322 -381.691388) (xy 21.61921 -381.6985) (xy 21.597616 -381.719409)
			(xy 21.549046 -381.754818) (xy 21.495522 -381.78217) (xy 21.438371 -381.800787) (xy 21.379008 -381.810208)
			(xy 21.348954 -381.810768) (xy 21.3217 -381.810365) (xy 21.267747 -381.802601) (xy 21.215448 -381.787238)
			(xy 21.165868 -381.764589) (xy 21.120016 -381.735114) (xy 21.078825 -381.699414) (xy 21.043135 -381.658215)
			(xy 21.01367 -381.612356) (xy 20.991032 -381.562771) (xy 20.975681 -381.510469) (xy 20.967929 -381.456514)
			(xy 20.967446 -381.42926) (xy 20.967897 -381.403517) (xy 20.974825 -381.3525) (xy 20.988548 -381.302878)
			(xy 21.008819 -381.255551) (xy 21.035268 -381.211379) (xy 21.051012 -381.191008) (xy 21.056854 -381.183642)
			(xy 21.062442 -381.165608) (xy 21.057616 -381.087884) (xy 21.056537 -381.078617) (xy 21.048737 -381.061687)
			(xy 21.042376 -381.054864) (xy 21.033534 -381.046143) (xy 21.016883 -381.027713) (xy 21.009102 -381.018034)
			(xy 21.001736 -381.008636) (xy 20.979892 -380.998476) (xy 20.87372 -381.001778) (xy 20.852638 -381.013462)
			(xy 20.84578 -381.023368) (xy 20.830474 -381.044859) (xy 20.794837 -381.083769) (xy 20.754179 -381.117397)
			(xy 20.709276 -381.145103) (xy 20.660984 -381.166358) (xy 20.610223 -381.180756) (xy 20.557963 -381.188023)
			(xy 20.531582 -381.188468) (xy 20.503359 -381.187956) (xy 20.447528 -381.179636) (xy 20.393529 -381.163194)
			(xy 20.342536 -381.138988) (xy 20.295657 -381.107544) (xy 20.253914 -381.069548) (xy 20.235672 -381.048006)
			(xy 20.22809 -381.039564) (xy 20.207634 -381.02981) (xy 20.196302 -381.02921) (xy 20.117562 -381.02921)
			(xy 20.106242 -381.029845) (xy 20.085809 -381.039608) (xy 20.078192 -381.048006) (xy 20.05995 -381.06955)
			(xy 20.018215 -381.107559) (xy 19.97134 -381.13901) (xy 19.920344 -381.163218) (xy 19.866341 -381.179654)
			(xy 19.810507 -381.187962) (xy 19.782282 -381.188468) (xy 19.753023 -381.187894) (xy 19.695192 -381.178951)
			(xy 19.639402 -381.161291) (xy 19.586959 -381.135327) (xy 19.539089 -381.101669) (xy 19.517614 -381.081788)
			(xy 19.510248 -381.074676) (xy 19.492468 -381.067564) (xy 19.402044 -381.067564) (xy 19.384264 -381.074676)
			(xy 19.376898 -381.081788) (xy 19.355462 -381.101717) (xy 19.307591 -381.135391) (xy 19.25514 -381.16136)
			(xy 19.199338 -381.179014) (xy 19.141494 -381.187941) (xy 19.11223 -381.188468) (xy 19.08491 -381.188023)
			(xy 19.03083 -381.180225) (xy 18.978417 -381.164786) (xy 18.928746 -381.142022) (xy 18.882833 -381.112399)
			(xy 18.841621 -381.076524) (xy 18.823432 -381.056134) (xy 18.815992 -381.048286) (xy 18.796384 -381.039209)
			(xy 18.785586 -381.038608) (xy 18.709132 -381.037846) (xy 18.698369 -381.038161) (xy 18.678632 -381.046726)
			(xy 18.671032 -381.054356) (xy 18.670778 -381.05461) (xy 18.652632 -381.074166) (xy 18.611793 -381.108492)
			(xy 18.566569 -381.136791) (xy 18.517842 -381.158512) (xy 18.466563 -381.17323) (xy 18.413734 -381.180659)
			(xy 18.38706 -381.181102) (xy 18.359807 -381.180659) (xy 18.305858 -381.172897) (xy 18.253562 -381.157537)
			(xy 18.203984 -381.134891) (xy 18.158134 -381.10542) (xy 18.116944 -381.069724) (xy 18.081253 -381.028529)
			(xy 18.051787 -380.982675) (xy 18.029147 -380.933095) (xy 18.013793 -380.880797) (xy 18.006037 -380.826847)
			(xy 18.005552 -380.799594) (xy 16.644405 -380.799594) (xy 16.636875 -380.851676) (xy 16.621374 -380.90418)
			(xy 16.598523 -380.953928) (xy 16.568792 -380.999896) (xy 16.551148 -381.020828) (xy 16.550894 -381.021082)
			(xy 16.545308 -381.028169) (xy 16.539061 -381.045085) (xy 16.538702 -381.054102) (xy 16.538702 -381.121158)
			(xy 16.539079 -381.130173) (xy 16.545313 -381.14709) (xy 16.550894 -381.154178) (xy 16.551148 -381.154178)
			(xy 16.551148 -381.154432) (xy 16.568761 -381.175386) (xy 16.598478 -381.221352) (xy 16.62132 -381.271094)
			(xy 16.636817 -381.32359) (xy 16.644651 -381.377762) (xy 16.645128 -381.40513) (xy 16.644642 -381.432381)
			(xy 16.636886 -381.486329) (xy 16.621531 -381.538624) (xy 16.598889 -381.588201) (xy 16.569423 -381.634051)
			(xy 16.533732 -381.675242) (xy 16.492541 -381.710933) (xy 16.446691 -381.740399) (xy 16.397114 -381.763041)
			(xy 16.344819 -381.778396) (xy 16.290871 -381.786152) (xy 16.236369 -381.786152) (xy 16.182421 -381.778396)
			(xy 16.130126 -381.763041) (xy 16.080549 -381.740399) (xy 16.034699 -381.710933) (xy 15.993508 -381.675242)
			(xy 15.957817 -381.634051) (xy 15.928351 -381.588201) (xy 15.905709 -381.538624) (xy 15.890354 -381.486329)
			(xy 15.882598 -381.432381) (xy 15.882112 -381.40513) (xy 10.071608 -381.40513) (xy 10.071608 -383.947162)
			(xy 10.072051 -383.957229) (xy 10.079759 -383.975827) (xy 10.086594 -383.98323) (xy 12.039092 -385.935982)
			(xy 12.056334 -385.954088) (xy 12.084085 -385.995671) (xy 12.09421 -386.018532) (xy 13.310108 -388.953756)
			(xy 13.31907 -388.977007) (xy 13.328783 -389.025873) (xy 13.329412 -389.050784) (xy 13.329412 -389.571484)
			(xy 20.902166 -389.571484) (xy 20.906237 -389.515862) (xy 20.918363 -389.461425) (xy 20.938286 -389.409334)
			(xy 20.965582 -389.360699) (xy 20.999668 -389.316556) (xy 21.039817 -389.277847) (xy 21.085175 -389.245396)
			(xy 21.134775 -389.219895) (xy 21.187559 -389.201888) (xy 21.242402 -389.191758) (xy 21.298136 -389.189721)
			(xy 21.353573 -389.195821) (xy 21.40753 -389.209927) (xy 21.458859 -389.231739) (xy 21.506465 -389.260793)
			(xy 21.549333 -389.296468) (xy 21.58655 -389.338005) (xy 21.617323 -389.384518) (xy 21.640995 -389.435015)
			(xy 21.657063 -389.488422) (xy 21.665183 -389.543598) (xy 21.665692 -389.571484) (xy 21.665183 -389.59937)
			(xy 21.657063 -389.654546) (xy 21.640995 -389.707953) (xy 21.617323 -389.75845) (xy 21.58655 -389.804963)
			(xy 21.549333 -389.8465) (xy 21.506465 -389.882175) (xy 21.458859 -389.911229) (xy 21.40753 -389.933041)
			(xy 21.353573 -389.947147) (xy 21.298136 -389.953247) (xy 21.242402 -389.95121) (xy 21.187559 -389.94108)
			(xy 21.134775 -389.923073) (xy 21.085175 -389.897572) (xy 21.039817 -389.865121) (xy 20.999668 -389.826412)
			(xy 20.965582 -389.782269) (xy 20.938286 -389.733634) (xy 20.918363 -389.681543) (xy 20.906237 -389.627106)
			(xy 20.902166 -389.571484) (xy 13.329412 -389.571484) (xy 13.329412 -390.89228) (xy 16.845547 -390.89228)
			(xy 16.849529 -390.839131) (xy 16.861389 -390.787169) (xy 16.880861 -390.737556) (xy 16.90751 -390.691398)
			(xy 16.940741 -390.649728) (xy 16.979811 -390.613476) (xy 17.023848 -390.583452) (xy 17.071868 -390.560327)
			(xy 17.122798 -390.544617) (xy 17.175501 -390.536674) (xy 17.20215 -390.536176) (xy 17.22851 -390.536672)
			(xy 17.280651 -390.544458) (xy 17.331072 -390.559853) (xy 17.37867 -390.582519) (xy 17.422403 -390.61196)
			(xy 17.44218 -390.629394) (xy 17.442434 -390.629648) (xy 17.449621 -390.635648) (xy 17.467112 -390.642294)
			(xy 17.47647 -390.642602) (xy 17.54505 -390.642602) (xy 17.554387 -390.642193) (xy 17.571838 -390.635549)
			(xy 17.579086 -390.629648) (xy 17.579594 -390.62914) (xy 17.599361 -390.611751) (xy 17.643074 -390.582412)
			(xy 17.690625 -390.559818) (xy 17.740981 -390.54446) (xy 17.793047 -390.536672) (xy 17.81937 -390.536176)
			(xy 17.84573 -390.53666) (xy 17.897872 -390.544449) (xy 17.948294 -390.559846) (xy 17.995891 -390.582515)
			(xy 18.039623 -390.611959) (xy 18.0594 -390.629394) (xy 18.059654 -390.629648) (xy 18.066835 -390.635657)
			(xy 18.08433 -390.642298) (xy 18.09369 -390.642602) (xy 18.16227 -390.642602) (xy 18.171608 -390.642203)
			(xy 18.189059 -390.635551) (xy 18.196306 -390.629648) (xy 18.196814 -390.62914) (xy 18.216573 -390.611742)
			(xy 18.260288 -390.582404) (xy 18.307841 -390.559811) (xy 18.358199 -390.544456) (xy 18.410267 -390.53667)
			(xy 18.43659 -390.536176) (xy 18.461586 -390.536601) (xy 18.511085 -390.543597) (xy 18.559123 -390.55744)
			(xy 18.604755 -390.577857) (xy 18.647087 -390.604449) (xy 18.66646 -390.62025) (xy 18.673318 -390.626092)
			(xy 18.690336 -390.632442) (xy 18.773902 -390.632442) (xy 18.79092 -390.626092) (xy 18.797778 -390.62025)
			(xy 18.817138 -390.604432) (xy 18.85947 -390.577833) (xy 18.905105 -390.557415) (xy 18.953146 -390.543578)
			(xy 19.002651 -390.536595) (xy 19.027648 -390.536176) (xy 19.053974 -390.536628) (xy 19.106051 -390.544396)
			(xy 19.156413 -390.559754) (xy 19.203962 -390.582368) (xy 19.247659 -390.611743) (xy 19.267424 -390.62914)
			(xy 19.267678 -390.629394) (xy 19.277408 -390.63725) (xy 19.301644 -390.643264) (xy 19.313906 -390.640824)
			(xy 19.408902 -390.616948) (xy 19.427444 -390.59993) (xy 19.431762 -390.587738) (xy 19.44086 -390.563228)
			(xy 19.464763 -390.516732) (xy 19.494791 -390.473936) (xy 19.530383 -390.435642) (xy 19.57087 -390.402567)
			(xy 19.615495 -390.37533) (xy 19.663421 -390.354442) (xy 19.71375 -390.340295) (xy 19.76554 -390.333153)
			(xy 19.79168 -390.332722) (xy 19.818936 -390.333124) (xy 19.872893 -390.340879) (xy 19.925198 -390.356234)
			(xy 19.974784 -390.378878) (xy 20.020644 -390.408347) (xy 20.061842 -390.444044) (xy 20.087094 -390.473184)
			(xy 20.905976 -390.473184) (xy 20.910047 -390.417562) (xy 20.922173 -390.363125) (xy 20.942096 -390.311034)
			(xy 20.969392 -390.262399) (xy 21.003478 -390.218256) (xy 21.043627 -390.179547) (xy 21.088985 -390.147096)
			(xy 21.138585 -390.121595) (xy 21.191369 -390.103588) (xy 21.246212 -390.093458) (xy 21.301946 -390.091421)
			(xy 21.357383 -390.097521) (xy 21.41134 -390.111627) (xy 21.462669 -390.133439) (xy 21.510275 -390.162493)
			(xy 21.553143 -390.198168) (xy 21.59036 -390.239705) (xy 21.621133 -390.286218) (xy 21.644805 -390.336715)
			(xy 21.660873 -390.390122) (xy 21.668993 -390.445298) (xy 21.669502 -390.473184) (xy 21.668993 -390.50107)
			(xy 21.660873 -390.556246) (xy 21.644805 -390.609653) (xy 21.621133 -390.66015) (xy 21.59036 -390.706663)
			(xy 21.553143 -390.7482) (xy 21.510275 -390.783875) (xy 21.462669 -390.812929) (xy 21.41134 -390.834741)
			(xy 21.357383 -390.848847) (xy 21.301946 -390.854947) (xy 21.246212 -390.85291) (xy 21.191369 -390.84278)
			(xy 21.138585 -390.824773) (xy 21.088985 -390.799272) (xy 21.043627 -390.766821) (xy 21.003478 -390.728112)
			(xy 20.969392 -390.683969) (xy 20.942096 -390.635334) (xy 20.922173 -390.583243) (xy 20.910047 -390.528806)
			(xy 20.905976 -390.473184) (xy 20.087094 -390.473184) (xy 20.097541 -390.48524) (xy 20.127013 -390.531098)
			(xy 20.149659 -390.580683) (xy 20.165017 -390.632987) (xy 20.172775 -390.686944) (xy 20.172775 -390.741456)
			(xy 20.165017 -390.795413) (xy 20.149659 -390.847717) (xy 20.127013 -390.897302) (xy 20.097541 -390.94316)
			(xy 20.061842 -390.984356) (xy 20.020644 -391.020053) (xy 19.974784 -391.049522) (xy 19.925198 -391.072166)
			(xy 19.872893 -391.087521) (xy 19.818936 -391.095276) (xy 19.79168 -391.095738) (xy 19.762096 -391.095179)
			(xy 19.703637 -391.086042) (xy 19.64729 -391.06799) (xy 19.594405 -391.041455) (xy 19.546251 -391.007075)
			(xy 19.524726 -390.986772) (xy 19.515836 -390.977882) (xy 19.491198 -390.97077) (xy 19.383248 -390.993884)
			(xy 19.36369 -391.010394) (xy 19.359118 -391.022332) (xy 19.348961 -391.046979) (xy 19.322322 -391.093153)
			(xy 19.289095 -391.134839) (xy 19.250024 -391.171104) (xy 19.205982 -391.201138) (xy 19.157955 -391.22427)
			(xy 19.107015 -391.239981) (xy 19.054302 -391.247922) (xy 19.027648 -391.248392) (xy 19.002653 -391.247952)
			(xy 18.953153 -391.240961) (xy 18.905116 -391.227122) (xy 18.859484 -391.206708) (xy 18.817151 -391.180118)
			(xy 18.797778 -391.164318) (xy 18.79092 -391.158476) (xy 18.773902 -391.152126) (xy 18.690336 -391.152126)
			(xy 18.673318 -391.158476) (xy 18.66646 -391.164318) (xy 18.647082 -391.180114) (xy 18.604756 -391.206717)
			(xy 18.559125 -391.22714) (xy 18.511088 -391.240982) (xy 18.461586 -391.247971) (xy 18.43659 -391.248392)
			(xy 18.410229 -391.247941) (xy 18.358085 -391.240145) (xy 18.307663 -391.22474) (xy 18.260065 -391.202064)
			(xy 18.216335 -391.172613) (xy 18.19656 -391.155174) (xy 18.196306 -391.15492) (xy 18.1891 -391.148945)
			(xy 18.171624 -391.142282) (xy 18.16227 -391.141966) (xy 18.09369 -391.141966) (xy 18.084354 -391.142379)
			(xy 18.066901 -391.149019) (xy 18.059654 -391.15492) (xy 18.059146 -391.155428) (xy 18.039359 -391.172793)
			(xy 17.995652 -391.202137) (xy 17.948106 -391.224736) (xy 17.897755 -391.2401) (xy 17.845691 -391.247893)
			(xy 17.81937 -391.248392) (xy 17.79301 -391.247893) (xy 17.740869 -391.240108) (xy 17.690447 -391.224715)
			(xy 17.642849 -391.202049) (xy 17.599117 -391.172608) (xy 17.57934 -391.155174) (xy 17.579086 -391.15492)
			(xy 17.571887 -391.148937) (xy 17.554405 -391.142279) (xy 17.54505 -391.141966) (xy 17.47647 -391.141966)
			(xy 17.467132 -391.142369) (xy 17.44968 -391.149016) (xy 17.442434 -391.15492) (xy 17.441926 -391.155428)
			(xy 17.422147 -391.172802) (xy 17.378438 -391.202145) (xy 17.33089 -391.224742) (xy 17.280537 -391.240104)
			(xy 17.228472 -391.247895) (xy 17.20215 -391.248392) (xy 17.175501 -391.247886) (xy 17.122798 -391.239943)
			(xy 17.071868 -391.224233) (xy 17.023848 -391.201108) (xy 16.979811 -391.171084) (xy 16.940741 -391.134832)
			(xy 16.90751 -391.093162) (xy 16.880861 -391.047004) (xy 16.861389 -390.997391) (xy 16.849529 -390.945429)
			(xy 16.845547 -390.89228) (xy 13.329412 -390.89228) (xy 13.329412 -391.761726) (xy 18.769076 -391.761726)
			(xy 18.769579 -391.734475) (xy 18.777332 -391.680526) (xy 18.792684 -391.62823) (xy 18.815323 -391.578651)
			(xy 18.844787 -391.532798) (xy 18.880476 -391.491606) (xy 18.921665 -391.455912) (xy 18.967514 -391.426443)
			(xy 19.01709 -391.403799) (xy 19.069385 -391.388441) (xy 19.123333 -391.380682) (xy 19.150584 -391.380218)
			(xy 19.176567 -391.380641) (xy 19.22805 -391.387704) (xy 19.278098 -391.401688) (xy 19.325786 -391.422335)
			(xy 19.370231 -391.449262) (xy 19.410611 -391.481971) (xy 19.428714 -391.500614) (xy 19.435935 -391.507604)
			(xy 19.454253 -391.515829) (xy 19.464274 -391.516616) (xy 19.546824 -391.519156) (xy 19.56562 -391.51179)
			(xy 19.572986 -391.504678) (xy 19.594416 -391.48501) (xy 19.642122 -391.451735) (xy 19.694323 -391.42608)
			(xy 19.749811 -391.408639) (xy 19.807302 -391.399815) (xy 19.836384 -391.399268) (xy 19.863634 -391.399793)
			(xy 19.917579 -391.407547) (xy 19.969871 -391.422899) (xy 20.019447 -391.445536) (xy 20.065296 -391.474998)
			(xy 20.106486 -391.510686) (xy 20.142178 -391.551872) (xy 20.171645 -391.597718) (xy 20.194287 -391.647291)
			(xy 20.209645 -391.699582) (xy 20.217404 -391.753526) (xy 20.217892 -391.780776) (xy 20.217454 -391.807389)
			(xy 20.210053 -391.860097) (xy 20.195392 -391.911264) (xy 20.173755 -391.959893) (xy 20.145564 -392.00504)
			(xy 20.111367 -392.045826) (xy 20.091908 -392.063986) (xy 20.085538 -392.070243) (xy 20.077218 -392.086029)
			(xy 20.074832 -392.103713) (xy 20.076414 -392.1125) (xy 20.094956 -392.198606) (xy 20.097239 -392.207265)
			(xy 20.106834 -392.222367) (xy 20.121056 -392.233223) (xy 20.1295 -392.236198) (xy 20.154903 -392.244743)
			(xy 20.203216 -392.267948) (xy 20.247807 -392.297683) (xy 20.2878 -392.333364) (xy 20.322409 -392.374289)
			(xy 20.350951 -392.419653) (xy 20.372867 -392.468564) (xy 20.387726 -392.52006) (xy 20.395234 -392.573128)
			(xy 20.395692 -392.599926) (xy 20.395246 -392.627179) (xy 20.387486 -392.681129) (xy 20.372127 -392.733425)
			(xy 20.349481 -392.783003) (xy 20.341544 -392.795352) (xy 24.261552 -392.795352) (xy 24.261552 -392.740848)
			(xy 24.269308 -392.686899) (xy 24.284663 -392.634603) (xy 24.307303 -392.585024) (xy 24.336769 -392.539172)
			(xy 24.37246 -392.49798) (xy 24.41365 -392.462286) (xy 24.4595 -392.432817) (xy 24.509077 -392.410173)
			(xy 24.561372 -392.394814) (xy 24.61532 -392.387054) (xy 24.642572 -392.386566) (xy 24.668493 -392.386996)
			(xy 24.719856 -392.394035) (xy 24.769793 -392.407961) (xy 24.817387 -392.428516) (xy 24.861761 -392.455323)
			(xy 24.902098 -392.487889) (xy 24.920194 -392.506454) (xy 24.92756 -392.514074) (xy 24.947118 -392.522456)
			(xy 25.032462 -392.52144) (xy 25.043051 -392.520757) (xy 25.062338 -392.511966) (xy 25.0698 -392.504422)
			(xy 25.087992 -392.484869) (xy 25.128845 -392.450472) (xy 25.174096 -392.42211) (xy 25.222861 -392.400337)
			(xy 25.274187 -392.385579) (xy 25.327069 -392.378126) (xy 25.353772 -392.377676) (xy 25.381025 -392.378169)
			(xy 25.434977 -392.385923) (xy 25.487276 -392.401276) (xy 25.536857 -392.423916) (xy 25.582712 -392.453382)
			(xy 25.623906 -392.489074) (xy 25.659601 -392.530266) (xy 25.689071 -392.576118) (xy 25.711714 -392.625698)
			(xy 25.727071 -392.677996) (xy 25.734829 -392.731947) (xy 25.734829 -392.786453) (xy 25.727071 -392.840404)
			(xy 25.711714 -392.892702) (xy 25.689071 -392.942282) (xy 25.659601 -392.988134) (xy 25.623906 -393.029326)
			(xy 25.582712 -393.065018) (xy 25.536857 -393.094484) (xy 25.487276 -393.117124) (xy 25.434977 -393.132477)
			(xy 25.381025 -393.140231) (xy 25.353772 -393.140692) (xy 25.327851 -393.140246) (xy 25.276489 -393.133212)
			(xy 25.226551 -393.119291) (xy 25.178957 -393.098738) (xy 25.134583 -393.071933) (xy 25.094245 -393.039369)
			(xy 25.07615 -393.020804) (xy 25.068784 -393.013184) (xy 25.049226 -393.004802) (xy 24.963882 -393.005818)
			(xy 24.953291 -393.006484) (xy 24.934006 -393.015289) (xy 24.926544 -393.022836) (xy 24.908391 -393.042427)
			(xy 24.867529 -393.076819) (xy 24.822269 -393.105175) (xy 24.773496 -393.126941) (xy 24.722164 -393.14169)
			(xy 24.669277 -393.149136) (xy 24.642572 -393.149582) (xy 24.61532 -393.149146) (xy 24.561372 -393.141386)
			(xy 24.509077 -393.126027) (xy 24.4595 -393.103383) (xy 24.41365 -393.073914) (xy 24.37246 -393.03822)
			(xy 24.336769 -392.997028) (xy 24.307303 -392.951176) (xy 24.284663 -392.901597) (xy 24.269308 -392.849301)
			(xy 24.261552 -392.795352) (xy 20.341544 -392.795352) (xy 20.320011 -392.828855) (xy 20.284315 -392.870045)
			(xy 20.243121 -392.905736) (xy 20.197267 -392.935201) (xy 20.147686 -392.957841) (xy 20.095388 -392.973195)
			(xy 20.041437 -392.980949) (xy 20.014184 -392.981434) (xy 19.985268 -392.98088) (xy 19.928097 -392.972162)
			(xy 19.872898 -392.954913) (xy 19.820936 -392.929528) (xy 19.773401 -392.896589) (xy 19.731384 -392.856852)
			(xy 19.713194 -392.834368) (xy 19.705585 -392.825563) (xy 19.684686 -392.815379) (xy 19.673062 -392.81481)
			(xy 19.593306 -392.81481) (xy 19.581676 -392.815364) (xy 19.560766 -392.825542) (xy 19.553174 -392.834368)
			(xy 19.53499 -392.856857) (xy 19.492969 -392.896594) (xy 19.445433 -392.929533) (xy 19.393471 -392.954921)
			(xy 19.338272 -392.972175) (xy 19.281101 -392.980901) (xy 19.252184 -392.981434) (xy 19.224934 -392.980937)
			(xy 19.170988 -392.973179) (xy 19.118695 -392.957823) (xy 19.069119 -392.935182) (xy 19.02327 -392.905717)
			(xy 18.982081 -392.870026) (xy 18.946389 -392.828838) (xy 18.916923 -392.78299) (xy 18.89428 -392.733415)
			(xy 18.878923 -392.681122) (xy 18.871164 -392.627176) (xy 18.870676 -392.599926) (xy 18.871129 -392.574237)
			(xy 18.878021 -392.523325) (xy 18.891684 -392.473798) (xy 18.91187 -392.426553) (xy 18.938215 -392.382444)
			(xy 18.970241 -392.342271) (xy 19.007369 -392.306759) (xy 19.027902 -392.291316) (xy 19.039078 -392.283188)
			(xy 19.05 -392.257788) (xy 19.036284 -392.142218) (xy 19.01952 -392.12012) (xy 19.006566 -392.11504)
			(xy 18.980604 -392.103918) (xy 18.932023 -392.07511) (xy 18.888218 -392.039457) (xy 18.850147 -391.997737)
			(xy 18.81864 -391.950861) (xy 18.794387 -391.899854) (xy 18.777916 -391.845829) (xy 18.769588 -391.789966)
			(xy 18.769076 -391.761726) (xy 13.329412 -391.761726) (xy 13.329412 -391.873232) (xy 13.328813 -391.898216)
			(xy 13.319067 -391.947226) (xy 13.299957 -391.993395) (xy 13.272214 -392.034955) (xy 13.25499 -392.053064)
			(xy 12.67079 -392.637264) (xy 12.663972 -392.644681) (xy 12.65624 -392.663267) (xy 12.655804 -392.673332)
			(xy 12.655804 -392.673586) (xy 12.655373 -392.700863) (xy 12.647676 -392.754869) (xy 12.632365 -392.807228)
			(xy 12.609751 -392.856872) (xy 12.580298 -392.902789) (xy 12.562957 -392.922831) (xy 15.26665 -392.922831)
			(xy 15.26665 -392.868329) (xy 15.274406 -392.814381) (xy 15.289761 -392.762087) (xy 15.312402 -392.71251)
			(xy 15.341868 -392.66666) (xy 15.37756 -392.62547) (xy 15.41875 -392.589778) (xy 15.4646 -392.560312)
			(xy 15.514177 -392.537671) (xy 15.566471 -392.522316) (xy 15.620419 -392.51456) (xy 15.64767 -392.514074)
			(xy 15.676293 -392.514562) (xy 15.732896 -392.523107) (xy 15.787589 -392.540011) (xy 15.839143 -392.564893)
			(xy 15.863062 -392.580622) (xy 15.871444 -392.586464) (xy 15.89151 -392.590528) (xy 15.97279 -392.574272)
			(xy 15.982729 -392.571805) (xy 15.999631 -392.560273) (xy 16.005556 -392.55192) (xy 16.020677 -392.529346)
			(xy 16.056374 -392.488382) (xy 16.097522 -392.452896) (xy 16.143288 -392.423608) (xy 16.192746 -392.401109)
			(xy 16.244896 -392.385854) (xy 16.298682 -392.378152) (xy 16.32585 -392.377676) (xy 16.353102 -392.378154)
			(xy 16.40705 -392.38591) (xy 16.459345 -392.401266) (xy 16.508923 -392.423907) (xy 16.554774 -392.453374)
			(xy 16.595964 -392.489066) (xy 16.631656 -392.530256) (xy 16.661123 -392.576107) (xy 16.683764 -392.625685)
			(xy 16.69912 -392.67798) (xy 16.706876 -392.731928) (xy 16.706876 -392.786432) (xy 16.69912 -392.84038)
			(xy 16.683764 -392.892675) (xy 16.661123 -392.942253) (xy 16.631656 -392.988104) (xy 16.595964 -393.029294)
			(xy 16.554774 -393.064986) (xy 16.508923 -393.094453) (xy 16.459345 -393.117094) (xy 16.40705 -393.13245)
			(xy 16.353102 -393.140206) (xy 16.32585 -393.140692) (xy 16.297228 -393.1402) (xy 16.240624 -393.131657)
			(xy 16.185931 -393.114755) (xy 16.134377 -393.089873) (xy 16.110458 -393.074144) (xy 16.102076 -393.068302)
			(xy 16.08201 -393.064238) (xy 16.00073 -393.080494) (xy 15.990786 -393.082946) (xy 15.973885 -393.094488)
			(xy 15.967964 -393.102846) (xy 15.952818 -393.125403) (xy 15.917126 -393.166369) (xy 15.875984 -393.201857)
			(xy 15.830222 -393.231148) (xy 15.780767 -393.25365) (xy 15.728621 -393.268907) (xy 15.674837 -393.276612)
			(xy 15.64767 -393.27709) (xy 15.620419 -393.2766) (xy 15.566471 -393.268844) (xy 15.514177 -393.253489)
			(xy 15.4646 -393.230848) (xy 15.41875 -393.201382) (xy 15.37756 -393.16569) (xy 15.341868 -393.1245)
			(xy 15.312402 -393.07865) (xy 15.289761 -393.029073) (xy 15.274406 -392.976779) (xy 15.26665 -392.922831)
			(xy 12.562957 -392.922831) (xy 12.544604 -392.944043) (xy 12.503398 -392.979792) (xy 12.45752 -393.009307)
			(xy 12.407906 -393.031986) (xy 12.355568 -393.047368) (xy 12.301572 -393.055137) (xy 12.274296 -393.055602)
			(xy 12.247031 -393.05515) (xy 12.193058 -393.047386) (xy 12.140739 -393.032016) (xy 12.091142 -393.009355)
			(xy 12.045276 -392.979862) (xy 12.004077 -392.944141) (xy 11.968383 -392.902917) (xy 11.938922 -392.857031)
			(xy 11.916293 -392.807419) (xy 11.900959 -392.75509) (xy 11.893232 -392.701111) (xy 11.893268 -392.646582)
			(xy 11.901068 -392.592613) (xy 11.916471 -392.540305) (xy 11.939165 -392.490722) (xy 11.968688 -392.444876)
			(xy 12.004436 -392.4037) (xy 12.045684 -392.368033) (xy 12.091588 -392.338602) (xy 12.141216 -392.316006)
			(xy 12.193555 -392.300706) (xy 12.247539 -392.293014) (xy 12.274804 -392.292586) (xy 12.275058 -392.292586)
			(xy 12.285125 -392.292142) (xy 12.303723 -392.284435) (xy 12.311126 -392.2776) (xy 12.805918 -391.782808)
			(xy 12.812749 -391.775401) (xy 12.820473 -391.756807) (xy 12.820904 -391.74674) (xy 12.820904 -389.111744)
			(xy 12.820815 -389.106725) (xy 12.818894 -389.096873) (xy 12.817094 -389.092186) (xy 11.647424 -386.26923)
			(xy 11.645444 -386.264652) (xy 11.639938 -386.256336) (xy 11.636502 -386.25272) (xy 9.637268 -384.253486)
			(xy 9.620024 -384.23538) (xy 9.592208 -384.19384) (xy 9.573031 -384.147672) (xy 9.563229 -384.09865)
			(xy 9.562592 -384.073654) (xy 9.562592 -381.134874) (xy 9.562182 -381.124803) (xy 9.554451 -381.106205)
			(xy 9.547606 -381.098806) (xy 9.526775 -381.077188) (xy 9.491438 -381.028659) (xy 9.464142 -380.975192)
			(xy 9.445561 -380.918109) (xy 9.436154 -380.85882) (xy 9.435592 -380.828804) (xy 7.170475 -380.828804)
			(xy 7.148068 -380.849344) (xy 7.104637 -380.8793) (xy 7.081266 -380.891542) (xy 7.068887 -380.898211)
			(xy 7.04815 -380.91719) (xy 7.033383 -380.94111) (xy 7.025709 -380.968153) (xy 7.025712 -380.996264)
			(xy 7.03339 -381.023306) (xy 7.048161 -381.047224) (xy 7.068902 -381.066199) (xy 7.081266 -381.072898)
			(xy 7.104634 -381.085144) (xy 7.148057 -381.115106) (xy 7.186942 -381.150761) (xy 7.220547 -381.19143)
			(xy 7.248234 -381.236338) (xy 7.269475 -381.284631) (xy 7.283866 -381.335387) (xy 7.291131 -381.387641)
			(xy 7.291578 -381.41402) (xy 7.291092 -381.441271) (xy 7.283336 -381.495219) (xy 7.267981 -381.547514)
			(xy 7.245339 -381.597091) (xy 7.215873 -381.642941) (xy 7.180182 -381.684132) (xy 7.138991 -381.719823)
			(xy 7.093141 -381.749289) (xy 7.043564 -381.771931) (xy 6.991269 -381.787286) (xy 6.937321 -381.795042)
			(xy 6.882819 -381.795042) (xy 6.828871 -381.787286) (xy 6.776576 -381.771931) (xy 6.726999 -381.749289)
			(xy 6.681149 -381.719823) (xy 6.639958 -381.684132) (xy 6.604267 -381.642941) (xy 6.574801 -381.597091)
			(xy 6.552159 -381.547514) (xy 6.536804 -381.495219) (xy 6.529048 -381.441271) (xy 6.528562 -381.41402)
			(xy 4.545328 -381.41402) (xy 11.133328 -388.002272) (xy 11.156011 -388.025571) (xy 11.196561 -388.07641)
			(xy 11.231161 -388.13147) (xy 11.259377 -388.190058) (xy 11.280854 -388.251439) (xy 11.29532 -388.314838)
			(xy 11.302595 -388.379459) (xy 11.303 -388.411974) (xy 11.303 -389.22833) (xy 11.907264 -389.22833)
			(xy 11.911335 -389.172708) (xy 11.923461 -389.118271) (xy 11.943384 -389.06618) (xy 11.97068 -389.017545)
			(xy 12.004766 -388.973402) (xy 12.044915 -388.934693) (xy 12.090273 -388.902242) (xy 12.139873 -388.876741)
			(xy 12.192657 -388.858734) (xy 12.2475 -388.848604) (xy 12.303234 -388.846567) (xy 12.358671 -388.852667)
			(xy 12.412628 -388.866773) (xy 12.463957 -388.888585) (xy 12.511563 -388.917639) (xy 12.554431 -388.953314)
			(xy 12.591648 -388.994851) (xy 12.622421 -389.041364) (xy 12.646093 -389.091861) (xy 12.662161 -389.145268)
			(xy 12.670281 -389.200444) (xy 12.67079 -389.22833) (xy 12.670281 -389.256216) (xy 12.662161 -389.311392)
			(xy 12.646093 -389.364799) (xy 12.622421 -389.415296) (xy 12.591648 -389.461809) (xy 12.554431 -389.503346)
			(xy 12.511563 -389.539021) (xy 12.463957 -389.568075) (xy 12.412628 -389.589887) (xy 12.358671 -389.603993)
			(xy 12.303234 -389.610093) (xy 12.2475 -389.608056) (xy 12.192657 -389.597926) (xy 12.139873 -389.579919)
			(xy 12.090273 -389.554418) (xy 12.044915 -389.521967) (xy 12.004766 -389.483258) (xy 11.97068 -389.439115)
			(xy 11.943384 -389.39048) (xy 11.923461 -389.338389) (xy 11.911335 -389.283952) (xy 11.907264 -389.22833)
			(xy 11.303 -389.22833) (xy 11.303 -390.219184) (xy 11.84986 -390.219184) (xy 11.853931 -390.163562)
			(xy 11.866057 -390.109125) (xy 11.88598 -390.057034) (xy 11.913276 -390.008399) (xy 11.947362 -389.964256)
			(xy 11.987511 -389.925547) (xy 12.032869 -389.893096) (xy 12.082469 -389.867595) (xy 12.135253 -389.849588)
			(xy 12.190096 -389.839458) (xy 12.24583 -389.837421) (xy 12.301267 -389.843521) (xy 12.355224 -389.857627)
			(xy 12.406553 -389.879439) (xy 12.454159 -389.908493) (xy 12.497027 -389.944168) (xy 12.534244 -389.985705)
			(xy 12.565017 -390.032218) (xy 12.588689 -390.082715) (xy 12.604757 -390.136122) (xy 12.612877 -390.191298)
			(xy 12.613386 -390.219184) (xy 12.612877 -390.24707) (xy 12.604757 -390.302246) (xy 12.588689 -390.355653)
			(xy 12.565017 -390.40615) (xy 12.534244 -390.452663) (xy 12.497027 -390.4942) (xy 12.454159 -390.529875)
			(xy 12.406553 -390.558929) (xy 12.355224 -390.580741) (xy 12.301267 -390.594847) (xy 12.24583 -390.600947)
			(xy 12.190096 -390.59891) (xy 12.135253 -390.58878) (xy 12.082469 -390.570773) (xy 12.032869 -390.545272)
			(xy 11.987511 -390.512821) (xy 11.947362 -390.474112) (xy 11.913276 -390.429969) (xy 11.88598 -390.381334)
			(xy 11.866057 -390.329243) (xy 11.853931 -390.274806) (xy 11.84986 -390.219184) (xy 11.303 -390.219184)
			(xy 11.303 -393.425426) (xy 11.302543 -393.457938) (xy 11.295263 -393.522553) (xy 11.281664 -393.582144)
			(xy 16.440148 -393.582144) (xy 16.444219 -393.526522) (xy 16.456345 -393.472085) (xy 16.476268 -393.419994)
			(xy 16.503564 -393.371359) (xy 16.53765 -393.327216) (xy 16.577799 -393.288507) (xy 16.623157 -393.256056)
			(xy 16.672757 -393.230555) (xy 16.725541 -393.212548) (xy 16.780384 -393.202418) (xy 16.836118 -393.200381)
			(xy 16.891555 -393.206481) (xy 16.945512 -393.220587) (xy 16.996841 -393.242399) (xy 17.044447 -393.271453)
			(xy 17.087315 -393.307128) (xy 17.124532 -393.348665) (xy 17.155305 -393.395178) (xy 17.178977 -393.445675)
			(xy 17.189926 -393.482068) (xy 23.315166 -393.482068) (xy 23.319237 -393.426446) (xy 23.331363 -393.372009)
			(xy 23.351286 -393.319918) (xy 23.378582 -393.271283) (xy 23.412668 -393.22714) (xy 23.452817 -393.188431)
			(xy 23.498175 -393.15598) (xy 23.547775 -393.130479) (xy 23.600559 -393.112472) (xy 23.655402 -393.102342)
			(xy 23.711136 -393.100305) (xy 23.766573 -393.106405) (xy 23.82053 -393.120511) (xy 23.871859 -393.142323)
			(xy 23.919465 -393.171377) (xy 23.962333 -393.207052) (xy 23.99955 -393.248589) (xy 24.030323 -393.295102)
			(xy 24.053995 -393.345599) (xy 24.070063 -393.399006) (xy 24.078183 -393.454182) (xy 24.078692 -393.482068)
			(xy 24.078183 -393.509954) (xy 24.070063 -393.56513) (xy 24.053995 -393.618537) (xy 24.030323 -393.669034)
			(xy 23.99955 -393.715547) (xy 23.962333 -393.757084) (xy 23.957065 -393.761468) (xy 25.528776 -393.761468)
			(xy 25.532847 -393.705846) (xy 25.544973 -393.651409) (xy 25.564896 -393.599318) (xy 25.592192 -393.550683)
			(xy 25.626278 -393.50654) (xy 25.666427 -393.467831) (xy 25.711785 -393.43538) (xy 25.761385 -393.409879)
			(xy 25.814169 -393.391872) (xy 25.869012 -393.381742) (xy 25.924746 -393.379705) (xy 25.980183 -393.385805)
			(xy 26.03414 -393.399911) (xy 26.085469 -393.421723) (xy 26.133075 -393.450777) (xy 26.175943 -393.486452)
			(xy 26.21316 -393.527989) (xy 26.243933 -393.574502) (xy 26.267605 -393.624999) (xy 26.283673 -393.678406)
			(xy 26.291793 -393.733582) (xy 26.292302 -393.761468) (xy 26.291793 -393.789354) (xy 26.283673 -393.84453)
			(xy 26.267605 -393.897937) (xy 26.243933 -393.948434) (xy 26.21316 -393.994947) (xy 26.175943 -394.036484)
			(xy 26.133075 -394.072159) (xy 26.085469 -394.101213) (xy 26.03414 -394.123025) (xy 25.980183 -394.137131)
			(xy 25.924746 -394.143231) (xy 25.869012 -394.141194) (xy 25.814169 -394.131064) (xy 25.761385 -394.113057)
			(xy 25.711785 -394.087556) (xy 25.666427 -394.055105) (xy 25.626278 -394.016396) (xy 25.592192 -393.972253)
			(xy 25.564896 -393.923618) (xy 25.544973 -393.871527) (xy 25.532847 -393.81709) (xy 25.528776 -393.761468)
			(xy 23.957065 -393.761468) (xy 23.919465 -393.792759) (xy 23.871859 -393.821813) (xy 23.82053 -393.843625)
			(xy 23.766573 -393.857731) (xy 23.711136 -393.863831) (xy 23.655402 -393.861794) (xy 23.600559 -393.851664)
			(xy 23.547775 -393.833657) (xy 23.498175 -393.808156) (xy 23.452817 -393.775705) (xy 23.412668 -393.736996)
			(xy 23.378582 -393.692853) (xy 23.351286 -393.644218) (xy 23.331363 -393.592127) (xy 23.319237 -393.53769)
			(xy 23.315166 -393.482068) (xy 17.189926 -393.482068) (xy 17.195045 -393.499082) (xy 17.203165 -393.554258)
			(xy 17.203674 -393.582144) (xy 17.203165 -393.61003) (xy 17.195045 -393.665206) (xy 17.178977 -393.718613)
			(xy 17.155305 -393.76911) (xy 17.124532 -393.815623) (xy 17.087315 -393.85716) (xy 17.044447 -393.892835)
			(xy 16.996841 -393.921889) (xy 16.945512 -393.943701) (xy 16.891555 -393.957807) (xy 16.836118 -393.963907)
			(xy 16.780384 -393.96187) (xy 16.725541 -393.95174) (xy 16.672757 -393.933733) (xy 16.623157 -393.908232)
			(xy 16.577799 -393.875781) (xy 16.53765 -393.837072) (xy 16.503564 -393.792929) (xy 16.476268 -393.744294)
			(xy 16.456345 -393.692203) (xy 16.444219 -393.637766) (xy 16.440148 -393.582144) (xy 11.281664 -393.582144)
			(xy 11.280796 -393.585948) (xy 11.259324 -393.647325) (xy 11.231119 -393.705913) (xy 11.196533 -393.760976)
			(xy 11.156001 -393.811822) (xy 11.133328 -393.835128) (xy 10.005669 -394.962888) (xy 12.04036 -394.962888)
			(xy 12.044431 -394.907266) (xy 12.056557 -394.852829) (xy 12.07648 -394.800738) (xy 12.103776 -394.752103)
			(xy 12.137862 -394.70796) (xy 12.178011 -394.669251) (xy 12.223369 -394.6368) (xy 12.272969 -394.611299)
			(xy 12.325753 -394.593292) (xy 12.380596 -394.583162) (xy 12.43633 -394.581125) (xy 12.491767 -394.587225)
			(xy 12.545724 -394.601331) (xy 12.597053 -394.623143) (xy 12.644659 -394.652197) (xy 12.687527 -394.687872)
			(xy 12.724744 -394.729409) (xy 12.755517 -394.775922) (xy 12.779189 -394.826419) (xy 12.795257 -394.879826)
			(xy 12.803377 -394.935002) (xy 12.803886 -394.962888) (xy 12.803377 -394.990774) (xy 12.795257 -395.04595)
			(xy 12.779189 -395.099357) (xy 12.755517 -395.149854) (xy 12.724744 -395.196367) (xy 12.687527 -395.237904)
			(xy 12.644659 -395.273579) (xy 12.597053 -395.302633) (xy 12.545724 -395.324445) (xy 12.491767 -395.338551)
			(xy 12.43633 -395.344651) (xy 12.380596 -395.342614) (xy 12.325753 -395.332484) (xy 12.272969 -395.314477)
			(xy 12.223369 -395.288976) (xy 12.178011 -395.256525) (xy 12.137862 -395.217816) (xy 12.103776 -395.173673)
			(xy 12.07648 -395.125038) (xy 12.056557 -395.072947) (xy 12.044431 -395.01851) (xy 12.04036 -394.962888)
			(xy 10.005669 -394.962888) (xy 8.907726 -396.06093) (xy 12.002514 -396.06093) (xy 12.006585 -396.005308)
			(xy 12.018711 -395.950871) (xy 12.038634 -395.89878) (xy 12.06593 -395.850145) (xy 12.100016 -395.806002)
			(xy 12.140165 -395.767293) (xy 12.185523 -395.734842) (xy 12.235123 -395.709341) (xy 12.287907 -395.691334)
			(xy 12.34275 -395.681204) (xy 12.398484 -395.679167) (xy 12.453921 -395.685267) (xy 12.507878 -395.699373)
			(xy 12.559207 -395.721185) (xy 12.606813 -395.750239) (xy 12.649681 -395.785914) (xy 12.686898 -395.827451)
			(xy 12.717671 -395.873964) (xy 12.741343 -395.924461) (xy 12.757411 -395.977868) (xy 12.765531 -396.033044)
			(xy 12.76604 -396.06093) (xy 12.765531 -396.088816) (xy 12.757411 -396.143992) (xy 12.741343 -396.197399)
			(xy 12.717671 -396.247896) (xy 12.686898 -396.294409) (xy 12.649681 -396.335946) (xy 12.606813 -396.371621)
			(xy 12.559207 -396.400675) (xy 12.507878 -396.422487) (xy 12.453921 -396.436593) (xy 12.398484 -396.442693)
			(xy 12.34275 -396.440656) (xy 12.287907 -396.430526) (xy 12.235123 -396.412519) (xy 12.185523 -396.387018)
			(xy 12.140165 -396.354567) (xy 12.100016 -396.315858) (xy 12.06593 -396.271715) (xy 12.038634 -396.22308)
			(xy 12.018711 -396.170989) (xy 12.006585 -396.116552) (xy 12.002514 -396.06093) (xy 8.907726 -396.06093)
			(xy 8.30199 -396.66672) (xy 8.295137 -396.674115) (xy 8.287395 -396.692714) (xy 8.287004 -396.702788)
			(xy 8.287004 -402.56079) (xy 11.742672 -402.56079) (xy 11.746743 -402.505168) (xy 11.758869 -402.450731)
			(xy 11.778792 -402.39864) (xy 11.806088 -402.350005) (xy 11.840174 -402.305862) (xy 11.880323 -402.267153)
			(xy 11.925681 -402.234702) (xy 11.975281 -402.209201) (xy 12.028065 -402.191194) (xy 12.082908 -402.181064)
			(xy 12.138642 -402.179027) (xy 12.194079 -402.185127) (xy 12.248036 -402.199233) (xy 12.299365 -402.221045)
			(xy 12.346971 -402.250099) (xy 12.389839 -402.285774) (xy 12.427056 -402.327311) (xy 12.457829 -402.373824)
			(xy 12.481501 -402.424321) (xy 12.497569 -402.477728) (xy 12.505689 -402.532904) (xy 12.506198 -402.56079)
			(xy 12.505689 -402.588676) (xy 12.497569 -402.643852) (xy 12.481501 -402.697259) (xy 12.457829 -402.747756)
			(xy 12.427056 -402.794269) (xy 12.389839 -402.835806) (xy 12.346971 -402.871481) (xy 12.299365 -402.900535)
			(xy 12.248036 -402.922347) (xy 12.194079 -402.936453) (xy 12.138642 -402.942553) (xy 12.082908 -402.940516)
			(xy 12.028065 -402.930386) (xy 11.975281 -402.912379) (xy 11.925681 -402.886878) (xy 11.880323 -402.854427)
			(xy 11.840174 -402.815718) (xy 11.806088 -402.771575) (xy 11.778792 -402.72294) (xy 11.758869 -402.670849)
			(xy 11.746743 -402.616412) (xy 11.742672 -402.56079) (xy 8.287004 -402.56079) (xy 8.287004 -404.21687)
			(xy 9.284714 -404.21687) (xy 9.288785 -404.161248) (xy 9.300911 -404.106811) (xy 9.320834 -404.05472)
			(xy 9.34813 -404.006085) (xy 9.382216 -403.961942) (xy 9.422365 -403.923233) (xy 9.467723 -403.890782)
			(xy 9.517323 -403.865281) (xy 9.570107 -403.847274) (xy 9.62495 -403.837144) (xy 9.680684 -403.835107)
			(xy 9.736121 -403.841207) (xy 9.789546 -403.855174) (xy 11.803124 -403.855174) (xy 11.807195 -403.799552)
			(xy 11.819321 -403.745115) (xy 11.839244 -403.693024) (xy 11.86654 -403.644389) (xy 11.900626 -403.600246)
			(xy 11.940775 -403.561537) (xy 11.986133 -403.529086) (xy 12.035733 -403.503585) (xy 12.088517 -403.485578)
			(xy 12.14336 -403.475448) (xy 12.199094 -403.473411) (xy 12.254531 -403.479511) (xy 12.308488 -403.493617)
			(xy 12.359817 -403.515429) (xy 12.407423 -403.544483) (xy 12.450291 -403.580158) (xy 12.487508 -403.621695)
			(xy 12.518281 -403.668208) (xy 12.541953 -403.718705) (xy 12.558021 -403.772112) (xy 12.566141 -403.827288)
			(xy 12.56665 -403.855174) (xy 12.566141 -403.88306) (xy 12.558021 -403.938236) (xy 12.541953 -403.991643)
			(xy 12.518281 -404.04214) (xy 12.487508 -404.088653) (xy 12.450291 -404.13019) (xy 12.407423 -404.165865)
			(xy 12.359817 -404.194919) (xy 12.308488 -404.216731) (xy 12.254531 -404.230837) (xy 12.199094 -404.236937)
			(xy 12.14336 -404.2349) (xy 12.088517 -404.22477) (xy 12.035733 -404.206763) (xy 11.986133 -404.181262)
			(xy 11.940775 -404.148811) (xy 11.900626 -404.110102) (xy 11.86654 -404.065959) (xy 11.839244 -404.017324)
			(xy 11.819321 -403.965233) (xy 11.807195 -403.910796) (xy 11.803124 -403.855174) (xy 9.789546 -403.855174)
			(xy 9.790078 -403.855313) (xy 9.841407 -403.877125) (xy 9.889013 -403.906179) (xy 9.931881 -403.941854)
			(xy 9.969098 -403.983391) (xy 9.999871 -404.029904) (xy 10.023543 -404.080401) (xy 10.039611 -404.133808)
			(xy 10.047731 -404.188984) (xy 10.04824 -404.21687) (xy 10.047731 -404.244756) (xy 10.039611 -404.299932)
			(xy 10.023543 -404.353339) (xy 9.999871 -404.403836) (xy 9.969098 -404.450349) (xy 9.931881 -404.491886)
			(xy 9.889013 -404.527561) (xy 9.841407 -404.556615) (xy 9.790078 -404.578427) (xy 9.736121 -404.592533)
			(xy 9.680684 -404.598633) (xy 9.62495 -404.596596) (xy 9.570107 -404.586466) (xy 9.517323 -404.568459)
			(xy 9.467723 -404.542958) (xy 9.422365 -404.510507) (xy 9.382216 -404.471798) (xy 9.34813 -404.427655)
			(xy 9.320834 -404.37902) (xy 9.300911 -404.326929) (xy 9.288785 -404.272492) (xy 9.284714 -404.21687)
			(xy 8.287004 -404.21687) (xy 8.287004 -405.505412) (xy 8.28802 -405.515318) (xy 8.40809 -406.119584)
			(xy 8.5504 -406.119584) (xy 8.554471 -406.063962) (xy 8.566597 -406.009525) (xy 8.58652 -405.957434)
			(xy 8.613816 -405.908799) (xy 8.647902 -405.864656) (xy 8.688051 -405.825947) (xy 8.733409 -405.793496)
			(xy 8.783009 -405.767995) (xy 8.835793 -405.749988) (xy 8.890636 -405.739858) (xy 8.94637 -405.737821)
			(xy 9.001807 -405.743921) (xy 9.055764 -405.758027) (xy 9.107093 -405.779839) (xy 9.154699 -405.808893)
			(xy 9.197567 -405.844568) (xy 9.234784 -405.886105) (xy 9.265557 -405.932618) (xy 9.289229 -405.983115)
			(xy 9.305297 -406.036522) (xy 9.313417 -406.091698) (xy 9.313926 -406.119584) (xy 9.313417 -406.14747)
			(xy 9.305297 -406.202646) (xy 9.289229 -406.256053) (xy 9.265557 -406.30655) (xy 9.234784 -406.353063)
			(xy 9.197567 -406.3946) (xy 9.154699 -406.430275) (xy 9.107093 -406.459329) (xy 9.055764 -406.481141)
			(xy 9.001807 -406.495247) (xy 8.94637 -406.501347) (xy 8.890636 -406.49931) (xy 8.835793 -406.48918)
			(xy 8.783009 -406.471173) (xy 8.733409 -406.445672) (xy 8.688051 -406.413221) (xy 8.647902 -406.374512)
			(xy 8.613816 -406.330369) (xy 8.58652 -406.281734) (xy 8.566597 -406.229643) (xy 8.554471 -406.175206)
			(xy 8.5504 -406.119584) (xy 8.40809 -406.119584) (xy 8.506206 -406.61336) (xy 8.507948 -406.620697)
			(xy 8.515049 -406.633992) (xy 8.520176 -406.639522) (xy 8.733536 -406.852882) (xy 8.740376 -406.860282)
			(xy 8.748091 -406.878881) (xy 8.748522 -406.88895) (xy 8.748522 -407.391616) (xy 11.423396 -407.391616)
			(xy 11.423396 -406.238456) (xy 11.423773 -406.228381) (xy 11.431525 -406.209782) (xy 11.438382 -406.202388)
			(xy 11.760708 -405.880062) (xy 11.768107 -405.873221) (xy 11.786707 -405.865503) (xy 11.796776 -405.865076)
			(xy 13.36548 -405.865076) (xy 13.375551 -405.865492) (xy 13.39415 -405.873217) (xy 13.401548 -405.880062)
			(xy 13.456228 -405.934751) (xy 14.302972 -405.934751) (xy 14.302972 -405.880249) (xy 14.310728 -405.826301)
			(xy 14.326083 -405.774005) (xy 14.348724 -405.724428) (xy 14.378191 -405.678577) (xy 14.413882 -405.637386)
			(xy 14.455072 -405.601694) (xy 14.500923 -405.572227) (xy 14.5505 -405.549585) (xy 14.602795 -405.53423)
			(xy 14.656743 -405.526472) (xy 14.683994 -405.525986) (xy 14.713337 -405.526528) (xy 14.771331 -405.535514)
			(xy 14.827264 -405.553275) (xy 14.879819 -405.579391) (xy 14.927754 -405.613248) (xy 14.969939 -405.654045)
			(xy 15.005379 -405.700822) (xy 15.019782 -405.726392) (xy 15.027447 -405.739632) (xy 15.049269 -405.76106)
			(xy 15.076451 -405.775076) (xy 15.106563 -405.780428) (xy 15.136911 -405.776636) (xy 15.16478 -405.764039)
			(xy 15.187677 -405.743765) (xy 15.196058 -405.730964) (xy 15.21095 -405.707329) (xy 15.2466 -405.66432)
			(xy 15.288146 -405.626974) (xy 15.334697 -405.596092) (xy 15.385257 -405.572334) (xy 15.438742 -405.556209)
			(xy 15.494008 -405.548062) (xy 15.52194 -405.547576) (xy 15.549192 -405.548054) (xy 15.60314 -405.55581)
			(xy 15.655435 -405.571166) (xy 15.705013 -405.593807) (xy 15.750864 -405.623274) (xy 15.792054 -405.658966)
			(xy 15.827746 -405.700156) (xy 15.857213 -405.746007) (xy 15.879854 -405.795585) (xy 15.89521 -405.84788)
			(xy 15.902966 -405.901828) (xy 15.902966 -405.956332) (xy 15.89521 -406.01028) (xy 15.879854 -406.062575)
			(xy 15.857213 -406.112153) (xy 15.827746 -406.158004) (xy 15.792054 -406.199194) (xy 15.750864 -406.234886)
			(xy 15.705013 -406.264353) (xy 15.655435 -406.286994) (xy 15.60314 -406.30235) (xy 15.549192 -406.310106)
			(xy 15.52194 -406.310592) (xy 15.492597 -406.310034) (xy 15.434604 -406.301053) (xy 15.37867 -406.283296)
			(xy 15.326115 -406.257182) (xy 15.27818 -406.223328) (xy 15.235995 -406.182531) (xy 15.200555 -406.135756)
			(xy 15.186152 -406.110186) (xy 15.178439 -406.096978) (xy 15.156625 -406.075557) (xy 15.129453 -406.061544)
			(xy 15.099353 -406.05619) (xy 15.069016 -406.059975) (xy 15.041153 -406.07256) (xy 15.018258 -406.09282)
			(xy 15.009876 -406.105614) (xy 14.994953 -406.129229) (xy 14.959309 -406.172239) (xy 14.917769 -406.209586)
			(xy 14.871223 -406.240472) (xy 14.820668 -406.264233) (xy 14.767187 -406.280362) (xy 14.711924 -406.288514)
			(xy 14.683994 -406.289002) (xy 14.656743 -406.288528) (xy 14.602795 -406.28077) (xy 14.5505 -406.265415)
			(xy 14.500923 -406.242773) (xy 14.455072 -406.213306) (xy 14.413882 -406.177614) (xy 14.378191 -406.136423)
			(xy 14.348724 -406.090572) (xy 14.326083 -406.040995) (xy 14.310728 -405.988699) (xy 14.302972 -405.934751)
			(xy 13.456228 -405.934751) (xy 14.90853 -407.387298) (xy 14.915366 -407.394701) (xy 14.923087 -407.413298)
			(xy 14.923516 -407.423366) (xy 14.923516 -411.973776) (xy 14.92395 -411.983844) (xy 14.931664 -412.002443)
			(xy 14.938502 -412.009844) (xy 15.08379 -412.155132) (xy 15.091251 -412.161852) (xy 15.109826 -412.169427)
			(xy 15.119858 -412.169864) (xy 16.649954 -412.169864) (xy 16.679672 -412.199582) (xy 16.679672 -412.207964)
			(xy 16.680139 -412.218005) (xy 16.687828 -412.236556) (xy 16.702045 -412.250739) (xy 16.711168 -412.254954)
			(xy 16.720556 -412.258307) (xy 16.740472 -412.258302) (xy 16.758883 -412.25071) (xy 16.766286 -412.244032)
			(xy 17.01165 -411.998922) (xy 17.018466 -411.991503) (xy 17.026201 -411.972918) (xy 17.026636 -411.962854)
			(xy 17.026636 -406.016206) (xy 17.026224 -406.006135) (xy 17.018496 -405.987536) (xy 17.01165 -405.980138)
			(xy 16.25219 -405.220678) (xy 16.24479 -405.213838) (xy 16.226191 -405.206119) (xy 16.216122 -405.205692)
			(xy 14.385798 -405.205692) (xy 14.360816 -405.205051) (xy 14.31181 -405.195315) (xy 14.265641 -405.176216)
			(xy 14.224078 -405.148487) (xy 14.205966 -405.13127) (xy 13.121894 -404.047198) (xy 13.104664 -404.029095)
			(xy 13.076922 -403.987534) (xy 13.057816 -403.941362) (xy 13.04808 -403.892351) (xy 13.047472 -403.867366)
			(xy 13.047472 -402.374862) (xy 13.048072 -402.349878) (xy 13.057818 -402.300869) (xy 13.076929 -402.254699)
			(xy 13.104671 -402.213139) (xy 13.121894 -402.19503) (xy 13.413486 -401.903184) (xy 13.420324 -401.895782)
			(xy 13.428045 -401.877184) (xy 13.428472 -401.867116) (xy 13.428472 -394.968222) (xy 13.428333 -394.962577)
			(xy 13.425904 -394.951553) (xy 13.423646 -394.946378) (xy 13.249656 -394.58138) (xy 13.244963 -394.572471)
			(xy 13.23004 -394.558979) (xy 13.2207 -394.555218) (xy 12.699492 -394.370814) (xy 12.689896 -394.367865)
			(xy 12.669864 -394.368908) (xy 12.66063 -394.372846) (xy 12.634852 -394.384622) (xy 12.580671 -394.401237)
			(xy 12.524628 -394.409652) (xy 12.496292 -394.410184) (xy 12.495784 -394.410184) (xy 12.468531 -394.409729)
			(xy 12.414579 -394.401972) (xy 12.36228 -394.386616) (xy 12.312699 -394.363974) (xy 12.266845 -394.334506)
			(xy 12.225651 -394.298812) (xy 12.189957 -394.257619) (xy 12.160488 -394.211765) (xy 12.137845 -394.162184)
			(xy 12.122489 -394.109885) (xy 12.114731 -394.055933) (xy 12.114731 -394.001427) (xy 12.122489 -393.947475)
			(xy 12.137845 -393.895176) (xy 12.160488 -393.845595) (xy 12.189957 -393.799741) (xy 12.225651 -393.758548)
			(xy 12.266845 -393.722854) (xy 12.312699 -393.693386) (xy 12.36228 -393.670744) (xy 12.414579 -393.655388)
			(xy 12.468531 -393.647631) (xy 12.495784 -393.647168) (xy 12.522688 -393.647584) (xy 12.575961 -393.655143)
			(xy 12.627644 -393.670113) (xy 12.676711 -393.692197) (xy 12.722188 -393.720956) (xy 12.763172 -393.755821)
			(xy 12.79885 -393.796099) (xy 12.828514 -393.840991) (xy 12.840462 -393.8651) (xy 12.84478 -393.874244)
			(xy 12.859766 -393.887706) (xy 13.509498 -394.11783) (xy 13.536422 -394.129006) (xy 13.544237 -394.132402)
			(xy 13.561153 -394.134359) (xy 13.577775 -394.130663) (xy 13.58519 -394.126466) (xy 13.669772 -394.074396)
			(xy 13.682472 -394.052044) (xy 13.682472 -394.038836) (xy 13.683252 -394.011788) (xy 13.691509 -393.95831)
			(xy 13.707239 -393.906536) (xy 13.730125 -393.857503) (xy 13.759709 -393.812196) (xy 13.795398 -393.771522)
			(xy 13.836475 -393.736299) (xy 13.882116 -393.707233) (xy 13.931407 -393.684906) (xy 13.983357 -393.669767)
			(xy 14.036925 -393.662119) (xy 14.06398 -393.661646) (xy 14.091229 -393.662197) (xy 14.145172 -393.669949)
			(xy 14.197462 -393.6853) (xy 14.247036 -393.707935) (xy 14.292885 -393.737395) (xy 14.334074 -393.77308)
			(xy 14.369766 -393.814263) (xy 14.399233 -393.860106) (xy 14.421877 -393.909676) (xy 14.437237 -393.961964)
			(xy 14.444999 -394.015905) (xy 14.445488 -394.043154) (xy 14.444883 -394.073168) (xy 14.435478 -394.132454)
			(xy 14.416907 -394.189538) (xy 14.389629 -394.24301) (xy 14.354317 -394.291552) (xy 14.333474 -394.313156)
			(xy 14.326657 -394.320574) (xy 14.318924 -394.33916) (xy 14.318488 -394.349224) (xy 14.318488 -395.964664)
			(xy 19.52498 -395.964664) (xy 19.525405 -395.937292) (xy 19.53323 -395.88311) (xy 19.548728 -395.830606)
			(xy 19.571579 -395.78086) (xy 19.601314 -395.734896) (xy 19.61896 -395.713966) (xy 19.619214 -395.713712)
			(xy 19.624803 -395.706627) (xy 19.631048 -395.689709) (xy 19.631406 -395.680692) (xy 19.631406 -395.613636)
			(xy 19.631031 -395.604621) (xy 19.624796 -395.587704) (xy 19.619214 -395.580616) (xy 19.61896 -395.580616)
			(xy 19.61896 -395.580362) (xy 19.60133 -395.559423) (xy 19.571618 -395.513451) (xy 19.548781 -395.463706)
			(xy 19.533287 -395.411207) (xy 19.525456 -395.357033) (xy 19.52498 -395.329664) (xy 19.525466 -395.302413)
			(xy 19.533222 -395.248465) (xy 19.548577 -395.19617) (xy 19.571219 -395.146593) (xy 19.600685 -395.100743)
			(xy 19.636376 -395.059552) (xy 19.677567 -395.023861) (xy 19.723417 -394.994395) (xy 19.772994 -394.971753)
			(xy 19.825289 -394.956398) (xy 19.879237 -394.948642) (xy 19.933739 -394.948642) (xy 19.987687 -394.956398)
			(xy 20.039982 -394.971753) (xy 20.089559 -394.994395) (xy 20.135409 -395.023861) (xy 20.1766 -395.059552)
			(xy 20.212291 -395.100743) (xy 20.241757 -395.146593) (xy 20.264399 -395.19617) (xy 20.279754 -395.248465)
			(xy 20.28751 -395.302413) (xy 20.287996 -395.329664) (xy 20.28751 -395.357034) (xy 20.279697 -395.411212)
			(xy 20.264213 -395.463715) (xy 20.241375 -395.513462) (xy 20.211655 -395.55943) (xy 20.194016 -395.580362)
			(xy 20.193762 -395.580616) (xy 20.188158 -395.587691) (xy 20.181923 -395.604617) (xy 20.18157 -395.613636)
			(xy 20.18157 -395.680692) (xy 20.181937 -395.689708) (xy 20.188179 -395.706624) (xy 20.193762 -395.713712)
			(xy 20.194016 -395.713712) (xy 20.194016 -395.713966) (xy 20.211655 -395.734898) (xy 20.241366 -395.780871)
			(xy 20.264202 -395.830619) (xy 20.279693 -395.883119) (xy 20.287522 -395.937295) (xy 20.287996 -395.964664)
			(xy 20.28751 -395.991915) (xy 20.279754 -396.045863) (xy 20.264399 -396.098158) (xy 20.241757 -396.147735)
			(xy 20.212291 -396.193585) (xy 20.1766 -396.234776) (xy 20.135409 -396.270467) (xy 20.089559 -396.299933)
			(xy 20.039982 -396.322575) (xy 19.987687 -396.33793) (xy 19.933739 -396.345686) (xy 19.879237 -396.345686)
			(xy 19.825289 -396.33793) (xy 19.772994 -396.322575) (xy 19.723417 -396.299933) (xy 19.677567 -396.270467)
			(xy 19.636376 -396.234776) (xy 19.600685 -396.193585) (xy 19.571219 -396.147735) (xy 19.548577 -396.098158)
			(xy 19.533222 -396.045863) (xy 19.525466 -395.991915) (xy 19.52498 -395.964664) (xy 14.318488 -395.964664)
			(xy 14.318488 -398.878552) (xy 19.56308 -398.878552) (xy 19.563557 -398.851182) (xy 19.571369 -398.797003)
			(xy 19.586855 -398.744499) (xy 19.609694 -398.694752) (xy 19.639419 -398.648785) (xy 19.65706 -398.627854)
			(xy 19.657314 -398.6276) (xy 19.662908 -398.620519) (xy 19.66915 -398.603598) (xy 19.669506 -398.59458)
			(xy 19.669506 -398.527524) (xy 19.669136 -398.518508) (xy 19.662897 -398.501591) (xy 19.657314 -398.494504)
			(xy 19.65706 -398.494504) (xy 19.65706 -398.49425) (xy 19.639424 -398.473315) (xy 19.609713 -398.427343)
			(xy 19.586877 -398.377596) (xy 19.571385 -398.325096) (xy 19.563555 -398.270921) (xy 19.56308 -398.243552)
			(xy 19.563499 -398.217882) (xy 19.570385 -398.167007) (xy 19.584026 -398.117513) (xy 19.604176 -398.070293)
			(xy 19.630472 -398.026199) (xy 19.662439 -397.986026) (xy 19.680682 -397.967962) (xy 19.687823 -397.960475)
			(xy 19.695948 -397.941467) (xy 19.69643 -397.931132) (xy 19.69643 -397.858234) (xy 19.695996 -397.84789)
			(xy 19.68785 -397.828876) (xy 19.680682 -397.821404) (xy 19.662461 -397.803318) (xy 19.630484 -397.763154)
			(xy 19.604181 -397.719066) (xy 19.584026 -397.67185) (xy 19.570383 -397.622358) (xy 19.563498 -397.571483)
			(xy 19.56308 -397.545814) (xy 19.563535 -397.518443) (xy 19.571352 -397.464263) (xy 19.586843 -397.411759)
			(xy 19.609688 -397.362012) (xy 19.639416 -397.316046) (xy 19.65706 -397.295116) (xy 19.657314 -397.294862)
			(xy 19.662882 -397.287763) (xy 19.66914 -397.270856) (xy 19.669506 -397.261842) (xy 19.669506 -397.194786)
			(xy 19.669154 -397.185769) (xy 19.662903 -397.168852) (xy 19.657314 -397.161766) (xy 19.65706 -397.161766)
			(xy 19.65706 -397.161512) (xy 19.639406 -397.140592) (xy 19.609698 -397.094615) (xy 19.586865 -397.044864)
			(xy 19.571378 -396.992361) (xy 19.563552 -396.938184) (xy 19.56308 -396.910814) (xy 19.563566 -396.883563)
			(xy 19.571322 -396.829615) (xy 19.586677 -396.77732) (xy 19.609319 -396.727743) (xy 19.638785 -396.681893)
			(xy 19.674476 -396.640702) (xy 19.715667 -396.605011) (xy 19.761517 -396.575545) (xy 19.811094 -396.552903)
			(xy 19.863389 -396.537548) (xy 19.917337 -396.529792) (xy 19.971839 -396.529792) (xy 20.025787 -396.537548)
			(xy 20.078082 -396.552903) (xy 20.127659 -396.575545) (xy 20.173509 -396.605011) (xy 20.2147 -396.640702)
			(xy 20.250391 -396.681893) (xy 20.279857 -396.727743) (xy 20.302499 -396.77732) (xy 20.317854 -396.829615)
			(xy 20.32561 -396.883563) (xy 20.326096 -396.910814) (xy 20.325639 -396.938185) (xy 20.317819 -396.992364)
			(xy 20.302328 -397.044867) (xy 20.279484 -397.094614) (xy 20.249758 -397.140581) (xy 20.232116 -397.161512)
			(xy 20.231862 -397.161766) (xy 20.226279 -397.168855) (xy 20.220031 -397.18577) (xy 20.21967 -397.194786)
			(xy 20.21967 -397.261842) (xy 20.220061 -397.270855) (xy 20.226286 -397.287772) (xy 20.231862 -397.294862)
			(xy 20.232116 -397.294862) (xy 20.232116 -397.295116) (xy 20.249732 -397.316067) (xy 20.279446 -397.362035)
			(xy 20.302287 -397.411778) (xy 20.317783 -397.464274) (xy 20.325618 -397.518446) (xy 20.326096 -397.545814)
			(xy 20.325662 -397.571483) (xy 20.31878 -397.622359) (xy 20.305143 -397.671853) (xy 20.284995 -397.719073)
			(xy 20.258702 -397.763167) (xy 20.226736 -397.80334) (xy 20.208494 -397.821404) (xy 20.201365 -397.8289)
			(xy 20.193234 -397.847901) (xy 20.192746 -397.858234) (xy 20.192746 -397.931132) (xy 20.193205 -397.941473)
			(xy 20.201335 -397.960486) (xy 20.208494 -397.967962) (xy 20.226761 -397.986003) (xy 20.258731 -398.026178)
			(xy 20.285026 -398.070276) (xy 20.305172 -398.117501) (xy 20.318807 -398.167) (xy 20.325682 -398.217881)
			(xy 20.326096 -398.243552) (xy 20.325527 -398.273028) (xy 20.316465 -398.33128) (xy 20.29855 -398.387445)
			(xy 20.272207 -398.440185) (xy 20.238064 -398.488244) (xy 20.217892 -398.509744) (xy 20.211344 -398.517069)
			(xy 20.203907 -398.535237) (xy 20.203414 -398.54505) (xy 20.203414 -398.577054) (xy 20.203878 -398.586871)
			(xy 20.211338 -398.605035) (xy 20.217892 -398.61236) (xy 20.231608 -398.627346) (xy 20.231862 -398.6276)
			(xy 20.239698 -398.635616) (xy 20.260276 -398.644441) (xy 20.271486 -398.644618) (xy 20.350226 -398.641824)
			(xy 20.361449 -398.640812) (xy 20.381476 -398.630545) (xy 20.388834 -398.622012) (xy 20.389088 -398.621758)
			(xy 20.407229 -398.598733) (xy 20.449382 -398.558002) (xy 20.497271 -398.524202) (xy 20.549769 -398.498128)
			(xy 20.605639 -398.480395) (xy 20.663564 -398.471421) (xy 20.692872 -398.470882) (xy 20.721929 -398.471455)
			(xy 20.77937 -398.480283) (xy 20.834807 -398.497722) (xy 20.886956 -398.52337) (xy 20.934611 -398.556633)
			(xy 20.956016 -398.576292) (xy 20.963347 -398.582656) (xy 20.981369 -398.589835) (xy 20.991068 -398.590262)
			(xy 21.071332 -398.590262) (xy 21.089366 -398.58315) (xy 21.096478 -398.576292) (xy 21.117891 -398.556639)
			(xy 21.165535 -398.523356) (xy 21.217681 -398.497695) (xy 21.273119 -398.480251) (xy 21.330563 -398.471428)
			(xy 21.359622 -398.470882) (xy 21.386871 -398.47139) (xy 21.440815 -398.479149) (xy 21.493106 -398.494505)
			(xy 21.542679 -398.517147) (xy 21.588525 -398.546613) (xy 21.629712 -398.582304) (xy 21.6654 -398.623492)
			(xy 21.694864 -398.66934) (xy 21.717502 -398.718915) (xy 21.732856 -398.771206) (xy 21.740612 -398.825151)
			(xy 21.740612 -398.879649) (xy 21.732856 -398.933594) (xy 21.717502 -398.985885) (xy 21.694864 -399.03546)
			(xy 21.6654 -399.081308) (xy 21.629712 -399.122496) (xy 21.588526 -399.158187) (xy 21.542679 -399.187653)
			(xy 21.493106 -399.210295) (xy 21.440815 -399.225651) (xy 21.386871 -399.23341) (xy 21.359622 -399.233898)
			(xy 21.330564 -399.233334) (xy 21.273123 -399.224505) (xy 21.217686 -399.207064) (xy 21.165536 -399.181413)
			(xy 21.117882 -399.148148) (xy 21.096478 -399.128488) (xy 21.089151 -399.122118) (xy 21.071126 -399.114943)
			(xy 21.061426 -399.114518) (xy 20.981162 -399.114518) (xy 20.963128 -399.12163) (xy 20.956016 -399.128488)
			(xy 20.934618 -399.148157) (xy 20.886969 -399.181435) (xy 20.834819 -399.207092) (xy 20.779378 -399.224533)
			(xy 20.721932 -399.233353) (xy 20.692872 -399.233898) (xy 20.665778 -399.233464) (xy 20.612138 -399.225788)
			(xy 20.560125 -399.210593) (xy 20.510787 -399.188187) (xy 20.465119 -399.159021) (xy 20.42404 -399.123682)
			(xy 20.405852 -399.103596) (xy 20.405598 -399.103342) (xy 20.397772 -399.095314) (xy 20.377186 -399.086493)
			(xy 20.365974 -399.086324) (xy 20.287234 -399.089118) (xy 20.276005 -399.090094) (xy 20.255979 -399.100385)
			(xy 20.248626 -399.10893) (xy 20.248372 -399.109184) (xy 20.230239 -399.132216) (xy 20.188086 -399.172949)
			(xy 20.140196 -399.20675) (xy 20.087696 -399.232823) (xy 20.031824 -399.250554) (xy 19.973897 -399.259524)
			(xy 19.944588 -399.26006) (xy 19.917333 -399.259656) (xy 19.863377 -399.251896) (xy 19.811075 -399.236536)
			(xy 19.761492 -399.213889) (xy 19.715636 -399.184415) (xy 19.674442 -399.148715) (xy 19.638749 -399.107516)
			(xy 19.609282 -399.061656) (xy 19.586643 -399.012069) (xy 19.571291 -398.959764) (xy 19.56354 -398.905807)
			(xy 19.56308 -398.878552) (xy 14.318488 -398.878552) (xy 14.318488 -402.151596) (xy 14.317846 -402.176592)
			(xy 14.308043 -402.225614) (xy 14.288871 -402.271784) (xy 14.261066 -402.313331) (xy 14.243812 -402.331428)
			(xy 13.951966 -402.623274) (xy 13.94514 -402.630685) (xy 13.937413 -402.649276) (xy 13.93698 -402.659342)
			(xy 13.93698 -403.220174) (xy 14.510764 -403.220174) (xy 14.514835 -403.164552) (xy 14.526961 -403.110115)
			(xy 14.546884 -403.058024) (xy 14.57418 -403.009389) (xy 14.608266 -402.965246) (xy 14.648415 -402.926537)
			(xy 14.693773 -402.894086) (xy 14.743373 -402.868585) (xy 14.796157 -402.850578) (xy 14.851 -402.840448)
			(xy 14.906734 -402.838411) (xy 14.962171 -402.844511) (xy 15.016128 -402.858617) (xy 15.067457 -402.880429)
			(xy 15.115063 -402.909483) (xy 15.157931 -402.945158) (xy 15.195148 -402.986695) (xy 15.225921 -403.033208)
			(xy 15.249593 -403.083705) (xy 15.265661 -403.137112) (xy 15.273781 -403.192288) (xy 15.27429 -403.220174)
			(xy 15.780764 -403.220174) (xy 15.784835 -403.164552) (xy 15.796961 -403.110115) (xy 15.816884 -403.058024)
			(xy 15.84418 -403.009389) (xy 15.878266 -402.965246) (xy 15.918415 -402.926537) (xy 15.963773 -402.894086)
			(xy 16.013373 -402.868585) (xy 16.066157 -402.850578) (xy 16.121 -402.840448) (xy 16.176734 -402.838411)
			(xy 16.232171 -402.844511) (xy 16.286128 -402.858617) (xy 16.337457 -402.880429) (xy 16.385063 -402.909483)
			(xy 16.427931 -402.945158) (xy 16.465148 -402.986695) (xy 16.495921 -403.033208) (xy 16.519593 -403.083705)
			(xy 16.535661 -403.137112) (xy 16.543781 -403.192288) (xy 16.54429 -403.220174) (xy 16.543781 -403.24806)
			(xy 16.535661 -403.303236) (xy 16.528937 -403.325584) (xy 16.923764 -403.325584) (xy 16.927835 -403.269962)
			(xy 16.939961 -403.215525) (xy 16.959884 -403.163434) (xy 16.98718 -403.114799) (xy 17.021266 -403.070656)
			(xy 17.061415 -403.031947) (xy 17.106773 -402.999496) (xy 17.156373 -402.973995) (xy 17.209157 -402.955988)
			(xy 17.264 -402.945858) (xy 17.319734 -402.943821) (xy 17.375171 -402.949921) (xy 17.429128 -402.964027)
			(xy 17.480457 -402.985839) (xy 17.528063 -403.014893) (xy 17.570931 -403.050568) (xy 17.608148 -403.092105)
			(xy 17.638921 -403.138618) (xy 17.662593 -403.189115) (xy 17.663073 -403.19071) (xy 18.073622 -403.19071)
			(xy 18.077693 -403.135088) (xy 18.089819 -403.080651) (xy 18.109742 -403.02856) (xy 18.137038 -402.979925)
			(xy 18.171124 -402.935782) (xy 18.211273 -402.897073) (xy 18.256631 -402.864622) (xy 18.306231 -402.839121)
			(xy 18.359015 -402.821114) (xy 18.413858 -402.810984) (xy 18.469592 -402.808947) (xy 18.525029 -402.815047)
			(xy 18.578986 -402.829153) (xy 18.630315 -402.850965) (xy 18.677921 -402.880019) (xy 18.720789 -402.915694)
			(xy 18.758006 -402.957231) (xy 18.788779 -403.003744) (xy 18.812451 -403.054241) (xy 18.828519 -403.107648)
			(xy 18.836639 -403.162824) (xy 18.837148 -403.19071) (xy 18.836639 -403.218596) (xy 18.828519 -403.273772)
			(xy 18.812451 -403.327179) (xy 18.788779 -403.377676) (xy 18.758006 -403.424189) (xy 18.720789 -403.465726)
			(xy 18.677921 -403.501401) (xy 18.630315 -403.530455) (xy 18.578986 -403.552267) (xy 18.525029 -403.566373)
			(xy 18.469592 -403.572473) (xy 18.413858 -403.570436) (xy 18.359015 -403.560306) (xy 18.306231 -403.542299)
			(xy 18.256631 -403.516798) (xy 18.211273 -403.484347) (xy 18.171124 -403.445638) (xy 18.137038 -403.401495)
			(xy 18.109742 -403.35286) (xy 18.089819 -403.300769) (xy 18.077693 -403.246332) (xy 18.073622 -403.19071)
			(xy 17.663073 -403.19071) (xy 17.678661 -403.242522) (xy 17.686781 -403.297698) (xy 17.68729 -403.325584)
			(xy 17.686781 -403.35347) (xy 17.678661 -403.408646) (xy 17.662593 -403.462053) (xy 17.638921 -403.51255)
			(xy 17.608148 -403.559063) (xy 17.570931 -403.6006) (xy 17.528063 -403.636275) (xy 17.480457 -403.665329)
			(xy 17.429128 -403.687141) (xy 17.375171 -403.701247) (xy 17.319734 -403.707347) (xy 17.264 -403.70531)
			(xy 17.209157 -403.69518) (xy 17.156373 -403.677173) (xy 17.106773 -403.651672) (xy 17.061415 -403.619221)
			(xy 17.021266 -403.580512) (xy 16.98718 -403.536369) (xy 16.959884 -403.487734) (xy 16.939961 -403.435643)
			(xy 16.927835 -403.381206) (xy 16.923764 -403.325584) (xy 16.528937 -403.325584) (xy 16.519593 -403.356643)
			(xy 16.495921 -403.40714) (xy 16.465148 -403.453653) (xy 16.427931 -403.49519) (xy 16.385063 -403.530865)
			(xy 16.337457 -403.559919) (xy 16.286128 -403.581731) (xy 16.232171 -403.595837) (xy 16.176734 -403.601937)
			(xy 16.121 -403.5999) (xy 16.066157 -403.58977) (xy 16.013373 -403.571763) (xy 15.963773 -403.546262)
			(xy 15.918415 -403.513811) (xy 15.878266 -403.475102) (xy 15.84418 -403.430959) (xy 15.816884 -403.382324)
			(xy 15.796961 -403.330233) (xy 15.784835 -403.275796) (xy 15.780764 -403.220174) (xy 15.27429 -403.220174)
			(xy 15.273781 -403.24806) (xy 15.265661 -403.303236) (xy 15.249593 -403.356643) (xy 15.225921 -403.40714)
			(xy 15.195148 -403.453653) (xy 15.157931 -403.49519) (xy 15.115063 -403.530865) (xy 15.067457 -403.559919)
			(xy 15.016128 -403.581731) (xy 14.962171 -403.595837) (xy 14.906734 -403.601937) (xy 14.851 -403.5999)
			(xy 14.796157 -403.58977) (xy 14.743373 -403.571763) (xy 14.693773 -403.546262) (xy 14.648415 -403.513811)
			(xy 14.608266 -403.475102) (xy 14.57418 -403.430959) (xy 14.546884 -403.382324) (xy 14.526961 -403.330233)
			(xy 14.514835 -403.275796) (xy 14.510764 -403.220174) (xy 13.93698 -403.220174) (xy 13.93698 -403.582886)
			(xy 13.937391 -403.592957) (xy 13.94512 -403.611556) (xy 13.951966 -403.618954) (xy 14.63421 -404.301198)
			(xy 14.641613 -404.308035) (xy 14.66021 -404.315756) (xy 14.670278 -404.316184) (xy 16.500602 -404.316184)
			(xy 16.525585 -404.316803) (xy 16.574593 -404.326543) (xy 16.620763 -404.345648) (xy 16.662324 -404.373385)
			(xy 16.680434 -404.390606) (xy 17.841722 -405.551894) (xy 17.858951 -405.569998) (xy 17.886692 -405.611559)
			(xy 17.905798 -405.657731) (xy 17.915535 -405.706742) (xy 17.916144 -405.731726) (xy 17.916144 -407.192734)
			(xy 17.916627 -407.203032) (xy 17.924779 -407.221951) (xy 17.939687 -407.236169) (xy 17.949164 -407.240232)
			(xy 18.038572 -407.273506) (xy 18.048432 -407.276613) (xy 18.069056 -407.275607) (xy 18.087607 -407.266539)
			(xy 18.094706 -407.259028) (xy 18.112909 -407.238708) (xy 18.154126 -407.20297) (xy 18.200012 -407.173466)
			(xy 18.249632 -407.150796) (xy 18.301975 -407.135424) (xy 18.355973 -407.127663) (xy 18.38325 -407.127202)
			(xy 18.410501 -407.127688) (xy 18.464449 -407.135444) (xy 18.516744 -407.150799) (xy 18.566321 -407.173441)
			(xy 18.612171 -407.202907) (xy 18.653362 -407.238598) (xy 18.689053 -407.279789) (xy 18.718519 -407.325639)
			(xy 18.741161 -407.375216) (xy 18.756516 -407.427511) (xy 18.764272 -407.481459) (xy 18.764272 -407.535961)
			(xy 18.756516 -407.589909) (xy 18.741161 -407.642204) (xy 18.718519 -407.691781) (xy 18.689053 -407.737631)
			(xy 18.653362 -407.778822) (xy 18.612171 -407.814513) (xy 18.566321 -407.843979) (xy 18.516744 -407.866621)
			(xy 18.464449 -407.881976) (xy 18.410501 -407.889732) (xy 18.38325 -407.890218) (xy 18.355975 -407.889748)
			(xy 18.30198 -407.881977) (xy 18.249641 -407.866601) (xy 18.200023 -407.843933) (xy 18.154136 -407.814434)
			(xy 18.112915 -407.778704) (xy 18.094706 -407.758392) (xy 18.087577 -407.750921) (xy 18.069028 -407.741888)
			(xy 18.048424 -407.74082) (xy 18.038572 -407.743914) (xy 17.949164 -407.777188) (xy 17.939663 -407.781215)
			(xy 17.924724 -407.795423) (xy 17.916612 -407.814377) (xy 17.916144 -407.824686) (xy 17.916144 -409.167584)
			(xy 18.447764 -409.167584) (xy 18.451835 -409.111962) (xy 18.463961 -409.057525) (xy 18.483884 -409.005434)
			(xy 18.51118 -408.956799) (xy 18.545266 -408.912656) (xy 18.585415 -408.873947) (xy 18.630773 -408.841496)
			(xy 18.680373 -408.815995) (xy 18.733157 -408.797988) (xy 18.788 -408.787858) (xy 18.843734 -408.785821)
			(xy 18.899171 -408.791921) (xy 18.953128 -408.806027) (xy 19.004457 -408.827839) (xy 19.052063 -408.856893)
			(xy 19.094931 -408.892568) (xy 19.132148 -408.934105) (xy 19.162921 -408.980618) (xy 19.186593 -409.031115)
			(xy 19.202661 -409.084522) (xy 19.210781 -409.139698) (xy 19.21129 -409.167584) (xy 19.210781 -409.19547)
			(xy 19.202661 -409.250646) (xy 19.186593 -409.304053) (xy 19.162921 -409.35455) (xy 19.132148 -409.401063)
			(xy 19.094931 -409.4426) (xy 19.052063 -409.478275) (xy 19.004457 -409.507329) (xy 18.953128 -409.529141)
			(xy 18.899171 -409.543247) (xy 18.843734 -409.549347) (xy 18.788 -409.54731) (xy 18.733157 -409.53718)
			(xy 18.680373 -409.519173) (xy 18.630773 -409.493672) (xy 18.585415 -409.461221) (xy 18.545266 -409.422512)
			(xy 18.51118 -409.378369) (xy 18.483884 -409.329734) (xy 18.463961 -409.277643) (xy 18.451835 -409.223206)
			(xy 18.447764 -409.167584) (xy 17.916144 -409.167584) (xy 17.916144 -410.301186) (xy 17.916626 -410.311119)
			(xy 17.924197 -410.329487) (xy 17.938172 -410.343607) (xy 17.947132 -410.347922) (xy 18.033238 -410.384752)
			(xy 18.042504 -410.388196) (xy 18.062248 -410.388521) (xy 18.080638 -410.381326) (xy 18.088102 -410.374846)
			(xy 18.08861 -410.374592) (xy 18.110029 -410.354724) (xy 18.157807 -410.321105) (xy 18.21015 -410.295158)
			(xy 18.265834 -410.277488) (xy 18.32356 -410.268508) (xy 18.35277 -410.267912) (xy 18.380026 -410.268333)
			(xy 18.433983 -410.276087) (xy 18.486287 -410.291441) (xy 18.535874 -410.314083) (xy 18.581733 -410.343552)
			(xy 18.622931 -410.379247) (xy 18.65863 -410.420443) (xy 18.688103 -410.4663) (xy 18.710748 -410.515885)
			(xy 18.726107 -410.568188) (xy 18.733865 -410.622144) (xy 18.733865 -410.676656) (xy 18.726107 -410.730612)
			(xy 18.710748 -410.782915) (xy 18.688103 -410.8325) (xy 18.65863 -410.878357) (xy 18.622931 -410.919553)
			(xy 18.581733 -410.955248) (xy 18.535874 -410.984717) (xy 18.486287 -411.007359) (xy 18.433983 -411.022713)
			(xy 18.380026 -411.030467) (xy 18.35277 -411.030928) (xy 18.32353 -411.03042) (xy 18.265738 -411.02147)
			(xy 18.209991 -411.0038) (xy 18.157595 -410.977825) (xy 18.109781 -410.944154) (xy 18.088356 -410.924248)
			(xy 18.088102 -410.923994) (xy 18.080631 -410.917534) (xy 18.062237 -410.910381) (xy 18.042504 -410.910665)
			(xy 18.033238 -410.914088) (xy 17.947132 -410.950918) (xy 17.93816 -410.955218) (xy 17.924168 -410.969333)
			(xy 17.916612 -410.987716) (xy 17.916144 -410.997654) (xy 17.916144 -411.834584) (xy 18.448018 -411.834584)
			(xy 18.452089 -411.778962) (xy 18.464215 -411.724525) (xy 18.484138 -411.672434) (xy 18.511434 -411.623799)
			(xy 18.54552 -411.579656) (xy 18.585669 -411.540947) (xy 18.631027 -411.508496) (xy 18.680627 -411.482995)
			(xy 18.733411 -411.464988) (xy 18.788254 -411.454858) (xy 18.843988 -411.452821) (xy 18.899425 -411.458921)
			(xy 18.953382 -411.473027) (xy 19.004711 -411.494839) (xy 19.052317 -411.523893) (xy 19.095185 -411.559568)
			(xy 19.132402 -411.601105) (xy 19.163175 -411.647618) (xy 19.186847 -411.698115) (xy 19.202915 -411.751522)
			(xy 19.211035 -411.806698) (xy 19.211544 -411.834584) (xy 19.211035 -411.86247) (xy 19.202915 -411.917646)
			(xy 19.186847 -411.971053) (xy 19.163175 -412.02155) (xy 19.132402 -412.068063) (xy 19.095185 -412.1096)
			(xy 19.052317 -412.145275) (xy 19.004711 -412.174329) (xy 18.953382 -412.196141) (xy 18.899425 -412.210247)
			(xy 18.843988 -412.216347) (xy 18.788254 -412.21431) (xy 18.733411 -412.20418) (xy 18.680627 -412.186173)
			(xy 18.631027 -412.160672) (xy 18.585669 -412.128221) (xy 18.54552 -412.089512) (xy 18.511434 -412.045369)
			(xy 18.484138 -411.996734) (xy 18.464215 -411.944643) (xy 18.452089 -411.890206) (xy 18.448018 -411.834584)
			(xy 17.916144 -411.834584) (xy 17.916144 -412.247588) (xy 17.915508 -412.27257) (xy 17.905773 -412.321577)
			(xy 17.886672 -412.367747) (xy 17.85894 -412.409309) (xy 17.841722 -412.42742) (xy 17.830292 -412.43885)
			(xy 17.823648 -412.446292) (xy 17.816051 -412.464712) (xy 17.816041 -412.484637) (xy 17.823619 -412.503065)
			(xy 17.830292 -412.510478) (xy 17.838928 -412.519114) (xy 17.86128 -412.526734) (xy 17.873218 -412.524956)
			(xy 17.885859 -412.523384) (xy 17.91128 -412.521732) (xy 17.924018 -412.521654) (xy 17.951271 -412.522113)
			(xy 18.005223 -412.52987) (xy 18.057521 -412.545226) (xy 18.107101 -412.567868) (xy 18.152955 -412.597337)
			(xy 18.194148 -412.63303) (xy 18.229842 -412.674223) (xy 18.259311 -412.720077) (xy 18.281953 -412.769657)
			(xy 18.29731 -412.821956) (xy 18.305067 -412.875907) (xy 18.305067 -412.930413) (xy 18.29731 -412.984364)
			(xy 18.281953 -413.036663) (xy 18.259311 -413.086243) (xy 18.229842 -413.132097) (xy 18.194148 -413.17329)
			(xy 18.152955 -413.208983) (xy 18.107101 -413.238452) (xy 18.057521 -413.261094) (xy 18.005223 -413.27645)
			(xy 17.951271 -413.284207) (xy 17.924018 -413.28467) (xy 17.896601 -413.284178) (xy 17.842335 -413.276309)
			(xy 17.789752 -413.260759) (xy 17.739934 -413.237848) (xy 17.693905 -413.208047) (xy 17.652612 -413.171968)
			(xy 17.616905 -413.130354) (xy 17.587516 -413.084061) (xy 17.565052 -413.034039) (xy 17.549973 -412.98132)
			(xy 17.545812 -412.954216) (xy 17.544238 -412.944852) (xy 17.53516 -412.928188) (xy 17.520637 -412.915973)
			(xy 17.511776 -412.91256) (xy 17.42567 -412.883604) (xy 17.416585 -412.880857) (xy 17.397636 -412.88165)
			(xy 17.380292 -412.889328) (xy 17.373346 -412.895796) (xy 16.948658 -413.320484) (xy 16.941827 -413.327891)
			(xy 16.934103 -413.346485) (xy 16.933672 -413.356552) (xy 16.933672 -413.415988) (xy 18.764502 -413.415988)
			(xy 18.768573 -413.360366) (xy 18.780699 -413.305929) (xy 18.800622 -413.253838) (xy 18.827918 -413.205203)
			(xy 18.862004 -413.16106) (xy 18.902153 -413.122351) (xy 18.947511 -413.0899) (xy 18.997111 -413.064399)
			(xy 19.049895 -413.046392) (xy 19.104738 -413.036262) (xy 19.160472 -413.034225) (xy 19.215909 -413.040325)
			(xy 19.269866 -413.054431) (xy 19.321195 -413.076243) (xy 19.368801 -413.105297) (xy 19.411669 -413.140972)
			(xy 19.448886 -413.182509) (xy 19.479659 -413.229022) (xy 19.503331 -413.279519) (xy 19.519399 -413.332926)
			(xy 19.527519 -413.388102) (xy 19.528028 -413.415988) (xy 19.527519 -413.443874) (xy 19.519399 -413.49905)
			(xy 19.503331 -413.552457) (xy 19.479659 -413.602954) (xy 19.448886 -413.649467) (xy 19.411669 -413.691004)
			(xy 19.368801 -413.726679) (xy 19.321195 -413.755733) (xy 19.269866 -413.777545) (xy 19.215909 -413.791651)
			(xy 19.160472 -413.797751) (xy 19.104738 -413.795714) (xy 19.049895 -413.785584) (xy 18.997111 -413.767577)
			(xy 18.947511 -413.742076) (xy 18.902153 -413.709625) (xy 18.862004 -413.670916) (xy 18.827918 -413.626773)
			(xy 18.800622 -413.578138) (xy 18.780699 -413.526047) (xy 18.768573 -413.47161) (xy 18.764502 -413.415988)
			(xy 16.933672 -413.415988) (xy 16.933672 -414.123378) (xy 16.93409 -414.133449) (xy 16.941814 -414.152047)
			(xy 16.948658 -414.159446) (xy 17.049242 -414.26003) (xy 17.05663 -414.266885) (xy 17.075239 -414.274595)
			(xy 17.08531 -414.275016) (xy 18.962878 -414.275016) (xy 18.972949 -414.274602) (xy 18.991548 -414.266876)
			(xy 18.998946 -414.26003) (xy 19.742658 -413.516064) (xy 19.7495 -413.508666) (xy 19.75722 -413.490065)
			(xy 19.757644 -413.479996) (xy 19.757644 -408.119072) (xy 19.757248 -408.108999) (xy 19.749508 -408.090401)
			(xy 19.742658 -408.083004) (xy 18.26133 -406.601422) (xy 18.244101 -406.583319) (xy 18.216362 -406.541757)
			(xy 18.197256 -406.495585) (xy 18.187518 -406.446574) (xy 18.186908 -406.42159) (xy 18.186908 -404.2537)
			(xy 18.18755 -404.228718) (xy 18.197286 -404.179712) (xy 18.216384 -404.133543) (xy 18.244113 -404.09198)
			(xy 18.26133 -404.073868) (xy 19.007074 -403.32787) (xy 19.013916 -403.320471) (xy 19.021635 -403.301871)
			(xy 19.02206 -403.291802) (xy 19.02206 -402.95449) (xy 19.02165 -402.944419) (xy 19.01392 -402.92582)
			(xy 19.007074 -402.918422) (xy 18.369026 -402.28012) (xy 18.351795 -402.262018) (xy 18.324057 -402.220455)
			(xy 18.304952 -402.174283) (xy 18.295214 -402.125272) (xy 18.294604 -402.100288) (xy 18.294604 -400.694906)
			(xy 18.295251 -400.669924) (xy 18.304985 -400.620919) (xy 18.324082 -400.57475) (xy 18.35181 -400.533186)
			(xy 18.369026 -400.515074) (xy 19.294348 -399.589752) (xy 19.312438 -399.572489) (xy 19.353983 -399.544678)
			(xy 19.400157 -399.525506) (xy 19.449183 -399.51571) (xy 19.47418 -399.515076) (xy 21.614892 -399.515076)
			(xy 21.624962 -399.514653) (xy 21.64356 -399.506931) (xy 21.65096 -399.50009) (xy 22.364954 -398.78635)
			(xy 22.371758 -398.778921) (xy 22.3795 -398.760344) (xy 22.37994 -398.750282) (xy 22.37994 -395.934438)
			(xy 22.379686 -395.929866) (xy 22.255988 -394.601446) (xy 22.24659 -394.583666) (xy 22.238716 -394.577316)
			(xy 22.217464 -394.559083) (xy 22.179987 -394.517478) (xy 22.148992 -394.470844) (xy 22.125145 -394.42018)
			(xy 22.108957 -394.366576) (xy 22.100777 -394.311182) (xy 22.100286 -394.283184) (xy 22.100763 -394.255933)
			(xy 22.108521 -394.201985) (xy 22.123878 -394.14969) (xy 22.146521 -394.100113) (xy 22.175988 -394.054263)
			(xy 22.211681 -394.013074) (xy 22.252871 -393.977382) (xy 22.298722 -393.947916) (xy 22.3483 -393.925275)
			(xy 22.400595 -393.909919) (xy 22.454543 -393.902162) (xy 22.481794 -393.901676) (xy 22.510712 -393.90217)
			(xy 22.567886 -393.9109) (xy 22.623086 -393.928161) (xy 22.675049 -393.953557) (xy 22.722582 -393.986506)
			(xy 22.764596 -394.026253) (xy 22.782784 -394.048742) (xy 22.790401 -394.057539) (xy 22.811294 -394.067726)
			(xy 22.822916 -394.0683) (xy 22.902672 -394.0683) (xy 22.9143 -394.06773) (xy 22.93521 -394.057563)
			(xy 22.942804 -394.048742) (xy 22.961003 -394.026265) (xy 23.00302 -393.986528) (xy 23.050553 -393.953587)
			(xy 23.102513 -393.928197) (xy 23.157709 -393.91094) (xy 23.214878 -393.902211) (xy 23.243794 -393.901676)
			(xy 23.271044 -393.902183) (xy 23.324991 -393.909939) (xy 23.377284 -393.925292) (xy 23.42686 -393.947931)
			(xy 23.47271 -393.977396) (xy 23.5139 -394.013085) (xy 23.549591 -394.054273) (xy 23.579058 -394.100121)
			(xy 23.6017 -394.149695) (xy 23.617057 -394.201988) (xy 23.624815 -394.255934) (xy 23.625302 -394.283184)
			(xy 23.624795 -394.31118) (xy 23.616607 -394.366571) (xy 23.600418 -394.420173) (xy 23.576576 -394.470836)
			(xy 23.545591 -394.517475) (xy 23.508128 -394.559089) (xy 23.486872 -394.577316) (xy 23.478998 -394.583666)
			(xy 23.4696 -394.601446) (xy 23.360069 -395.77772) (xy 28.172664 -395.77772) (xy 28.173126 -395.750349)
			(xy 28.180943 -395.69617) (xy 28.196432 -395.643666) (xy 28.219275 -395.593919) (xy 28.249001 -395.547953)
			(xy 28.266644 -395.527022) (xy 28.266898 -395.526768) (xy 28.272462 -395.519666) (xy 28.278722 -395.502761)
			(xy 28.27909 -395.493748) (xy 28.27909 -395.426692) (xy 28.278739 -395.417674) (xy 28.272488 -395.400757)
			(xy 28.266898 -395.393672) (xy 28.266644 -395.393672) (xy 28.266644 -395.393418) (xy 28.249007 -395.372484)
			(xy 28.219293 -395.326513) (xy 28.196456 -395.276766) (xy 28.180965 -395.224265) (xy 28.173137 -395.170089)
			(xy 28.172664 -395.14272) (xy 28.17315 -395.115469) (xy 28.180906 -395.061521) (xy 28.196261 -395.009226)
			(xy 28.218903 -394.959649) (xy 28.248369 -394.913799) (xy 28.28406 -394.872608) (xy 28.325251 -394.836917)
			(xy 28.371101 -394.807451) (xy 28.420678 -394.784809) (xy 28.472973 -394.769454) (xy 28.526921 -394.761698)
			(xy 28.581423 -394.761698) (xy 28.635371 -394.769454) (xy 28.687666 -394.784809) (xy 28.737243 -394.807451)
			(xy 28.783093 -394.836917) (xy 28.824284 -394.872608) (xy 28.859975 -394.913799) (xy 28.889441 -394.959649)
			(xy 28.912083 -395.009226) (xy 28.927438 -395.061521) (xy 28.935194 -395.115469) (xy 28.93568 -395.14272)
			(xy 28.935231 -395.170091) (xy 28.927409 -395.224271) (xy 28.911917 -395.276774) (xy 28.889071 -395.326521)
			(xy 28.859343 -395.372487) (xy 28.8417 -395.393418) (xy 28.841446 -395.393672) (xy 28.835859 -395.400758)
			(xy 28.829614 -395.417675) (xy 28.829254 -395.426692) (xy 28.829254 -395.493748) (xy 28.829624 -395.502764)
			(xy 28.835861 -395.519682) (xy 28.841446 -395.526768) (xy 28.8417 -395.526768) (xy 28.8417 -395.527022)
			(xy 28.859316 -395.547973) (xy 28.889031 -395.59394) (xy 28.911872 -395.643683) (xy 28.927368 -395.69618)
			(xy 28.935203 -395.750352) (xy 28.93568 -395.77772) (xy 28.935194 -395.804971) (xy 28.927438 -395.858919)
			(xy 28.912083 -395.911214) (xy 28.889441 -395.960791) (xy 28.859975 -396.006641) (xy 28.824284 -396.047832)
			(xy 28.783093 -396.083523) (xy 28.737243 -396.112989) (xy 28.687666 -396.135631) (xy 28.635371 -396.150986)
			(xy 28.581423 -396.158742) (xy 28.526921 -396.158742) (xy 28.472973 -396.150986) (xy 28.420678 -396.135631)
			(xy 28.371101 -396.112989) (xy 28.325251 -396.083523) (xy 28.28406 -396.047832) (xy 28.248369 -396.006641)
			(xy 28.218903 -395.960791) (xy 28.196261 -395.911214) (xy 28.180906 -395.858919) (xy 28.17315 -395.804971)
			(xy 28.172664 -395.77772) (xy 23.360069 -395.77772) (xy 23.345902 -395.929866) (xy 23.345648 -395.934438)
			(xy 23.345648 -397.51381) (xy 28.152598 -397.51381) (xy 28.15307 -397.48644) (xy 28.160887 -397.432261)
			(xy 28.176374 -397.379758) (xy 28.199215 -397.330011) (xy 28.228938 -397.284044) (xy 28.246578 -397.263112)
			(xy 28.246832 -397.262858) (xy 28.252404 -397.255762) (xy 28.258658 -397.238852) (xy 28.259024 -397.229838)
			(xy 28.259024 -397.162782) (xy 28.258671 -397.153765) (xy 28.25242 -397.136848) (xy 28.246832 -397.129762)
			(xy 28.246578 -397.129762) (xy 28.246578 -397.129508) (xy 28.228926 -397.108587) (xy 28.199217 -397.06261)
			(xy 28.176384 -397.01286) (xy 28.160896 -396.960357) (xy 28.15307 -396.90618) (xy 28.152598 -396.87881)
			(xy 28.153084 -396.851559) (xy 28.16084 -396.797611) (xy 28.176195 -396.745316) (xy 28.198837 -396.695739)
			(xy 28.228303 -396.649889) (xy 28.263994 -396.608698) (xy 28.305185 -396.573007) (xy 28.351035 -396.543541)
			(xy 28.400612 -396.520899) (xy 28.452907 -396.505544) (xy 28.506855 -396.497788) (xy 28.561357 -396.497788)
			(xy 28.615305 -396.505544) (xy 28.6676 -396.520899) (xy 28.717177 -396.543541) (xy 28.763027 -396.573007)
			(xy 28.804218 -396.608698) (xy 28.839909 -396.649889) (xy 28.869375 -396.695739) (xy 28.892017 -396.745316)
			(xy 28.907372 -396.797611) (xy 28.915128 -396.851559) (xy 28.915614 -396.87881) (xy 28.91515 -396.90618)
			(xy 28.907331 -396.960359) (xy 28.891842 -397.012862) (xy 28.868999 -397.062609) (xy 28.839275 -397.108576)
			(xy 28.821634 -397.129508) (xy 28.82138 -397.129762) (xy 28.815801 -397.136854) (xy 28.80955 -397.153767)
			(xy 28.809188 -397.162782) (xy 28.809188 -397.229838) (xy 28.809529 -397.238856) (xy 28.815788 -397.255773)
			(xy 28.82138 -397.262858) (xy 28.821634 -397.262858) (xy 28.821634 -397.263112) (xy 28.839251 -397.284062)
			(xy 28.868965 -397.33003) (xy 28.891804 -397.379773) (xy 28.907301 -397.43227) (xy 28.915136 -397.486442)
			(xy 28.915614 -397.51381) (xy 28.915128 -397.541061) (xy 28.907372 -397.595009) (xy 28.892017 -397.647304)
			(xy 28.869375 -397.696881) (xy 28.839909 -397.742731) (xy 28.804218 -397.783922) (xy 28.763027 -397.819613)
			(xy 28.717177 -397.849079) (xy 28.6676 -397.871721) (xy 28.615305 -397.887076) (xy 28.561357 -397.894832)
			(xy 28.506855 -397.894832) (xy 28.452907 -397.887076) (xy 28.400612 -397.871721) (xy 28.351035 -397.849079)
			(xy 28.305185 -397.819613) (xy 28.263994 -397.783922) (xy 28.228303 -397.742731) (xy 28.198837 -397.696881)
			(xy 28.176195 -397.647304) (xy 28.16084 -397.595009) (xy 28.153084 -397.541061) (xy 28.152598 -397.51381)
			(xy 23.345648 -397.51381) (xy 23.345648 -399.066258) (xy 23.345054 -399.091242) (xy 23.335305 -399.140251)
			(xy 23.316193 -399.186421) (xy 23.28845 -399.227981) (xy 23.271226 -399.24609) (xy 22.1107 -400.406616)
			(xy 22.092601 -400.423868) (xy 22.051057 -400.451678) (xy 22.004887 -400.470852) (xy 21.955864 -400.480654)
			(xy 21.930868 -400.481292) (xy 19.790156 -400.481292) (xy 19.780081 -400.48167) (xy 19.776722 -400.48307)
			(xy 23.694136 -400.48307) (xy 23.694576 -400.455699) (xy 23.702399 -400.401518) (xy 23.717893 -400.349014)
			(xy 23.740741 -400.299268) (xy 23.770472 -400.253303) (xy 23.788116 -400.232372) (xy 23.78837 -400.232118)
			(xy 23.793963 -400.225036) (xy 23.800204 -400.208116) (xy 23.800562 -400.199098) (xy 23.800562 -400.132042)
			(xy 23.800193 -400.123026) (xy 23.793955 -400.106109) (xy 23.78837 -400.099022) (xy 23.788116 -400.099022)
			(xy 23.788116 -400.098768) (xy 23.770498 -400.077819) (xy 23.740782 -400.031851) (xy 23.717942 -399.982108)
			(xy 23.702446 -399.929611) (xy 23.694613 -399.875438) (xy 23.694136 -399.84807) (xy 23.694527 -399.820814)
			(xy 23.702289 -399.766859) (xy 23.717651 -399.714557) (xy 23.740301 -399.664973) (xy 23.769776 -399.619118)
			(xy 23.805477 -399.577925) (xy 23.846678 -399.542231) (xy 23.892538 -399.512765) (xy 23.942126 -399.490125)
			(xy 23.994431 -399.474774) (xy 24.048388 -399.467022) (xy 24.075644 -399.466562) (xy 24.105766 -399.467165)
			(xy 24.165261 -399.476638) (xy 24.222529 -399.495341) (xy 24.276146 -399.52281) (xy 24.324782 -399.558362)
			(xy 24.346408 -399.579338) (xy 24.353807 -399.586179) (xy 24.372407 -399.593897) (xy 24.382476 -399.594324)
			(xy 24.454612 -399.594324) (xy 24.464685 -399.593925) (xy 24.483283 -399.586188) (xy 24.49068 -399.579338)
			(xy 24.512297 -399.558349) (xy 24.560927 -399.52278) (xy 24.614545 -399.495301) (xy 24.671818 -399.476595)
			(xy 24.731319 -399.467128) (xy 24.761444 -399.466562) (xy 24.788814 -399.467046) (xy 24.842993 -399.474857)
			(xy 24.895496 -399.490341) (xy 24.945243 -399.513179) (xy 24.99121 -399.542902) (xy 25.012142 -399.560542)
			(xy 25.012396 -399.560796) (xy 25.01948 -399.566387) (xy 25.036399 -399.572631) (xy 25.045416 -399.572988)
			(xy 25.112472 -399.572988) (xy 25.121488 -399.57262) (xy 25.138405 -399.566381) (xy 25.145492 -399.560796)
			(xy 25.145492 -399.560542) (xy 25.145746 -399.560542) (xy 25.166693 -399.542921) (xy 25.212661 -399.513205)
			(xy 25.262405 -399.490365) (xy 25.314902 -399.47487) (xy 25.369076 -399.467038) (xy 25.396444 -399.466562)
			(xy 25.423695 -399.467037) (xy 25.477642 -399.474799) (xy 25.529935 -399.490158) (xy 25.57951 -399.512802)
			(xy 25.625359 -399.54227) (xy 25.666548 -399.577962) (xy 25.702239 -399.619152) (xy 25.731705 -399.665002)
			(xy 25.754347 -399.714579) (xy 25.769704 -399.766872) (xy 25.777464 -399.820819) (xy 25.777952 -399.84807)
			(xy 25.77748 -399.87544) (xy 25.769665 -399.929619) (xy 25.754178 -399.982123) (xy 25.731338 -400.03187)
			(xy 25.701613 -400.077837) (xy 25.683972 -400.098768) (xy 25.683718 -400.099022) (xy 25.678119 -400.1061)
			(xy 25.671879 -400.123023) (xy 25.671526 -400.132042) (xy 25.671526 -400.199098) (xy 25.671878 -400.208115)
			(xy 25.678128 -400.225033) (xy 25.683718 -400.232118) (xy 25.683972 -400.232118) (xy 25.683972 -400.232372)
			(xy 25.701607 -400.253307) (xy 25.73132 -400.299279) (xy 25.754158 -400.349025) (xy 25.76965 -400.401526)
			(xy 25.777478 -400.455701) (xy 25.777952 -400.48307) (xy 25.777394 -400.510318) (xy 25.769643 -400.564261)
			(xy 25.754294 -400.616552) (xy 25.731659 -400.666126) (xy 25.725734 -400.675348) (xy 27.191462 -400.675348)
			(xy 27.191884 -400.648971) (xy 27.199149 -400.596719) (xy 27.213534 -400.545964) (xy 27.234764 -400.497671)
			(xy 27.262438 -400.452757) (xy 27.296027 -400.412079) (xy 27.31516 -400.393916) (xy 27.32255 -400.386385)
			(xy 27.331082 -400.367112) (xy 27.33167 -400.356578) (xy 27.33167 -400.281648) (xy 27.331137 -400.271099)
			(xy 27.322605 -400.251803) (xy 27.31516 -400.24431) (xy 27.296029 -400.226146) (xy 27.26244 -400.185469)
			(xy 27.234768 -400.140556) (xy 27.213541 -400.092262) (xy 27.199162 -400.041506) (xy 27.191905 -399.989255)
			(xy 27.191462 -399.962878) (xy 27.191948 -399.935627) (xy 27.199704 -399.881679) (xy 27.215059 -399.829384)
			(xy 27.237701 -399.779807) (xy 27.267167 -399.733957) (xy 27.302858 -399.692766) (xy 27.344049 -399.657075)
			(xy 27.389899 -399.627609) (xy 27.439476 -399.604967) (xy 27.491771 -399.589612) (xy 27.545719 -399.581856)
			(xy 27.600221 -399.581856) (xy 27.654169 -399.589612) (xy 27.706464 -399.604967) (xy 27.756041 -399.627609)
			(xy 27.801891 -399.657075) (xy 27.843082 -399.692766) (xy 27.878773 -399.733957) (xy 27.908239 -399.779807)
			(xy 27.930881 -399.829384) (xy 27.946236 -399.881679) (xy 27.953992 -399.935627) (xy 27.954478 -399.962878)
			(xy 27.953994 -399.989253) (xy 27.94674 -400.041501) (xy 27.932366 -400.092255) (xy 27.911147 -400.140548)
			(xy 27.883485 -400.185463) (xy 27.849908 -400.226145) (xy 27.83078 -400.24431) (xy 27.823369 -400.251823)
			(xy 27.814851 -400.27111) (xy 27.81427 -400.281648) (xy 27.81427 -400.356578) (xy 27.814806 -400.367127)
			(xy 27.823337 -400.386422) (xy 27.83078 -400.393916) (xy 27.849931 -400.412059) (xy 27.883517 -400.452742)
			(xy 27.911185 -400.49766) (xy 27.932409 -400.545957) (xy 27.946784 -400.596716) (xy 27.954037 -400.64897)
			(xy 27.954478 -400.675348) (xy 27.953992 -400.702599) (xy 27.946236 -400.756547) (xy 27.930881 -400.808842)
			(xy 27.908239 -400.858419) (xy 27.878773 -400.904269) (xy 27.843082 -400.94546) (xy 27.801891 -400.981151)
			(xy 27.756041 -401.010617) (xy 27.706464 -401.033259) (xy 27.654169 -401.048614) (xy 27.600221 -401.05637)
			(xy 27.545719 -401.05637) (xy 27.491771 -401.048614) (xy 27.439476 -401.033259) (xy 27.389899 -401.010617)
			(xy 27.344049 -400.981151) (xy 27.302858 -400.94546) (xy 27.267167 -400.904269) (xy 27.237701 -400.858419)
			(xy 27.215059 -400.808842) (xy 27.199704 -400.756547) (xy 27.191948 -400.702599) (xy 27.191462 -400.675348)
			(xy 25.725734 -400.675348) (xy 25.7022 -400.711974) (xy 25.666516 -400.753164) (xy 25.625334 -400.788856)
			(xy 25.579491 -400.818324) (xy 25.529921 -400.840968) (xy 25.477634 -400.856327) (xy 25.423692 -400.864089)
			(xy 25.396444 -400.864578) (xy 25.369074 -400.864092) (xy 25.314896 -400.856279) (xy 25.262393 -400.840795)
			(xy 25.212646 -400.817958) (xy 25.166678 -400.788237) (xy 25.145746 -400.770598) (xy 25.145492 -400.770344)
			(xy 25.138417 -400.764741) (xy 25.121491 -400.758506) (xy 25.112472 -400.758152) (xy 25.045416 -400.758152)
			(xy 25.036399 -400.758505) (xy 25.019481 -400.764754) (xy 25.012396 -400.770344) (xy 25.012396 -400.770598)
			(xy 25.012142 -400.770598) (xy 24.991205 -400.788231) (xy 24.945233 -400.817943) (xy 24.895487 -400.840781)
			(xy 24.842988 -400.856273) (xy 24.788813 -400.864103) (xy 24.761444 -400.864578) (xy 24.731322 -400.863971)
			(xy 24.671828 -400.854498) (xy 24.614561 -400.835795) (xy 24.560943 -400.808327) (xy 24.512306 -400.772777)
			(xy 24.49068 -400.751802) (xy 24.483281 -400.744961) (xy 24.464681 -400.737242) (xy 24.454612 -400.736816)
			(xy 24.382476 -400.736816) (xy 24.372405 -400.737225) (xy 24.353807 -400.744957) (xy 24.346408 -400.751802)
			(xy 24.324803 -400.772804) (xy 24.276169 -400.808369) (xy 24.222547 -400.835845) (xy 24.165273 -400.854548)
			(xy 24.10577 -400.864013) (xy 24.075644 -400.864578) (xy 24.048391 -400.864104) (xy 23.994439 -400.856352)
			(xy 23.942139 -400.841) (xy 23.892557 -400.81836) (xy 23.846703 -400.788894) (xy 23.805509 -400.753201)
			(xy 23.769814 -400.712009) (xy 23.740346 -400.666155) (xy 23.717705 -400.616574) (xy 23.702351 -400.564275)
			(xy 23.694597 -400.510323) (xy 23.694136 -400.48307) (xy 19.776722 -400.48307) (xy 19.761482 -400.489421)
			(xy 19.754088 -400.496278) (xy 19.199098 -401.051014) (xy 19.192259 -401.058415) (xy 19.184539 -401.077014)
			(xy 19.184112 -401.087082) (xy 19.184112 -401.426243) (xy 19.533319 -401.426243) (xy 19.533319 -401.371737)
			(xy 19.541076 -401.317787) (xy 19.556432 -401.265489) (xy 19.579075 -401.21591) (xy 19.608543 -401.170057)
			(xy 19.644236 -401.128865) (xy 19.685428 -401.093171) (xy 19.731281 -401.063704) (xy 19.780861 -401.041062)
			(xy 19.833159 -401.025706) (xy 19.887109 -401.017949) (xy 19.914362 -401.017486) (xy 19.944485 -401.018071)
			(xy 20.003981 -401.027547) (xy 20.061249 -401.046254) (xy 20.114867 -401.073727) (xy 20.163501 -401.109284)
			(xy 20.185126 -401.130262) (xy 20.192527 -401.137101) (xy 20.211125 -401.144822) (xy 20.221194 -401.145248)
			(xy 20.29333 -401.145248) (xy 20.303403 -401.144852) (xy 20.322001 -401.137112) (xy 20.329398 -401.130262)
			(xy 20.351011 -401.109268) (xy 20.399642 -401.073699) (xy 20.453261 -401.046221) (xy 20.510534 -401.027516)
			(xy 20.570037 -401.018051) (xy 20.600162 -401.017486) (xy 20.627531 -401.017978) (xy 20.681709 -401.02579)
			(xy 20.734212 -401.041273) (xy 20.783959 -401.064109) (xy 20.829927 -401.093828) (xy 20.85086 -401.111466)
			(xy 20.851114 -401.11172) (xy 20.858191 -401.117321) (xy 20.875115 -401.123558) (xy 20.884134 -401.123912)
			(xy 20.95119 -401.123912) (xy 20.960206 -401.123548) (xy 20.977123 -401.117305) (xy 20.98421 -401.11172)
			(xy 20.98421 -401.111466) (xy 20.984464 -401.111466) (xy 21.005394 -401.093825) (xy 21.051368 -401.064115)
			(xy 21.101116 -401.04128) (xy 21.153617 -401.025789) (xy 21.207793 -401.01796) (xy 21.235162 -401.017486)
			(xy 21.262416 -401.017959) (xy 21.31637 -401.025711) (xy 21.368672 -401.041064) (xy 21.418256 -401.063704)
			(xy 21.464113 -401.09317) (xy 21.50531 -401.128863) (xy 21.541007 -401.170056) (xy 21.570478 -401.215911)
			(xy 21.593123 -401.265492) (xy 21.608481 -401.317792) (xy 21.616239 -401.371746) (xy 21.616239 -401.426254)
			(xy 21.608481 -401.480208) (xy 21.593123 -401.532508) (xy 21.570478 -401.582089) (xy 21.541007 -401.627944)
			(xy 21.50531 -401.669137) (xy 21.464113 -401.70483) (xy 21.418256 -401.734296) (xy 21.368672 -401.756936)
			(xy 21.31637 -401.772289) (xy 21.262416 -401.780041) (xy 21.235162 -401.780502) (xy 21.207793 -401.779999)
			(xy 21.153616 -401.77219) (xy 21.101113 -401.75671) (xy 21.051365 -401.733876) (xy 21.005397 -401.704159)
			(xy 20.984464 -401.686522) (xy 20.98421 -401.686268) (xy 20.977127 -401.680676) (xy 20.960207 -401.674434)
			(xy 20.95119 -401.674076) (xy 20.884134 -401.674076) (xy 20.875119 -401.674454) (xy 20.858203 -401.680688)
			(xy 20.851114 -401.686268) (xy 20.851114 -401.686522) (xy 20.85086 -401.686522) (xy 20.829919 -401.70415)
			(xy 20.783948 -401.733863) (xy 20.734203 -401.7567) (xy 20.681704 -401.772194) (xy 20.62753 -401.780026)
			(xy 20.600162 -401.780502) (xy 20.570039 -401.779906) (xy 20.510544 -401.770433) (xy 20.453275 -401.751729)
			(xy 20.399658 -401.724258) (xy 20.351023 -401.688703) (xy 20.329398 -401.667726) (xy 20.32199 -401.660896)
			(xy 20.303397 -401.65317) (xy 20.29333 -401.65274) (xy 20.221194 -401.65274) (xy 20.211123 -401.653152)
			(xy 20.192525 -401.660881) (xy 20.185126 -401.667726) (xy 20.1635 -401.688706) (xy 20.114873 -401.724277)
			(xy 20.061257 -401.751758) (xy 20.003986 -401.770466) (xy 19.944486 -401.779935) (xy 19.914362 -401.780502)
			(xy 19.887109 -401.780031) (xy 19.833159 -401.772274) (xy 19.780861 -401.756918) (xy 19.731281 -401.734276)
			(xy 19.685428 -401.704809) (xy 19.644236 -401.669115) (xy 19.608543 -401.627923) (xy 19.579075 -401.58207)
			(xy 19.556432 -401.532491) (xy 19.541076 -401.480193) (xy 19.533319 -401.426243) (xy 19.184112 -401.426243)
			(xy 19.184112 -401.815808) (xy 19.18453 -401.825878) (xy 19.192256 -401.844476) (xy 19.199098 -401.851876)
			(xy 19.8374 -402.490178) (xy 19.854639 -402.508289) (xy 19.882452 -402.549829) (xy 19.90163 -402.595995)
			(xy 19.911435 -402.645015) (xy 19.912076 -402.67001) (xy 19.912076 -403.576282) (xy 19.911429 -403.601277)
			(xy 19.901628 -403.6503) (xy 19.882458 -403.69647) (xy 19.854654 -403.738017) (xy 19.8374 -403.756114)
			(xy 19.091402 -404.502112) (xy 19.084564 -404.509514) (xy 19.076843 -404.528112) (xy 19.076416 -404.53818)
			(xy 19.076416 -404.68931) (xy 20.194016 -404.68931) (xy 20.194502 -404.662059) (xy 20.202258 -404.608111)
			(xy 20.217613 -404.555816) (xy 20.240255 -404.506239) (xy 20.269721 -404.460389) (xy 20.305412 -404.419198)
			(xy 20.346603 -404.383507) (xy 20.392453 -404.354041) (xy 20.44203 -404.331399) (xy 20.494325 -404.316044)
			(xy 20.548273 -404.308288) (xy 20.602775 -404.308288) (xy 20.656723 -404.316044) (xy 20.709018 -404.331399)
			(xy 20.758595 -404.354041) (xy 20.804445 -404.383507) (xy 20.845636 -404.419198) (xy 20.881327 -404.460389)
			(xy 20.910793 -404.506239) (xy 20.933435 -404.555816) (xy 20.94879 -404.608111) (xy 20.956546 -404.662059)
			(xy 20.957032 -404.68931) (xy 20.956302 -404.722243) (xy 20.944935 -404.787122) (xy 20.934426 -404.818342)
			(xy 20.931632 -404.826724) (xy 20.931632 -405.976582) (xy 20.932058 -405.986651) (xy 20.939777 -406.00525)
			(xy 20.946618 -406.01265) (xy 20.954746 -406.020778) (xy 22.643338 -406.020778) (xy 22.64375 -405.995078)
			(xy 22.65065 -405.944142) (xy 22.664322 -405.894593) (xy 22.684518 -405.847326) (xy 22.710874 -405.803197)
			(xy 22.742913 -405.763003) (xy 22.761194 -405.744934) (xy 22.76856 -405.737822) (xy 22.776688 -405.719026)
			(xy 22.777704 -405.625808) (xy 22.76983 -405.606758) (xy 22.762464 -405.599646) (xy 22.741505 -405.57805)
			(xy 22.706018 -405.529447) (xy 22.678604 -405.475874) (xy 22.659945 -405.41866) (xy 22.650503 -405.359226)
			(xy 22.649942 -405.329136) (xy 22.649942 -405.328882) (xy 22.650387 -405.301511) (xy 22.658209 -405.247331)
			(xy 22.673702 -405.194827) (xy 22.696549 -405.14508) (xy 22.726278 -405.099115) (xy 22.743922 -405.078184)
			(xy 22.744176 -405.07793) (xy 22.749765 -405.070845) (xy 22.756008 -405.053927) (xy 22.756368 -405.04491)
			(xy 22.756368 -404.977854) (xy 22.755992 -404.968839) (xy 22.749758 -404.951921) (xy 22.744176 -404.944834)
			(xy 22.743922 -404.944834) (xy 22.743922 -404.94458) (xy 22.726264 -404.923661) (xy 22.69654 -404.877691)
			(xy 22.673696 -404.827942) (xy 22.658202 -404.775438) (xy 22.650375 -404.721258) (xy 22.650377 -404.666515)
			(xy 22.658207 -404.612335) (xy 22.673706 -404.559832) (xy 22.696553 -404.510085) (xy 22.72628 -404.464117)
			(xy 22.743922 -404.443184) (xy 22.744176 -404.44293) (xy 22.749765 -404.435845) (xy 22.756008 -404.418927)
			(xy 22.756368 -404.40991) (xy 22.756368 -404.342854) (xy 22.755992 -404.333839) (xy 22.749758 -404.316921)
			(xy 22.744176 -404.309834) (xy 22.743922 -404.309834) (xy 22.743922 -404.30958) (xy 22.72631 -404.288626)
			(xy 22.696594 -404.242659) (xy 22.673752 -404.192918) (xy 22.658255 -404.140422) (xy 22.65042 -404.08625)
			(xy 22.649942 -404.058882) (xy 22.650428 -404.031631) (xy 22.658184 -403.977683) (xy 22.673539 -403.925388)
			(xy 22.696181 -403.875811) (xy 22.725647 -403.829961) (xy 22.761338 -403.78877) (xy 22.802529 -403.753079)
			(xy 22.848379 -403.723613) (xy 22.897956 -403.700971) (xy 22.950251 -403.685616) (xy 23.004199 -403.67786)
			(xy 23.058701 -403.67786) (xy 23.112649 -403.685616) (xy 23.164944 -403.700971) (xy 23.214521 -403.723613)
			(xy 23.260371 -403.753079) (xy 23.301562 -403.78877) (xy 23.337253 -403.829961) (xy 23.366719 -403.875811)
			(xy 23.389361 -403.925388) (xy 23.404716 -403.977683) (xy 23.412472 -404.031631) (xy 23.412958 -404.058882)
			(xy 23.412492 -404.086252) (xy 23.404675 -404.140432) (xy 23.389187 -404.192935) (xy 23.366345 -404.242682)
			(xy 23.33662 -404.288649) (xy 23.318978 -404.30958) (xy 23.318724 -404.309834) (xy 23.31315 -404.316929)
			(xy 23.306898 -404.33384) (xy 23.306532 -404.342854) (xy 23.306532 -404.40991) (xy 23.306877 -404.418928)
			(xy 23.313132 -404.435846) (xy 23.318724 -404.44293) (xy 23.318978 -404.443184) (xy 23.323804 -404.448772)
			(xy 23.330662 -404.4569) (xy 23.34895 -404.466298) (xy 23.433024 -404.471632) (xy 23.443335 -404.471758)
			(xy 23.462732 -404.464815) (xy 23.470616 -404.45817) (xy 23.491895 -404.439221) (xy 23.539032 -404.407212)
			(xy 23.590401 -404.382562) (xy 23.644862 -404.365818) (xy 23.701207 -404.357351) (xy 23.729696 -404.356824)
			(xy 23.759819 -404.357405) (xy 23.819314 -404.366885) (xy 23.876582 -404.385593) (xy 23.930199 -404.413067)
			(xy 23.978834 -404.448623) (xy 24.00046 -404.4696) (xy 24.00788 -404.476415) (xy 24.026464 -404.484149)
			(xy 24.036528 -404.484586) (xy 24.108664 -404.484586) (xy 24.118732 -404.484146) (xy 24.13733 -404.476436)
			(xy 24.144732 -404.4696) (xy 24.166364 -404.448627) (xy 24.214991 -404.413058) (xy 24.268605 -404.385577)
			(xy 24.325874 -404.366867) (xy 24.385372 -404.357393) (xy 24.415496 -404.356824) (xy 24.441793 -404.357286)
			(xy 24.493889 -404.364503) (xy 24.544499 -404.378814) (xy 24.59266 -404.399948) (xy 24.637458 -404.427503)
			(xy 24.678041 -404.460956) (xy 24.696166 -404.480014) (xy 24.69642 -404.480268) (xy 24.703543 -404.487179)
			(xy 24.721584 -404.495409) (xy 24.731472 -404.49627) (xy 24.803862 -404.499064) (xy 24.813943 -404.499013)
			(xy 24.832803 -404.491933) (xy 24.840438 -404.485348) (xy 24.861768 -404.466081) (xy 24.909129 -404.433514)
			(xy 24.96084 -404.40842) (xy 25.01573 -404.391369) (xy 25.072557 -404.382745) (xy 25.101296 -404.382224)
			(xy 25.131419 -404.382805) (xy 25.190914 -404.392285) (xy 25.248182 -404.410993) (xy 25.301799 -404.438467)
			(xy 25.350434 -404.474023) (xy 25.37206 -404.495) (xy 25.37948 -404.501815) (xy 25.398064 -404.509549)
			(xy 25.408128 -404.509986) (xy 25.480264 -404.509986) (xy 25.490332 -404.509546) (xy 25.50893 -404.501836)
			(xy 25.516332 -404.495) (xy 25.537964 -404.474027) (xy 25.586591 -404.438458) (xy 25.640205 -404.410977)
			(xy 25.697474 -404.392267) (xy 25.756972 -404.382793) (xy 25.787096 -404.382224) (xy 25.81435 -404.382659)
			(xy 25.868304 -404.390416) (xy 25.920604 -404.405774) (xy 25.970186 -404.428418) (xy 26.016041 -404.457888)
			(xy 26.057235 -404.493585) (xy 26.092928 -404.534781) (xy 26.122396 -404.580638) (xy 26.145036 -404.630222)
			(xy 26.16039 -404.682524) (xy 26.168143 -404.736478) (xy 26.168604 -404.763732) (xy 26.168156 -404.791103)
			(xy 26.160333 -404.845283) (xy 26.14484 -404.897786) (xy 26.121995 -404.947532) (xy 26.092267 -404.993499)
			(xy 26.074624 -405.01443) (xy 26.07437 -405.014684) (xy 26.068781 -405.021769) (xy 26.062537 -405.038687)
			(xy 26.062178 -405.047704) (xy 26.062178 -405.11476) (xy 26.062559 -405.123774) (xy 26.06879 -405.140691)
			(xy 26.07437 -405.14778) (xy 26.074624 -405.14778) (xy 26.074624 -405.148034) (xy 26.092249 -405.168977)
			(xy 26.121962 -405.214947) (xy 26.144801 -405.264692) (xy 26.160295 -405.31719) (xy 26.168127 -405.371364)
			(xy 26.168604 -405.398732) (xy 26.168145 -405.425093) (xy 26.160898 -405.477315) (xy 26.146532 -405.528043)
			(xy 26.125321 -405.57631) (xy 26.097669 -405.621199) (xy 26.081228 -405.64181) (xy 26.075386 -405.648922)
			(xy 26.06929 -405.666956) (xy 26.072846 -405.74468) (xy 26.073688 -405.753954) (xy 26.081111 -405.771017)
			(xy 26.087324 -405.777954) (xy 26.107808 -405.799505) (xy 26.142506 -405.847786) (xy 26.169292 -405.900866)
			(xy 26.187517 -405.95746) (xy 26.196739 -406.016196) (xy 26.197306 -406.045924) (xy 26.196845 -406.073176)
			(xy 26.189085 -406.127125) (xy 26.173726 -406.17942) (xy 26.151082 -406.228997) (xy 26.121613 -406.274848)
			(xy 26.085919 -406.316038) (xy 26.044727 -406.351729) (xy 25.998875 -406.381195) (xy 25.949296 -406.403836)
			(xy 25.896999 -406.41919) (xy 25.84305 -406.426946) (xy 25.815798 -406.427432) (xy 25.785674 -406.426868)
			(xy 25.726177 -406.417386) (xy 25.668909 -406.398674) (xy 25.615292 -406.371196) (xy 25.566658 -406.335636)
			(xy 25.545034 -406.314656) (xy 25.537582 -406.30789) (xy 25.519018 -406.300173) (xy 25.508966 -406.29967)
			(xy 25.43683 -406.29967) (xy 25.42676 -406.300092) (xy 25.408161 -406.307813) (xy 25.400762 -406.314656)
			(xy 25.379126 -406.335624) (xy 25.330501 -406.371196) (xy 25.276887 -406.398679) (xy 25.219619 -406.41739)
			(xy 25.160122 -406.426863) (xy 25.129998 -406.427432) (xy 25.1037 -406.426988) (xy 25.051602 -406.419769)
			(xy 25.000992 -406.405455) (xy 24.952831 -406.384318) (xy 24.908034 -406.356759) (xy 24.867451 -406.323303)
			(xy 24.849328 -406.304242) (xy 24.849074 -406.303988) (xy 24.841958 -406.297068) (xy 24.823912 -406.288845)
			(xy 24.814022 -406.287986) (xy 24.741632 -406.285192) (xy 24.731552 -406.28525) (xy 24.712692 -406.292327)
			(xy 24.705056 -406.298908) (xy 24.683722 -406.31817) (xy 24.636363 -406.35074) (xy 24.584653 -406.375835)
			(xy 24.529763 -406.392887) (xy 24.472937 -406.401511) (xy 24.444198 -406.402032) (xy 24.414074 -406.401468)
			(xy 24.354577 -406.391986) (xy 24.297309 -406.373274) (xy 24.243692 -406.345796) (xy 24.195058 -406.310236)
			(xy 24.173434 -406.289256) (xy 24.165982 -406.28249) (xy 24.147418 -406.274773) (xy 24.137366 -406.27427)
			(xy 24.06523 -406.27427) (xy 24.05516 -406.274692) (xy 24.036561 -406.282413) (xy 24.029162 -406.289256)
			(xy 24.007526 -406.310224) (xy 23.958901 -406.345796) (xy 23.905287 -406.373279) (xy 23.848019 -406.39199)
			(xy 23.788522 -406.401463) (xy 23.758398 -406.402032) (xy 23.730987 -406.401592) (xy 23.676728 -406.393743)
			(xy 23.624152 -406.378209) (xy 23.574342 -406.355307) (xy 23.528323 -406.325511) (xy 23.487043 -406.289434)
			(xy 23.468838 -406.268936) (xy 23.461258 -406.260922) (xy 23.441247 -406.251701) (xy 23.43023 -406.251156)
			(xy 23.353268 -406.251156) (xy 23.342244 -406.251659) (xy 23.322227 -406.260901) (xy 23.31466 -406.268936)
			(xy 23.296441 -406.28946) (xy 23.255134 -406.325592) (xy 23.209079 -406.355436) (xy 23.159225 -406.378377)
			(xy 23.106598 -406.393941) (xy 23.052286 -406.401807) (xy 23.024846 -406.402286) (xy 22.997593 -406.401802)
			(xy 22.943642 -406.394051) (xy 22.891343 -406.378699) (xy 22.841762 -406.35606) (xy 22.795907 -406.326595)
			(xy 22.754714 -406.290903) (xy 22.719019 -406.249712) (xy 22.689551 -406.203859) (xy 22.666909 -406.154279)
			(xy 22.651555 -406.101982) (xy 22.6438 -406.048031) (xy 22.643338 -406.020778) (xy 20.954746 -406.020778)
			(xy 22.732238 -407.79827) (xy 22.739634 -407.805115) (xy 22.758236 -407.812833) (xy 22.768306 -407.813256)
			(xy 32.435292 -407.813256) (xy 32.463273 -407.813772) (xy 32.518544 -407.822546) (xy 32.571761 -407.839863)
			(xy 32.621611 -407.865296) (xy 32.666865 -407.898218) (xy 32.687006 -407.91765) (xy 32.938212 -408.168856)
			(xy 32.94634 -408.172666) (xy 32.970548 -408.18457) (xy 33.015619 -408.214214) (xy 33.056067 -408.249908)
			(xy 33.091087 -408.290942) (xy 33.119979 -408.336497) (xy 33.14217 -408.385667) (xy 33.157217 -408.437472)
			(xy 33.164819 -408.490879) (xy 33.165288 -408.517852) (xy 33.1648 -408.545105) (xy 33.157049 -408.599056)
			(xy 33.141698 -408.651354) (xy 33.11906 -408.700936) (xy 33.089595 -408.74679) (xy 33.053903 -408.787984)
			(xy 33.012712 -408.823678) (xy 32.96686 -408.853146) (xy 32.917281 -408.875788) (xy 32.864983 -408.891143)
			(xy 32.811033 -408.898898) (xy 32.78378 -408.89936) (xy 32.756806 -408.898894) (xy 32.703395 -408.891305)
			(xy 32.651586 -408.876266) (xy 32.602413 -408.854077) (xy 32.556856 -408.825182) (xy 32.515825 -408.790156)
			(xy 32.480139 -408.749698) (xy 32.450508 -408.704617) (xy 32.438594 -408.680412) (xy 32.434784 -408.672284)
			(xy 32.302704 -408.540204) (xy 32.295253 -408.533473) (xy 32.27667 -408.525906) (xy 32.266636 -408.525472)
			(xy 22.59965 -408.525472) (xy 22.57167 -408.524921) (xy 22.516401 -408.516154) (xy 22.463185 -408.498845)
			(xy 22.413335 -408.47342) (xy 22.368078 -408.440506) (xy 22.347936 -408.421078) (xy 20.32381 -406.396952)
			(xy 20.304432 -406.376767) (xy 20.271532 -406.331511) (xy 20.246108 -406.28167) (xy 20.228785 -406.228468)
			(xy 20.21999 -406.173213) (xy 20.219416 -406.145238) (xy 20.219416 -404.826724) (xy 20.216622 -404.818342)
			(xy 20.206108 -404.787123) (xy 20.194733 -404.722244) (xy 20.194016 -404.68931) (xy 19.076416 -404.68931)
			(xy 19.076416 -406.13711) (xy 19.076832 -406.14718) (xy 19.084559 -406.165778) (xy 19.091402 -406.173178)
			(xy 20.572984 -407.65476) (xy 20.590259 -407.672839) (xy 20.618066 -407.714389) (xy 20.637234 -407.760566)
			(xy 20.647027 -407.809594) (xy 20.64766 -407.834592) (xy 20.64766 -409.421584) (xy 21.165564 -409.421584)
			(xy 21.169635 -409.365962) (xy 21.181761 -409.311525) (xy 21.201684 -409.259434) (xy 21.22898 -409.210799)
			(xy 21.263066 -409.166656) (xy 21.303215 -409.127947) (xy 21.348573 -409.095496) (xy 21.398173 -409.069995)
			(xy 21.450957 -409.051988) (xy 21.5058 -409.041858) (xy 21.561534 -409.039821) (xy 21.616971 -409.045921)
			(xy 21.670928 -409.060027) (xy 21.722257 -409.081839) (xy 21.769863 -409.110893) (xy 21.812731 -409.146568)
			(xy 21.849948 -409.188105) (xy 21.880721 -409.234618) (xy 21.904393 -409.285115) (xy 21.920461 -409.338522)
			(xy 21.928581 -409.393698) (xy 21.92909 -409.421584) (xy 21.928581 -409.44947) (xy 21.920461 -409.504646)
			(xy 21.904393 -409.558053) (xy 21.880721 -409.60855) (xy 21.849948 -409.655063) (xy 21.812731 -409.6966)
			(xy 21.769863 -409.732275) (xy 21.722257 -409.761329) (xy 21.670928 -409.783141) (xy 21.616971 -409.797247)
			(xy 21.561534 -409.803347) (xy 21.5058 -409.80131) (xy 21.450957 -409.79118) (xy 21.398173 -409.773173)
			(xy 21.348573 -409.747672) (xy 21.303215 -409.715221) (xy 21.263066 -409.676512) (xy 21.22898 -409.632369)
			(xy 21.201684 -409.583734) (xy 21.181761 -409.531643) (xy 21.169635 -409.477206) (xy 21.165564 -409.421584)
			(xy 20.64766 -409.421584) (xy 20.64766 -411.34284) (xy 30.531052 -411.34284) (xy 30.535123 -411.287218)
			(xy 30.547249 -411.232781) (xy 30.567172 -411.18069) (xy 30.594468 -411.132055) (xy 30.628554 -411.087912)
			(xy 30.668703 -411.049203) (xy 30.714061 -411.016752) (xy 30.763661 -410.991251) (xy 30.816445 -410.973244)
			(xy 30.871288 -410.963114) (xy 30.927022 -410.961077) (xy 30.982459 -410.967177) (xy 31.036416 -410.981283)
			(xy 31.087745 -411.003095) (xy 31.135351 -411.032149) (xy 31.178219 -411.067824) (xy 31.215436 -411.109361)
			(xy 31.246209 -411.155874) (xy 31.269881 -411.206371) (xy 31.285949 -411.259778) (xy 31.294069 -411.314954)
			(xy 31.294578 -411.34284) (xy 31.294069 -411.370726) (xy 31.285949 -411.425902) (xy 31.269881 -411.479309)
			(xy 31.246209 -411.529806) (xy 31.215436 -411.576319) (xy 31.178219 -411.617856) (xy 31.135351 -411.653531)
			(xy 31.087745 -411.682585) (xy 31.036416 -411.704397) (xy 30.982459 -411.718503) (xy 30.927022 -411.724603)
			(xy 30.871288 -411.722566) (xy 30.816445 -411.712436) (xy 30.763661 -411.694429) (xy 30.714061 -411.668928)
			(xy 30.668703 -411.636477) (xy 30.628554 -411.597768) (xy 30.594468 -411.553625) (xy 30.567172 -411.50499)
			(xy 30.547249 -411.452899) (xy 30.535123 -411.398462) (xy 30.531052 -411.34284) (xy 20.64766 -411.34284)
			(xy 20.64766 -411.928564) (xy 29.502352 -411.928564) (xy 29.506423 -411.872942) (xy 29.518549 -411.818505)
			(xy 29.538472 -411.766414) (xy 29.565768 -411.717779) (xy 29.599854 -411.673636) (xy 29.640003 -411.634927)
			(xy 29.685361 -411.602476) (xy 29.734961 -411.576975) (xy 29.787745 -411.558968) (xy 29.842588 -411.548838)
			(xy 29.898322 -411.546801) (xy 29.953759 -411.552901) (xy 30.007716 -411.567007) (xy 30.059045 -411.588819)
			(xy 30.106651 -411.617873) (xy 30.149519 -411.653548) (xy 30.186736 -411.695085) (xy 30.217509 -411.741598)
			(xy 30.241181 -411.792095) (xy 30.257249 -411.845502) (xy 30.265369 -411.900678) (xy 30.265878 -411.928564)
			(xy 30.265369 -411.95645) (xy 30.257249 -412.011626) (xy 30.241181 -412.065033) (xy 30.217509 -412.11553)
			(xy 30.186736 -412.162043) (xy 30.149519 -412.20358) (xy 30.106651 -412.239255) (xy 30.059045 -412.268309)
			(xy 30.007716 -412.290121) (xy 29.953759 -412.304227) (xy 29.898322 -412.310327) (xy 29.842588 -412.30829)
			(xy 29.787745 -412.29816) (xy 29.734961 -412.280153) (xy 29.685361 -412.254652) (xy 29.640003 -412.222201)
			(xy 29.599854 -412.183492) (xy 29.565768 -412.139349) (xy 29.538472 -412.090714) (xy 29.518549 -412.038623)
			(xy 29.506423 -411.984186) (xy 29.502352 -411.928564) (xy 20.64766 -411.928564) (xy 20.64766 -412.633414)
			(xy 28.730954 -412.633414) (xy 28.735025 -412.577792) (xy 28.747151 -412.523355) (xy 28.767074 -412.471264)
			(xy 28.79437 -412.422629) (xy 28.828456 -412.378486) (xy 28.868605 -412.339777) (xy 28.913963 -412.307326)
			(xy 28.963563 -412.281825) (xy 29.016347 -412.263818) (xy 29.07119 -412.253688) (xy 29.126924 -412.251651)
			(xy 29.182361 -412.257751) (xy 29.236318 -412.271857) (xy 29.287647 -412.293669) (xy 29.335253 -412.322723)
			(xy 29.378121 -412.358398) (xy 29.415338 -412.399935) (xy 29.446111 -412.446448) (xy 29.469783 -412.496945)
			(xy 29.485851 -412.550352) (xy 29.493971 -412.605528) (xy 29.49448 -412.633414) (xy 29.493971 -412.6613)
			(xy 29.485851 -412.716476) (xy 29.469783 -412.769883) (xy 29.446111 -412.82038) (xy 29.415338 -412.866893)
			(xy 29.378121 -412.90843) (xy 29.335253 -412.944105) (xy 29.287647 -412.973159) (xy 29.236318 -412.994971)
			(xy 29.182361 -413.009077) (xy 29.126924 -413.015177) (xy 29.07119 -413.01314) (xy 29.016347 -413.00301)
			(xy 28.963563 -412.985003) (xy 28.913963 -412.959502) (xy 28.868605 -412.927051) (xy 28.828456 -412.888342)
			(xy 28.79437 -412.844199) (xy 28.767074 -412.795564) (xy 28.747151 -412.743473) (xy 28.735025 -412.689036)
			(xy 28.730954 -412.633414) (xy 20.64766 -412.633414) (xy 20.64766 -413.764476) (xy 20.647014 -413.789472)
			(xy 20.637214 -413.838494) (xy 20.618043 -413.884665) (xy 20.590238 -413.926211) (xy 20.572984 -413.944308)
			(xy 19.420332 -415.09696) (xy 19.402253 -415.114235) (xy 19.360703 -415.142043) (xy 19.314527 -415.161212)
			(xy 19.265498 -415.171004) (xy 19.2405 -415.171636) (xy 16.646652 -415.171636) (xy 16.636606 -415.171997)
			(xy 16.618009 -415.179591) (xy 16.610584 -415.186368) (xy 16.445195 -415.351976) (xy 29.832806 -415.351976)
			(xy 29.836877 -415.296354) (xy 29.849003 -415.241917) (xy 29.868926 -415.189826) (xy 29.896222 -415.141191)
			(xy 29.930308 -415.097048) (xy 29.970457 -415.058339) (xy 30.015815 -415.025888) (xy 30.065415 -415.000387)
			(xy 30.118199 -414.98238) (xy 30.173042 -414.97225) (xy 30.228776 -414.970213) (xy 30.284213 -414.976313)
			(xy 30.33817 -414.990419) (xy 30.389499 -415.012231) (xy 30.437105 -415.041285) (xy 30.479973 -415.07696)
			(xy 30.51719 -415.118497) (xy 30.547963 -415.16501) (xy 30.571635 -415.215507) (xy 30.587703 -415.268914)
			(xy 30.595823 -415.32409) (xy 30.596332 -415.351976) (xy 30.595823 -415.379862) (xy 30.587703 -415.435038)
			(xy 30.571635 -415.488445) (xy 30.547963 -415.538942) (xy 30.51719 -415.585455) (xy 30.479973 -415.626992)
			(xy 30.437105 -415.662667) (xy 30.389499 -415.691721) (xy 30.33817 -415.713533) (xy 30.284213 -415.727639)
			(xy 30.228776 -415.733739) (xy 30.173042 -415.731702) (xy 30.118199 -415.721572) (xy 30.065415 -415.703565)
			(xy 30.015815 -415.678064) (xy 29.970457 -415.645613) (xy 29.930308 -415.606904) (xy 29.896222 -415.562761)
			(xy 29.868926 -415.514126) (xy 29.849003 -415.462035) (xy 29.836877 -415.407598) (xy 29.832806 -415.351976)
			(xy 16.445195 -415.351976) (xy 16.418814 -415.378392) (xy 16.411359 -415.385118) (xy 16.392779 -415.392688)
			(xy 16.382746 -415.393124) (xy 14.9225 -415.393124) (xy 14.912428 -415.392719) (xy 14.893829 -415.384986)
			(xy 14.886432 -415.378138) (xy 13.840714 -414.33242) (xy 13.808456 -414.32734) (xy 13.793724 -414.334706)
			(xy 13.767087 -414.347423) (xy 13.710864 -414.365397) (xy 13.652548 -414.374518) (xy 13.623036 -414.375092)
			(xy 13.622782 -414.375092) (xy 13.59553 -414.374639) (xy 13.54158 -414.36688) (xy 13.489284 -414.351521)
			(xy 13.439705 -414.328877) (xy 13.393854 -414.299407) (xy 13.352664 -414.263712) (xy 13.316972 -414.222519)
			(xy 13.287507 -414.176665) (xy 13.264867 -414.127085) (xy 13.249513 -414.074787) (xy 13.241759 -414.020836)
			(xy 13.241274 -413.993584) (xy 13.241274 -413.99333) (xy 13.241813 -413.963815) (xy 13.250921 -413.905492)
			(xy 13.268924 -413.849274) (xy 13.28166 -413.822642) (xy 13.289026 -413.80791) (xy 13.283946 -413.775652)
			(xy 12.761214 -413.253174) (xy 12.754372 -413.245775) (xy 12.746653 -413.227175) (xy 12.746228 -413.217106)
			(xy 12.746228 -412.907226) (xy 12.745466 -412.906464) (xy 12.7381 -412.888176) (xy 12.7381 -408.74823)
			(xy 12.737685 -408.738159) (xy 12.72996 -408.71956) (xy 12.723114 -408.712162) (xy 11.438382 -407.427684)
			(xy 11.43154 -407.420285) (xy 11.423822 -407.401685) (xy 11.423396 -407.391616) (xy 8.748522 -407.391616)
			(xy 8.748522 -407.825956) (xy 8.749538 -407.835862) (xy 8.812364 -408.151584) (xy 10.700764 -408.151584)
			(xy 10.704835 -408.095962) (xy 10.716961 -408.041525) (xy 10.736884 -407.989434) (xy 10.76418 -407.940799)
			(xy 10.798266 -407.896656) (xy 10.838415 -407.857947) (xy 10.883773 -407.825496) (xy 10.933373 -407.799995)
			(xy 10.986157 -407.781988) (xy 11.041 -407.771858) (xy 11.096734 -407.769821) (xy 11.152171 -407.775921)
			(xy 11.206128 -407.790027) (xy 11.257457 -407.811839) (xy 11.305063 -407.840893) (xy 11.347931 -407.876568)
			(xy 11.385148 -407.918105) (xy 11.415921 -407.964618) (xy 11.439593 -408.015115) (xy 11.455661 -408.068522)
			(xy 11.463781 -408.123698) (xy 11.46429 -408.151584) (xy 11.463781 -408.17947) (xy 11.455661 -408.234646)
			(xy 11.439593 -408.288053) (xy 11.415921 -408.33855) (xy 11.385148 -408.385063) (xy 11.347931 -408.4266)
			(xy 11.305063 -408.462275) (xy 11.257457 -408.491329) (xy 11.206128 -408.513141) (xy 11.152171 -408.527247)
			(xy 11.096734 -408.533347) (xy 11.041 -408.53131) (xy 10.986157 -408.52118) (xy 10.933373 -408.503173)
			(xy 10.883773 -408.477672) (xy 10.838415 -408.445221) (xy 10.798266 -408.406512) (xy 10.76418 -408.362369)
			(xy 10.736884 -408.313734) (xy 10.716961 -408.261643) (xy 10.704835 -408.207206) (xy 10.700764 -408.151584)
			(xy 8.812364 -408.151584) (xy 8.919718 -408.69108) (xy 8.932418 -408.690826) (xy 8.959669 -408.691291)
			(xy 9.013616 -408.69905) (xy 9.06591 -408.714408) (xy 9.115486 -408.737052) (xy 9.161334 -408.766521)
			(xy 9.202522 -408.802215) (xy 9.23821 -408.843408) (xy 9.267673 -408.88926) (xy 9.29031 -408.938839)
			(xy 9.305661 -408.991135) (xy 9.313413 -409.045083) (xy 9.313926 -409.072334) (xy 9.313417 -409.100529)
			(xy 9.305114 -409.156305) (xy 9.288694 -409.210252) (xy 9.264514 -409.261195) (xy 9.2331 -409.308025)
			(xy 9.195138 -409.349723) (xy 9.151452 -409.38538) (xy 9.12749 -409.400248) (xy 9.119875 -409.4052)
			(xy 9.108479 -409.419328) (xy 9.102729 -409.436545) (xy 9.103347 -409.454686) (xy 9.106408 -409.46324)
			(xy 9.239504 -409.784804) (xy 9.302578 -409.937023) (xy 10.777937 -409.937023) (xy 10.777937 -409.882517)
			(xy 10.785694 -409.828566) (xy 10.80105 -409.776269) (xy 10.823693 -409.726689) (xy 10.853161 -409.680836)
			(xy 10.888855 -409.639643) (xy 10.930047 -409.60395) (xy 10.9759 -409.574482) (xy 11.025481 -409.55184)
			(xy 11.077778 -409.536484) (xy 11.131729 -409.528727) (xy 11.158982 -409.528264) (xy 11.186427 -409.528721)
			(xy 11.24075 -409.536598) (xy 11.293379 -409.552193) (xy 11.343224 -409.575181) (xy 11.3665 -409.589732)
			(xy 11.37867 -409.597011) (xy 11.40576 -409.605338) (xy 11.434095 -409.605891) (xy 11.461489 -409.598628)
			(xy 11.485829 -409.584109) (xy 11.505235 -409.563455) (xy 11.51821 -409.538259) (xy 11.52144 -409.524454)
			(xy 11.527693 -409.496008) (xy 11.54769 -409.441309) (xy 11.575765 -409.390283) (xy 11.611268 -409.344116)
			(xy 11.653373 -409.303879) (xy 11.701103 -409.270507) (xy 11.753349 -409.244774) (xy 11.808899 -409.227279)
			(xy 11.866462 -409.218427) (xy 11.895582 -409.217876) (xy 11.922835 -409.21837) (xy 11.976785 -409.226125)
			(xy 12.029083 -409.241478) (xy 12.078663 -409.264119) (xy 12.124517 -409.293585) (xy 12.16571 -409.329277)
			(xy 12.201404 -409.370469) (xy 12.230872 -409.416321) (xy 12.253515 -409.4659) (xy 12.268872 -409.518197)
			(xy 12.276629 -409.572147) (xy 12.276629 -409.626653) (xy 12.268872 -409.680603) (xy 12.253515 -409.7329)
			(xy 12.230872 -409.782479) (xy 12.201404 -409.828331) (xy 12.16571 -409.869523) (xy 12.124517 -409.905215)
			(xy 12.078663 -409.934681) (xy 12.029083 -409.957322) (xy 11.976785 -409.972675) (xy 11.922835 -409.98043)
			(xy 11.895582 -409.980892) (xy 11.868137 -409.980412) (xy 11.813815 -409.972542) (xy 11.761186 -409.956955)
			(xy 11.71134 -409.933973) (xy 11.688064 -409.919424) (xy 11.675937 -409.912065) (xy 11.648831 -409.903736)
			(xy 11.62048 -409.903187) (xy 11.593073 -409.910461) (xy 11.568725 -409.924997) (xy 11.549317 -409.945671)
			(xy 11.536348 -409.970887) (xy 11.533124 -409.984702) (xy 11.526851 -410.013142) (xy 11.506851 -410.067836)
			(xy 11.478775 -410.118858) (xy 11.443273 -410.165022) (xy 11.401171 -410.205257) (xy 11.353445 -410.23863)
			(xy 11.301204 -410.264365) (xy 11.245659 -410.281865) (xy 11.1881 -410.290725) (xy 11.158982 -410.29128)
			(xy 11.131729 -410.290813) (xy 11.077778 -410.283056) (xy 11.025481 -410.2677) (xy 10.9759 -410.245058)
			(xy 10.930047 -410.21559) (xy 10.888855 -410.179897) (xy 10.853161 -410.138704) (xy 10.823693 -410.092851)
			(xy 10.80105 -410.043271) (xy 10.785694 -409.990974) (xy 10.777937 -409.937023) (xy 9.302578 -409.937023)
			(xy 9.601454 -410.65831) (xy 9.603459 -410.662875) (xy 9.608954 -410.671194) (xy 9.612376 -410.67482)
			(xy 10.123424 -411.185868) (xy 10.130836 -411.192552) (xy 10.149269 -411.200149) (xy 10.169207 -411.200149)
			(xy 10.18764 -411.192552) (xy 10.195052 -411.185868) (xy 10.195306 -411.185614) (xy 10.216954 -411.164504)
			(xy 10.265682 -411.12871) (xy 10.319445 -411.101047) (xy 10.376897 -411.082207) (xy 10.436601 -411.072663)
			(xy 10.466832 -411.072076) (xy 10.494082 -411.072564) (xy 10.548027 -411.080324) (xy 10.600319 -411.095682)
			(xy 10.649893 -411.118325) (xy 10.695741 -411.147791) (xy 10.736929 -411.183483) (xy 10.772618 -411.224672)
			(xy 10.802083 -411.270521) (xy 10.824724 -411.320096) (xy 10.840079 -411.372388) (xy 10.847837 -411.426334)
			(xy 10.84834 -411.453584) (xy 10.847764 -411.483816) (xy 10.838227 -411.543525) (xy 10.81939 -411.60098)
			(xy 10.791724 -411.654745) (xy 10.755923 -411.703472) (xy 10.734802 -411.72511) (xy 10.734548 -411.725364)
			(xy 10.727858 -411.732775) (xy 10.72025 -411.751212) (xy 10.720244 -411.771157) (xy 10.727841 -411.789599)
			(xy 10.734548 -411.796992) (xy 11.259312 -412.321756) (xy 11.266159 -412.329153) (xy 11.273887 -412.347753)
			(xy 11.274298 -412.357824) (xy 11.274298 -412.64713) (xy 11.274727 -412.657198) (xy 11.282449 -412.675794)
			(xy 11.289284 -412.683198) (xy 11.551158 -412.945326) (xy 11.573833 -412.968638) (xy 11.614392 -413.019475)
			(xy 11.649009 -413.074532) (xy 11.677247 -413.133116) (xy 11.698753 -413.194492) (xy 11.713256 -413.257889)
			(xy 11.720574 -413.322511) (xy 11.721084 -413.355028) (xy 11.721084 -414.230058) (xy 11.721517 -414.240124)
			(xy 11.729245 -414.258715) (xy 11.73607 -414.266126) (xy 12.840462 -415.370772) (xy 12.863139 -415.394083)
			(xy 12.903703 -415.444919) (xy 12.938324 -415.499975) (xy 12.966568 -415.558559) (xy 12.988079 -415.619935)
			(xy 13.002588 -415.683333) (xy 13.009912 -415.747956) (xy 13.010388 -415.780474) (xy 13.010388 -415.823471)
			(xy 18.86304 -415.823471) (xy 18.86304 -415.768969) (xy 18.870796 -415.715022) (xy 18.886151 -415.662728)
			(xy 18.908792 -415.613151) (xy 18.938257 -415.567301) (xy 18.973948 -415.526111) (xy 19.015138 -415.49042)
			(xy 19.060988 -415.460954) (xy 19.110564 -415.438312) (xy 19.162858 -415.422957) (xy 19.216805 -415.4152)
			(xy 19.244056 -415.414714) (xy 19.270419 -415.415193) (xy 19.32264 -415.422472) (xy 19.373363 -415.43687)
			(xy 19.42162 -415.458113) (xy 19.466494 -415.485797) (xy 19.50713 -415.519394) (xy 19.542755 -415.558265)
			(xy 19.572689 -415.60167) (xy 19.584924 -415.625026) (xy 19.591646 -415.637388) (xy 19.610658 -415.658118)
			(xy 19.634603 -415.672877) (xy 19.661665 -415.680548) (xy 19.689793 -415.680548) (xy 19.716855 -415.672877)
			(xy 19.7408 -415.658118) (xy 19.759812 -415.637388) (xy 19.766534 -415.625026) (xy 19.778775 -415.601643)
			(xy 19.808708 -415.558174) (xy 19.844346 -415.519244) (xy 19.885007 -415.485596) (xy 19.929918 -415.457872)
			(xy 19.97822 -415.4366) (xy 20.028993 -415.422188) (xy 20.081267 -415.414909) (xy 20.107656 -415.41446)
			(xy 20.134909 -415.414927) (xy 20.18886 -415.422684) (xy 20.241158 -415.438039) (xy 20.290738 -415.460681)
			(xy 20.336592 -415.490149) (xy 20.377785 -415.525842) (xy 20.413479 -415.567035) (xy 20.442947 -415.612888)
			(xy 20.465589 -415.662468) (xy 20.480946 -415.714766) (xy 20.488703 -415.768717) (xy 20.488703 -415.823223)
			(xy 20.480946 -415.877174) (xy 20.465589 -415.929472) (xy 20.442947 -415.979052) (xy 20.413479 -416.024905)
			(xy 20.377785 -416.066098) (xy 20.336592 -416.101791) (xy 20.290738 -416.131259) (xy 20.241158 -416.153901)
			(xy 20.18886 -416.169256) (xy 20.134909 -416.177013) (xy 20.107656 -416.177476) (xy 20.081293 -416.176993)
			(xy 20.029072 -416.169715) (xy 19.978349 -416.155318) (xy 19.930092 -416.134076) (xy 19.885218 -416.106393)
			(xy 19.844581 -416.072796) (xy 19.808957 -416.033925) (xy 19.779022 -415.99052) (xy 19.766788 -415.967164)
			(xy 19.760097 -415.954762) (xy 19.741114 -415.933951) (xy 19.717161 -415.919127) (xy 19.690067 -415.911421)
			(xy 19.661899 -415.911421) (xy 19.634805 -415.919127) (xy 19.610852 -415.933951) (xy 19.591869 -415.954762)
			(xy 19.585178 -415.967164) (xy 19.572923 -415.99054) (xy 19.542993 -416.034009) (xy 19.507357 -416.07294)
			(xy 19.466698 -416.106588) (xy 19.421789 -416.134314) (xy 19.373489 -416.155586) (xy 19.322718 -416.17)
			(xy 19.270445 -416.17728) (xy 19.244056 -416.17773) (xy 19.216805 -416.17724) (xy 19.162858 -416.169483)
			(xy 19.110564 -416.154128) (xy 19.060988 -416.131486) (xy 19.015138 -416.10202) (xy 18.973948 -416.066329)
			(xy 18.938257 -416.025139) (xy 18.908792 -415.979289) (xy 18.886151 -415.929712) (xy 18.870796 -415.877418)
			(xy 18.86304 -415.823471) (xy 13.010388 -415.823471) (xy 13.010388 -416.080194) (xy 13.01081 -416.090265)
			(xy 13.018521 -416.108872) (xy 13.025374 -416.116262) (xy 13.58392 -416.675062) (xy 13.618464 -416.67938)
			(xy 13.633704 -416.670236) (xy 13.65604 -416.657339) (xy 13.703442 -416.637013) (xy 13.75315 -416.623255)
			(xy 13.804258 -416.616316) (xy 13.830046 -416.61588) (xy 13.858358 -416.616392) (xy 13.914359 -416.624755)
			(xy 13.96851 -416.641305) (xy 14.019618 -416.665679) (xy 14.066562 -416.697341) (xy 14.108308 -416.735595)
			(xy 14.143941 -416.7796) (xy 14.172677 -416.828389) (xy 14.193884 -416.880891) (xy 14.207096 -416.935951)
			(xy 14.21003 -416.964114) (xy 14.211808 -416.983672) (xy 14.240764 -417.010342)
		)
		(stroke
			(width 0)
			(type solid)
		)
		(fill yes)
		(layer "In15.Cu")
		(net "GND")
	)
	(gr_poly
		(pts
			(xy 95.348298 -398.35328) (xy 95.358368 -398.352857) (xy 95.376971 -398.345141) (xy 95.384366 -398.338294)
			(xy 98.963734 -394.758926) (xy 98.970576 -394.751527) (xy 98.978294 -394.732928) (xy 98.97872 -394.722858)
			(xy 98.97872 -393.879578) (xy 98.96094 -393.85367) (xy 98.945954 -393.848082) (xy 98.929056 -393.841457)
			(xy 98.896487 -393.825429) (xy 98.88093 -393.816078) (xy 98.868992 -393.808712) (xy 98.841814 -393.808204)
			(xy 98.73996 -393.8651) (xy 98.726244 -393.888722) (xy 98.72599 -393.902692) (xy 98.725481 -393.930093)
			(xy 98.717644 -393.984332) (xy 98.702172 -394.036905) (xy 98.679378 -394.086742) (xy 98.649728 -394.13283)
			(xy 98.613822 -394.174232) (xy 98.572393 -394.210105) (xy 98.526282 -394.23972) (xy 98.476427 -394.262475)
			(xy 98.423842 -394.277907) (xy 98.369597 -394.285702) (xy 98.342196 -394.286232) (xy 98.314775 -394.285743)
			(xy 98.260492 -394.277941) (xy 98.207871 -394.262496) (xy 98.157982 -394.239722) (xy 98.11184 -394.210083)
			(xy 98.070384 -394.174181) (xy 98.034457 -394.132747) (xy 98.00479 -394.086623) (xy 97.981986 -394.036748)
			(xy 97.966509 -393.984137) (xy 97.958674 -393.929858) (xy 97.958148 -393.902438) (xy 97.958676 -393.874156)
			(xy 97.967019 -393.81821) (xy 97.983472 -393.76409) (xy 98.00768 -393.712967) (xy 98.039119 -393.665943)
			(xy 98.057716 -393.644628) (xy 98.063678 -393.637477) (xy 98.070435 -393.620145) (xy 98.070924 -393.610846)
			(xy 98.071178 -393.579604) (xy 98.070859 -393.570251) (xy 98.064193 -393.552777) (xy 98.058224 -393.545568)
			(xy 98.04031 -393.524529) (xy 98.010106 -393.478259) (xy 97.986893 -393.428116) (xy 97.971155 -393.375149)
			(xy 97.963222 -393.320466) (xy 97.96272 -393.292838) (xy 97.96272 -392.429238) (xy 97.963142 -392.402887)
			(xy 97.970353 -392.350683) (xy 97.984686 -392.299969) (xy 98.005866 -392.251712) (xy 98.033491 -392.206833)
			(xy 98.067033 -392.166185) (xy 98.086164 -392.14806) (xy 98.093276 -392.14171) (xy 98.101404 -392.124946)
			(xy 98.109786 -392.038332) (xy 98.104706 -392.020552) (xy 98.099118 -392.012678) (xy 98.084958 -391.992834)
			(xy 98.062467 -391.949587) (xy 98.047145 -391.903311) (xy 98.039385 -391.855187) (xy 98.03892 -391.830814)
			(xy 98.039442 -391.805559) (xy 98.047755 -391.755737) (xy 98.064156 -391.707963) (xy 98.088197 -391.66354)
			(xy 98.119221 -391.62368) (xy 98.156383 -391.58947) (xy 98.198669 -391.561844) (xy 98.244925 -391.541554)
			(xy 98.29389 -391.529154) (xy 98.344228 -391.524983) (xy 98.394566 -391.529154) (xy 98.443531 -391.541554)
			(xy 98.489787 -391.561844) (xy 98.532073 -391.58947) (xy 98.569235 -391.62368) (xy 98.600259 -391.66354)
			(xy 98.6243 -391.707963) (xy 98.640701 -391.755737) (xy 98.649014 -391.805559) (xy 98.649536 -391.830814)
			(xy 98.649038 -391.855184) (xy 98.641258 -391.903299) (xy 98.625945 -391.949572) (xy 98.603487 -391.99283)
			(xy 98.589338 -392.012678) (xy 98.58375 -392.020552) (xy 98.57867 -392.038332) (xy 98.587052 -392.124946)
			(xy 98.59518 -392.14171) (xy 98.602292 -392.14806) (xy 98.62139 -392.166214) (xy 98.654913 -392.206867)
			(xy 98.682525 -392.251745) (xy 98.703703 -392.299994) (xy 98.718042 -392.350698) (xy 98.725271 -392.402892)
			(xy 98.725736 -392.429238) (xy 98.725736 -393.079986) (xy 98.726142 -393.088986) (xy 98.732457 -393.105846)
			(xy 98.744208 -393.119487) (xy 98.751898 -393.124182) (xy 98.841306 -393.17422) (xy 98.868992 -393.173712)
			(xy 98.880676 -393.166346) (xy 98.896296 -393.156989) (xy 98.92899 -393.140958) (xy 98.945954 -393.134342)
			(xy 98.96094 -393.128754) (xy 98.97872 -393.102846) (xy 98.97872 -390.311132) (xy 98.973894 -390.300718)
			(xy 98.963943 -390.27861) (xy 98.94991 -390.232204) (xy 98.942825 -390.184243) (xy 98.942398 -390.160002)
			(xy 98.942869 -390.135766) (xy 98.949982 -390.087817) (xy 98.963998 -390.041415) (xy 98.973894 -390.019286)
			(xy 98.97872 -390.008872) (xy 98.97872 -389.853424) (xy 98.978081 -389.840868) (xy 98.966221 -389.818736)
			(xy 98.956114 -389.81126) (xy 98.875596 -389.757158) (xy 98.85045 -389.754618) (xy 98.838766 -389.759444)
			(xy 98.81007 -389.770355) (xy 98.749825 -389.782116) (xy 98.719132 -389.782812) (xy 98.693737 -389.782307)
			(xy 98.643601 -389.77418) (xy 98.595412 -389.758132) (xy 98.550415 -389.734577) (xy 98.509768 -389.704121)
			(xy 98.474523 -389.667551) (xy 98.445586 -389.625809) (xy 98.423705 -389.579974) (xy 98.41611 -389.555736)
			(xy 98.414586 -389.549894) (xy 98.094292 -388.996174) (xy 98.090228 -388.991856) (xy 98.074011 -388.974158)
			(xy 98.046579 -388.934769) (xy 98.025433 -388.891678) (xy 98.011062 -388.845879) (xy 98.003798 -388.798432)
			(xy 98.00336 -388.774432) (xy 98.003518 -388.76238) (xy 98.005427 -388.738352) (xy 98.00717 -388.726426)
			(xy 98.00844 -388.717536) (xy 98.005392 -388.700518) (xy 97.963228 -388.629652) (xy 97.95002 -388.618476)
			(xy 97.941638 -388.615428) (xy 97.928476 -388.610495) (xy 97.903034 -388.59854) (xy 97.890838 -388.591552)
			(xy 97.884996 -388.587996) (xy 97.872042 -388.58444) (xy 97.458022 -388.58444) (xy 97.448001 -388.584856)
			(xy 97.429483 -388.592524) (xy 97.415314 -388.606698) (xy 97.407653 -388.625219) (xy 97.407222 -388.63524)
			(xy 97.407222 -388.645146) (xy 97.411032 -388.654544) (xy 97.422462 -388.686802) (xy 97.423986 -388.692644)
			(xy 97.743772 -389.245602) (xy 97.747836 -389.24992) (xy 97.764051 -389.267619) (xy 97.791481 -389.307009)
			(xy 97.812626 -389.3501) (xy 97.826997 -389.395898) (xy 97.834263 -389.443344) (xy 97.834704 -389.467344)
			(xy 97.834239 -389.492147) (xy 97.826469 -389.541141) (xy 97.811128 -389.588315) (xy 97.788594 -389.632508)
			(xy 97.759422 -389.67263) (xy 97.72433 -389.707692) (xy 97.684184 -389.736831) (xy 97.639973 -389.759328)
			(xy 97.592786 -389.77463) (xy 97.543785 -389.782359) (xy 97.518982 -389.782812) (xy 97.493589 -389.782303)
			(xy 97.443459 -389.77417) (xy 97.395276 -389.758117) (xy 97.350286 -389.734558) (xy 97.309646 -389.704101)
			(xy 97.274406 -389.667531) (xy 97.245475 -389.625791) (xy 97.223599 -389.579958) (xy 97.21596 -389.555736)
			(xy 97.214436 -389.549894) (xy 96.893888 -388.995412) (xy 96.889824 -388.991094) (xy 96.87372 -388.973425)
			(xy 96.846482 -388.93414) (xy 96.825472 -388.891199) (xy 96.811171 -388.845583) (xy 96.803905 -388.798334)
			(xy 96.803464 -388.774432) (xy 96.803622 -388.76238) (xy 96.805531 -388.738352) (xy 96.807274 -388.726426)
			(xy 96.808544 -388.717536) (xy 96.805496 -388.700518) (xy 96.763332 -388.629652) (xy 96.750124 -388.618476)
			(xy 96.741742 -388.615428) (xy 96.72858 -388.610495) (xy 96.703138 -388.59854) (xy 96.690942 -388.591552)
			(xy 96.6851 -388.587996) (xy 96.672146 -388.58444) (xy 96.257872 -388.58444) (xy 96.247857 -388.584865)
			(xy 96.229357 -388.592541) (xy 96.215203 -388.606714) (xy 96.207552 -388.625225) (xy 96.207072 -388.63524)
			(xy 96.207072 -388.645146) (xy 96.210882 -388.654544) (xy 96.222058 -388.68604) (xy 96.223582 -388.691882)
			(xy 96.543876 -389.245602) (xy 96.54794 -389.24992) (xy 96.564155 -389.267619) (xy 96.591584 -389.307009)
			(xy 96.612729 -389.3501) (xy 96.6271 -389.395898) (xy 96.634366 -389.443344) (xy 96.634808 -389.467344)
			(xy 96.634343 -389.492147) (xy 96.626573 -389.541141) (xy 96.611232 -389.588316) (xy 96.588698 -389.632509)
			(xy 96.559526 -389.672631) (xy 96.524434 -389.707694) (xy 96.484289 -389.736833) (xy 96.440077 -389.759331)
			(xy 96.39289 -389.774633) (xy 96.34389 -389.782363) (xy 96.319086 -389.782812) (xy 96.293693 -389.782303)
			(xy 96.243562 -389.774171) (xy 96.195379 -389.758118) (xy 96.150388 -389.73456) (xy 96.109748 -389.704103)
			(xy 96.074508 -389.667533) (xy 96.045576 -389.625793) (xy 96.0237 -389.57996) (xy 96.016064 -389.555736)
			(xy 96.01454 -389.549894) (xy 95.694246 -388.996174) (xy 95.690182 -388.991856) (xy 95.673994 -388.974146)
			(xy 95.64662 -388.934743) (xy 95.625532 -388.891648) (xy 95.611216 -388.845855) (xy 95.604003 -388.798422)
			(xy 95.603568 -388.774432) (xy 95.603654 -388.762384) (xy 95.605437 -388.738355) (xy 95.607124 -388.726426)
			(xy 95.608394 -388.717536) (xy 95.605346 -388.700518) (xy 95.563182 -388.629652) (xy 95.549974 -388.618476)
			(xy 95.541592 -388.615428) (xy 95.519851 -388.607023) (xy 95.479005 -388.584571) (xy 95.442046 -388.556172)
			(xy 95.409832 -388.522486) (xy 95.383112 -388.484295) (xy 95.362507 -388.442488) (xy 95.348495 -388.398034)
			(xy 95.341402 -388.351967) (xy 95.340932 -388.328662) (xy 95.341025 -388.318406) (xy 95.342426 -388.297942)
			(xy 95.343726 -388.287768) (xy 95.34525 -388.276084) (xy 95.33763 -388.253478) (xy 94.903036 -387.818884)
			(xy 94.894034 -387.810841) (xy 94.871101 -387.803416) (xy 94.859094 -387.80466) (xy 94.765876 -387.819392)
			(xy 94.746318 -387.833362) (xy 94.74073 -387.844284) (xy 94.730096 -387.864298) (xy 94.70417 -387.901471)
			(xy 94.67341 -387.934754) (xy 94.656148 -387.94944) (xy 94.647258 -387.956552) (xy 94.63786 -387.97611)
			(xy 94.635066 -388.075424) (xy 94.643702 -388.09549) (xy 94.652084 -388.10311) (xy 94.670507 -388.120597)
			(xy 94.70185 -388.160565) (xy 94.726148 -388.205167) (xy 94.742731 -388.253176) (xy 94.751142 -388.303266)
			(xy 94.751652 -388.328662) (xy 94.75158 -388.33802) (xy 94.750434 -388.356702) (xy 94.749366 -388.366)
			(xy 94.74835 -388.37489) (xy 94.75216 -388.391654) (xy 94.796102 -388.461504) (xy 94.809818 -388.471918)
			(xy 94.8182 -388.474712) (xy 94.842296 -388.483195) (xy 94.887582 -388.506826) (xy 94.928474 -388.537439)
			(xy 94.963905 -388.574235) (xy 94.99295 -388.616255) (xy 95.014853 -388.662402) (xy 95.022416 -388.686802)
			(xy 95.02394 -388.692644) (xy 95.343726 -389.245602) (xy 95.34779 -389.24992) (xy 95.363981 -389.267628)
			(xy 95.39136 -389.30703) (xy 95.412453 -389.350125) (xy 95.426774 -389.395919) (xy 95.433991 -389.443353)
			(xy 95.434404 -389.467344) (xy 95.433915 -389.492132) (xy 95.426154 -389.541098) (xy 95.410829 -389.588247)
			(xy 95.388319 -389.632419) (xy 95.359177 -389.672526) (xy 95.32412 -389.707582) (xy 95.284012 -389.736723)
			(xy 95.23984 -389.759232) (xy 95.19269 -389.774556) (xy 95.143724 -389.782315) (xy 95.118936 -389.782812)
			(xy 95.093541 -389.782307) (xy 95.043404 -389.774181) (xy 94.995215 -389.758134) (xy 94.950217 -389.734578)
			(xy 94.90957 -389.704122) (xy 94.874324 -389.667552) (xy 94.845387 -389.625811) (xy 94.823506 -389.579975)
			(xy 94.815914 -389.555736) (xy 94.81439 -389.549894) (xy 94.493842 -388.995412) (xy 94.489778 -388.991094)
			(xy 94.473698 -388.973416) (xy 94.44651 -388.934119) (xy 94.425551 -388.891174) (xy 94.4113 -388.845563)
			(xy 94.404082 -388.798325) (xy 94.403672 -388.774432) (xy 94.403758 -388.762384) (xy 94.405541 -388.738355)
			(xy 94.407228 -388.726426) (xy 94.408498 -388.717536) (xy 94.40545 -388.700518) (xy 94.363286 -388.629652)
			(xy 94.350078 -388.618476) (xy 94.341696 -388.615428) (xy 94.319955 -388.607023) (xy 94.279108 -388.584572)
			(xy 94.242149 -388.556173) (xy 94.209935 -388.522487) (xy 94.183214 -388.484296) (xy 94.162609 -388.442488)
			(xy 94.148597 -388.398034) (xy 94.141503 -388.351967) (xy 94.141036 -388.328662) (xy 94.141536 -388.303264)
			(xy 94.149936 -388.253169) (xy 94.166516 -388.205155) (xy 94.190816 -388.16055) (xy 94.222166 -388.120584)
			(xy 94.240604 -388.10311) (xy 94.248986 -388.09549) (xy 94.257622 -388.075424) (xy 94.254828 -387.97611)
			(xy 94.24543 -387.956552) (xy 94.23654 -387.94944) (xy 94.217977 -387.933639) (xy 94.185246 -387.897514)
			(xy 94.15817 -387.856977) (xy 94.137335 -387.812907) (xy 94.123191 -387.766257) (xy 94.116044 -387.718036)
			(xy 94.115636 -387.693662) (xy 94.116075 -387.669546) (xy 94.123081 -387.621826) (xy 94.13694 -387.575629)
			(xy 94.157357 -387.531932) (xy 94.170246 -387.511544) (xy 94.176088 -387.502654) (xy 94.179644 -387.482588)
			(xy 94.158562 -387.390386) (xy 94.14637 -387.373622) (xy 94.13748 -387.368288) (xy 94.116676 -387.355434)
			(xy 94.078756 -387.324557) (xy 94.045803 -387.288427) (xy 94.018537 -387.247833) (xy 93.997553 -387.203663)
			(xy 93.983311 -387.156882) (xy 93.976121 -387.108513) (xy 93.975682 -387.084062) (xy 93.97645 -387.052132)
			(xy 93.98873 -386.989462) (xy 94.000066 -386.959602) (xy 94.005654 -386.945378) (xy 93.999812 -386.91566)
			(xy 93.963744 -386.879592) (xy 93.956342 -386.872755) (xy 93.937744 -386.865042) (xy 93.927676 -386.864606)
			(xy 92.453206 -386.864606) (xy 92.441789 -386.865068) (xy 92.421167 -386.874856) (xy 92.413582 -386.883402)
			(xy 92.356686 -386.954014) (xy 92.351352 -386.976366) (xy 92.353892 -386.987542) (xy 92.35869 -387.011382)
			(xy 92.363777 -387.059746) (xy 92.364052 -387.084062) (xy 92.363448 -387.117382) (xy 92.353778 -387.183316)
			(xy 92.334652 -387.247153) (xy 92.321126 -387.27761) (xy 92.316866 -387.28808) (xy 92.316941 -387.310654)
			(xy 92.32669 -387.331015) (xy 92.335096 -387.33857) (xy 92.357345 -387.357243) (xy 92.397411 -387.399298)
			(xy 92.431836 -387.446083) (xy 92.460065 -387.496848) (xy 92.481644 -387.550776) (xy 92.496228 -387.607001)
			(xy 92.503581 -387.664619) (xy 92.504006 -387.693662) (xy 92.503555 -387.722666) (xy 92.496225 -387.780209)
			(xy 92.481688 -387.836366) (xy 92.460178 -387.890239) (xy 92.43204 -387.940965) (xy 92.397722 -387.987733)
			(xy 92.357775 -388.029795) (xy 92.335604 -388.0485) (xy 92.328492 -388.054088) (xy 92.319348 -388.069328)
			(xy 92.304108 -388.152132) (xy 92.306902 -388.169404) (xy 92.311474 -388.177532) (xy 92.324069 -388.20071)
			(xy 92.341957 -388.250331) (xy 92.35104 -388.302289) (xy 92.351606 -388.328662) (xy 92.940886 -388.328662)
			(xy 92.941408 -388.303407) (xy 92.949721 -388.253585) (xy 92.966122 -388.205811) (xy 92.990163 -388.161388)
			(xy 93.021187 -388.121528) (xy 93.058349 -388.087318) (xy 93.100635 -388.059692) (xy 93.146891 -388.039402)
			(xy 93.195856 -388.027002) (xy 93.246194 -388.022831) (xy 93.296532 -388.027002) (xy 93.345497 -388.039402)
			(xy 93.391753 -388.059692) (xy 93.434039 -388.087318) (xy 93.471201 -388.121528) (xy 93.502225 -388.161388)
			(xy 93.526266 -388.205811) (xy 93.542667 -388.253585) (xy 93.55098 -388.303407) (xy 93.551502 -388.328662)
			(xy 93.551434 -388.338021) (xy 93.55029 -388.356703) (xy 93.549216 -388.366) (xy 93.5482 -388.37489)
			(xy 93.55201 -388.391654) (xy 93.595952 -388.461504) (xy 93.609668 -388.471918) (xy 93.61805 -388.474712)
			(xy 93.64208 -388.483174) (xy 93.687252 -388.506729) (xy 93.728057 -388.537229) (xy 93.763436 -388.573885)
			(xy 93.792471 -388.615746) (xy 93.814409 -388.661724) (xy 93.822012 -388.68604) (xy 93.823536 -388.691882)
			(xy 94.14383 -389.245602) (xy 94.147894 -389.24992) (xy 94.164098 -389.267615) (xy 94.191458 -389.307029)
			(xy 94.212539 -389.350128) (xy 94.226856 -389.395922) (xy 94.23408 -389.443354) (xy 94.234508 -389.467344)
			(xy 94.234023 -389.492133) (xy 94.226262 -389.541099) (xy 94.210937 -389.588249) (xy 94.188427 -389.632422)
			(xy 94.159284 -389.67253) (xy 94.124227 -389.707587) (xy 94.084119 -389.736729) (xy 94.039946 -389.759239)
			(xy 93.992795 -389.774562) (xy 93.943829 -389.782323) (xy 93.91904 -389.782812) (xy 93.893647 -389.782276)
			(xy 93.843515 -389.774152) (xy 93.79533 -389.758106) (xy 93.750336 -389.734553) (xy 93.709693 -389.704101)
			(xy 93.674449 -389.667534) (xy 93.645514 -389.625796) (xy 93.623635 -389.579965) (xy 93.616018 -389.555736)
			(xy 93.614494 -389.549894) (xy 93.2942 -388.996174) (xy 93.290136 -388.991856) (xy 93.273922 -388.974157)
			(xy 93.246502 -388.934763) (xy 93.225362 -388.891671) (xy 93.21099 -388.845875) (xy 93.203718 -388.798431)
			(xy 93.203268 -388.774432) (xy 93.20341 -388.76238) (xy 93.205316 -388.73835) (xy 93.207078 -388.726426)
			(xy 93.208348 -388.717536) (xy 93.2053 -388.700518) (xy 93.163136 -388.629652) (xy 93.149928 -388.618476)
			(xy 93.141546 -388.615428) (xy 93.119793 -388.607046) (xy 93.078935 -388.584602) (xy 93.041966 -388.556206)
			(xy 93.009744 -388.522518) (xy 92.983019 -388.484323) (xy 92.962414 -388.442508) (xy 92.948407 -388.398045)
			(xy 92.941324 -388.35197) (xy 92.940886 -388.328662) (xy 92.351606 -388.328662) (xy 92.351534 -388.33802)
			(xy 92.350388 -388.356702) (xy 92.34932 -388.366) (xy 92.348304 -388.37489) (xy 92.352114 -388.391654)
			(xy 92.396056 -388.461504) (xy 92.409772 -388.471918) (xy 92.418154 -388.474712) (xy 92.442187 -388.483168)
			(xy 92.487364 -388.506718) (xy 92.528171 -388.537217) (xy 92.563551 -388.573875) (xy 92.592583 -388.615739)
			(xy 92.614515 -388.661723) (xy 92.622116 -388.68604) (xy 92.62364 -388.691882) (xy 92.943934 -389.245602)
			(xy 92.947998 -389.24992) (xy 92.964188 -389.267629) (xy 92.991567 -389.307031) (xy 93.012659 -389.350126)
			(xy 93.02698 -389.395919) (xy 93.034197 -389.443353) (xy 93.034612 -389.467344) (xy 93.034123 -389.492133)
			(xy 93.026362 -389.541099) (xy 93.011038 -389.588248) (xy 92.988527 -389.632421) (xy 92.959385 -389.672529)
			(xy 92.924329 -389.707585) (xy 92.884221 -389.736727) (xy 92.840048 -389.759238) (xy 92.792899 -389.774562)
			(xy 92.743933 -389.782323) (xy 92.719144 -389.782812) (xy 92.693748 -389.782308) (xy 92.643611 -389.774183)
			(xy 92.595421 -389.758136) (xy 92.550422 -389.734581) (xy 92.509774 -389.704126) (xy 92.474526 -389.667555)
			(xy 92.445588 -389.625814) (xy 92.423707 -389.579977) (xy 92.416122 -389.555736) (xy 92.414598 -389.549894)
			(xy 92.094304 -388.996174) (xy 92.09024 -388.991856) (xy 92.074023 -388.974158) (xy 92.04659 -388.93477)
			(xy 92.025443 -388.891678) (xy 92.011071 -388.84588) (xy 92.003807 -388.798432) (xy 92.003372 -388.774432)
			(xy 92.00353 -388.76238) (xy 92.005439 -388.738352) (xy 92.007182 -388.726426) (xy 92.008452 -388.717536)
			(xy 92.005404 -388.700518) (xy 91.96324 -388.629652) (xy 91.950032 -388.618476) (xy 91.94165 -388.615428)
			(xy 91.91874 -388.606542) (xy 91.875878 -388.582519) (xy 91.837418 -388.55194) (xy 91.804353 -388.515595)
			(xy 91.79052 -388.495286) (xy 91.78417 -388.485634) (xy 91.764612 -388.473696) (xy 91.674696 -388.464298)
			(xy 91.663344 -388.463768) (xy 91.641972 -388.471405) (xy 91.633548 -388.47903) (xy 91.562682 -388.549896)
			(xy 91.555283 -388.55674) (xy 91.536685 -388.564468) (xy 91.526614 -388.564882) (xy 91.449144 -388.564882)
			(xy 91.439116 -388.565294) (xy 91.420581 -388.572955) (xy 91.40639 -388.587128) (xy 91.398706 -388.605654)
			(xy 91.398344 -388.615682) (xy 91.398344 -388.627366) (xy 91.403424 -388.63778) (xy 91.408915 -388.649499)
			(xy 91.418199 -388.673659) (xy 91.421966 -388.68604) (xy 91.42349 -388.691882) (xy 91.743784 -389.245602)
			(xy 91.747848 -389.24992) (xy 91.764067 -389.267617) (xy 91.791504 -389.307005) (xy 91.812655 -389.350096)
			(xy 91.827031 -389.395894) (xy 91.834299 -389.443343) (xy 91.834716 -389.467344) (xy 91.834251 -389.492147)
			(xy 91.826481 -389.541142) (xy 91.81114 -389.588317) (xy 91.788606 -389.632511) (xy 91.759434 -389.672633)
			(xy 91.724343 -389.707697) (xy 91.684197 -389.736837) (xy 91.639986 -389.759336) (xy 91.592799 -389.77464)
			(xy 91.543798 -389.78237) (xy 91.518994 -389.782812) (xy 91.493601 -389.782304) (xy 91.443469 -389.774173)
			(xy 91.395285 -389.758121) (xy 91.350292 -389.734563) (xy 91.309651 -389.704106) (xy 91.27441 -389.667536)
			(xy 91.245478 -389.625796) (xy 91.223601 -389.579962) (xy 91.215972 -389.555736) (xy 91.214448 -389.549894)
			(xy 90.894154 -388.996174) (xy 90.89009 -388.991856) (xy 90.873901 -388.974147) (xy 90.846527 -388.934744)
			(xy 90.825439 -388.891648) (xy 90.811122 -388.845855) (xy 90.803909 -388.798422) (xy 90.803476 -388.774432)
			(xy 90.803562 -388.762384) (xy 90.805345 -388.738355) (xy 90.807032 -388.726426) (xy 90.808302 -388.717536)
			(xy 90.805254 -388.700518) (xy 90.76309 -388.629652) (xy 90.749882 -388.618476) (xy 90.7415 -388.615428)
			(xy 90.721322 -388.607668) (xy 90.683201 -388.587276) (xy 90.665554 -388.574788) (xy 90.658856 -388.570204)
			(xy 90.64344 -388.56516) (xy 90.635328 -388.564882) (xy 90.249248 -388.564882) (xy 90.239219 -388.565293)
			(xy 90.220683 -388.572954) (xy 90.206491 -388.587127) (xy 90.198806 -388.605654) (xy 90.198448 -388.615682)
			(xy 90.198448 -388.627366) (xy 90.203528 -388.63778) (xy 90.209019 -388.649499) (xy 90.218303 -388.673659)
			(xy 90.22207 -388.68604) (xy 90.223594 -388.691882) (xy 90.543888 -389.245602) (xy 90.547952 -389.24992)
			(xy 90.564171 -389.267617) (xy 90.591608 -389.307005) (xy 90.612758 -389.350096) (xy 90.627134 -389.395895)
			(xy 90.634402 -389.443343) (xy 90.63482 -389.467344) (xy 90.634355 -389.492145) (xy 90.626584 -389.541134)
			(xy 90.611242 -389.588303) (xy 90.588707 -389.632489) (xy 90.559533 -389.672604) (xy 90.52444 -389.707658)
			(xy 90.484294 -389.736788) (xy 90.440083 -389.759275) (xy 90.392897 -389.774565) (xy 90.343899 -389.782282)
			(xy 90.319098 -389.782812) (xy 90.293704 -389.782304) (xy 90.243572 -389.774173) (xy 90.195388 -389.758122)
			(xy 90.150395 -389.734564) (xy 90.109753 -389.704107) (xy 90.074512 -389.667537) (xy 90.045579 -389.625797)
			(xy 90.023701 -389.579963) (xy 90.016076 -389.555736) (xy 90.014552 -389.549894) (xy 89.694258 -388.996174)
			(xy 89.690194 -388.991856) (xy 89.674005 -388.974147) (xy 89.646631 -388.934744) (xy 89.625542 -388.891648)
			(xy 89.611225 -388.845855) (xy 89.604012 -388.798422) (xy 89.60358 -388.774432) (xy 89.603666 -388.762384)
			(xy 89.605449 -388.738355) (xy 89.607136 -388.726426) (xy 89.608406 -388.717536) (xy 89.605358 -388.700518)
			(xy 89.563194 -388.629652) (xy 89.549986 -388.618476) (xy 89.541604 -388.615428) (xy 89.521425 -388.607668)
			(xy 89.483305 -388.587277) (xy 89.465658 -388.574788) (xy 89.458961 -388.570203) (xy 89.443544 -388.565158)
			(xy 89.435432 -388.564882) (xy 89.049352 -388.564882) (xy 89.039349 -388.565378) (xy 89.020871 -388.573045)
			(xy 89.006728 -388.587196) (xy 88.999072 -388.605679) (xy 88.998552 -388.615682) (xy 88.998552 -388.627366)
			(xy 89.003632 -388.63778) (xy 89.009224 -388.649675) (xy 89.018636 -388.674217) (xy 89.022428 -388.686802)
			(xy 89.023952 -388.692644) (xy 89.343738 -389.245602) (xy 89.347802 -389.24992) (xy 89.363992 -389.267629)
			(xy 89.39137 -389.307031) (xy 89.412463 -389.350126) (xy 89.426783 -389.395919) (xy 89.434 -389.443353)
			(xy 89.434416 -389.467344) (xy 89.433927 -389.492133) (xy 89.426166 -389.541099) (xy 89.410842 -389.588249)
			(xy 89.388332 -389.632422) (xy 89.35919 -389.67253) (xy 89.324133 -389.707587) (xy 89.284025 -389.736729)
			(xy 89.239853 -389.75924) (xy 89.192703 -389.774565) (xy 89.143737 -389.782326) (xy 89.118948 -389.782812)
			(xy 89.093552 -389.782308) (xy 89.043414 -389.774184) (xy 88.995224 -389.758137) (xy 88.950224 -389.734583)
			(xy 88.909576 -389.704127) (xy 88.874328 -389.667557) (xy 88.845389 -389.625815) (xy 88.823507 -389.579979)
			(xy 88.815926 -389.555736) (xy 88.814402 -389.549894) (xy 88.493854 -388.995412) (xy 88.48979 -388.991094)
			(xy 88.47371 -388.973416) (xy 88.44652 -388.934119) (xy 88.42556 -388.891175) (xy 88.411309 -388.845563)
			(xy 88.404091 -388.798325) (xy 88.403684 -388.774432) (xy 88.40377 -388.762384) (xy 88.405553 -388.738355)
			(xy 88.40724 -388.726426) (xy 88.40851 -388.717536) (xy 88.405462 -388.700518) (xy 88.363298 -388.629652)
			(xy 88.35009 -388.618476) (xy 88.341708 -388.615428) (xy 88.321533 -388.607663) (xy 88.283419 -388.587262)
			(xy 88.265762 -388.574788) (xy 88.259065 -388.570203) (xy 88.243648 -388.565156) (xy 88.235536 -388.564882)
			(xy 87.849202 -388.564882) (xy 87.839193 -388.565369) (xy 87.820697 -388.573028) (xy 87.806539 -388.58718)
			(xy 87.798873 -388.605673) (xy 87.798402 -388.615682) (xy 87.798402 -388.627366) (xy 87.803482 -388.63778)
			(xy 87.808972 -388.649499) (xy 87.818255 -388.673659) (xy 87.822024 -388.68604) (xy 87.823548 -388.691882)
			(xy 88.143842 -389.245602) (xy 88.147906 -389.24992) (xy 88.164096 -389.267629) (xy 88.191474 -389.307031)
			(xy 88.212566 -389.350126) (xy 88.226886 -389.395919) (xy 88.234103 -389.443354) (xy 88.23452 -389.467344)
			(xy 88.234056 -389.492132) (xy 88.226293 -389.541097) (xy 88.210967 -389.588244) (xy 88.188453 -389.632413)
			(xy 88.159308 -389.672517) (xy 88.124247 -389.707567) (xy 88.084135 -389.736702) (xy 88.039959 -389.759202)
			(xy 87.992807 -389.774515) (xy 87.94384 -389.782263) (xy 87.919052 -389.782812) (xy 87.89366 -389.782301)
			(xy 87.843533 -389.774164) (xy 87.795355 -389.758108) (xy 87.750368 -389.734547) (xy 87.709733 -389.704089)
			(xy 87.674497 -389.667519) (xy 87.645569 -389.62578) (xy 87.623696 -389.579949) (xy 87.61603 -389.555736)
			(xy 87.614506 -389.549894) (xy 87.294212 -388.996174) (xy 87.290148 -388.991856) (xy 87.27393 -388.974158)
			(xy 87.246497 -388.93477) (xy 87.225349 -388.891679) (xy 87.210977 -388.84588) (xy 87.203713 -388.798432)
			(xy 87.20328 -388.774432) (xy 87.203438 -388.76238) (xy 87.205347 -388.738352) (xy 87.20709 -388.726426)
			(xy 87.20836 -388.717536) (xy 87.205312 -388.700518) (xy 87.163148 -388.629652) (xy 87.14994 -388.618476)
			(xy 87.141558 -388.615428) (xy 87.121381 -388.607665) (xy 87.083263 -388.58727) (xy 87.065612 -388.574788)
			(xy 87.058916 -388.570196) (xy 87.0435 -388.565134) (xy 87.035386 -388.564882) (xy 86.649306 -388.564882)
			(xy 86.639296 -388.565369) (xy 86.620799 -388.573026) (xy 86.60664 -388.587179) (xy 86.598973 -388.605672)
			(xy 86.598506 -388.615682) (xy 86.598506 -388.627366) (xy 86.603586 -388.63778) (xy 86.609076 -388.649499)
			(xy 86.618359 -388.673659) (xy 86.622128 -388.68604) (xy 86.623652 -388.691882) (xy 86.943946 -389.245602)
			(xy 86.94801 -389.24992) (xy 86.9642 -389.267629) (xy 86.991577 -389.307031) (xy 87.012669 -389.350127)
			(xy 87.026989 -389.39592) (xy 87.034206 -389.443354) (xy 87.034624 -389.467344) (xy 87.034134 -389.49213)
			(xy 87.026373 -389.541091) (xy 87.011047 -389.588235) (xy 86.988536 -389.632401) (xy 86.959392 -389.672502)
			(xy 86.924335 -389.70755) (xy 86.884226 -389.736682) (xy 86.840053 -389.759181) (xy 86.792905 -389.774493)
			(xy 86.743942 -389.782241) (xy 86.719156 -389.782812) (xy 86.693764 -389.782301) (xy 86.643637 -389.774165)
			(xy 86.595458 -389.758109) (xy 86.55047 -389.734549) (xy 86.509834 -389.704091) (xy 86.474598 -389.667521)
			(xy 86.44567 -389.625782) (xy 86.423796 -389.579951) (xy 86.416134 -389.555736) (xy 86.41461 -389.549894)
			(xy 86.094316 -388.996174) (xy 86.090252 -388.991856) (xy 86.074034 -388.974159) (xy 86.0466 -388.93477)
			(xy 86.025453 -388.891679) (xy 86.01108 -388.84588) (xy 86.003816 -388.798432) (xy 86.003384 -388.774432)
			(xy 86.003542 -388.76238) (xy 86.005451 -388.738352) (xy 86.007194 -388.726426) (xy 86.008464 -388.717536)
			(xy 86.005416 -388.700518) (xy 85.963252 -388.629652) (xy 85.950044 -388.618476) (xy 85.941662 -388.615428)
			(xy 85.919923 -388.607022) (xy 85.87908 -388.584567) (xy 85.842125 -388.556167) (xy 85.809914 -388.52248)
			(xy 85.783197 -388.48429) (xy 85.762594 -388.442483) (xy 85.748584 -388.398031) (xy 85.741492 -388.351966)
			(xy 85.741002 -388.328662) (xy 85.741505 -388.303653) (xy 85.749656 -388.254305) (xy 85.765735 -388.206942)
			(xy 85.77707 -388.184644) (xy 85.784944 -388.169658) (xy 85.780118 -388.136638) (xy 85.656674 -388.013194)
			(xy 85.649821 -388.005799) (xy 85.642077 -387.9872) (xy 85.641688 -387.977126) (xy 85.641688 -387.91388)
			(xy 85.639148 -387.902704) (xy 85.636354 -387.89737) (xy 85.621285 -387.86555) (xy 85.600005 -387.798439)
			(xy 85.589234 -387.728864) (xy 85.588602 -387.693662) (xy 85.589224 -387.658458) (xy 85.599969 -387.588875)
			(xy 85.621262 -387.521765) (xy 85.636354 -387.489954) (xy 85.638816 -387.484628) (xy 85.64151 -387.473212)
			(xy 85.641688 -387.467348) (xy 85.641688 -387.457442) (xy 85.616536 -387.438963) (xy 85.570995 -387.396287)
			(xy 85.531673 -387.347821) (xy 85.499299 -387.294462) (xy 85.474472 -387.237201) (xy 85.457653 -387.177098)
			(xy 85.449154 -387.115268) (xy 85.448648 -387.084062) (xy 85.449093 -387.055137) (xy 85.456387 -386.997748)
			(xy 85.470854 -386.941735) (xy 85.492263 -386.887992) (xy 85.520272 -386.837374) (xy 85.554437 -386.790689)
			(xy 85.594211 -386.748681) (xy 85.616288 -386.729986) (xy 85.623357 -386.723718) (xy 85.632633 -386.707276)
			(xy 85.634322 -386.697982) (xy 85.63864 -386.666994) (xy 85.639588 -386.657756) (xy 85.635556 -386.639643)
			(xy 85.630766 -386.631688) (xy 85.617731 -386.611291) (xy 85.597128 -386.567489) (xy 85.58314 -386.52115)
			(xy 85.576065 -386.473264) (xy 85.575648 -386.449062) (xy 85.575902 -386.43687) (xy 85.576156 -386.427218)
			(xy 85.57006 -386.409184) (xy 85.511386 -386.341874) (xy 85.494622 -386.333238) (xy 85.484716 -386.332222)
			(xy 85.4578 -386.328875) (xy 85.405493 -386.314537) (xy 85.356228 -386.291853) (xy 85.311327 -386.261432)
			(xy 85.271993 -386.22409) (xy 85.239282 -386.180829) (xy 85.214071 -386.132808) (xy 85.197036 -386.081317)
			(xy 85.192362 -386.0546) (xy 85.190838 -386.045202) (xy 84.918042 -385.57327) (xy 84.910676 -385.567428)
			(xy 84.8919 -385.551623) (xy 84.858773 -385.515414) (xy 84.831358 -385.474708) (xy 84.810257 -385.430399)
			(xy 84.795933 -385.383459) (xy 84.788701 -385.334919) (xy 84.788248 -385.31038) (xy 84.788759 -385.284393)
			(xy 84.796892 -385.233058) (xy 84.812954 -385.183627) (xy 84.83655 -385.137317) (xy 84.8671 -385.095268)
			(xy 84.90385 -385.058515) (xy 84.945897 -385.027963) (xy 84.992205 -385.004363) (xy 85.041635 -384.988297)
			(xy 85.092969 -384.980161) (xy 85.118956 -384.979672) (xy 85.144969 -384.980154) (xy 85.196354 -384.988295)
			(xy 85.245829 -385.004383) (xy 85.292175 -385.028021) (xy 85.334247 -385.058626) (xy 85.371006 -385.095442)
			(xy 85.401546 -385.137561) (xy 85.425112 -385.183943) (xy 85.441124 -385.233443) (xy 85.4456 -385.259072)
			(xy 85.447124 -385.26847) (xy 85.660738 -385.63804) (xy 85.666804 -385.647392) (xy 85.685055 -385.660147)
			(xy 85.706987 -385.663994) (xy 85.717888 -385.661662) (xy 85.734652 -385.65709) (xy 85.75548 -385.629912)
			(xy 85.75548 -384.870706) (xy 85.755097 -384.861511) (xy 85.74859 -384.844314) (xy 85.74278 -384.837178)
			(xy 85.725456 -384.816881) (xy 85.696913 -384.771795) (xy 85.675978 -384.722712) (xy 85.663196 -384.670904)
			(xy 85.658896 -384.617716) (xy 85.66319 -384.564528) (xy 85.675968 -384.51272) (xy 85.696897 -384.463634)
			(xy 85.725436 -384.418546) (xy 85.74278 -384.398266) (xy 85.748563 -384.391112) (xy 85.755092 -384.373928)
			(xy 85.75548 -384.364738) (xy 85.75548 -383.746502) (xy 85.755057 -383.736432) (xy 85.747341 -383.717829)
			(xy 85.740494 -383.710434) (xy 85.478366 -383.448306) (xy 85.470966 -383.441464) (xy 85.452368 -383.433741)
			(xy 85.442298 -383.43332) (xy 77.029564 -383.43332) (xy 77.021022 -383.433653) (xy 77.004892 -383.439289)
			(xy 76.991518 -383.44992) (xy 76.986638 -383.456942) (xy 76.933806 -383.541016) (xy 76.932282 -383.56667)
			(xy 76.93787 -383.578608) (xy 76.94964 -383.604433) (xy 76.966266 -383.658696) (xy 76.974672 -383.714824)
			(xy 76.975208 -383.7432) (xy 76.974722 -383.770451) (xy 76.966966 -383.824399) (xy 76.951611 -383.876694)
			(xy 76.928969 -383.926271) (xy 76.899503 -383.972121) (xy 76.863812 -384.013312) (xy 76.822621 -384.049003)
			(xy 76.776771 -384.078469) (xy 76.727194 -384.101111) (xy 76.674899 -384.116466) (xy 76.620951 -384.124222)
			(xy 76.566449 -384.124222) (xy 76.512501 -384.116466) (xy 76.460206 -384.101111) (xy 76.410629 -384.078469)
			(xy 76.364779 -384.049003) (xy 76.323588 -384.013312) (xy 76.287897 -383.972121) (xy 76.258431 -383.926271)
			(xy 76.235789 -383.876694) (xy 76.220434 -383.824399) (xy 76.212678 -383.770451) (xy 76.212192 -383.7432)
			(xy 76.212713 -383.714823) (xy 76.221123 -383.658695) (xy 76.237758 -383.604433) (xy 76.24953 -383.578608)
			(xy 76.255118 -383.56667) (xy 76.253594 -383.541016) (xy 76.200762 -383.456942) (xy 76.195913 -383.4499)
			(xy 76.182521 -383.439285) (xy 76.16638 -383.433675) (xy 76.157836 -383.43332) (xy 72.311768 -383.43332)
			(xy 72.283574 -383.457958) (xy 72.28078 -383.477008) (xy 72.275446 -383.507488) (xy 72.274094 -383.516334)
			(xy 72.276826 -383.534004) (xy 72.28078 -383.542032) (xy 72.295258 -383.568702) (xy 72.299932 -383.576402)
			(xy 72.313608 -383.588107) (xy 72.321928 -383.591562) (xy 72.350536 -383.602872) (xy 72.405023 -383.631436)
			(xy 72.45567 -383.666359) (xy 72.501737 -383.707132) (xy 72.542553 -383.753162) (xy 72.577523 -383.803776)
			(xy 72.606136 -383.858237) (xy 72.627975 -383.91575) (xy 72.642722 -383.975476) (xy 72.650162 -384.036544)
			(xy 72.650604 -384.067304) (xy 72.650125 -384.097999) (xy 72.642705 -384.15894) (xy 72.628008 -384.218546)
			(xy 72.606248 -384.275951) (xy 72.577742 -384.330322) (xy 72.560688 -384.355848) (xy 72.555218 -384.3646)
			(xy 72.551091 -384.384803) (xy 72.55522 -384.405006) (xy 72.560688 -384.41376) (xy 72.577745 -384.439287)
			(xy 72.606277 -384.493648) (xy 72.628052 -384.551052) (xy 72.64275 -384.610661) (xy 72.649075 -384.66268)
			(xy 76.211682 -384.66268) (xy 76.215753 -384.607058) (xy 76.227879 -384.552621) (xy 76.247802 -384.50053)
			(xy 76.275098 -384.451895) (xy 76.309184 -384.407752) (xy 76.349333 -384.369043) (xy 76.394691 -384.336592)
			(xy 76.444291 -384.311091) (xy 76.497075 -384.293084) (xy 76.551918 -384.282954) (xy 76.607652 -384.280917)
			(xy 76.663089 -384.287017) (xy 76.717046 -384.301123) (xy 76.768375 -384.322935) (xy 76.815981 -384.351989)
			(xy 76.853676 -384.383359) (xy 77.59878 -384.383359) (xy 77.59878 -384.331385) (xy 77.60691 -384.28005)
			(xy 77.622971 -384.23062) (xy 77.646567 -384.18431) (xy 77.677117 -384.142262) (xy 77.713868 -384.105511)
			(xy 77.755916 -384.074961) (xy 77.802226 -384.051365) (xy 77.851656 -384.035304) (xy 77.902991 -384.027174)
			(xy 77.954965 -384.027174) (xy 78.0063 -384.035304) (xy 78.05573 -384.051365) (xy 78.10204 -384.074961)
			(xy 78.144088 -384.105511) (xy 78.180839 -384.142262) (xy 78.211389 -384.18431) (xy 78.234985 -384.23062)
			(xy 78.251046 -384.28005) (xy 78.259176 -384.331385) (xy 78.259686 -384.357372) (xy 78.259176 -384.383359)
			(xy 78.251046 -384.434694) (xy 78.234985 -384.484124) (xy 78.211389 -384.530434) (xy 78.180839 -384.572482)
			(xy 78.144088 -384.609233) (xy 78.10204 -384.639783) (xy 78.094335 -384.643709) (xy 79.65999 -384.643709)
			(xy 79.65999 -384.591735) (xy 79.66812 -384.5404) (xy 79.684181 -384.49097) (xy 79.707777 -384.44466)
			(xy 79.738327 -384.402612) (xy 79.775078 -384.365861) (xy 79.817126 -384.335311) (xy 79.863436 -384.311715)
			(xy 79.912866 -384.295654) (xy 79.964201 -384.287524) (xy 80.016175 -384.287524) (xy 80.06751 -384.295654)
			(xy 80.11694 -384.311715) (xy 80.16325 -384.335311) (xy 80.205298 -384.365861) (xy 80.242049 -384.402612)
			(xy 80.272599 -384.44466) (xy 80.296195 -384.49097) (xy 80.312256 -384.5404) (xy 80.320386 -384.591735)
			(xy 80.320896 -384.617722) (xy 80.320386 -384.643709) (xy 80.859886 -384.643709) (xy 80.859886 -384.591735)
			(xy 80.868016 -384.5404) (xy 80.884077 -384.49097) (xy 80.907673 -384.44466) (xy 80.938223 -384.402612)
			(xy 80.974974 -384.365861) (xy 81.017022 -384.335311) (xy 81.063332 -384.311715) (xy 81.112762 -384.295654)
			(xy 81.164097 -384.287524) (xy 81.216071 -384.287524) (xy 81.267406 -384.295654) (xy 81.316836 -384.311715)
			(xy 81.363146 -384.335311) (xy 81.405194 -384.365861) (xy 81.441945 -384.402612) (xy 81.472495 -384.44466)
			(xy 81.496091 -384.49097) (xy 81.512152 -384.5404) (xy 81.520282 -384.591735) (xy 81.520792 -384.617722)
			(xy 81.520282 -384.643709) (xy 82.060036 -384.643709) (xy 82.060036 -384.591735) (xy 82.068166 -384.5404)
			(xy 82.084227 -384.49097) (xy 82.107823 -384.44466) (xy 82.138373 -384.402612) (xy 82.175124 -384.365861)
			(xy 82.217172 -384.335311) (xy 82.263482 -384.311715) (xy 82.312912 -384.295654) (xy 82.364247 -384.287524)
			(xy 82.416221 -384.287524) (xy 82.467556 -384.295654) (xy 82.516986 -384.311715) (xy 82.563296 -384.335311)
			(xy 82.605344 -384.365861) (xy 82.642095 -384.402612) (xy 82.672645 -384.44466) (xy 82.696241 -384.49097)
			(xy 82.712302 -384.5404) (xy 82.720432 -384.591735) (xy 82.720942 -384.617722) (xy 82.720432 -384.643709)
			(xy 83.259932 -384.643709) (xy 83.259932 -384.591735) (xy 83.268062 -384.5404) (xy 83.284123 -384.49097)
			(xy 83.307719 -384.44466) (xy 83.338269 -384.402612) (xy 83.37502 -384.365861) (xy 83.417068 -384.335311)
			(xy 83.463378 -384.311715) (xy 83.512808 -384.295654) (xy 83.564143 -384.287524) (xy 83.616117 -384.287524)
			(xy 83.667452 -384.295654) (xy 83.716882 -384.311715) (xy 83.763192 -384.335311) (xy 83.80524 -384.365861)
			(xy 83.841991 -384.402612) (xy 83.872541 -384.44466) (xy 83.896137 -384.49097) (xy 83.912198 -384.5404)
			(xy 83.920328 -384.591735) (xy 83.920838 -384.617722) (xy 83.920328 -384.643709) (xy 84.460082 -384.643709)
			(xy 84.460082 -384.591735) (xy 84.468212 -384.5404) (xy 84.484273 -384.49097) (xy 84.507869 -384.44466)
			(xy 84.538419 -384.402612) (xy 84.57517 -384.365861) (xy 84.617218 -384.335311) (xy 84.663528 -384.311715)
			(xy 84.712958 -384.295654) (xy 84.764293 -384.287524) (xy 84.816267 -384.287524) (xy 84.867602 -384.295654)
			(xy 84.917032 -384.311715) (xy 84.963342 -384.335311) (xy 85.00539 -384.365861) (xy 85.042141 -384.402612)
			(xy 85.072691 -384.44466) (xy 85.096287 -384.49097) (xy 85.112348 -384.5404) (xy 85.120478 -384.591735)
			(xy 85.120988 -384.617722) (xy 85.120478 -384.643709) (xy 85.112348 -384.695044) (xy 85.096287 -384.744474)
			(xy 85.072691 -384.790784) (xy 85.042141 -384.832832) (xy 85.00539 -384.869583) (xy 84.963342 -384.900133)
			(xy 84.917032 -384.923729) (xy 84.867602 -384.93979) (xy 84.816267 -384.94792) (xy 84.764293 -384.94792)
			(xy 84.712958 -384.93979) (xy 84.663528 -384.923729) (xy 84.617218 -384.900133) (xy 84.57517 -384.869583)
			(xy 84.538419 -384.832832) (xy 84.507869 -384.790784) (xy 84.484273 -384.744474) (xy 84.468212 -384.695044)
			(xy 84.460082 -384.643709) (xy 83.920328 -384.643709) (xy 83.912198 -384.695044) (xy 83.896137 -384.744474)
			(xy 83.872541 -384.790784) (xy 83.841991 -384.832832) (xy 83.80524 -384.869583) (xy 83.763192 -384.900133)
			(xy 83.716882 -384.923729) (xy 83.667452 -384.93979) (xy 83.616117 -384.94792) (xy 83.564143 -384.94792)
			(xy 83.512808 -384.93979) (xy 83.463378 -384.923729) (xy 83.417068 -384.900133) (xy 83.37502 -384.869583)
			(xy 83.338269 -384.832832) (xy 83.307719 -384.790784) (xy 83.284123 -384.744474) (xy 83.268062 -384.695044)
			(xy 83.259932 -384.643709) (xy 82.720432 -384.643709) (xy 82.712302 -384.695044) (xy 82.696241 -384.744474)
			(xy 82.672645 -384.790784) (xy 82.642095 -384.832832) (xy 82.605344 -384.869583) (xy 82.563296 -384.900133)
			(xy 82.516986 -384.923729) (xy 82.467556 -384.93979) (xy 82.416221 -384.94792) (xy 82.364247 -384.94792)
			(xy 82.312912 -384.93979) (xy 82.263482 -384.923729) (xy 82.217172 -384.900133) (xy 82.175124 -384.869583)
			(xy 82.138373 -384.832832) (xy 82.107823 -384.790784) (xy 82.084227 -384.744474) (xy 82.068166 -384.695044)
			(xy 82.060036 -384.643709) (xy 81.520282 -384.643709) (xy 81.512152 -384.695044) (xy 81.496091 -384.744474)
			(xy 81.472495 -384.790784) (xy 81.441945 -384.832832) (xy 81.405194 -384.869583) (xy 81.363146 -384.900133)
			(xy 81.316836 -384.923729) (xy 81.267406 -384.93979) (xy 81.216071 -384.94792) (xy 81.164097 -384.94792)
			(xy 81.112762 -384.93979) (xy 81.063332 -384.923729) (xy 81.017022 -384.900133) (xy 80.974974 -384.869583)
			(xy 80.938223 -384.832832) (xy 80.907673 -384.790784) (xy 80.884077 -384.744474) (xy 80.868016 -384.695044)
			(xy 80.859886 -384.643709) (xy 80.320386 -384.643709) (xy 80.312256 -384.695044) (xy 80.296195 -384.744474)
			(xy 80.272599 -384.790784) (xy 80.242049 -384.832832) (xy 80.205298 -384.869583) (xy 80.16325 -384.900133)
			(xy 80.11694 -384.923729) (xy 80.06751 -384.93979) (xy 80.016175 -384.94792) (xy 79.964201 -384.94792)
			(xy 79.912866 -384.93979) (xy 79.863436 -384.923729) (xy 79.817126 -384.900133) (xy 79.775078 -384.869583)
			(xy 79.738327 -384.832832) (xy 79.707777 -384.790784) (xy 79.684181 -384.744474) (xy 79.66812 -384.695044)
			(xy 79.65999 -384.643709) (xy 78.094335 -384.643709) (xy 78.05573 -384.663379) (xy 78.0063 -384.67944)
			(xy 77.954965 -384.68757) (xy 77.902991 -384.68757) (xy 77.851656 -384.67944) (xy 77.802226 -384.663379)
			(xy 77.755916 -384.639783) (xy 77.713868 -384.609233) (xy 77.677117 -384.572482) (xy 77.646567 -384.530434)
			(xy 77.622971 -384.484124) (xy 77.60691 -384.434694) (xy 77.59878 -384.383359) (xy 76.853676 -384.383359)
			(xy 76.858849 -384.387664) (xy 76.896066 -384.429201) (xy 76.926839 -384.475714) (xy 76.950511 -384.526211)
			(xy 76.966579 -384.579618) (xy 76.974699 -384.634794) (xy 76.975208 -384.66268) (xy 76.974699 -384.690566)
			(xy 76.966579 -384.745742) (xy 76.950511 -384.799149) (xy 76.926839 -384.849646) (xy 76.896066 -384.896159)
			(xy 76.858849 -384.937696) (xy 76.815981 -384.973371) (xy 76.768375 -385.002425) (xy 76.717046 -385.024237)
			(xy 76.663089 -385.038343) (xy 76.607652 -385.044443) (xy 76.551918 -385.042406) (xy 76.497075 -385.032276)
			(xy 76.444291 -385.014269) (xy 76.394691 -384.988768) (xy 76.349333 -384.956317) (xy 76.309184 -384.917608)
			(xy 76.275098 -384.873465) (xy 76.247802 -384.82483) (xy 76.227879 -384.772739) (xy 76.215753 -384.718302)
			(xy 76.211682 -384.66268) (xy 72.649075 -384.66268) (xy 72.65016 -384.671607) (xy 72.650604 -384.702304)
			(xy 72.650102 -384.734265) (xy 72.642091 -384.797683) (xy 72.626194 -384.859597) (xy 72.602662 -384.91903)
			(xy 72.571868 -384.975045) (xy 72.534295 -385.02676) (xy 72.490538 -385.073357) (xy 72.441285 -385.114102)
			(xy 72.387314 -385.148353) (xy 72.329475 -385.17557) (xy 72.268682 -385.195323) (xy 72.205892 -385.207301)
			(xy 72.142096 -385.211315) (xy 72.0783 -385.207301) (xy 72.01551 -385.195323) (xy 71.954717 -385.17557)
			(xy 71.896878 -385.148353) (xy 71.842907 -385.114102) (xy 71.793654 -385.073357) (xy 71.749897 -385.02676)
			(xy 71.712324 -384.975045) (xy 71.68153 -384.91903) (xy 71.657998 -384.859597) (xy 71.642101 -384.797683)
			(xy 71.63409 -384.734265) (xy 71.633588 -384.702304) (xy 71.634066 -384.671609) (xy 71.641486 -384.610667)
			(xy 71.656182 -384.551061) (xy 71.67794 -384.493655) (xy 71.706445 -384.439283) (xy 71.723504 -384.41376)
			(xy 71.728977 -384.405008) (xy 71.733106 -384.384803) (xy 71.728979 -384.364598) (xy 71.723504 -384.355848)
			(xy 71.700136 -384.319018) (xy 71.693278 -384.306572) (xy 71.66864 -384.292856) (xy 71.550276 -384.29692)
			(xy 71.526654 -384.312414) (xy 71.520558 -384.325114) (xy 71.506352 -384.353358) (xy 71.471966 -384.406414)
			(xy 71.431275 -384.454803) (xy 71.384903 -384.497779) (xy 71.359522 -384.51663) (xy 71.350098 -384.524291)
			(xy 71.339098 -384.545904) (xy 71.33844 -384.558032) (xy 71.33844 -384.640328) (xy 71.339072 -384.652459)
			(xy 71.350095 -384.674065) (xy 71.359522 -384.68173) (xy 71.383701 -384.699677) (xy 71.428082 -384.740375)
			(xy 71.467347 -384.786029) (xy 71.500948 -384.835999) (xy 71.528413 -384.889588) (xy 71.54936 -384.946044)
			(xy 71.563493 -385.004578) (xy 71.570617 -385.064372) (xy 71.571104 -385.09448) (xy 71.570645 -385.125139)
			(xy 71.563274 -385.186013) (xy 71.548635 -385.245558) (xy 71.526942 -385.302911) (xy 71.498509 -385.357239)
			(xy 71.46375 -385.407754) (xy 71.423168 -385.453721) (xy 71.377352 -385.494475) (xy 71.35241 -385.51231)
			(xy 71.343012 -385.518914) (xy 71.331582 -385.538726) (xy 71.328333 -385.58216) (xy 76.211682 -385.58216)
			(xy 76.215753 -385.526538) (xy 76.227879 -385.472101) (xy 76.247802 -385.42001) (xy 76.275098 -385.371375)
			(xy 76.309184 -385.327232) (xy 76.349333 -385.288523) (xy 76.394691 -385.256072) (xy 76.444291 -385.230571)
			(xy 76.497075 -385.212564) (xy 76.551918 -385.202434) (xy 76.607652 -385.200397) (xy 76.663089 -385.206497)
			(xy 76.717046 -385.220603) (xy 76.768375 -385.242415) (xy 76.815981 -385.271469) (xy 76.858849 -385.307144)
			(xy 76.896066 -385.348681) (xy 76.926839 -385.395194) (xy 76.950511 -385.445691) (xy 76.966579 -385.499098)
			(xy 76.974699 -385.554274) (xy 76.975208 -385.58216) (xy 76.974699 -385.610046) (xy 76.971951 -385.628721)
			(xy 77.177394 -385.628721) (xy 77.177394 -385.576747) (xy 77.185524 -385.525412) (xy 77.201585 -385.475982)
			(xy 77.225181 -385.429672) (xy 77.255731 -385.387624) (xy 77.292482 -385.350873) (xy 77.33453 -385.320323)
			(xy 77.38084 -385.296727) (xy 77.43027 -385.280666) (xy 77.481605 -385.272536) (xy 77.533579 -385.272536)
			(xy 77.584914 -385.280666) (xy 77.634344 -385.296727) (xy 77.66114 -385.31038) (xy 79.98841 -385.31038)
			(xy 79.988883 -385.284391) (xy 79.997017 -385.233054) (xy 80.013082 -385.183622) (xy 80.036682 -385.137311)
			(xy 80.067236 -385.095263) (xy 80.103992 -385.058511) (xy 80.146044 -385.027962) (xy 80.192357 -385.004368)
			(xy 80.241791 -384.988308) (xy 80.293129 -384.98018) (xy 80.319118 -384.979672) (xy 80.345129 -384.980125)
			(xy 80.396506 -384.988287) (xy 80.445973 -385.00439) (xy 80.492309 -385.028038) (xy 80.534372 -385.058648)
			(xy 80.571125 -385.095464) (xy 80.601661 -385.13758) (xy 80.625229 -385.183957) (xy 80.641247 -385.233451)
			(xy 80.645762 -385.259072) (xy 80.647286 -385.26847) (xy 80.671512 -385.31038) (xy 81.188306 -385.31038)
			(xy 81.188783 -385.284392) (xy 81.196917 -385.233055) (xy 81.212982 -385.183623) (xy 81.236581 -385.137313)
			(xy 81.267135 -385.095264) (xy 81.30389 -385.058513) (xy 81.345942 -385.027963) (xy 81.392254 -385.004369)
			(xy 81.441688 -384.988309) (xy 81.493026 -384.98018) (xy 81.519014 -384.979672) (xy 81.545025 -384.980129)
			(xy 81.596402 -384.98829) (xy 81.645868 -385.004392) (xy 81.692204 -385.02804) (xy 81.734267 -385.058649)
			(xy 81.77102 -385.095465) (xy 81.801557 -385.137581) (xy 81.825125 -385.183958) (xy 81.841143 -385.233452)
			(xy 81.845658 -385.259072) (xy 81.847182 -385.26847) (xy 81.871408 -385.31038) (xy 82.388456 -385.31038)
			(xy 82.388983 -385.284394) (xy 82.397115 -385.233062) (xy 82.413177 -385.183635) (xy 82.436772 -385.137327)
			(xy 82.46732 -385.095281) (xy 82.504069 -385.058531) (xy 82.546114 -385.02798) (xy 82.59242 -385.004383)
			(xy 82.641847 -384.988319) (xy 82.693178 -384.980184) (xy 82.719164 -384.979672) (xy 82.745207 -384.980166)
			(xy 82.796646 -384.988348) (xy 82.846169 -385.004485) (xy 82.892555 -385.028178) (xy 82.934657 -385.058844)
			(xy 82.971438 -385.095724) (xy 83.001989 -385.137909) (xy 83.025557 -385.184358) (xy 83.04156 -385.233924)
			(xy 83.046062 -385.25958) (xy 83.047332 -385.268978) (xy 83.071268 -385.31038) (xy 83.588352 -385.31038)
			(xy 83.588883 -385.284394) (xy 83.597015 -385.233063) (xy 83.613077 -385.183636) (xy 83.636671 -385.137329)
			(xy 83.667219 -385.095282) (xy 83.703967 -385.058532) (xy 83.746012 -385.027982) (xy 83.792317 -385.004384)
			(xy 83.841743 -384.98832) (xy 83.893074 -384.980185) (xy 83.91906 -384.979672) (xy 83.945072 -384.980087)
			(xy 83.996451 -384.988255) (xy 84.045918 -385.004364) (xy 84.092254 -385.028017) (xy 84.134317 -385.058632)
			(xy 84.171069 -385.095453) (xy 84.201605 -385.137573) (xy 84.225172 -385.183953) (xy 84.241189 -385.23345)
			(xy 84.245704 -385.259072) (xy 84.247228 -385.26847) (xy 84.520024 -385.740402) (xy 84.52739 -385.746244)
			(xy 84.546169 -385.762044) (xy 84.579287 -385.798261) (xy 84.606697 -385.83897) (xy 84.627798 -385.883278)
			(xy 84.642127 -385.930215) (xy 84.649372 -385.978754) (xy 84.649818 -386.003292) (xy 84.649564 -386.015484)
			(xy 84.64931 -386.025136) (xy 84.655406 -386.04317) (xy 84.71408 -386.11048) (xy 84.730844 -386.119116)
			(xy 84.740496 -386.120132) (xy 84.767257 -386.123495) (xy 84.81928 -386.137717) (xy 84.868306 -386.160191)
			(xy 84.913036 -386.190322) (xy 84.952283 -386.227312) (xy 84.985009 -386.27018) (xy 85.010346 -386.31779)
			(xy 85.027621 -386.36888) (xy 85.036378 -386.422096) (xy 85.036914 -386.449062) (xy 85.036404 -386.475049)
			(xy 85.028274 -386.526384) (xy 85.012213 -386.575814) (xy 84.988617 -386.622124) (xy 84.958067 -386.664172)
			(xy 84.921316 -386.700923) (xy 84.879268 -386.731473) (xy 84.832958 -386.755069) (xy 84.783528 -386.77113)
			(xy 84.732193 -386.77926) (xy 84.680219 -386.77926) (xy 84.628884 -386.77113) (xy 84.579454 -386.755069)
			(xy 84.533144 -386.731473) (xy 84.491096 -386.700923) (xy 84.454345 -386.664172) (xy 84.423795 -386.622124)
			(xy 84.400199 -386.575814) (xy 84.384138 -386.526384) (xy 84.376008 -386.475049) (xy 84.375498 -386.449062)
			(xy 84.375752 -386.43687) (xy 84.376006 -386.427218) (xy 84.36991 -386.409184) (xy 84.311236 -386.341874)
			(xy 84.294472 -386.333238) (xy 84.28482 -386.332222) (xy 84.257909 -386.328882) (xy 84.205622 -386.314512)
			(xy 84.156379 -386.291808) (xy 84.111497 -386.261378) (xy 84.072178 -386.224036) (xy 84.039474 -386.180783)
			(xy 84.014262 -386.132775) (xy 83.997215 -386.081299) (xy 83.992466 -386.0546) (xy 83.990942 -386.045202)
			(xy 83.718146 -385.57327) (xy 83.71078 -385.567428) (xy 83.692029 -385.551596) (xy 83.65891 -385.515385)
			(xy 83.631498 -385.474683) (xy 83.610393 -385.430381) (xy 83.596056 -385.383449) (xy 83.588802 -385.334916)
			(xy 83.588352 -385.31038) (xy 83.071268 -385.31038) (xy 83.319874 -385.740402) (xy 83.32724 -385.746244)
			(xy 83.34603 -385.762032) (xy 83.379145 -385.798253) (xy 83.406552 -385.838964) (xy 83.427651 -385.883275)
			(xy 83.441979 -385.930214) (xy 83.449223 -385.978753) (xy 83.449668 -386.003292) (xy 83.449414 -386.015484)
			(xy 83.44916 -386.025136) (xy 83.455256 -386.04317) (xy 83.51393 -386.11048) (xy 83.530694 -386.119116)
			(xy 83.5406 -386.120132) (xy 83.567362 -386.123492) (xy 83.619385 -386.137714) (xy 83.668411 -386.160189)
			(xy 83.71314 -386.190321) (xy 83.752388 -386.227311) (xy 83.785113 -386.270179) (xy 83.81045 -386.31779)
			(xy 83.827725 -386.36888) (xy 83.836482 -386.422096) (xy 83.837018 -386.449062) (xy 83.836481 -386.476347)
			(xy 83.827527 -386.530177) (xy 83.809855 -386.581806) (xy 83.783946 -386.629833) (xy 83.750502 -386.672954)
			(xy 83.730846 -386.691886) (xy 83.723455 -386.699417) (xy 83.714923 -386.71869) (xy 83.714336 -386.729224)
			(xy 83.714336 -386.8039) (xy 83.714841 -386.814453) (xy 83.723392 -386.833749) (xy 83.730846 -386.841238)
			(xy 83.750488 -386.860182) (xy 83.783921 -386.903305) (xy 83.809825 -386.95133) (xy 83.827496 -387.002955)
			(xy 83.836457 -387.056779) (xy 83.837018 -387.084062) (xy 83.836573 -387.108178) (xy 83.829576 -387.155901)
			(xy 83.815725 -387.202102) (xy 83.795314 -387.245803) (xy 83.782408 -387.26618) (xy 83.776566 -387.27507)
			(xy 83.77301 -387.295136) (xy 83.794092 -387.387338) (xy 83.806284 -387.404102) (xy 83.815174 -387.409436)
			(xy 83.835984 -387.422277) (xy 83.873888 -387.45317) (xy 83.906828 -387.489309) (xy 83.934088 -387.529904)
			(xy 83.955071 -387.574072) (xy 83.969322 -387.620848) (xy 83.976529 -387.669213) (xy 83.976972 -387.693662)
			(xy 83.976561 -387.718036) (xy 83.969415 -387.766256) (xy 83.955271 -387.812906) (xy 83.934436 -387.856977)
			(xy 83.90736 -387.897513) (xy 83.874631 -387.933639) (xy 83.856068 -387.94944) (xy 83.847178 -387.956552)
			(xy 83.83778 -387.97611) (xy 83.834986 -388.075424) (xy 83.843622 -388.09549) (xy 83.852004 -388.10311)
			(xy 83.870443 -388.120582) (xy 83.901793 -388.160549) (xy 83.926093 -388.205155) (xy 83.942672 -388.253168)
			(xy 83.951072 -388.303264) (xy 83.951572 -388.328662) (xy 84.540852 -388.328662) (xy 84.541374 -388.303407)
			(xy 84.549687 -388.253585) (xy 84.566088 -388.205811) (xy 84.590129 -388.161388) (xy 84.621153 -388.121528)
			(xy 84.658315 -388.087318) (xy 84.700601 -388.059692) (xy 84.746857 -388.039402) (xy 84.795822 -388.027002)
			(xy 84.84616 -388.022831) (xy 84.896498 -388.027002) (xy 84.945463 -388.039402) (xy 84.991719 -388.059692)
			(xy 85.034005 -388.087318) (xy 85.071167 -388.121528) (xy 85.102191 -388.161388) (xy 85.126232 -388.205811)
			(xy 85.142633 -388.253585) (xy 85.150946 -388.303407) (xy 85.151468 -388.328662) (xy 85.151399 -388.338021)
			(xy 85.150256 -388.356703) (xy 85.149182 -388.366) (xy 85.148166 -388.37489) (xy 85.151976 -388.391654)
			(xy 85.195918 -388.461504) (xy 85.209634 -388.471918) (xy 85.218016 -388.474712) (xy 85.24204 -388.483193)
			(xy 85.287212 -388.506742) (xy 85.328018 -388.537239) (xy 85.363398 -388.573891) (xy 85.392435 -388.615749)
			(xy 85.414374 -388.661725) (xy 85.421978 -388.68604) (xy 85.423502 -388.691882) (xy 85.743796 -389.245602)
			(xy 85.74786 -389.24992) (xy 85.764062 -389.26763) (xy 85.791484 -389.307021) (xy 85.812626 -389.35011)
			(xy 85.827001 -389.395904) (xy 85.834276 -389.443346) (xy 85.834728 -389.467344) (xy 85.834346 -389.492151)
			(xy 85.826574 -389.541154) (xy 85.811228 -389.588336) (xy 85.788687 -389.632535) (xy 85.759506 -389.672661)
			(xy 85.724404 -389.707725) (xy 85.684246 -389.736864) (xy 85.640023 -389.759358) (xy 85.592825 -389.774653)
			(xy 85.543814 -389.782373) (xy 85.519006 -389.782812) (xy 85.493612 -389.782306) (xy 85.443478 -389.774177)
			(xy 85.395293 -389.758126) (xy 85.350299 -389.734568) (xy 85.309656 -389.704112) (xy 85.274413 -389.667541)
			(xy 85.245479 -389.625801) (xy 85.223601 -389.579966) (xy 85.215984 -389.555736) (xy 85.21446 -389.549894)
			(xy 84.894166 -388.996174) (xy 84.890102 -388.991856) (xy 84.873951 -388.974115) (xy 84.84658 -388.934716)
			(xy 84.825487 -388.891628) (xy 84.811157 -388.845844) (xy 84.803922 -388.798419) (xy 84.803488 -388.774432)
			(xy 84.803569 -388.762384) (xy 84.805352 -388.738355) (xy 84.807044 -388.726426) (xy 84.808314 -388.717536)
			(xy 84.805266 -388.700518) (xy 84.763102 -388.629652) (xy 84.749894 -388.618476) (xy 84.741512 -388.615428)
			(xy 84.719773 -388.60701) (xy 84.678914 -388.584574) (xy 84.641941 -388.556185) (xy 84.609717 -388.522504)
			(xy 84.58299 -388.484313) (xy 84.562383 -388.442501) (xy 84.548374 -388.398042) (xy 84.54129 -388.351969)
			(xy 84.540852 -388.328662) (xy 83.951572 -388.328662) (xy 83.951503 -388.338021) (xy 83.95036 -388.356703)
			(xy 83.949286 -388.366) (xy 83.94827 -388.37489) (xy 83.95208 -388.391654) (xy 83.996022 -388.461504)
			(xy 84.009738 -388.471918) (xy 84.01812 -388.474712) (xy 84.042144 -388.48319) (xy 84.087317 -388.506741)
			(xy 84.128123 -388.537238) (xy 84.163503 -388.573891) (xy 84.192539 -388.615748) (xy 84.214479 -388.661725)
			(xy 84.222082 -388.68604) (xy 84.223606 -388.691882) (xy 84.5439 -389.245602) (xy 84.547964 -389.24992)
			(xy 84.564166 -389.267629) (xy 84.591588 -389.307021) (xy 84.61273 -389.35011) (xy 84.627105 -389.395904)
			(xy 84.63438 -389.443346) (xy 84.634832 -389.467344) (xy 84.634447 -389.492151) (xy 84.626674 -389.541153)
			(xy 84.611329 -389.588335) (xy 84.588788 -389.632534) (xy 84.559607 -389.67266) (xy 84.524505 -389.707724)
			(xy 84.484349 -389.736862) (xy 84.440126 -389.759357) (xy 84.392928 -389.774652) (xy 84.343918 -389.782373)
			(xy 84.31911 -389.782812) (xy 84.293716 -389.782303) (xy 84.243583 -389.774174) (xy 84.195397 -389.758124)
			(xy 84.150403 -389.734567) (xy 84.10976 -389.70411) (xy 84.074517 -389.66754) (xy 84.045583 -389.6258)
			(xy 84.023705 -389.579966) (xy 84.016088 -389.555736) (xy 84.014564 -389.549894) (xy 83.69427 -388.996174)
			(xy 83.690206 -388.991856) (xy 83.674039 -388.974129) (xy 83.646673 -388.934724) (xy 83.625585 -388.891633)
			(xy 83.611259 -388.845846) (xy 83.604026 -388.79842) (xy 83.603592 -388.774432) (xy 83.603673 -388.762384)
			(xy 83.605456 -388.738355) (xy 83.607148 -388.726426) (xy 83.608418 -388.717536) (xy 83.60537 -388.700518)
			(xy 83.563206 -388.629652) (xy 83.549998 -388.618476) (xy 83.541616 -388.615428) (xy 83.519878 -388.607008)
			(xy 83.479018 -388.584573) (xy 83.442046 -388.556184) (xy 83.409821 -388.522503) (xy 83.383094 -388.484312)
			(xy 83.362487 -388.442501) (xy 83.348478 -388.398042) (xy 83.341394 -388.351969) (xy 83.340956 -388.328662)
			(xy 83.341464 -388.303266) (xy 83.349875 -388.253175) (xy 83.366458 -388.205167) (xy 83.390757 -388.160564)
			(xy 83.422101 -388.120597) (xy 83.440524 -388.10311) (xy 83.448906 -388.09549) (xy 83.457542 -388.075424)
			(xy 83.454748 -387.97611) (xy 83.44535 -387.956552) (xy 83.43646 -387.94944) (xy 83.417924 -387.93361)
			(xy 83.385203 -387.897485) (xy 83.358132 -387.856952) (xy 83.337298 -387.812888) (xy 83.32315 -387.766246)
			(xy 83.315994 -387.718033) (xy 83.315556 -387.693662) (xy 83.315969 -387.669544) (xy 83.322976 -387.621821)
			(xy 83.336836 -387.57562) (xy 83.357257 -387.53192) (xy 83.370166 -387.511544) (xy 83.376008 -387.502654)
			(xy 83.379564 -387.482588) (xy 83.358482 -387.390386) (xy 83.34629 -387.373622) (xy 83.3374 -387.368288)
			(xy 83.316618 -387.355404) (xy 83.27871 -387.324521) (xy 83.245765 -387.288391) (xy 83.218501 -387.247802)
			(xy 83.197513 -387.203641) (xy 83.183258 -387.15687) (xy 83.176047 -387.10851) (xy 83.175602 -387.084062)
			(xy 83.176148 -387.056777) (xy 83.185099 -387.002947) (xy 83.202768 -386.951318) (xy 83.228676 -386.903291)
			(xy 83.262119 -386.86017) (xy 83.281774 -386.841238) (xy 83.289157 -386.833701) (xy 83.297693 -386.814433)
			(xy 83.298284 -386.8039) (xy 83.298284 -386.729224) (xy 83.29776 -386.718674) (xy 83.289222 -386.699378)
			(xy 83.281774 -386.691886) (xy 83.262147 -386.672927) (xy 83.228711 -386.629808) (xy 83.202804 -386.581787)
			(xy 83.185129 -386.530166) (xy 83.176165 -386.476344) (xy 83.175602 -386.449062) (xy 83.175856 -386.43687)
			(xy 83.17611 -386.427218) (xy 83.170014 -386.409184) (xy 83.11134 -386.341874) (xy 83.094576 -386.333238)
			(xy 83.08467 -386.332222) (xy 83.057764 -386.328843) (xy 83.005479 -386.31448) (xy 82.956235 -386.291783)
			(xy 82.911352 -386.261359) (xy 82.872032 -386.224023) (xy 82.839327 -386.180774) (xy 82.814114 -386.13277)
			(xy 82.797066 -386.081297) (xy 82.792316 -386.0546) (xy 82.790792 -386.045202) (xy 82.517742 -385.572762)
			(xy 82.51063 -385.56692) (xy 82.491884 -385.551156) (xy 82.458833 -385.515009) (xy 82.43148 -385.47438)
			(xy 82.410423 -385.430158) (xy 82.396125 -385.383313) (xy 82.388898 -385.33487) (xy 82.388456 -385.31038)
			(xy 81.871408 -385.31038) (xy 82.119978 -385.740402) (xy 82.127344 -385.746244) (xy 82.146135 -385.762031)
			(xy 82.179249 -385.798252) (xy 82.206656 -385.838964) (xy 82.227755 -385.883275) (xy 82.242083 -385.930214)
			(xy 82.249327 -385.978753) (xy 82.249772 -386.003292) (xy 82.249518 -386.015484) (xy 82.249264 -386.025136)
			(xy 82.25536 -386.04317) (xy 82.314034 -386.11048) (xy 82.330798 -386.119116) (xy 82.340704 -386.120132)
			(xy 82.367466 -386.123488) (xy 82.419489 -386.137711) (xy 82.468515 -386.160187) (xy 82.513244 -386.190319)
			(xy 82.552492 -386.22731) (xy 82.585217 -386.270179) (xy 82.610554 -386.317789) (xy 82.627829 -386.368879)
			(xy 82.636586 -386.422096) (xy 82.637122 -386.449062) (xy 82.636584 -386.476347) (xy 82.62763 -386.530177)
			(xy 82.609958 -386.581806) (xy 82.584049 -386.629833) (xy 82.550605 -386.672953) (xy 82.53095 -386.691886)
			(xy 82.52356 -386.699418) (xy 82.515027 -386.71869) (xy 82.51444 -386.729224) (xy 82.51444 -386.8039)
			(xy 82.514944 -386.814453) (xy 82.523495 -386.833749) (xy 82.53095 -386.841238) (xy 82.550593 -386.860181)
			(xy 82.584026 -386.903304) (xy 82.609929 -386.95133) (xy 82.627601 -387.002954) (xy 82.636561 -387.056779)
			(xy 82.637122 -387.084062) (xy 82.636677 -387.108178) (xy 82.62968 -387.155901) (xy 82.615829 -387.202102)
			(xy 82.595417 -387.245803) (xy 82.582512 -387.26618) (xy 82.57667 -387.27507) (xy 82.573114 -387.295136)
			(xy 82.594196 -387.387338) (xy 82.606388 -387.404102) (xy 82.615278 -387.409436) (xy 82.636066 -387.422311)
			(xy 82.673974 -387.453195) (xy 82.70692 -387.489326) (xy 82.734184 -387.529916) (xy 82.755171 -387.574079)
			(xy 82.769425 -387.620852) (xy 82.776633 -387.669214) (xy 82.777076 -387.693662) (xy 82.776664 -387.718036)
			(xy 82.769517 -387.766256) (xy 82.755374 -387.812906) (xy 82.734539 -387.856976) (xy 82.707464 -387.897513)
			(xy 82.674735 -387.933638) (xy 82.656172 -387.94944) (xy 82.647282 -387.956552) (xy 82.637884 -387.97611)
			(xy 82.63509 -388.075424) (xy 82.643726 -388.09549) (xy 82.652108 -388.10311) (xy 82.670548 -388.120581)
			(xy 82.701898 -388.160548) (xy 82.726197 -388.205154) (xy 82.742776 -388.253168) (xy 82.751176 -388.303264)
			(xy 82.751676 -388.328662) (xy 82.751607 -388.338021) (xy 82.750464 -388.356703) (xy 82.74939 -388.366)
			(xy 82.748374 -388.37489) (xy 82.752184 -388.391654) (xy 82.796126 -388.461504) (xy 82.809842 -388.471918)
			(xy 82.818224 -388.474712) (xy 82.842326 -388.483179) (xy 82.887617 -388.506808) (xy 82.928511 -388.537422)
			(xy 82.963941 -388.574222) (xy 82.992983 -388.616247) (xy 83.014878 -388.6624) (xy 83.02244 -388.686802)
			(xy 83.023964 -388.692644) (xy 83.34375 -389.245602) (xy 83.347814 -389.24992) (xy 83.364004 -389.267627)
			(xy 83.391369 -389.307036) (xy 83.412455 -389.350132) (xy 83.426775 -389.395924) (xy 83.433999 -389.443355)
			(xy 83.434428 -389.467344) (xy 83.434022 -389.492137) (xy 83.426259 -389.541111) (xy 83.410929 -389.588268)
			(xy 83.388412 -389.632446) (xy 83.359261 -389.672558) (xy 83.324194 -389.707615) (xy 83.284074 -389.736756)
			(xy 83.23989 -389.759262) (xy 83.192729 -389.774578) (xy 83.143753 -389.782329) (xy 83.11896 -389.782812)
			(xy 83.093564 -389.782347) (xy 83.043429 -389.77421) (xy 82.995243 -389.758153) (xy 82.950248 -389.734589)
			(xy 82.909606 -389.704127) (xy 82.874364 -389.667551) (xy 82.845431 -389.625806) (xy 82.823554 -389.579968)
			(xy 82.815938 -389.555736) (xy 82.814414 -389.549894) (xy 82.493866 -388.995412) (xy 82.489802 -388.991094)
			(xy 82.473695 -388.973441) (xy 82.446509 -388.934139) (xy 82.42556 -388.891188) (xy 82.411325 -388.845569)
			(xy 82.404131 -388.798326) (xy 82.403696 -388.774432) (xy 82.403777 -388.762384) (xy 82.40556 -388.738355)
			(xy 82.407252 -388.726426) (xy 82.408522 -388.717536) (xy 82.405474 -388.700518) (xy 82.36331 -388.629652)
			(xy 82.350102 -388.618476) (xy 82.34172 -388.615428) (xy 82.319983 -388.607005) (xy 82.279123 -388.584571)
			(xy 82.242151 -388.556183) (xy 82.209926 -388.522502) (xy 82.183199 -388.484311) (xy 82.162591 -388.4425)
			(xy 82.148582 -388.398041) (xy 82.141498 -388.351969) (xy 82.14106 -388.328662) (xy 82.141566 -388.303266)
			(xy 82.149977 -388.253175) (xy 82.166561 -388.205167) (xy 82.19086 -388.160564) (xy 82.222205 -388.120597)
			(xy 82.240628 -388.10311) (xy 82.24901 -388.09549) (xy 82.257646 -388.075424) (xy 82.254852 -387.97611)
			(xy 82.245454 -387.956552) (xy 82.236564 -387.94944) (xy 82.218029 -387.933609) (xy 82.185308 -387.897485)
			(xy 82.158237 -387.856952) (xy 82.137402 -387.812888) (xy 82.123254 -387.766246) (xy 82.116098 -387.718033)
			(xy 82.11566 -387.693662) (xy 82.116072 -387.669544) (xy 82.123079 -387.621821) (xy 82.13694 -387.57562)
			(xy 82.15736 -387.53192) (xy 82.17027 -387.511544) (xy 82.176112 -387.502654) (xy 82.179668 -387.482588)
			(xy 82.158586 -387.390386) (xy 82.146394 -387.373622) (xy 82.137504 -387.368288) (xy 82.116722 -387.355403)
			(xy 82.078815 -387.32452) (xy 82.04587 -387.28839) (xy 82.018606 -387.247802) (xy 81.997617 -387.203641)
			(xy 81.983362 -387.15687) (xy 81.976151 -387.108509) (xy 81.975706 -387.084062) (xy 81.976251 -387.056777)
			(xy 81.985202 -387.002947) (xy 82.002871 -386.951318) (xy 82.028779 -386.903291) (xy 82.062223 -386.86017)
			(xy 82.081878 -386.841238) (xy 82.089262 -386.833701) (xy 82.097797 -386.814433) (xy 82.098388 -386.8039)
			(xy 82.098388 -386.729224) (xy 82.097863 -386.718674) (xy 82.089325 -386.699378) (xy 82.081878 -386.691886)
			(xy 82.062252 -386.672926) (xy 82.028816 -386.629808) (xy 82.002909 -386.581787) (xy 81.985233 -386.530166)
			(xy 81.976269 -386.476344) (xy 81.975706 -386.449062) (xy 81.97596 -386.43687) (xy 81.976214 -386.427218)
			(xy 81.970118 -386.409184) (xy 81.911444 -386.341874) (xy 81.89468 -386.333238) (xy 81.884774 -386.332222)
			(xy 81.857869 -386.328839) (xy 81.805583 -386.314478) (xy 81.75634 -386.291781) (xy 81.711457 -386.261358)
			(xy 81.672137 -386.224022) (xy 81.639432 -386.180773) (xy 81.614218 -386.13277) (xy 81.59717 -386.081297)
			(xy 81.59242 -386.0546) (xy 81.590896 -386.045202) (xy 81.3181 -385.57327) (xy 81.310734 -385.567428)
			(xy 81.291974 -385.551607) (xy 81.258858 -385.515392) (xy 81.231448 -385.474687) (xy 81.210344 -385.430384)
			(xy 81.196009 -385.383451) (xy 81.188756 -385.334917) (xy 81.188306 -385.31038) (xy 80.671512 -385.31038)
			(xy 80.920082 -385.740402) (xy 80.927448 -385.746244) (xy 80.946239 -385.76203) (xy 80.979354 -385.798252)
			(xy 81.006761 -385.838964) (xy 81.027859 -385.883274) (xy 81.042187 -385.930214) (xy 81.049431 -385.978753)
			(xy 81.049876 -386.003292) (xy 81.049622 -386.015484) (xy 81.049368 -386.025136) (xy 81.055464 -386.04317)
			(xy 81.114138 -386.11048) (xy 81.130902 -386.119116) (xy 81.140554 -386.120132) (xy 81.167311 -386.123529)
			(xy 81.219333 -386.137744) (xy 81.268359 -386.160213) (xy 81.313089 -386.190339) (xy 81.352338 -386.227325)
			(xy 81.385065 -386.270189) (xy 81.410402 -386.317796) (xy 81.427679 -386.368884) (xy 81.436436 -386.422097)
			(xy 81.436972 -386.449062) (xy 81.43645 -386.476348) (xy 81.427494 -386.530179) (xy 81.40982 -386.581809)
			(xy 81.383906 -386.629836) (xy 81.350458 -386.672955) (xy 81.3308 -386.691886) (xy 81.323403 -386.699411)
			(xy 81.314876 -386.718688) (xy 81.31429 -386.729224) (xy 81.31429 -386.8039) (xy 81.314808 -386.814451)
			(xy 81.323351 -386.833746) (xy 81.3308 -386.841238) (xy 81.350434 -386.86019) (xy 81.38387 -386.90331)
			(xy 81.409776 -386.951333) (xy 81.427449 -387.002956) (xy 81.436411 -387.05678) (xy 81.436972 -387.084062)
			(xy 81.436518 -387.108178) (xy 81.429523 -387.1559) (xy 81.415674 -387.202101) (xy 81.395266 -387.245802)
			(xy 81.382362 -387.26618) (xy 81.37652 -387.27507) (xy 81.372964 -387.295136) (xy 81.394046 -387.387338)
			(xy 81.406238 -387.404102) (xy 81.415128 -387.409436) (xy 81.435928 -387.422293) (xy 81.473833 -387.453182)
			(xy 81.506776 -387.489317) (xy 81.534038 -387.52991) (xy 81.555023 -387.574075) (xy 81.569275 -387.62085)
			(xy 81.576483 -387.669213) (xy 81.576926 -387.693662) (xy 81.576496 -387.718035) (xy 81.56935 -387.766253)
			(xy 81.555209 -387.812902) (xy 81.534378 -387.856972) (xy 81.507307 -387.897509) (xy 81.474582 -387.933637)
			(xy 81.456022 -387.94944) (xy 81.447132 -387.956552) (xy 81.437734 -387.97611) (xy 81.43494 -388.075424)
			(xy 81.443576 -388.09549) (xy 81.451958 -388.10311) (xy 81.470408 -388.120571) (xy 81.501754 -388.160542)
			(xy 81.526051 -388.205151) (xy 81.542627 -388.253167) (xy 81.551027 -388.303264) (xy 81.551526 -388.328662)
			(xy 81.551457 -388.338021) (xy 81.550314 -388.356703) (xy 81.54924 -388.366) (xy 81.548224 -388.37489)
			(xy 81.552034 -388.391654) (xy 81.595976 -388.461504) (xy 81.609692 -388.471918) (xy 81.618074 -388.474712)
			(xy 81.642089 -388.483215) (xy 81.687263 -388.506759) (xy 81.72807 -388.53725) (xy 81.763452 -388.573899)
			(xy 81.792491 -388.615753) (xy 81.814432 -388.661726) (xy 81.822036 -388.68604) (xy 81.82356 -388.691882)
			(xy 82.143854 -389.245602) (xy 82.147918 -389.24992) (xy 82.164109 -389.267627) (xy 82.191474 -389.307036)
			(xy 82.212559 -389.350132) (xy 82.226879 -389.395923) (xy 82.234103 -389.443355) (xy 82.234532 -389.467344)
			(xy 82.234122 -389.492137) (xy 82.226359 -389.54111) (xy 82.21103 -389.588267) (xy 82.188513 -389.632445)
			(xy 82.159362 -389.672556) (xy 82.124295 -389.707614) (xy 82.084176 -389.736755) (xy 82.039993 -389.75926)
			(xy 81.992833 -389.774578) (xy 81.943857 -389.782329) (xy 81.919064 -389.782812) (xy 81.893669 -389.782343)
			(xy 81.843533 -389.774207) (xy 81.795347 -389.75815) (xy 81.750353 -389.734587) (xy 81.70971 -389.704125)
			(xy 81.674468 -389.66755) (xy 81.645536 -389.625806) (xy 81.623658 -389.579968) (xy 81.616042 -389.555736)
			(xy 81.614518 -389.549894) (xy 81.294224 -388.996174) (xy 81.29016 -388.991856) (xy 81.27395 -388.974153)
			(xy 81.246528 -388.93476) (xy 81.225387 -388.891669) (xy 81.211015 -388.845874) (xy 81.203742 -388.798431)
			(xy 81.203292 -388.774432) (xy 81.203434 -388.76238) (xy 81.20534 -388.73835) (xy 81.207102 -388.726426)
			(xy 81.208372 -388.717536) (xy 81.205324 -388.700518) (xy 81.16316 -388.629652) (xy 81.149952 -388.618476)
			(xy 81.14157 -388.615428) (xy 81.119822 -388.607033) (xy 81.078964 -388.584592) (xy 81.041993 -388.556199)
			(xy 81.00977 -388.522513) (xy 80.983045 -388.484319) (xy 80.962439 -388.442505) (xy 80.948431 -388.398044)
			(xy 80.941348 -388.35197) (xy 80.94091 -388.328662) (xy 80.941433 -388.303267) (xy 80.949842 -388.253178)
			(xy 80.966423 -388.20517) (xy 80.990718 -388.160567) (xy 81.022057 -388.120599) (xy 81.040478 -388.10311)
			(xy 81.04886 -388.09549) (xy 81.057496 -388.075424) (xy 81.054702 -387.97611) (xy 81.045304 -387.956552)
			(xy 81.036414 -387.94944) (xy 81.017869 -387.933621) (xy 80.98515 -387.897492) (xy 80.958082 -387.856957)
			(xy 80.93725 -387.812891) (xy 80.923103 -387.766247) (xy 80.915947 -387.718033) (xy 80.91551 -387.693662)
			(xy 80.91593 -387.669545) (xy 80.922936 -387.621822) (xy 80.936795 -387.575621) (xy 80.957212 -387.531921)
			(xy 80.97012 -387.511544) (xy 80.975962 -387.502654) (xy 80.979518 -387.482588) (xy 80.958436 -387.390386)
			(xy 80.946244 -387.373622) (xy 80.937354 -387.368288) (xy 80.916561 -387.355421) (xy 80.878656 -387.324533)
			(xy 80.845714 -387.288399) (xy 80.818452 -387.247808) (xy 80.797465 -387.203645) (xy 80.783211 -387.156872)
			(xy 80.776001 -387.10851) (xy 80.775556 -387.084062) (xy 80.776117 -387.056778) (xy 80.785066 -387.002949)
			(xy 80.802733 -386.951321) (xy 80.828637 -386.903294) (xy 80.862075 -386.860172) (xy 80.881728 -386.841238)
			(xy 80.889104 -386.833695) (xy 80.897646 -386.814432) (xy 80.898238 -386.8039) (xy 80.898238 -386.729224)
			(xy 80.897698 -386.718676) (xy 80.889169 -386.699381) (xy 80.881728 -386.691886) (xy 80.862093 -386.672936)
			(xy 80.82866 -386.629814) (xy 80.802755 -386.58179) (xy 80.785082 -386.530167) (xy 80.776119 -386.476344)
			(xy 80.775556 -386.449062) (xy 80.77581 -386.43687) (xy 80.776064 -386.427218) (xy 80.769968 -386.409184)
			(xy 80.711294 -386.341874) (xy 80.69453 -386.333238) (xy 80.684878 -386.332222) (xy 80.657973 -386.328836)
			(xy 80.605688 -386.314475) (xy 80.556444 -386.291779) (xy 80.511561 -386.261356) (xy 80.472241 -386.224021)
			(xy 80.439536 -386.180772) (xy 80.414322 -386.13277) (xy 80.397274 -386.081297) (xy 80.392524 -386.0546)
			(xy 80.391 -386.045202) (xy 80.118204 -385.57327) (xy 80.110838 -385.567428) (xy 80.092078 -385.551606)
			(xy 80.058962 -385.515392) (xy 80.031552 -385.474687) (xy 80.010448 -385.430383) (xy 79.996113 -385.383451)
			(xy 79.98886 -385.334916) (xy 79.98841 -385.31038) (xy 77.66114 -385.31038) (xy 77.680654 -385.320323)
			(xy 77.722702 -385.350873) (xy 77.759453 -385.387624) (xy 77.790003 -385.429672) (xy 77.813599 -385.475982)
			(xy 77.82966 -385.525412) (xy 77.83779 -385.576747) (xy 77.8383 -385.602734) (xy 77.83779 -385.628721)
			(xy 77.82966 -385.680056) (xy 77.813599 -385.729486) (xy 77.790003 -385.775796) (xy 77.759453 -385.817844)
			(xy 77.722702 -385.854595) (xy 77.693888 -385.87553) (xy 79.361792 -385.87553) (xy 79.362302 -385.849543)
			(xy 79.370432 -385.798208) (xy 79.386493 -385.748778) (xy 79.410089 -385.702468) (xy 79.440639 -385.66042)
			(xy 79.47739 -385.623669) (xy 79.519438 -385.593119) (xy 79.565748 -385.569523) (xy 79.615178 -385.553462)
			(xy 79.666513 -385.545332) (xy 79.718487 -385.545332) (xy 79.769822 -385.553462) (xy 79.819252 -385.569523)
			(xy 79.865562 -385.593119) (xy 79.90761 -385.623669) (xy 79.944361 -385.66042) (xy 79.974911 -385.702468)
			(xy 79.998507 -385.748778) (xy 80.014568 -385.798208) (xy 80.022698 -385.849543) (xy 80.023208 -385.87553)
			(xy 80.02282 -385.899206) (xy 80.016088 -385.946077) (xy 80.002725 -385.991503) (xy 79.993236 -386.013198)
			(xy 79.988918 -386.022596) (xy 79.988156 -386.042662) (xy 80.020414 -386.129022) (xy 80.03413 -386.143754)
			(xy 80.043528 -386.148072) (xy 80.067892 -386.159773) (xy 80.112763 -386.189897) (xy 80.152142 -386.226913)
			(xy 80.184981 -386.269836) (xy 80.210408 -386.317526) (xy 80.227747 -386.368714) (xy 80.236536 -386.42204)
			(xy 80.237076 -386.449062) (xy 80.236553 -386.476348) (xy 80.227597 -386.530179) (xy 80.209923 -386.581809)
			(xy 80.18401 -386.629836) (xy 80.150562 -386.672955) (xy 80.130904 -386.691886) (xy 80.123507 -386.699412)
			(xy 80.11498 -386.718689) (xy 80.114394 -386.729224) (xy 80.114394 -386.8039) (xy 80.114911 -386.814451)
			(xy 80.123455 -386.833746) (xy 80.130904 -386.841238) (xy 80.150538 -386.86019) (xy 80.183974 -386.90331)
			(xy 80.20988 -386.951333) (xy 80.227553 -387.002956) (xy 80.236515 -387.05678) (xy 80.237076 -387.084062)
			(xy 80.236622 -387.108178) (xy 80.229626 -387.1559) (xy 80.215778 -387.202101) (xy 80.19537 -387.245802)
			(xy 80.182466 -387.26618) (xy 80.176624 -387.27507) (xy 80.173068 -387.295136) (xy 80.19415 -387.387338)
			(xy 80.206342 -387.404102) (xy 80.215232 -387.409436) (xy 80.236032 -387.422292) (xy 80.273938 -387.453181)
			(xy 80.306881 -387.489316) (xy 80.334142 -387.529909) (xy 80.355128 -387.574075) (xy 80.369379 -387.62085)
			(xy 80.376587 -387.669213) (xy 80.37703 -387.693662) (xy 80.376598 -387.718035) (xy 80.369453 -387.766253)
			(xy 80.355312 -387.812902) (xy 80.334481 -387.856972) (xy 80.30741 -387.897509) (xy 80.274686 -387.933637)
			(xy 80.256126 -387.94944) (xy 80.247236 -387.956552) (xy 80.237838 -387.97611) (xy 80.235044 -388.075424)
			(xy 80.24368 -388.09549) (xy 80.252062 -388.10311) (xy 80.270512 -388.120571) (xy 80.301859 -388.160542)
			(xy 80.326155 -388.205151) (xy 80.342732 -388.253166) (xy 80.351131 -388.303264) (xy 80.35163 -388.328662)
			(xy 80.351561 -388.338021) (xy 80.350418 -388.356703) (xy 80.349344 -388.366) (xy 80.348328 -388.37489)
			(xy 80.352138 -388.391654) (xy 80.39608 -388.461504) (xy 80.409796 -388.471918) (xy 80.418178 -388.474712)
			(xy 80.442194 -388.483213) (xy 80.487368 -388.506757) (xy 80.528175 -388.537249) (xy 80.563557 -388.573898)
			(xy 80.592595 -388.615752) (xy 80.614536 -388.661726) (xy 80.62214 -388.68604) (xy 80.623664 -388.691882)
			(xy 80.943958 -389.245602) (xy 80.948022 -389.24992) (xy 80.964214 -389.267626) (xy 80.991578 -389.307035)
			(xy 81.012663 -389.350132) (xy 81.026983 -389.395923) (xy 81.034207 -389.443355) (xy 81.034636 -389.467344)
			(xy 81.034222 -389.492136) (xy 81.026459 -389.54111) (xy 81.01113 -389.588266) (xy 80.988613 -389.632444)
			(xy 80.959463 -389.672555) (xy 80.924397 -389.707613) (xy 80.884279 -389.736753) (xy 80.840096 -389.759259)
			(xy 80.792936 -389.774577) (xy 80.743961 -389.782328) (xy 80.719168 -389.782812) (xy 80.693773 -389.78234)
			(xy 80.643638 -389.774204) (xy 80.595452 -389.758148) (xy 80.550457 -389.734585) (xy 80.509815 -389.704124)
			(xy 80.474573 -389.66755) (xy 80.44564 -389.625805) (xy 80.423762 -389.579968) (xy 80.416146 -389.555736)
			(xy 80.414622 -389.549894) (xy 80.094328 -388.996174) (xy 80.090264 -388.991856) (xy 80.074055 -388.974153)
			(xy 80.046633 -388.93476) (xy 80.025492 -388.891669) (xy 80.011119 -388.845874) (xy 80.003846 -388.798431)
			(xy 80.003396 -388.774432) (xy 80.003538 -388.76238) (xy 80.005444 -388.73835) (xy 80.007206 -388.726426)
			(xy 80.008476 -388.717536) (xy 80.005428 -388.700518) (xy 79.963264 -388.629652) (xy 79.950056 -388.618476)
			(xy 79.941674 -388.615428) (xy 79.919927 -388.607031) (xy 79.879068 -388.58459) (xy 79.842098 -388.556197)
			(xy 79.809875 -388.522512) (xy 79.783149 -388.484319) (xy 79.762543 -388.442505) (xy 79.748535 -388.398044)
			(xy 79.741452 -388.35197) (xy 79.741014 -388.328662) (xy 79.741535 -388.303267) (xy 79.749945 -388.253177)
			(xy 79.766526 -388.20517) (xy 79.790821 -388.160567) (xy 79.822161 -388.120598) (xy 79.840582 -388.10311)
			(xy 79.848964 -388.09549) (xy 79.8576 -388.075424) (xy 79.854806 -387.97611) (xy 79.845408 -387.956552)
			(xy 79.836518 -387.94944) (xy 79.817974 -387.93362) (xy 79.785255 -387.897492) (xy 79.758187 -387.856957)
			(xy 79.737354 -387.812891) (xy 79.723207 -387.766247) (xy 79.716051 -387.718033) (xy 79.715614 -387.693662)
			(xy 79.716034 -387.669545) (xy 79.72304 -387.621822) (xy 79.736899 -387.575621) (xy 79.757316 -387.531921)
			(xy 79.770224 -387.511544) (xy 79.776066 -387.502654) (xy 79.779622 -387.482588) (xy 79.75854 -387.390386)
			(xy 79.746348 -387.373622) (xy 79.737458 -387.368288) (xy 79.716666 -387.355419) (xy 79.678761 -387.324532)
			(xy 79.645818 -387.288398) (xy 79.618556 -387.247808) (xy 79.597569 -387.203644) (xy 79.583315 -387.156872)
			(xy 79.576105 -387.10851) (xy 79.57566 -387.084062) (xy 79.576219 -387.056778) (xy 79.585169 -387.002949)
			(xy 79.602836 -386.951321) (xy 79.62874 -386.903293) (xy 79.662179 -386.860172) (xy 79.681832 -386.841238)
			(xy 79.689209 -386.833695) (xy 79.69775 -386.814432) (xy 79.698342 -386.8039) (xy 79.698342 -386.729224)
			(xy 79.697801 -386.718676) (xy 79.689273 -386.699381) (xy 79.681832 -386.691886) (xy 79.662198 -386.672935)
			(xy 79.628764 -386.629813) (xy 79.60286 -386.58179) (xy 79.585186 -386.530167) (xy 79.576223 -386.476344)
			(xy 79.57566 -386.449062) (xy 79.57604 -386.425386) (xy 79.582774 -386.378515) (xy 79.596141 -386.333088)
			(xy 79.605632 -386.311394) (xy 79.60995 -386.301996) (xy 79.610712 -386.28193) (xy 79.578454 -386.19557)
			(xy 79.564738 -386.180838) (xy 79.55534 -386.17652) (xy 79.530966 -386.16484) (xy 79.486096 -386.134711)
			(xy 79.446719 -386.097691) (xy 79.413881 -386.054764) (xy 79.388456 -386.007071) (xy 79.371119 -385.955881)
			(xy 79.362331 -385.902553) (xy 79.361792 -385.87553) (xy 77.693888 -385.87553) (xy 77.680654 -385.885145)
			(xy 77.634344 -385.908741) (xy 77.584914 -385.924802) (xy 77.533579 -385.932932) (xy 77.481605 -385.932932)
			(xy 77.43027 -385.924802) (xy 77.38084 -385.908741) (xy 77.33453 -385.885145) (xy 77.292482 -385.854595)
			(xy 77.255731 -385.817844) (xy 77.225181 -385.775796) (xy 77.201585 -385.729486) (xy 77.185524 -385.680056)
			(xy 77.177394 -385.628721) (xy 76.971951 -385.628721) (xy 76.966579 -385.665222) (xy 76.950511 -385.718629)
			(xy 76.926839 -385.769126) (xy 76.896066 -385.815639) (xy 76.858849 -385.857176) (xy 76.815981 -385.892851)
			(xy 76.768375 -385.921905) (xy 76.717046 -385.943717) (xy 76.663089 -385.957823) (xy 76.607652 -385.963923)
			(xy 76.551918 -385.961886) (xy 76.497075 -385.951756) (xy 76.444291 -385.933749) (xy 76.394691 -385.908248)
			(xy 76.349333 -385.875797) (xy 76.309184 -385.837088) (xy 76.275098 -385.792945) (xy 76.247802 -385.74431)
			(xy 76.227879 -385.692219) (xy 76.215753 -385.637782) (xy 76.211682 -385.58216) (xy 71.328333 -385.58216)
			(xy 71.323962 -385.64058) (xy 71.332344 -385.661916) (xy 71.340726 -385.66979) (xy 71.362092 -385.690413)
			(xy 71.400369 -385.735816) (xy 71.433095 -385.785369) (xy 71.459824 -385.838398) (xy 71.480193 -385.89418)
			(xy 71.493922 -385.951956) (xy 71.500827 -386.010938) (xy 71.501254 -386.04063) (xy 71.500789 -386.071361)
			(xy 71.493377 -386.132374) (xy 71.478666 -386.192049) (xy 71.45687 -386.249517) (xy 71.428307 -386.303938)
			(xy 71.393393 -386.35452) (xy 71.352636 -386.400525) (xy 71.306633 -386.441283) (xy 71.256052 -386.476199)
			(xy 71.201631 -386.504764) (xy 71.144165 -386.526562) (xy 71.08449 -386.541275) (xy 71.023477 -386.548688)
			(xy 70.992746 -386.549138) (xy 70.961887 -386.54867) (xy 70.900629 -386.541155) (xy 70.870572 -386.534152)
			(xy 70.86092 -386.531866) (xy 70.842378 -386.534406) (xy 70.764654 -386.577586) (xy 70.752462 -386.592064)
			(xy 70.749414 -386.601462) (xy 70.738517 -386.633427) (xy 70.709442 -386.694382) (xy 70.672544 -386.750946)
			(xy 70.628476 -386.802121) (xy 70.603618 -386.824982) (xy 70.595194 -386.833237) (xy 70.586358 -386.855074)
			(xy 70.588204 -386.878558) (xy 70.593712 -386.88899) (xy 70.606438 -386.91121) (xy 70.62648 -386.958332)
			(xy 70.640042 -387.00771) (xy 70.64688 -387.058459) (xy 70.647306 -387.084062) (xy 70.64682 -387.111313)
			(xy 70.639064 -387.165261) (xy 70.623709 -387.217556) (xy 70.601067 -387.267133) (xy 70.571601 -387.312983)
			(xy 70.53591 -387.354174) (xy 70.494719 -387.389865) (xy 70.448869 -387.419331) (xy 70.399292 -387.441973)
			(xy 70.346997 -387.457328) (xy 70.293049 -387.465084) (xy 70.238547 -387.465084) (xy 70.184599 -387.457328)
			(xy 70.132304 -387.441973) (xy 70.082727 -387.419331) (xy 70.036877 -387.389865) (xy 69.995686 -387.354174)
			(xy 69.959995 -387.312983) (xy 69.930529 -387.267133) (xy 69.907887 -387.217556) (xy 69.892532 -387.165261)
			(xy 69.884776 -387.111313) (xy 69.88429 -387.084062) (xy 69.884705 -387.058459) (xy 69.891552 -387.007712)
			(xy 69.905119 -386.958335) (xy 69.925163 -386.911213) (xy 69.937884 -386.88899) (xy 69.943364 -386.878559)
			(xy 69.945146 -386.85509) (xy 69.93637 -386.833251) (xy 69.927978 -386.824982) (xy 69.904173 -386.803146)
			(xy 69.86172 -386.754455) (xy 69.825777 -386.700779) (xy 69.796923 -386.642982) (xy 69.775622 -386.581996)
			(xy 69.762217 -386.518804) (xy 69.759068 -386.486654) (xy 69.758052 -386.474716) (xy 69.74586 -386.454396)
			(xy 69.657976 -386.398008) (xy 69.634354 -386.395468) (xy 69.623178 -386.399532) (xy 69.591835 -386.410074)
			(xy 69.526699 -386.421445) (xy 69.493638 -386.422138) (xy 69.466381 -386.421678) (xy 69.412422 -386.413924)
			(xy 69.360115 -386.398571) (xy 69.310526 -386.375928) (xy 69.264665 -386.346459) (xy 69.223464 -386.310763)
			(xy 69.187764 -386.269566) (xy 69.15829 -386.223707) (xy 69.135643 -386.17412) (xy 69.120284 -386.121815)
			(xy 69.112525 -386.067857) (xy 69.112525 -386.013343) (xy 69.120284 -385.959385) (xy 69.135643 -385.90708)
			(xy 69.15829 -385.857493) (xy 69.187764 -385.811634) (xy 69.223464 -385.770437) (xy 69.264665 -385.734741)
			(xy 69.310526 -385.705272) (xy 69.360115 -385.682629) (xy 69.412422 -385.667276) (xy 69.466381 -385.659522)
			(xy 69.493638 -385.659122) (xy 69.52144 -385.65962) (xy 69.576457 -385.667681) (xy 69.629722 -385.683643)
			(xy 69.680105 -385.707166) (xy 69.726541 -385.737753) (xy 69.768046 -385.774757) (xy 69.80374 -385.817392)
			(xy 69.832869 -385.864756) (xy 69.854814 -385.915847) (xy 69.862446 -385.942586) (xy 69.865494 -385.954016)
			(xy 69.880988 -385.971796) (xy 69.977508 -386.011928) (xy 70.00113 -386.010404) (xy 70.01129 -386.004562)
			(xy 70.040405 -385.988321) (xy 70.10198 -385.962761) (xy 70.166368 -385.945469) (xy 70.232463 -385.936741)
			(xy 70.265798 -385.936236) (xy 70.296657 -385.9367) (xy 70.357917 -385.944209) (xy 70.387972 -385.951222)
			(xy 70.397624 -385.953508) (xy 70.416166 -385.950968) (xy 70.49389 -385.907788) (xy 70.506082 -385.89331)
			(xy 70.50913 -385.883912) (xy 70.519817 -385.852566) (xy 70.548195 -385.792728) (xy 70.584116 -385.73709)
			(xy 70.626968 -385.686596) (xy 70.676023 -385.642105) (xy 70.702932 -385.6228) (xy 70.71233 -385.616196)
			(xy 70.72376 -385.596384) (xy 70.73138 -385.49453) (xy 70.722998 -385.473194) (xy 70.714616 -385.46532)
			(xy 70.699019 -385.450356) (xy 70.670153 -385.418178) (xy 70.656958 -385.401058) (xy 70.650354 -385.392422)
			(xy 70.632574 -385.382262) (xy 70.537578 -385.371848) (xy 70.51802 -385.377944) (xy 70.509892 -385.384802)
			(xy 70.489097 -385.401927) (xy 70.443598 -385.430767) (xy 70.394494 -385.452919) (xy 70.342762 -385.467941)
			(xy 70.289431 -385.475534) (xy 70.262496 -385.475988) (xy 70.235893 -385.475527) (xy 70.183202 -385.468136)
			(xy 70.132049 -385.453499) (xy 70.083424 -385.431899) (xy 70.03827 -385.403756) (xy 69.997463 -385.369613)
			(xy 69.961794 -385.330134) (xy 69.94652 -385.308348) (xy 69.939042 -385.298365) (xy 69.917066 -385.286628)
			(xy 69.90461 -385.285996) (xy 69.820282 -385.285996) (xy 69.807838 -385.286684) (xy 69.785867 -385.298392)
			(xy 69.778372 -385.308348) (xy 69.763079 -385.330122) (xy 69.727424 -385.369616) (xy 69.686625 -385.403771)
			(xy 69.641475 -385.431923) (xy 69.592849 -385.453526) (xy 69.541694 -385.46816) (xy 69.489 -385.475541)
			(xy 69.462396 -385.475988) (xy 69.435566 -385.475532) (xy 69.382437 -385.468014) (xy 69.330884 -385.453127)
			(xy 69.281925 -385.431165) (xy 69.236526 -385.40256) (xy 69.215762 -385.385564) (xy 69.200776 -385.372864)
			(xy 69.161152 -385.374388) (xy 68.620132 -385.915408) (xy 68.61425 -385.921731) (xy 68.606738 -385.93727)
			(xy 68.604807 -385.954421) (xy 68.606416 -385.962906) (xy 68.629022 -386.059934) (xy 68.646802 -386.079238)
			(xy 68.659248 -386.083556) (xy 68.684067 -386.092456) (xy 68.73118 -386.116127) (xy 68.774587 -386.146057)
			(xy 68.81346 -386.181678) (xy 68.847059 -386.222312) (xy 68.874745 -386.267184) (xy 68.895989 -386.31544)
			(xy 68.910388 -386.366161) (xy 68.917668 -386.418381) (xy 68.918074 -386.444744) (xy 68.917585 -386.471992)
			(xy 68.909823 -386.525933) (xy 68.894464 -386.578221) (xy 68.87182 -386.62779) (xy 68.842352 -386.673633)
			(xy 68.80666 -386.714815) (xy 68.76547 -386.750498) (xy 68.719622 -386.779957) (xy 68.670048 -386.802591)
			(xy 68.617757 -386.81794) (xy 68.563814 -386.82569) (xy 68.536566 -386.826252) (xy 68.510202 -386.825811)
			(xy 68.457976 -386.818556) (xy 68.407247 -386.804175) (xy 68.358983 -386.782942) (xy 68.314104 -386.755262)
			(xy 68.273467 -386.721664) (xy 68.237846 -386.682787) (xy 68.207921 -386.639374) (xy 68.184261 -386.592252)
			(xy 68.175378 -386.567426) (xy 68.17106 -386.55498) (xy 68.151756 -386.5372) (xy 68.054728 -386.514594)
			(xy 68.046243 -386.512985) (xy 68.029091 -386.514911) (xy 68.013554 -386.522428) (xy 68.00723 -386.52831)
			(xy 67.06616 -387.46938) (xy 67.059477 -387.47679) (xy 67.051894 -387.495226) (xy 67.051428 -387.505194)
			(xy 67.051428 -387.7945) (xy 71.957182 -387.7945) (xy 71.961253 -387.738878) (xy 71.973379 -387.684441)
			(xy 71.993302 -387.63235) (xy 72.020598 -387.583715) (xy 72.054684 -387.539572) (xy 72.094833 -387.500863)
			(xy 72.140191 -387.468412) (xy 72.189791 -387.442911) (xy 72.242575 -387.424904) (xy 72.297418 -387.414774)
			(xy 72.353152 -387.412737) (xy 72.408589 -387.418837) (xy 72.462546 -387.432943) (xy 72.513875 -387.454755)
			(xy 72.561481 -387.483809) (xy 72.604349 -387.519484) (xy 72.641566 -387.561021) (xy 72.672339 -387.607534)
			(xy 72.696011 -387.658031) (xy 72.712079 -387.711438) (xy 72.720199 -387.766614) (xy 72.72062 -387.789674)
			(xy 73.42886 -387.789674) (xy 73.42886 -386.926074) (xy 73.4293 -386.898803) (xy 73.437066 -386.844817)
			(xy 73.452436 -386.792485) (xy 73.475097 -386.742873) (xy 73.504587 -386.696991) (xy 73.540307 -386.655773)
			(xy 73.58153 -386.620059) (xy 73.627415 -386.590574) (xy 73.67703 -386.567919) (xy 73.729364 -386.552556)
			(xy 73.783351 -386.544797) (xy 73.810622 -386.544312) (xy 73.825737 -386.544475) (xy 73.855872 -386.546891)
			(xy 73.87082 -386.549138) (xy 73.881488 -386.550916) (xy 73.902316 -386.545328) (xy 73.978008 -386.484622)
			(xy 73.98766 -386.465572) (xy 73.988168 -386.45465) (xy 73.990422 -386.425847) (xy 74.002411 -386.369335)
			(xy 74.02278 -386.315274) (xy 74.051062 -386.2649) (xy 74.086612 -386.219364) (xy 74.128618 -386.179704)
			(xy 74.17612 -386.146827) (xy 74.228035 -386.121484) (xy 74.283176 -386.104252) (xy 74.340283 -386.095527)
			(xy 74.369168 -386.094986) (xy 74.396422 -386.095459) (xy 74.450375 -386.103212) (xy 74.502676 -386.118565)
			(xy 74.55226 -386.141206) (xy 74.598116 -386.170672) (xy 74.639312 -386.206365) (xy 74.675009 -386.247558)
			(xy 74.704479 -386.293412) (xy 74.727123 -386.342994) (xy 74.742481 -386.395293) (xy 74.750239 -386.449246)
			(xy 74.750239 -386.489448) (xy 77.278738 -386.489448) (xy 77.279248 -386.463461) (xy 77.287378 -386.412126)
			(xy 77.303439 -386.362696) (xy 77.327035 -386.316386) (xy 77.357585 -386.274338) (xy 77.394336 -386.237587)
			(xy 77.436384 -386.207037) (xy 77.482694 -386.183441) (xy 77.532124 -386.16738) (xy 77.583459 -386.15925)
			(xy 77.635433 -386.15925) (xy 77.686768 -386.16738) (xy 77.736198 -386.183441) (xy 77.782508 -386.207037)
			(xy 77.824556 -386.237587) (xy 77.861307 -386.274338) (xy 77.891857 -386.316386) (xy 77.915453 -386.362696)
			(xy 77.931514 -386.412126) (xy 77.939644 -386.463461) (xy 77.940154 -386.489448) (xy 77.939606 -386.516777)
			(xy 77.930613 -386.570689) (xy 77.912878 -386.62239) (xy 77.886886 -386.670472) (xy 77.870558 -386.692394)
			(xy 77.86497 -386.69976) (xy 77.859382 -386.716524) (xy 77.862938 -386.800598) (xy 77.869796 -386.816854)
			(xy 77.875892 -386.823712) (xy 77.89227 -386.842116) (xy 77.919923 -386.882887) (xy 77.941226 -386.927307)
			(xy 77.955708 -386.974394) (xy 77.96305 -387.023108) (xy 77.963522 -387.04774) (xy 77.963012 -387.073727)
			(xy 77.954882 -387.125062) (xy 77.938821 -387.174492) (xy 77.915225 -387.220802) (xy 77.884675 -387.26285)
			(xy 77.847924 -387.299601) (xy 77.805876 -387.330151) (xy 77.759566 -387.353747) (xy 77.710136 -387.369808)
			(xy 77.658801 -387.377938) (xy 77.606827 -387.377938) (xy 77.555492 -387.369808) (xy 77.506062 -387.353747)
			(xy 77.459752 -387.330151) (xy 77.417704 -387.299601) (xy 77.380953 -387.26285) (xy 77.350403 -387.220802)
			(xy 77.326807 -387.174492) (xy 77.310746 -387.125062) (xy 77.302616 -387.073727) (xy 77.302106 -387.04774)
			(xy 77.302689 -387.020413) (xy 77.31167 -386.966501) (xy 77.329393 -386.9148) (xy 77.355378 -386.866717)
			(xy 77.371702 -386.844794) (xy 77.37729 -386.837428) (xy 77.382878 -386.820664) (xy 77.379322 -386.73659)
			(xy 77.372464 -386.720334) (xy 77.366368 -386.713476) (xy 77.350025 -386.695043) (xy 77.322369 -386.654279)
			(xy 77.30106 -386.609866) (xy 77.286569 -386.562786) (xy 77.279216 -386.514078) (xy 77.278738 -386.489448)
			(xy 74.750239 -386.489448) (xy 74.750239 -386.503754) (xy 74.742481 -386.557707) (xy 74.727123 -386.610006)
			(xy 74.704479 -386.659588) (xy 74.675009 -386.705442) (xy 74.639312 -386.746635) (xy 74.598116 -386.782328)
			(xy 74.55226 -386.811794) (xy 74.502676 -386.834435) (xy 74.450375 -386.849788) (xy 74.396422 -386.857541)
			(xy 74.369168 -386.858002) (xy 74.346661 -386.857658) (xy 74.301967 -386.852306) (xy 74.280014 -386.847334)
			(xy 74.268525 -386.845217) (xy 74.245766 -386.850361) (xy 74.236326 -386.85724) (xy 74.21118 -386.87756)
			(xy 74.202376 -386.885287) (xy 74.192466 -386.906488) (xy 74.19213 -386.9182) (xy 74.192384 -386.926074)
			(xy 74.192384 -387.789674) (xy 74.191757 -387.820816) (xy 74.181585 -387.882263) (xy 74.161556 -387.941239)
			(xy 74.147426 -387.968998) (xy 74.142346 -387.978904) (xy 74.140822 -388.000494) (xy 74.175366 -388.092442)
			(xy 74.190606 -388.107936) (xy 74.200766 -388.111746) (xy 74.227437 -388.122441) (xy 74.277454 -388.150733)
			(xy 74.322655 -388.186213) (xy 74.362017 -388.228079) (xy 74.394646 -388.27538) (xy 74.419802 -388.327044)
			(xy 74.428858 -388.354316) (xy 74.432668 -388.367016) (xy 74.451464 -388.384796) (xy 74.560176 -388.413752)
			(xy 74.585068 -388.407656) (xy 74.59472 -388.398512) (xy 74.618314 -388.377319) (xy 74.669812 -388.340304)
			(xy 74.725516 -388.309984) (xy 74.78456 -388.286831) (xy 74.846025 -388.271204) (xy 74.908957 -388.263346)
			(xy 74.940668 -388.262876) (xy 74.972631 -388.263387) (xy 75.036052 -388.271395) (xy 75.09797 -388.28729)
			(xy 75.124201 -388.297674) (xy 76.33665 -388.297674) (xy 76.340721 -388.242052) (xy 76.352847 -388.187615)
			(xy 76.37277 -388.135524) (xy 76.400066 -388.086889) (xy 76.434152 -388.042746) (xy 76.474301 -388.004037)
			(xy 76.519659 -387.971586) (xy 76.569259 -387.946085) (xy 76.622043 -387.928078) (xy 76.676886 -387.917948)
			(xy 76.73262 -387.915911) (xy 76.788057 -387.922011) (xy 76.842014 -387.936117) (xy 76.893343 -387.957929)
			(xy 76.940949 -387.986983) (xy 76.983817 -388.022658) (xy 77.021034 -388.064195) (xy 77.051807 -388.110708)
			(xy 77.075479 -388.161205) (xy 77.091547 -388.214612) (xy 77.099667 -388.269788) (xy 77.100176 -388.297674)
			(xy 77.099729 -388.322137) (xy 77.302616 -388.322137) (xy 77.302616 -388.270163) (xy 77.310746 -388.218828)
			(xy 77.326807 -388.169398) (xy 77.350403 -388.123088) (xy 77.380953 -388.08104) (xy 77.417704 -388.044289)
			(xy 77.459752 -388.013739) (xy 77.506062 -387.990143) (xy 77.555492 -387.974082) (xy 77.606827 -387.965952)
			(xy 77.658801 -387.965952) (xy 77.710136 -387.974082) (xy 77.759566 -387.990143) (xy 77.805876 -388.013739)
			(xy 77.847924 -388.044289) (xy 77.884675 -388.08104) (xy 77.915225 -388.123088) (xy 77.938821 -388.169398)
			(xy 77.954882 -388.218828) (xy 77.963012 -388.270163) (xy 77.963522 -388.29615) (xy 77.963012 -388.322137)
			(xy 77.954882 -388.373472) (xy 77.938821 -388.422902) (xy 77.915225 -388.469212) (xy 77.884675 -388.51126)
			(xy 77.847924 -388.548011) (xy 77.805876 -388.578561) (xy 77.759566 -388.602157) (xy 77.710136 -388.618218)
			(xy 77.658801 -388.626348) (xy 77.606827 -388.626348) (xy 77.555492 -388.618218) (xy 77.506062 -388.602157)
			(xy 77.459752 -388.578561) (xy 77.417704 -388.548011) (xy 77.380953 -388.51126) (xy 77.350403 -388.469212)
			(xy 77.326807 -388.422902) (xy 77.310746 -388.373472) (xy 77.302616 -388.322137) (xy 77.099729 -388.322137)
			(xy 77.099667 -388.32556) (xy 77.091547 -388.380736) (xy 77.075479 -388.434143) (xy 77.051807 -388.48464)
			(xy 77.021034 -388.531153) (xy 76.983817 -388.57269) (xy 76.940949 -388.608365) (xy 76.893343 -388.637419)
			(xy 76.842014 -388.659231) (xy 76.788057 -388.673337) (xy 76.73262 -388.679437) (xy 76.676886 -388.6774)
			(xy 76.622043 -388.66727) (xy 76.569259 -388.649263) (xy 76.519659 -388.623762) (xy 76.474301 -388.591311)
			(xy 76.434152 -388.552602) (xy 76.400066 -388.508459) (xy 76.37277 -388.459824) (xy 76.352847 -388.407733)
			(xy 76.340721 -388.353296) (xy 76.33665 -388.297674) (xy 75.124201 -388.297674) (xy 75.157407 -388.310819)
			(xy 75.213427 -388.341613) (xy 75.265145 -388.379185) (xy 75.311746 -388.422944) (xy 75.352495 -388.472198)
			(xy 75.386749 -388.526171) (xy 75.413968 -388.584012) (xy 75.433723 -388.644808) (xy 75.445701 -388.707601)
			(xy 75.449716 -388.7714) (xy 75.445701 -388.835199) (xy 75.433723 -388.897992) (xy 75.413968 -388.958788)
			(xy 75.386749 -389.016629) (xy 75.352495 -389.070602) (xy 75.311746 -389.119856) (xy 75.265145 -389.163615)
			(xy 75.213427 -389.201187) (xy 75.157407 -389.231981) (xy 75.09797 -389.25551) (xy 75.036052 -389.271405)
			(xy 74.972631 -389.279413) (xy 74.940668 -389.279892) (xy 74.909581 -389.279395) (xy 74.84787 -389.271809)
			(xy 74.787546 -389.256752) (xy 74.729508 -389.234452) (xy 74.674623 -389.205239) (xy 74.623711 -389.16955)
			(xy 74.600308 -389.149082) (xy 74.590402 -389.140192) (xy 74.564494 -389.13435) (xy 74.455782 -389.166862)
			(xy 74.43724 -389.186166) (xy 74.433938 -389.19912) (xy 74.426478 -389.226028) (xy 74.404678 -389.277436)
			(xy 74.375622 -389.325119) (xy 74.339928 -389.36806) (xy 74.29836 -389.405344) (xy 74.251803 -389.436173)
			(xy 74.201252 -389.45989) (xy 74.147784 -389.47599) (xy 74.092541 -389.484128) (xy 74.064622 -389.484616)
			(xy 74.03737 -389.484124) (xy 73.983421 -389.47637) (xy 73.931124 -389.461018) (xy 73.881544 -389.438378)
			(xy 73.835691 -389.408913) (xy 73.794499 -389.373223) (xy 73.758805 -389.332033) (xy 73.729336 -389.286182)
			(xy 73.706693 -389.236604) (xy 73.691336 -389.184309) (xy 73.683578 -389.13036) (xy 73.683114 -389.103108)
			(xy 73.683581 -389.075738) (xy 73.691398 -389.021559) (xy 73.706887 -388.969055) (xy 73.729728 -388.919308)
			(xy 73.759453 -388.873342) (xy 73.777094 -388.85241) (xy 73.78319 -388.845298) (xy 73.78954 -388.82828)
			(xy 73.78954 -388.742936) (xy 73.78319 -388.725918) (xy 73.777094 -388.718806) (xy 73.759443 -388.697883)
			(xy 73.729733 -388.651908) (xy 73.7069 -388.602158) (xy 73.691411 -388.549655) (xy 73.683586 -388.495478)
			(xy 73.683114 -388.468108) (xy 73.683726 -388.436977) (xy 73.693795 -388.375535) (xy 73.713731 -388.316552)
			(xy 73.727818 -388.288784) (xy 73.732898 -388.279132) (xy 73.734422 -388.257542) (xy 73.700132 -388.165594)
			(xy 73.684638 -388.1501) (xy 73.674478 -388.14629) (xy 73.647768 -388.135527) (xy 73.59766 -388.107154)
			(xy 73.552383 -388.071575) (xy 73.512965 -388.029597) (xy 73.480301 -387.982174) (xy 73.455132 -387.930382)
			(xy 73.43803 -387.875397) (xy 73.429383 -387.818466) (xy 73.42886 -387.789674) (xy 72.72062 -387.789674)
			(xy 72.720708 -387.7945) (xy 72.720199 -387.822386) (xy 72.712079 -387.877562) (xy 72.696011 -387.930969)
			(xy 72.672339 -387.981466) (xy 72.641566 -388.027979) (xy 72.604349 -388.069516) (xy 72.561481 -388.105191)
			(xy 72.513875 -388.134245) (xy 72.462546 -388.156057) (xy 72.408589 -388.170163) (xy 72.353152 -388.176263)
			(xy 72.297418 -388.174226) (xy 72.242575 -388.164096) (xy 72.189791 -388.146089) (xy 72.140191 -388.120588)
			(xy 72.094833 -388.088137) (xy 72.054684 -388.049428) (xy 72.020598 -388.005285) (xy 71.993302 -387.95665)
			(xy 71.973379 -387.904559) (xy 71.961253 -387.850122) (xy 71.957182 -387.7945) (xy 67.051428 -387.7945)
			(xy 67.051428 -390.034018) (xy 67.054476 -390.042908) (xy 67.064523 -390.071134) (xy 67.075385 -390.130049)
			(xy 67.076066 -390.160002) (xy 67.075368 -390.189953) (xy 67.064502 -390.248864) (xy 67.054476 -390.277096)
			(xy 67.051428 -390.285986) (xy 67.051428 -390.819132) (xy 67.369944 -390.819132) (xy 67.370476 -390.79154)
			(xy 67.379631 -390.737121) (xy 67.397694 -390.684976) (xy 67.424161 -390.636554) (xy 67.4583 -390.593197)
			(xy 67.499162 -390.556109) (xy 67.52209 -390.540748) (xy 67.52965 -390.53548) (xy 67.540722 -390.520772)
			(xy 67.54368 -390.512046) (xy 67.552316 -390.482074) (xy 67.554529 -390.473126) (xy 67.553085 -390.454762)
			(xy 67.549522 -390.44626) (xy 67.539734 -390.424287) (xy 67.525935 -390.378206) (xy 67.518965 -390.330611)
			(xy 67.518534 -390.30656) (xy 67.518967 -390.282787) (xy 67.525763 -390.235729) (xy 67.539238 -390.190132)
			(xy 67.559112 -390.146939) (xy 67.584975 -390.107042) (xy 67.600322 -390.088882) (xy 67.605992 -390.081751)
			(xy 67.612386 -390.064709) (xy 67.612768 -390.055608) (xy 67.612768 -390.024112) (xy 67.612374 -390.015011)
			(xy 67.606 -389.997961) (xy 67.600322 -389.990838) (xy 67.584991 -389.972665) (xy 67.559133 -389.932767)
			(xy 67.539255 -389.889577) (xy 67.525769 -389.843985) (xy 67.518951 -389.796932) (xy 67.518534 -389.77316)
			(xy 67.518927 -389.74875) (xy 67.526123 -389.700462) (xy 67.540337 -389.653756) (xy 67.561261 -389.609646)
			(xy 67.588441 -389.56909) (xy 67.621286 -389.532969) (xy 67.659084 -389.502068) (xy 67.679824 -389.489188)
			(xy 67.691254 -389.48233) (xy 67.704462 -389.459216) (xy 67.704462 -389.344916) (xy 67.691508 -389.321802)
			(xy 67.679824 -389.31469) (xy 67.659109 -389.301821) (xy 67.621367 -389.270939) (xy 67.588575 -389.234845)
			(xy 67.561443 -389.194323) (xy 67.540563 -389.150253) (xy 67.526386 -389.103592) (xy 67.519223 -389.055355)
			(xy 67.518788 -389.030972) (xy 67.519362 -389.003351) (xy 67.528538 -388.948878) (xy 67.546629 -388.896683)
			(xy 67.573135 -388.848216) (xy 67.607319 -388.804822) (xy 67.648233 -388.767705) (xy 67.671188 -388.752334)
			(xy 67.682618 -388.745222) (xy 67.695064 -388.7216) (xy 67.691508 -388.6073) (xy 67.677792 -388.584694)
			(xy 67.665854 -388.57809) (xy 67.644174 -388.565431) (xy 67.604515 -388.534653) (xy 67.569967 -388.498231)
			(xy 67.541325 -388.457005) (xy 67.519245 -388.41192) (xy 67.504238 -388.364015) (xy 67.496648 -388.314392)
			(xy 67.496182 -388.289292) (xy 67.496692 -388.263305) (xy 67.504822 -388.21197) (xy 67.520883 -388.16254)
			(xy 67.544479 -388.11623) (xy 67.575029 -388.074182) (xy 67.61178 -388.037431) (xy 67.653828 -388.006881)
			(xy 67.700138 -387.983285) (xy 67.749568 -387.967224) (xy 67.800903 -387.959094) (xy 67.852877 -387.959094)
			(xy 67.904212 -387.967224) (xy 67.953642 -387.983285) (xy 67.999952 -388.006881) (xy 68.042 -388.037431)
			(xy 68.078751 -388.074182) (xy 68.109301 -388.11623) (xy 68.132897 -388.16254) (xy 68.148958 -388.21197)
			(xy 68.157088 -388.263305) (xy 68.157598 -388.289292) (xy 68.157079 -388.316915) (xy 68.147892 -388.371392)
			(xy 68.12979 -388.423588) (xy 68.103274 -388.472055) (xy 68.06908 -388.515447) (xy 68.028157 -388.552561)
			(xy 68.005198 -388.56793) (xy 67.993768 -388.575042) (xy 67.981322 -388.598664) (xy 67.984878 -388.712964)
			(xy 67.998594 -388.73557) (xy 68.010532 -388.742174) (xy 68.032237 -388.754793) (xy 68.071896 -388.785577)
			(xy 68.106444 -388.822005) (xy 68.135084 -388.863238) (xy 68.157159 -388.90833) (xy 68.160734 -388.919747)
			(xy 68.38192 -388.919747) (xy 68.38192 -388.865253) (xy 68.389675 -388.811313) (xy 68.405028 -388.759025)
			(xy 68.427665 -388.709455) (xy 68.457126 -388.663611) (xy 68.492811 -388.622426) (xy 68.533995 -388.586738)
			(xy 68.579837 -388.557274) (xy 68.629407 -388.534635) (xy 68.681693 -388.519279) (xy 68.735633 -388.511522)
			(xy 68.76288 -388.511034) (xy 68.79025 -388.511504) (xy 68.844429 -388.519319) (xy 68.896933 -388.534807)
			(xy 68.94668 -388.557648) (xy 68.992647 -388.587373) (xy 69.013578 -388.605014) (xy 69.02069 -388.61111)
			(xy 69.037708 -388.61746) (xy 69.123052 -388.61746) (xy 69.14007 -388.61111) (xy 69.147182 -388.605014)
			(xy 69.168115 -388.587373) (xy 69.214083 -388.557649) (xy 69.263829 -388.534803) (xy 69.316331 -388.519307)
			(xy 69.370509 -388.511478) (xy 69.425251 -388.511478) (xy 69.479429 -388.519307) (xy 69.531931 -388.534803)
			(xy 69.581677 -388.557649) (xy 69.627645 -388.587373) (xy 69.648578 -388.605014) (xy 69.65569 -388.61111)
			(xy 69.672708 -388.61746) (xy 69.758052 -388.61746) (xy 69.77507 -388.61111) (xy 69.782182 -388.605014)
			(xy 69.803112 -388.587372) (xy 69.849085 -388.55766) (xy 69.898833 -388.534825) (xy 69.951334 -388.519334)
			(xy 70.005511 -388.511507) (xy 70.03288 -388.511034) (xy 70.060137 -388.511412) (xy 70.114096 -388.519167)
			(xy 70.166402 -388.534523) (xy 70.21599 -388.557167) (xy 70.261851 -388.586638) (xy 70.30305 -388.622335)
			(xy 70.33875 -388.663533) (xy 70.368223 -388.709392) (xy 70.39087 -388.758979) (xy 70.40243 -388.798348)
			(xy 71.741308 -388.798348) (xy 71.741308 -388.743852) (xy 71.749064 -388.68991) (xy 71.764417 -388.63762)
			(xy 71.787055 -388.588048) (xy 71.816517 -388.542202) (xy 71.852204 -388.501016) (xy 71.893389 -388.465327)
			(xy 71.939234 -388.435863) (xy 71.988805 -388.413222) (xy 72.041094 -388.397867) (xy 72.095036 -388.390109)
			(xy 72.122284 -388.389622) (xy 72.149654 -388.390092) (xy 72.203833 -388.397908) (xy 72.256337 -388.413396)
			(xy 72.306083 -388.436237) (xy 72.35205 -388.465961) (xy 72.372982 -388.483602) (xy 72.380094 -388.489698)
			(xy 72.397112 -388.496048) (xy 72.482456 -388.496048) (xy 72.499474 -388.489698) (xy 72.506586 -388.483602)
			(xy 72.527513 -388.465956) (xy 72.573487 -388.436245) (xy 72.623236 -388.413411) (xy 72.675738 -388.397921)
			(xy 72.729914 -388.390095) (xy 72.757284 -388.389622) (xy 72.78454 -388.390024) (xy 72.838497 -388.39778)
			(xy 72.890801 -388.413135) (xy 72.940387 -388.435779) (xy 72.986246 -388.465249) (xy 73.027443 -388.500945)
			(xy 73.063142 -388.542142) (xy 73.092613 -388.587999) (xy 73.115259 -388.637584) (xy 73.130617 -388.689888)
			(xy 73.138375 -388.743844) (xy 73.138375 -388.798356) (xy 73.130617 -388.852312) (xy 73.115259 -388.904616)
			(xy 73.092613 -388.954201) (xy 73.063142 -389.000058) (xy 73.027443 -389.041255) (xy 72.986246 -389.076951)
			(xy 72.940387 -389.106421) (xy 72.890801 -389.129065) (xy 72.838497 -389.14442) (xy 72.78454 -389.152176)
			(xy 72.757284 -389.152638) (xy 72.729913 -389.152196) (xy 72.675732 -389.144375) (xy 72.623228 -389.128881)
			(xy 72.573481 -389.106033) (xy 72.527516 -389.076303) (xy 72.506586 -389.058658) (xy 72.499474 -389.052562)
			(xy 72.482456 -389.046212) (xy 72.397112 -389.046212) (xy 72.380094 -389.052562) (xy 72.372982 -389.058658)
			(xy 72.352024 -389.076266) (xy 72.306059 -389.105984) (xy 72.256318 -389.128826) (xy 72.203823 -389.144325)
			(xy 72.149652 -389.15216) (xy 72.122284 -389.152638) (xy 72.095036 -389.152091) (xy 72.041094 -389.144333)
			(xy 71.988805 -389.128978) (xy 71.939234 -389.106337) (xy 71.893389 -389.076873) (xy 71.852204 -389.041184)
			(xy 71.816517 -388.999998) (xy 71.787055 -388.954152) (xy 71.764417 -388.90458) (xy 71.749064 -388.85229)
			(xy 71.741308 -388.798348) (xy 70.40243 -388.798348) (xy 70.406229 -388.811285) (xy 70.413987 -388.865243)
			(xy 70.413987 -388.919757) (xy 70.406229 -388.973715) (xy 70.39087 -389.026021) (xy 70.368223 -389.075608)
			(xy 70.33875 -389.121467) (xy 70.30305 -389.162665) (xy 70.261851 -389.198362) (xy 70.21599 -389.227833)
			(xy 70.166402 -389.250477) (xy 70.114096 -389.265833) (xy 70.060137 -389.273588) (xy 70.03288 -389.27405)
			(xy 70.005509 -389.273608) (xy 69.951328 -389.265786) (xy 69.898824 -389.250292) (xy 69.849078 -389.227445)
			(xy 69.803112 -389.197714) (xy 69.782182 -389.18007) (xy 69.77507 -389.173974) (xy 69.758052 -389.167624)
			(xy 69.672708 -389.167624) (xy 69.65569 -389.173974) (xy 69.648578 -389.18007) (xy 69.627645 -389.197711)
			(xy 69.581677 -389.227435) (xy 69.531931 -389.250281) (xy 69.479429 -389.265777) (xy 69.425251 -389.273606)
			(xy 69.370509 -389.273606) (xy 69.316331 -389.265777) (xy 69.263829 -389.250281) (xy 69.214083 -389.227435)
			(xy 69.168115 -389.197711) (xy 69.147182 -389.18007) (xy 69.14007 -389.173974) (xy 69.123052 -389.167624)
			(xy 69.037708 -389.167624) (xy 69.02069 -389.173974) (xy 69.013578 -389.18007) (xy 68.992623 -389.197681)
			(xy 68.946657 -389.227398) (xy 68.896916 -389.25024) (xy 68.84442 -389.265738) (xy 68.790248 -389.273573)
			(xy 68.76288 -389.27405) (xy 68.735633 -389.273478) (xy 68.681693 -389.265721) (xy 68.629407 -389.250365)
			(xy 68.579837 -389.227726) (xy 68.533995 -389.198262) (xy 68.492811 -389.162574) (xy 68.457126 -389.121389)
			(xy 68.427665 -389.075545) (xy 68.405028 -389.025975) (xy 68.389675 -388.973687) (xy 68.38192 -388.919747)
			(xy 68.160734 -388.919747) (xy 68.17216 -388.956241) (xy 68.179743 -389.00587) (xy 68.180204 -389.030972)
			(xy 68.179739 -389.05538) (xy 68.172554 -389.103663) (xy 68.158351 -389.150367) (xy 68.137438 -389.194476)
			(xy 68.11027 -389.235033) (xy 68.077436 -389.271156) (xy 68.039649 -389.302061) (xy 68.018914 -389.314944)
			(xy 68.007484 -389.321802) (xy 67.994276 -389.344916) (xy 67.994276 -389.459216) (xy 68.00723 -389.48233)
			(xy 68.018914 -389.489442) (xy 68.039607 -389.502344) (xy 68.077347 -389.533222) (xy 68.11014 -389.569311)
			(xy 68.137273 -389.609828) (xy 68.158157 -389.653892) (xy 68.172339 -389.700547) (xy 68.179511 -389.748779)
			(xy 68.17995 -389.77316) (xy 68.179532 -389.796934) (xy 68.172733 -389.843993) (xy 68.159256 -389.88959)
			(xy 68.139378 -389.932783) (xy 68.113511 -389.972678) (xy 68.098162 -389.990838) (xy 68.092482 -389.997962)
			(xy 68.086094 -390.015009) (xy 68.085716 -390.024112) (xy 68.085716 -390.055608) (xy 68.086104 -390.064709)
			(xy 68.092483 -390.08176) (xy 68.098162 -390.088882) (xy 68.1135 -390.10705) (xy 68.139358 -390.146949)
			(xy 68.159234 -390.19014) (xy 68.172719 -390.235733) (xy 68.179535 -390.282787) (xy 68.17995 -390.30656)
			(xy 68.179415 -390.334152) (xy 68.174217 -390.365051) (xy 70.12228 -390.365051) (xy 70.12228 -390.310549)
			(xy 70.130036 -390.256603) (xy 70.14539 -390.20431) (xy 70.16803 -390.154733) (xy 70.197496 -390.108884)
			(xy 70.233186 -390.067694) (xy 70.274374 -390.032003) (xy 70.320223 -390.002536) (xy 70.369798 -389.979895)
			(xy 70.422091 -389.964538) (xy 70.476037 -389.956781) (xy 70.503288 -389.956294) (xy 70.530658 -389.956769)
			(xy 70.584837 -389.964585) (xy 70.63734 -389.980072) (xy 70.687087 -390.002912) (xy 70.733054 -390.032634)
			(xy 70.753986 -390.050274) (xy 70.761098 -390.05637) (xy 70.778116 -390.06272) (xy 70.86346 -390.06272)
			(xy 70.880478 -390.05637) (xy 70.88759 -390.050274) (xy 70.908512 -390.032622) (xy 70.954488 -390.002913)
			(xy 71.004238 -389.98008) (xy 71.056741 -389.964592) (xy 71.110918 -389.956767) (xy 71.138288 -389.956294)
			(xy 71.165542 -389.956753) (xy 71.219494 -389.964508) (xy 71.271794 -389.979863) (xy 71.321376 -390.002505)
			(xy 71.36723 -390.031973) (xy 71.408425 -390.067667) (xy 71.44412 -390.10886) (xy 71.473589 -390.154714)
			(xy 71.496233 -390.204295) (xy 71.511589 -390.256594) (xy 71.519347 -390.310546) (xy 71.519347 -390.365054)
			(xy 71.511589 -390.419006) (xy 71.496233 -390.471305) (xy 71.473589 -390.520886) (xy 71.44412 -390.56674)
			(xy 71.408425 -390.607933) (xy 71.36723 -390.643627) (xy 71.321376 -390.673095) (xy 71.271794 -390.695737)
			(xy 71.219494 -390.711092) (xy 71.165542 -390.718847) (xy 71.138288 -390.71931) (xy 71.110918 -390.718849)
			(xy 71.056738 -390.711029) (xy 71.004235 -390.695539) (xy 70.954489 -390.672696) (xy 70.908522 -390.642971)
			(xy 70.88759 -390.62533) (xy 70.880478 -390.619234) (xy 70.86346 -390.612884) (xy 70.778116 -390.612884)
			(xy 70.761098 -390.619234) (xy 70.753986 -390.62533) (xy 70.733036 -390.642947) (xy 70.687068 -390.672661)
			(xy 70.637325 -390.695501) (xy 70.584828 -390.710997) (xy 70.530656 -390.718832) (xy 70.503288 -390.71931)
			(xy 70.476037 -390.718819) (xy 70.422091 -390.711062) (xy 70.369798 -390.695705) (xy 70.320223 -390.673064)
			(xy 70.274374 -390.643597) (xy 70.233186 -390.607906) (xy 70.197496 -390.566716) (xy 70.16803 -390.520867)
			(xy 70.14539 -390.47129) (xy 70.130036 -390.418997) (xy 70.12228 -390.365051) (xy 68.174217 -390.365051)
			(xy 68.17026 -390.388571) (xy 68.152199 -390.440716) (xy 68.125732 -390.489138) (xy 68.091594 -390.532495)
			(xy 68.050731 -390.569583) (xy 68.027804 -390.584944) (xy 68.020245 -390.590213) (xy 68.009173 -390.604921)
			(xy 68.006214 -390.613646) (xy 67.997578 -390.643618) (xy 67.995369 -390.652567) (xy 67.99681 -390.67093)
			(xy 68.000372 -390.679432) (xy 68.010157 -390.701407) (xy 68.023957 -390.747487) (xy 68.030929 -390.795081)
			(xy 68.03136 -390.819132) (xy 68.03085 -390.845119) (xy 68.02272 -390.896454) (xy 68.006659 -390.945884)
			(xy 67.983063 -390.992194) (xy 67.952513 -391.034242) (xy 67.915762 -391.070993) (xy 67.873714 -391.101543)
			(xy 67.827404 -391.125139) (xy 67.777974 -391.1412) (xy 67.726639 -391.14933) (xy 67.674665 -391.14933)
			(xy 67.62333 -391.1412) (xy 67.5739 -391.125139) (xy 67.52759 -391.101543) (xy 67.485542 -391.070993)
			(xy 67.448791 -391.034242) (xy 67.418241 -390.992194) (xy 67.394645 -390.945884) (xy 67.378584 -390.896454)
			(xy 67.370454 -390.845119) (xy 67.369944 -390.819132) (xy 67.051428 -390.819132) (xy 67.051428 -391.483088)
			(xy 67.050894 -391.493077) (xy 67.043186 -391.511515) (xy 67.036442 -391.518902) (xy 67.0306 -391.524744)
			(xy 67.02298 -391.543286) (xy 67.02298 -392.714226) (xy 67.51142 -392.714226) (xy 67.515491 -392.658604)
			(xy 67.527617 -392.604167) (xy 67.54754 -392.552076) (xy 67.574836 -392.503441) (xy 67.608922 -392.459298)
			(xy 67.649071 -392.420589) (xy 67.694429 -392.388138) (xy 67.744029 -392.362637) (xy 67.796813 -392.34463)
			(xy 67.851656 -392.3345) (xy 67.90739 -392.332463) (xy 67.962827 -392.338563) (xy 68.016784 -392.352669)
			(xy 68.068113 -392.374481) (xy 68.115719 -392.403535) (xy 68.158587 -392.43921) (xy 68.195804 -392.480747)
			(xy 68.226577 -392.52726) (xy 68.250249 -392.577757) (xy 68.266317 -392.631164) (xy 68.274437 -392.68634)
			(xy 68.274946 -392.714226) (xy 68.274437 -392.742112) (xy 68.266317 -392.797288) (xy 68.250249 -392.850695)
			(xy 68.226577 -392.901192) (xy 68.195804 -392.947705) (xy 68.158587 -392.989242) (xy 68.115719 -393.024917)
			(xy 68.068113 -393.053971) (xy 68.016784 -393.075783) (xy 67.962827 -393.089889) (xy 67.90739 -393.095989)
			(xy 67.851656 -393.093952) (xy 67.796813 -393.083822) (xy 67.744029 -393.065815) (xy 67.694429 -393.040314)
			(xy 67.649071 -393.007863) (xy 67.608922 -392.969154) (xy 67.574836 -392.925011) (xy 67.54754 -392.876376)
			(xy 67.527617 -392.824285) (xy 67.515491 -392.769848) (xy 67.51142 -392.714226) (xy 67.02298 -392.714226)
			(xy 67.02298 -393.335002) (xy 68.233288 -393.335002) (xy 68.237359 -393.27938) (xy 68.249485 -393.224943)
			(xy 68.269408 -393.172852) (xy 68.296704 -393.124217) (xy 68.33079 -393.080074) (xy 68.370939 -393.041365)
			(xy 68.416297 -393.008914) (xy 68.465897 -392.983413) (xy 68.518681 -392.965406) (xy 68.573524 -392.955276)
			(xy 68.629258 -392.953239) (xy 68.684695 -392.959339) (xy 68.738652 -392.973445) (xy 68.789981 -392.995257)
			(xy 68.837587 -393.024311) (xy 68.880455 -393.059986) (xy 68.917672 -393.101523) (xy 68.948445 -393.148036)
			(xy 68.972117 -393.198533) (xy 68.988185 -393.25194) (xy 68.996305 -393.307116) (xy 68.996814 -393.335002)
			(xy 68.996305 -393.362888) (xy 68.988185 -393.418064) (xy 68.972117 -393.471471) (xy 68.948932 -393.52093)
			(xy 69.226176 -393.52093) (xy 69.226637 -393.490233) (xy 69.234043 -393.429288) (xy 69.248738 -393.369679)
			(xy 69.270509 -393.312276) (xy 69.299037 -393.257913) (xy 69.316092 -393.232386) (xy 69.321539 -393.223621)
			(xy 69.325677 -393.203425) (xy 69.321559 -393.183225) (xy 69.316092 -393.174474) (xy 69.299047 -393.148943)
			(xy 69.270539 -393.094573) (xy 69.248778 -393.037169) (xy 69.23408 -392.977564) (xy 69.226656 -392.916625)
			(xy 69.226176 -392.88593) (xy 69.226666 -392.855199) (xy 69.234071 -392.794185) (xy 69.248776 -392.734509)
			(xy 69.270568 -392.67704) (xy 69.299128 -392.622617) (xy 69.334039 -392.572033) (xy 69.374794 -392.526027)
			(xy 69.420797 -392.485268) (xy 69.471377 -392.450352) (xy 69.525798 -392.421787) (xy 69.583265 -392.39999)
			(xy 69.64294 -392.385279) (xy 69.703953 -392.377869) (xy 69.734684 -392.377422) (xy 69.765381 -392.377868)
			(xy 69.826327 -392.385276) (xy 69.885936 -392.399974) (xy 69.94334 -392.421749) (xy 69.997702 -392.450281)
			(xy 70.023228 -392.467338) (xy 70.03198 -392.472809) (xy 70.052184 -392.476937) (xy 70.072388 -392.472809)
			(xy 70.08114 -392.467338) (xy 70.106671 -392.450292) (xy 70.161041 -392.421784) (xy 70.218444 -392.400022)
			(xy 70.278049 -392.385324) (xy 70.338989 -392.377902) (xy 70.369684 -392.377422) (xy 70.400381 -392.377868)
			(xy 70.461327 -392.385276) (xy 70.520936 -392.399974) (xy 70.57834 -392.421749) (xy 70.632702 -392.450281)
			(xy 70.658228 -392.467338) (xy 70.66698 -392.472809) (xy 70.687184 -392.476937) (xy 70.707388 -392.472809)
			(xy 70.71614 -392.467338) (xy 70.741671 -392.450292) (xy 70.796041 -392.421784) (xy 70.853444 -392.400022)
			(xy 70.913049 -392.385324) (xy 70.973989 -392.377902) (xy 71.004684 -392.377422) (xy 71.025766 -392.37793)
			(xy 71.036688 -392.378438) (xy 71.056246 -392.370818) (xy 71.124572 -392.302492) (xy 71.132192 -392.282934)
			(xy 71.131684 -392.272012) (xy 71.131176 -392.25093) (xy 71.131637 -392.220233) (xy 71.139043 -392.159288)
			(xy 71.153738 -392.099679) (xy 71.175509 -392.042276) (xy 71.204037 -391.987913) (xy 71.221092 -391.962386)
			(xy 71.226539 -391.953621) (xy 71.230677 -391.933425) (xy 71.226559 -391.913225) (xy 71.221092 -391.904474)
			(xy 71.204047 -391.878943) (xy 71.175539 -391.824573) (xy 71.153778 -391.767169) (xy 71.13908 -391.707564)
			(xy 71.131656 -391.646625) (xy 71.131176 -391.61593) (xy 71.131729 -391.582694) (xy 71.140399 -391.51679)
			(xy 71.157582 -391.452578) (xy 71.182986 -391.391152) (xy 71.216177 -391.33356) (xy 71.256589 -391.280783)
			(xy 71.303533 -391.233723) (xy 71.356209 -391.19318) (xy 71.413719 -391.159846) (xy 71.475081 -391.13429)
			(xy 71.539251 -391.116947) (xy 71.57212 -391.111994) (xy 71.58355 -391.11047) (xy 71.602092 -391.098532)
			(xy 71.65594 -391.013188) (xy 71.658734 -390.991344) (xy 71.655178 -390.980168) (xy 71.64388 -390.942435)
			(xy 71.631763 -390.86461) (xy 71.631048 -390.825228) (xy 71.631582 -390.794499) (xy 71.638987 -390.73349)
			(xy 71.653691 -390.673817) (xy 71.67548 -390.616352) (xy 71.704037 -390.561932) (xy 71.738946 -390.511352)
			(xy 71.779696 -390.465347) (xy 71.825695 -390.42459) (xy 71.876271 -390.389675) (xy 71.930686 -390.36111)
			(xy 71.988148 -390.339312) (xy 72.047819 -390.3246) (xy 72.108827 -390.317187) (xy 72.139556 -390.31672)
			(xy 72.170253 -390.31718) (xy 72.231198 -390.324585) (xy 72.290807 -390.33928) (xy 72.348211 -390.361051)
			(xy 72.402573 -390.389581) (xy 72.4281 -390.406636) (xy 72.436852 -390.412107) (xy 72.457056 -390.416235)
			(xy 72.47726 -390.412107) (xy 72.486012 -390.406636) (xy 72.511551 -390.389602) (xy 72.565918 -390.361092)
			(xy 72.62332 -390.339328) (xy 72.682923 -390.324627) (xy 72.743862 -390.317201) (xy 72.774556 -390.31672)
			(xy 72.805288 -390.317179) (xy 72.866305 -390.324583) (xy 72.925984 -390.339289) (xy 72.983456 -390.361081)
			(xy 73.037881 -390.389643) (xy 73.088467 -390.424557) (xy 73.134474 -390.465314) (xy 73.175233 -390.511321)
			(xy 73.210149 -390.561905) (xy 73.238712 -390.616329) (xy 73.260507 -390.6738) (xy 73.275214 -390.733479)
			(xy 73.28262 -390.794496) (xy 73.283064 -390.825228) (xy 73.282486 -390.860074) (xy 73.272972 -390.929113)
			(xy 73.254125 -390.996208) (xy 73.226297 -391.060103) (xy 73.208642 -391.09015) (xy 73.203562 -391.098278)
			(xy 73.20026 -391.116058) (xy 73.214738 -391.200386) (xy 73.223882 -391.21588) (xy 73.230994 -391.221976)
			(xy 73.255613 -391.24275) (xy 73.299994 -391.289437) (xy 73.338127 -391.341352) (xy 73.369402 -391.397666)
			(xy 73.39332 -391.457477) (xy 73.409496 -391.519828) (xy 73.417673 -391.583723) (xy 73.418192 -391.61593)
			(xy 73.417716 -391.646626) (xy 73.410315 -391.707571) (xy 73.395623 -391.76718) (xy 73.373856 -391.824584)
			(xy 73.34533 -391.878947) (xy 73.328276 -391.904474) (xy 73.32278 -391.913213) (xy 73.318662 -391.933425)
			(xy 73.3228 -391.953633) (xy 73.328276 -391.962386) (xy 73.3453 -391.987931) (xy 73.373812 -392.042297)
			(xy 73.395578 -392.099697) (xy 73.410281 -392.159299) (xy 73.417709 -392.220236) (xy 73.418192 -392.25093)
			(xy 73.417772 -392.281662) (xy 73.41036 -392.342678) (xy 73.395647 -392.402356) (xy 73.373849 -392.459825)
			(xy 73.345282 -392.514248) (xy 73.310363 -392.56483) (xy 73.269603 -392.610835) (xy 73.223594 -392.651592)
			(xy 73.173008 -392.686506) (xy 73.118583 -392.715067) (xy 73.061112 -392.736861) (xy 73.001433 -392.751568)
			(xy 72.940416 -392.758975) (xy 72.909684 -392.759438) (xy 72.888602 -392.75893) (xy 72.87768 -392.758422)
			(xy 72.858122 -392.766042) (xy 72.789796 -392.834368) (xy 72.782176 -392.853926) (xy 72.782684 -392.864848)
			(xy 72.783192 -392.88593) (xy 72.782716 -392.916626) (xy 72.775315 -392.977571) (xy 72.760623 -393.03718)
			(xy 72.738856 -393.094584) (xy 72.71033 -393.148947) (xy 72.693276 -393.174474) (xy 72.68778 -393.183213)
			(xy 72.683662 -393.203425) (xy 72.6878 -393.223633) (xy 72.693276 -393.232386) (xy 72.7103 -393.257931)
			(xy 72.738812 -393.312297) (xy 72.760578 -393.369697) (xy 72.775281 -393.429299) (xy 72.782709 -393.490236)
			(xy 72.783192 -393.52093) (xy 73.638156 -393.52093) (xy 73.638626 -393.49356) (xy 73.646441 -393.43938)
			(xy 73.661928 -393.386877) (xy 73.684769 -393.33713) (xy 73.714494 -393.291163) (xy 73.732136 -393.270232)
			(xy 73.738232 -393.26312) (xy 73.744582 -393.246102) (xy 73.744582 -393.160758) (xy 73.738232 -393.14374)
			(xy 73.732136 -393.136628) (xy 73.714524 -393.115672) (xy 73.684798 -393.069708) (xy 73.66195 -393.019966)
			(xy 73.646451 -392.967467) (xy 73.638619 -392.913292) (xy 73.638616 -392.858553) (xy 73.646441 -392.804377)
			(xy 73.661934 -392.751877) (xy 73.684776 -392.702131) (xy 73.714497 -392.656165) (xy 73.732136 -392.635232)
			(xy 73.738232 -392.62812) (xy 73.744582 -392.611102) (xy 73.744582 -392.525758) (xy 73.738232 -392.50874)
			(xy 73.732136 -392.501628) (xy 73.714524 -392.480672) (xy 73.684798 -392.434708) (xy 73.66195 -392.384966)
			(xy 73.646451 -392.332467) (xy 73.638619 -392.278292) (xy 73.638616 -392.223553) (xy 73.646441 -392.169377)
			(xy 73.661934 -392.116877) (xy 73.684776 -392.067131) (xy 73.714497 -392.021165) (xy 73.732136 -392.000232)
			(xy 73.738232 -391.99312) (xy 73.744582 -391.976102) (xy 73.744582 -391.890758) (xy 73.738232 -391.87374)
			(xy 73.732136 -391.866628) (xy 73.714502 -391.845692) (xy 73.684788 -391.799721) (xy 73.661951 -391.749974)
			(xy 73.646459 -391.697474) (xy 73.63863 -391.643299) (xy 73.638156 -391.61593) (xy 73.638641 -391.58846)
			(xy 73.646525 -391.534089) (xy 73.66212 -391.481408) (xy 73.685104 -391.431507) (xy 73.715002 -391.385415)
			(xy 73.751198 -391.344083) (xy 73.77176 -391.325862) (xy 73.77938 -391.319258) (xy 73.788524 -391.301478)
			(xy 73.795636 -391.209276) (xy 73.789286 -391.189972) (xy 73.782428 -391.182352) (xy 73.765029 -391.161451)
			(xy 73.735723 -391.115641) (xy 73.713205 -391.066139) (xy 73.69793 -391.013946) (xy 73.690206 -390.960115)
			(xy 73.689718 -390.932924) (xy 73.690194 -390.905554) (xy 73.698009 -390.851375) (xy 73.713495 -390.798872)
			(xy 73.736335 -390.749125) (xy 73.766058 -390.703158) (xy 73.783698 -390.682226) (xy 73.789794 -390.675114)
			(xy 73.796144 -390.658096) (xy 73.796144 -390.572752) (xy 73.789794 -390.555734) (xy 73.783698 -390.548622)
			(xy 73.766055 -390.527693) (xy 73.736344 -390.481719) (xy 73.713509 -390.431971) (xy 73.698019 -390.37947)
			(xy 73.690191 -390.325293) (xy 73.689718 -390.297924) (xy 73.690204 -390.270673) (xy 73.69796 -390.216725)
			(xy 73.713315 -390.16443) (xy 73.735957 -390.114853) (xy 73.765423 -390.069003) (xy 73.801114 -390.027812)
			(xy 73.842305 -389.992121) (xy 73.888155 -389.962655) (xy 73.937732 -389.940013) (xy 73.990027 -389.924658)
			(xy 74.043975 -389.916902) (xy 74.098477 -389.916902) (xy 74.152425 -389.924658) (xy 74.20472 -389.940013)
			(xy 74.254297 -389.962655) (xy 74.300147 -389.992121) (xy 74.341338 -390.027812) (xy 74.377029 -390.069003)
			(xy 74.406495 -390.114853) (xy 74.429137 -390.16443) (xy 74.444492 -390.216725) (xy 74.452248 -390.270673)
			(xy 74.452734 -390.297924) (xy 74.452298 -390.325296) (xy 74.444475 -390.379477) (xy 74.42898 -390.431981)
			(xy 74.406131 -390.481727) (xy 74.376399 -390.527692) (xy 74.358754 -390.548622) (xy 74.352658 -390.555734)
			(xy 74.346308 -390.572752) (xy 74.346308 -390.626092) (xy 77.290422 -390.626092) (xy 77.290828 -390.602858)
			(xy 77.297322 -390.556848) (xy 77.310196 -390.5122) (xy 77.329196 -390.469795) (xy 77.353948 -390.430469)
			(xy 77.368654 -390.412478) (xy 77.37475 -390.405366) (xy 77.380846 -390.388856) (xy 77.380846 -390.304528)
			(xy 77.37475 -390.288018) (xy 77.368654 -390.280906) (xy 77.353942 -390.262919) (xy 77.329194 -390.22359)
			(xy 77.310195 -390.181184) (xy 77.297317 -390.136536) (xy 77.290815 -390.090526) (xy 77.290422 -390.067292)
			(xy 77.290932 -390.041305) (xy 77.299062 -389.98997) (xy 77.315123 -389.94054) (xy 77.338719 -389.89423)
			(xy 77.369269 -389.852182) (xy 77.40602 -389.815431) (xy 77.448068 -389.784881) (xy 77.494378 -389.761285)
			(xy 77.543808 -389.745224) (xy 77.595143 -389.737094) (xy 77.647117 -389.737094) (xy 77.698452 -389.745224)
			(xy 77.747882 -389.761285) (xy 77.794192 -389.784881) (xy 77.83624 -389.815431) (xy 77.872991 -389.852182)
			(xy 77.903541 -389.89423) (xy 77.927137 -389.94054) (xy 77.943198 -389.98997) (xy 77.951328 -390.041305)
			(xy 77.951838 -390.067292) (xy 77.951467 -390.090527) (xy 77.944962 -390.136538) (xy 77.938192 -390.160002)
			(xy 79.61301 -390.160002) (xy 79.61697 -390.110948) (xy 79.628747 -390.063164) (xy 79.648038 -390.017888)
			(xy 79.674341 -389.976292) (xy 79.706976 -389.939455) (xy 79.745097 -389.90833) (xy 79.787718 -389.883723)
			(xy 79.833734 -389.866271) (xy 79.881953 -389.856427) (xy 79.931128 -389.854446) (xy 79.979983 -389.860378)
			(xy 80.027254 -389.87407) (xy 80.071716 -389.895168) (xy 80.112219 -389.923124) (xy 80.147712 -389.957216)
			(xy 80.177277 -389.99656) (xy 80.200148 -390.040137) (xy 80.215732 -390.086818) (xy 80.223627 -390.135395)
			(xy 80.224122 -390.160002) (xy 80.81316 -390.160002) (xy 80.81712 -390.110948) (xy 80.828897 -390.063164)
			(xy 80.848188 -390.017888) (xy 80.874491 -389.976292) (xy 80.907126 -389.939455) (xy 80.945247 -389.90833)
			(xy 80.987868 -389.883723) (xy 81.033884 -389.866271) (xy 81.082103 -389.856427) (xy 81.131278 -389.854446)
			(xy 81.180133 -389.860378) (xy 81.227404 -389.87407) (xy 81.271866 -389.895168) (xy 81.312369 -389.923124)
			(xy 81.347862 -389.957216) (xy 81.377427 -389.99656) (xy 81.400298 -390.040137) (xy 81.415882 -390.086818)
			(xy 81.423777 -390.135395) (xy 81.424272 -390.160002) (xy 82.01331 -390.160002) (xy 82.01727 -390.110948)
			(xy 82.029047 -390.063164) (xy 82.048338 -390.017888) (xy 82.074641 -389.976292) (xy 82.107276 -389.939455)
			(xy 82.145397 -389.90833) (xy 82.188018 -389.883723) (xy 82.234034 -389.866271) (xy 82.282253 -389.856427)
			(xy 82.331428 -389.854446) (xy 82.380283 -389.860378) (xy 82.427554 -389.87407) (xy 82.472016 -389.895168)
			(xy 82.512519 -389.923124) (xy 82.548012 -389.957216) (xy 82.577577 -389.99656) (xy 82.600448 -390.040137)
			(xy 82.616032 -390.086818) (xy 82.623927 -390.135395) (xy 82.624422 -390.160002) (xy 83.213206 -390.160002)
			(xy 83.217166 -390.110948) (xy 83.228943 -390.063164) (xy 83.248234 -390.017888) (xy 83.274537 -389.976292)
			(xy 83.307172 -389.939455) (xy 83.345293 -389.90833) (xy 83.387914 -389.883723) (xy 83.43393 -389.866271)
			(xy 83.482149 -389.856427) (xy 83.531324 -389.854446) (xy 83.580179 -389.860378) (xy 83.62745 -389.87407)
			(xy 83.671912 -389.895168) (xy 83.712415 -389.923124) (xy 83.747908 -389.957216) (xy 83.777473 -389.99656)
			(xy 83.800344 -390.040137) (xy 83.815928 -390.086818) (xy 83.823823 -390.135395) (xy 83.824318 -390.160002)
			(xy 84.413356 -390.160002) (xy 84.417316 -390.110948) (xy 84.429093 -390.063164) (xy 84.448384 -390.017888)
			(xy 84.474687 -389.976292) (xy 84.507322 -389.939455) (xy 84.545443 -389.90833) (xy 84.588064 -389.883723)
			(xy 84.63408 -389.866271) (xy 84.682299 -389.856427) (xy 84.731474 -389.854446) (xy 84.780329 -389.860378)
			(xy 84.8276 -389.87407) (xy 84.872062 -389.895168) (xy 84.912565 -389.923124) (xy 84.948058 -389.957216)
			(xy 84.977623 -389.99656) (xy 85.000494 -390.040137) (xy 85.016078 -390.086818) (xy 85.023973 -390.135395)
			(xy 85.024468 -390.160002) (xy 85.613252 -390.160002) (xy 85.617212 -390.110948) (xy 85.628989 -390.063164)
			(xy 85.64828 -390.017888) (xy 85.674583 -389.976292) (xy 85.707218 -389.939455) (xy 85.745339 -389.90833)
			(xy 85.78796 -389.883723) (xy 85.833976 -389.866271) (xy 85.882195 -389.856427) (xy 85.93137 -389.854446)
			(xy 85.980225 -389.860378) (xy 86.027496 -389.87407) (xy 86.071958 -389.895168) (xy 86.112461 -389.923124)
			(xy 86.147954 -389.957216) (xy 86.177519 -389.99656) (xy 86.20039 -390.040137) (xy 86.215974 -390.086818)
			(xy 86.223869 -390.135395) (xy 86.224364 -390.160002) (xy 86.813148 -390.160002) (xy 86.817108 -390.110948)
			(xy 86.828885 -390.063164) (xy 86.848176 -390.017888) (xy 86.874479 -389.976292) (xy 86.907114 -389.939455)
			(xy 86.945235 -389.90833) (xy 86.987856 -389.883723) (xy 87.033872 -389.866271) (xy 87.082091 -389.856427)
			(xy 87.131266 -389.854446) (xy 87.180121 -389.860378) (xy 87.227392 -389.87407) (xy 87.271854 -389.895168)
			(xy 87.312357 -389.923124) (xy 87.34785 -389.957216) (xy 87.377415 -389.99656) (xy 87.400286 -390.040137)
			(xy 87.41587 -390.086818) (xy 87.423765 -390.135395) (xy 87.42426 -390.160002) (xy 88.013298 -390.160002)
			(xy 88.017258 -390.110948) (xy 88.029035 -390.063164) (xy 88.048326 -390.017888) (xy 88.074629 -389.976292)
			(xy 88.107264 -389.939455) (xy 88.145385 -389.90833) (xy 88.188006 -389.883723) (xy 88.234022 -389.866271)
			(xy 88.282241 -389.856427) (xy 88.331416 -389.854446) (xy 88.380271 -389.860378) (xy 88.427542 -389.87407)
			(xy 88.472004 -389.895168) (xy 88.512507 -389.923124) (xy 88.548 -389.957216) (xy 88.577565 -389.99656)
			(xy 88.600436 -390.040137) (xy 88.61602 -390.086818) (xy 88.623915 -390.135395) (xy 88.62441 -390.160002)
			(xy 89.213194 -390.160002) (xy 89.217154 -390.110948) (xy 89.228931 -390.063164) (xy 89.248222 -390.017888)
			(xy 89.274525 -389.976292) (xy 89.30716 -389.939455) (xy 89.345281 -389.90833) (xy 89.387902 -389.883723)
			(xy 89.433918 -389.866271) (xy 89.482137 -389.856427) (xy 89.531312 -389.854446) (xy 89.580167 -389.860378)
			(xy 89.627438 -389.87407) (xy 89.6719 -389.895168) (xy 89.712403 -389.923124) (xy 89.747896 -389.957216)
			(xy 89.777461 -389.99656) (xy 89.800332 -390.040137) (xy 89.815916 -390.086818) (xy 89.823811 -390.135395)
			(xy 89.824306 -390.160002) (xy 90.413344 -390.160002) (xy 90.417304 -390.110948) (xy 90.429081 -390.063164)
			(xy 90.448372 -390.017888) (xy 90.474675 -389.976292) (xy 90.50731 -389.939455) (xy 90.545431 -389.90833)
			(xy 90.588052 -389.883723) (xy 90.634068 -389.866271) (xy 90.682287 -389.856427) (xy 90.731462 -389.854446)
			(xy 90.780317 -389.860378) (xy 90.827588 -389.87407) (xy 90.87205 -389.895168) (xy 90.912553 -389.923124)
			(xy 90.948046 -389.957216) (xy 90.977611 -389.99656) (xy 91.000482 -390.040137) (xy 91.016066 -390.086818)
			(xy 91.023961 -390.135395) (xy 91.024456 -390.160002) (xy 91.61324 -390.160002) (xy 91.6172 -390.110948)
			(xy 91.628977 -390.063164) (xy 91.648268 -390.017888) (xy 91.674571 -389.976292) (xy 91.707206 -389.939455)
			(xy 91.745327 -389.90833) (xy 91.787948 -389.883723) (xy 91.833964 -389.866271) (xy 91.882183 -389.856427)
			(xy 91.931358 -389.854446) (xy 91.980213 -389.860378) (xy 92.027484 -389.87407) (xy 92.071946 -389.895168)
			(xy 92.112449 -389.923124) (xy 92.147942 -389.957216) (xy 92.177507 -389.99656) (xy 92.200378 -390.040137)
			(xy 92.215962 -390.086818) (xy 92.223857 -390.135395) (xy 92.224352 -390.160002) (xy 92.813136 -390.160002)
			(xy 92.817096 -390.110948) (xy 92.828873 -390.063164) (xy 92.848164 -390.017888) (xy 92.874467 -389.976292)
			(xy 92.907102 -389.939455) (xy 92.945223 -389.90833) (xy 92.987844 -389.883723) (xy 93.03386 -389.866271)
			(xy 93.082079 -389.856427) (xy 93.131254 -389.854446) (xy 93.180109 -389.860378) (xy 93.22738 -389.87407)
			(xy 93.271842 -389.895168) (xy 93.312345 -389.923124) (xy 93.347838 -389.957216) (xy 93.377403 -389.99656)
			(xy 93.400274 -390.040137) (xy 93.415858 -390.086818) (xy 93.423753 -390.135395) (xy 93.424248 -390.160002)
			(xy 94.013286 -390.160002) (xy 94.017246 -390.110948) (xy 94.029023 -390.063164) (xy 94.048314 -390.017888)
			(xy 94.074617 -389.976292) (xy 94.107252 -389.939455) (xy 94.145373 -389.90833) (xy 94.187994 -389.883723)
			(xy 94.23401 -389.866271) (xy 94.282229 -389.856427) (xy 94.331404 -389.854446) (xy 94.380259 -389.860378)
			(xy 94.42753 -389.87407) (xy 94.471992 -389.895168) (xy 94.512495 -389.923124) (xy 94.547988 -389.957216)
			(xy 94.577553 -389.99656) (xy 94.600424 -390.040137) (xy 94.616008 -390.086818) (xy 94.623903 -390.135395)
			(xy 94.624398 -390.160002) (xy 95.213182 -390.160002) (xy 95.217142 -390.110948) (xy 95.228919 -390.063164)
			(xy 95.24821 -390.017888) (xy 95.274513 -389.976292) (xy 95.307148 -389.939455) (xy 95.345269 -389.90833)
			(xy 95.38789 -389.883723) (xy 95.433906 -389.866271) (xy 95.482125 -389.856427) (xy 95.5313 -389.854446)
			(xy 95.580155 -389.860378) (xy 95.627426 -389.87407) (xy 95.671888 -389.895168) (xy 95.712391 -389.923124)
			(xy 95.747884 -389.957216) (xy 95.777449 -389.99656) (xy 95.80032 -390.040137) (xy 95.815904 -390.086818)
			(xy 95.823799 -390.135395) (xy 95.824294 -390.160002) (xy 96.413332 -390.160002) (xy 96.417292 -390.110948)
			(xy 96.429069 -390.063164) (xy 96.44836 -390.017888) (xy 96.474663 -389.976292) (xy 96.507298 -389.939455)
			(xy 96.545419 -389.90833) (xy 96.58804 -389.883723) (xy 96.634056 -389.866271) (xy 96.682275 -389.856427)
			(xy 96.73145 -389.854446) (xy 96.780305 -389.860378) (xy 96.827576 -389.87407) (xy 96.872038 -389.895168)
			(xy 96.912541 -389.923124) (xy 96.948034 -389.957216) (xy 96.977599 -389.99656) (xy 97.00047 -390.040137)
			(xy 97.016054 -390.086818) (xy 97.023949 -390.135395) (xy 97.024444 -390.160002) (xy 97.613228 -390.160002)
			(xy 97.617188 -390.110948) (xy 97.628965 -390.063164) (xy 97.648256 -390.017888) (xy 97.674559 -389.976292)
			(xy 97.707194 -389.939455) (xy 97.745315 -389.90833) (xy 97.787936 -389.883723) (xy 97.833952 -389.866271)
			(xy 97.882171 -389.856427) (xy 97.931346 -389.854446) (xy 97.980201 -389.860378) (xy 98.027472 -389.87407)
			(xy 98.071934 -389.895168) (xy 98.112437 -389.923124) (xy 98.14793 -389.957216) (xy 98.177495 -389.99656)
			(xy 98.200366 -390.040137) (xy 98.21595 -390.086818) (xy 98.223845 -390.135395) (xy 98.22434 -390.160002)
			(xy 98.223845 -390.184609) (xy 98.21595 -390.233186) (xy 98.200366 -390.279867) (xy 98.177495 -390.323444)
			(xy 98.14793 -390.362788) (xy 98.112437 -390.39688) (xy 98.071934 -390.424836) (xy 98.027472 -390.445934)
			(xy 97.980201 -390.459626) (xy 97.931346 -390.465558) (xy 97.882171 -390.463577) (xy 97.833952 -390.453733)
			(xy 97.787936 -390.436281) (xy 97.745315 -390.411674) (xy 97.707194 -390.380549) (xy 97.674559 -390.343712)
			(xy 97.648256 -390.302116) (xy 97.628965 -390.25684) (xy 97.617188 -390.209056) (xy 97.613228 -390.160002)
			(xy 97.024444 -390.160002) (xy 97.023949 -390.184609) (xy 97.016054 -390.233186) (xy 97.00047 -390.279867)
			(xy 96.977599 -390.323444) (xy 96.948034 -390.362788) (xy 96.912541 -390.39688) (xy 96.872038 -390.424836)
			(xy 96.827576 -390.445934) (xy 96.780305 -390.459626) (xy 96.73145 -390.465558) (xy 96.682275 -390.463577)
			(xy 96.634056 -390.453733) (xy 96.58804 -390.436281) (xy 96.545419 -390.411674) (xy 96.507298 -390.380549)
			(xy 96.474663 -390.343712) (xy 96.44836 -390.302116) (xy 96.429069 -390.25684) (xy 96.417292 -390.209056)
			(xy 96.413332 -390.160002) (xy 95.824294 -390.160002) (xy 95.823799 -390.184609) (xy 95.815904 -390.233186)
			(xy 95.80032 -390.279867) (xy 95.777449 -390.323444) (xy 95.747884 -390.362788) (xy 95.712391 -390.39688)
			(xy 95.671888 -390.424836) (xy 95.627426 -390.445934) (xy 95.580155 -390.459626) (xy 95.5313 -390.465558)
			(xy 95.482125 -390.463577) (xy 95.433906 -390.453733) (xy 95.38789 -390.436281) (xy 95.345269 -390.411674)
			(xy 95.307148 -390.380549) (xy 95.274513 -390.343712) (xy 95.24821 -390.302116) (xy 95.228919 -390.25684)
			(xy 95.217142 -390.209056) (xy 95.213182 -390.160002) (xy 94.624398 -390.160002) (xy 94.623903 -390.184609)
			(xy 94.616008 -390.233186) (xy 94.600424 -390.279867) (xy 94.577553 -390.323444) (xy 94.547988 -390.362788)
			(xy 94.512495 -390.39688) (xy 94.471992 -390.424836) (xy 94.42753 -390.445934) (xy 94.380259 -390.459626)
			(xy 94.331404 -390.465558) (xy 94.282229 -390.463577) (xy 94.23401 -390.453733) (xy 94.187994 -390.436281)
			(xy 94.145373 -390.411674) (xy 94.107252 -390.380549) (xy 94.074617 -390.343712) (xy 94.048314 -390.302116)
			(xy 94.029023 -390.25684) (xy 94.017246 -390.209056) (xy 94.013286 -390.160002) (xy 93.424248 -390.160002)
			(xy 93.423753 -390.184609) (xy 93.415858 -390.233186) (xy 93.400274 -390.279867) (xy 93.377403 -390.323444)
			(xy 93.347838 -390.362788) (xy 93.312345 -390.39688) (xy 93.271842 -390.424836) (xy 93.22738 -390.445934)
			(xy 93.180109 -390.459626) (xy 93.131254 -390.465558) (xy 93.082079 -390.463577) (xy 93.03386 -390.453733)
			(xy 92.987844 -390.436281) (xy 92.945223 -390.411674) (xy 92.907102 -390.380549) (xy 92.874467 -390.343712)
			(xy 92.848164 -390.302116) (xy 92.828873 -390.25684) (xy 92.817096 -390.209056) (xy 92.813136 -390.160002)
			(xy 92.224352 -390.160002) (xy 92.223857 -390.184609) (xy 92.215962 -390.233186) (xy 92.200378 -390.279867)
			(xy 92.177507 -390.323444) (xy 92.147942 -390.362788) (xy 92.112449 -390.39688) (xy 92.071946 -390.424836)
			(xy 92.027484 -390.445934) (xy 91.980213 -390.459626) (xy 91.931358 -390.465558) (xy 91.882183 -390.463577)
			(xy 91.833964 -390.453733) (xy 91.787948 -390.436281) (xy 91.745327 -390.411674) (xy 91.707206 -390.380549)
			(xy 91.674571 -390.343712) (xy 91.648268 -390.302116) (xy 91.628977 -390.25684) (xy 91.6172 -390.209056)
			(xy 91.61324 -390.160002) (xy 91.024456 -390.160002) (xy 91.023961 -390.184609) (xy 91.016066 -390.233186)
			(xy 91.000482 -390.279867) (xy 90.977611 -390.323444) (xy 90.948046 -390.362788) (xy 90.912553 -390.39688)
			(xy 90.87205 -390.424836) (xy 90.827588 -390.445934) (xy 90.780317 -390.459626) (xy 90.731462 -390.465558)
			(xy 90.682287 -390.463577) (xy 90.634068 -390.453733) (xy 90.588052 -390.436281) (xy 90.545431 -390.411674)
			(xy 90.50731 -390.380549) (xy 90.474675 -390.343712) (xy 90.448372 -390.302116) (xy 90.429081 -390.25684)
			(xy 90.417304 -390.209056) (xy 90.413344 -390.160002) (xy 89.824306 -390.160002) (xy 89.823811 -390.184609)
			(xy 89.815916 -390.233186) (xy 89.800332 -390.279867) (xy 89.777461 -390.323444) (xy 89.747896 -390.362788)
			(xy 89.712403 -390.39688) (xy 89.6719 -390.424836) (xy 89.627438 -390.445934) (xy 89.580167 -390.459626)
			(xy 89.531312 -390.465558) (xy 89.482137 -390.463577) (xy 89.433918 -390.453733) (xy 89.387902 -390.436281)
			(xy 89.345281 -390.411674) (xy 89.30716 -390.380549) (xy 89.274525 -390.343712) (xy 89.248222 -390.302116)
			(xy 89.228931 -390.25684) (xy 89.217154 -390.209056) (xy 89.213194 -390.160002) (xy 88.62441 -390.160002)
			(xy 88.623915 -390.184609) (xy 88.61602 -390.233186) (xy 88.600436 -390.279867) (xy 88.577565 -390.323444)
			(xy 88.548 -390.362788) (xy 88.512507 -390.39688) (xy 88.472004 -390.424836) (xy 88.427542 -390.445934)
			(xy 88.380271 -390.459626) (xy 88.331416 -390.465558) (xy 88.282241 -390.463577) (xy 88.234022 -390.453733)
			(xy 88.188006 -390.436281) (xy 88.145385 -390.411674) (xy 88.107264 -390.380549) (xy 88.074629 -390.343712)
			(xy 88.048326 -390.302116) (xy 88.029035 -390.25684) (xy 88.017258 -390.209056) (xy 88.013298 -390.160002)
			(xy 87.42426 -390.160002) (xy 87.423765 -390.184609) (xy 87.41587 -390.233186) (xy 87.400286 -390.279867)
			(xy 87.377415 -390.323444) (xy 87.34785 -390.362788) (xy 87.312357 -390.39688) (xy 87.271854 -390.424836)
			(xy 87.227392 -390.445934) (xy 87.180121 -390.459626) (xy 87.131266 -390.465558) (xy 87.082091 -390.463577)
			(xy 87.033872 -390.453733) (xy 86.987856 -390.436281) (xy 86.945235 -390.411674) (xy 86.907114 -390.380549)
			(xy 86.874479 -390.343712) (xy 86.848176 -390.302116) (xy 86.828885 -390.25684) (xy 86.817108 -390.209056)
			(xy 86.813148 -390.160002) (xy 86.224364 -390.160002) (xy 86.223869 -390.184609) (xy 86.215974 -390.233186)
			(xy 86.20039 -390.279867) (xy 86.177519 -390.323444) (xy 86.147954 -390.362788) (xy 86.112461 -390.39688)
			(xy 86.071958 -390.424836) (xy 86.027496 -390.445934) (xy 85.980225 -390.459626) (xy 85.93137 -390.465558)
			(xy 85.882195 -390.463577) (xy 85.833976 -390.453733) (xy 85.78796 -390.436281) (xy 85.745339 -390.411674)
			(xy 85.707218 -390.380549) (xy 85.674583 -390.343712) (xy 85.64828 -390.302116) (xy 85.628989 -390.25684)
			(xy 85.617212 -390.209056) (xy 85.613252 -390.160002) (xy 85.024468 -390.160002) (xy 85.023973 -390.184609)
			(xy 85.016078 -390.233186) (xy 85.000494 -390.279867) (xy 84.977623 -390.323444) (xy 84.948058 -390.362788)
			(xy 84.912565 -390.39688) (xy 84.872062 -390.424836) (xy 84.8276 -390.445934) (xy 84.780329 -390.459626)
			(xy 84.731474 -390.465558) (xy 84.682299 -390.463577) (xy 84.63408 -390.453733) (xy 84.588064 -390.436281)
			(xy 84.545443 -390.411674) (xy 84.507322 -390.380549) (xy 84.474687 -390.343712) (xy 84.448384 -390.302116)
			(xy 84.429093 -390.25684) (xy 84.417316 -390.209056) (xy 84.413356 -390.160002) (xy 83.824318 -390.160002)
			(xy 83.823823 -390.184609) (xy 83.815928 -390.233186) (xy 83.800344 -390.279867) (xy 83.777473 -390.323444)
			(xy 83.747908 -390.362788) (xy 83.712415 -390.39688) (xy 83.671912 -390.424836) (xy 83.62745 -390.445934)
			(xy 83.580179 -390.459626) (xy 83.531324 -390.465558) (xy 83.482149 -390.463577) (xy 83.43393 -390.453733)
			(xy 83.387914 -390.436281) (xy 83.345293 -390.411674) (xy 83.307172 -390.380549) (xy 83.274537 -390.343712)
			(xy 83.248234 -390.302116) (xy 83.228943 -390.25684) (xy 83.217166 -390.209056) (xy 83.213206 -390.160002)
			(xy 82.624422 -390.160002) (xy 82.623927 -390.184609) (xy 82.616032 -390.233186) (xy 82.600448 -390.279867)
			(xy 82.577577 -390.323444) (xy 82.548012 -390.362788) (xy 82.512519 -390.39688) (xy 82.472016 -390.424836)
			(xy 82.427554 -390.445934) (xy 82.380283 -390.459626) (xy 82.331428 -390.465558) (xy 82.282253 -390.463577)
			(xy 82.234034 -390.453733) (xy 82.188018 -390.436281) (xy 82.145397 -390.411674) (xy 82.107276 -390.380549)
			(xy 82.074641 -390.343712) (xy 82.048338 -390.302116) (xy 82.029047 -390.25684) (xy 82.01727 -390.209056)
			(xy 82.01331 -390.160002) (xy 81.424272 -390.160002) (xy 81.423777 -390.184609) (xy 81.415882 -390.233186)
			(xy 81.400298 -390.279867) (xy 81.377427 -390.323444) (xy 81.347862 -390.362788) (xy 81.312369 -390.39688)
			(xy 81.271866 -390.424836) (xy 81.227404 -390.445934) (xy 81.180133 -390.459626) (xy 81.131278 -390.465558)
			(xy 81.082103 -390.463577) (xy 81.033884 -390.453733) (xy 80.987868 -390.436281) (xy 80.945247 -390.411674)
			(xy 80.907126 -390.380549) (xy 80.874491 -390.343712) (xy 80.848188 -390.302116) (xy 80.828897 -390.25684)
			(xy 80.81712 -390.209056) (xy 80.81316 -390.160002) (xy 80.224122 -390.160002) (xy 80.223627 -390.184609)
			(xy 80.215732 -390.233186) (xy 80.200148 -390.279867) (xy 80.177277 -390.323444) (xy 80.147712 -390.362788)
			(xy 80.112219 -390.39688) (xy 80.071716 -390.424836) (xy 80.027254 -390.445934) (xy 79.979983 -390.459626)
			(xy 79.931128 -390.465558) (xy 79.881953 -390.463577) (xy 79.833734 -390.453733) (xy 79.787718 -390.436281)
			(xy 79.745097 -390.411674) (xy 79.706976 -390.380549) (xy 79.674341 -390.343712) (xy 79.648038 -390.302116)
			(xy 79.628747 -390.25684) (xy 79.61697 -390.209056) (xy 79.61301 -390.160002) (xy 77.938192 -390.160002)
			(xy 77.932079 -390.181186) (xy 77.913072 -390.22359) (xy 77.888315 -390.262916) (xy 77.873606 -390.280906)
			(xy 77.86751 -390.288018) (xy 77.861414 -390.304528) (xy 77.861414 -390.388856) (xy 77.86751 -390.405366)
			(xy 77.873606 -390.412478) (xy 77.88832 -390.430463) (xy 77.913065 -390.469794) (xy 77.932063 -390.5122)
			(xy 77.944941 -390.556848) (xy 77.951444 -390.602858) (xy 77.951838 -390.626092) (xy 77.951421 -390.650184)
			(xy 77.944443 -390.697861) (xy 77.930633 -390.744025) (xy 77.92085 -390.766046) (xy 77.915516 -390.777476)
			(xy 77.916786 -390.802622) (xy 77.97292 -390.896602) (xy 77.99451 -390.909556) (xy 78.00721 -390.910318)
			(xy 78.03221 -390.912121) (xy 78.081255 -390.922459) (xy 78.128179 -390.94008) (xy 78.171908 -390.964578)
			(xy 78.21144 -390.995393) (xy 78.24587 -391.03182) (xy 78.274409 -391.073025) (xy 78.296406 -391.118064)
			(xy 78.311355 -391.165906) (xy 78.318914 -391.215456) (xy 78.319376 -391.240518) (xy 78.318866 -391.266505)
			(xy 78.310736 -391.31784) (xy 78.294675 -391.36727) (xy 78.271079 -391.41358) (xy 78.240529 -391.455628)
			(xy 78.203778 -391.492379) (xy 78.16173 -391.522929) (xy 78.11542 -391.546525) (xy 78.06599 -391.562586)
			(xy 78.014655 -391.570716) (xy 77.962681 -391.570716) (xy 77.911346 -391.562586) (xy 77.861916 -391.546525)
			(xy 77.815606 -391.522929) (xy 77.773558 -391.492379) (xy 77.736807 -391.455628) (xy 77.706257 -391.41358)
			(xy 77.682661 -391.36727) (xy 77.6666 -391.31784) (xy 77.65847 -391.266505) (xy 77.65796 -391.240518)
			(xy 77.658381 -391.216426) (xy 77.665357 -391.168749) (xy 77.679166 -391.122585) (xy 77.688948 -391.100564)
			(xy 77.694282 -391.089134) (xy 77.693012 -391.063988) (xy 77.636878 -390.970008) (xy 77.615288 -390.957054)
			(xy 77.602588 -390.956292) (xy 77.577589 -390.954481) (xy 77.528544 -390.944143) (xy 77.481621 -390.926523)
			(xy 77.437893 -390.902025) (xy 77.398362 -390.871211) (xy 77.363932 -390.834785) (xy 77.335392 -390.793581)
			(xy 77.313395 -390.748543) (xy 77.298445 -390.700702) (xy 77.290884 -390.651153) (xy 77.290422 -390.626092)
			(xy 74.346308 -390.626092) (xy 74.346308 -390.658096) (xy 74.352658 -390.675114) (xy 74.358754 -390.682226)
			(xy 74.376365 -390.703181) (xy 74.406082 -390.749147) (xy 74.428925 -390.798888) (xy 74.444422 -390.851384)
			(xy 74.452257 -390.905556) (xy 74.452734 -390.932924) (xy 74.452148 -390.962534) (xy 74.442988 -391.021042)
			(xy 74.424907 -391.077434) (xy 74.398337 -391.13036) (xy 74.363917 -391.17855) (xy 74.32247 -391.22085)
			(xy 74.299064 -391.238994) (xy 74.290619 -391.245907) (xy 74.280083 -391.264993) (xy 74.278744 -391.275824)
			(xy 74.27468 -391.331958) (xy 74.285856 -391.342626) (xy 74.293208 -391.349138) (xy 74.311355 -391.356596)
			(xy 74.321162 -391.357104) (xy 74.353166 -391.357104) (xy 74.362983 -391.356641) (xy 74.381147 -391.34918)
			(xy 74.388472 -391.342626) (xy 74.40998 -391.322462) (xy 74.458038 -391.288317) (xy 74.510775 -391.261969)
			(xy 74.566937 -391.244046) (xy 74.625188 -391.234973) (xy 74.654664 -391.234422) (xy 74.682034 -391.234904)
			(xy 74.736212 -391.242717) (xy 74.788715 -391.258202) (xy 74.838463 -391.28104) (xy 74.88443 -391.310762)
			(xy 74.905362 -391.328402) (xy 74.912474 -391.334498) (xy 74.929492 -391.340848) (xy 75.014836 -391.340848)
			(xy 75.031854 -391.334498) (xy 75.038966 -391.328402) (xy 75.059899 -391.310761) (xy 75.105867 -391.281037)
			(xy 75.155613 -391.258191) (xy 75.208115 -391.242695) (xy 75.262293 -391.234866) (xy 75.317035 -391.234866)
			(xy 75.371213 -391.242695) (xy 75.423715 -391.258191) (xy 75.473461 -391.281037) (xy 75.519429 -391.310761)
			(xy 75.540362 -391.328402) (xy 75.547474 -391.334498) (xy 75.564492 -391.340848) (xy 75.649836 -391.340848)
			(xy 75.666854 -391.334498) (xy 75.673966 -391.328402) (xy 75.6949 -391.310766) (xy 75.740872 -391.281053)
			(xy 75.790619 -391.258217) (xy 75.84312 -391.242725) (xy 75.897295 -391.234896) (xy 75.924664 -391.234422)
			(xy 75.951917 -391.234889) (xy 76.00587 -391.242642) (xy 76.058169 -391.257995) (xy 76.107751 -391.280635)
			(xy 76.153606 -391.310102) (xy 76.1948 -391.345796) (xy 76.230494 -391.386989) (xy 76.259962 -391.432843)
			(xy 76.282603 -391.482425) (xy 76.297957 -391.534724) (xy 76.305711 -391.588677) (xy 76.306172 -391.61593)
			(xy 76.30573 -391.643301) (xy 76.297908 -391.697482) (xy 76.282413 -391.749985) (xy 76.259566 -391.799732)
			(xy 76.229836 -391.845697) (xy 76.212192 -391.866628) (xy 76.206096 -391.87374) (xy 76.199746 -391.890758)
			(xy 76.199746 -391.976102) (xy 76.206096 -391.99312) (xy 76.212192 -392.000232) (xy 76.229861 -392.021141)
			(xy 76.259583 -392.067114) (xy 76.282426 -392.116864) (xy 76.297919 -392.169369) (xy 76.305744 -392.223551)
			(xy 76.305742 -392.251946) (xy 76.590906 -392.251946) (xy 76.591392 -392.224695) (xy 76.599148 -392.170747)
			(xy 76.614503 -392.118452) (xy 76.637145 -392.068875) (xy 76.666611 -392.023025) (xy 76.702302 -391.981834)
			(xy 76.743493 -391.946143) (xy 76.789343 -391.916677) (xy 76.83892 -391.894035) (xy 76.891215 -391.87868)
			(xy 76.945163 -391.870924) (xy 76.999665 -391.870924) (xy 77.053613 -391.87868) (xy 77.105908 -391.894035)
			(xy 77.155485 -391.916677) (xy 77.201335 -391.946143) (xy 77.242526 -391.981834) (xy 77.278217 -392.023025)
			(xy 77.307683 -392.068875) (xy 77.330325 -392.118452) (xy 77.34568 -392.170747) (xy 77.353436 -392.224695)
			(xy 77.353922 -392.251946) (xy 77.352652 -392.284204) (xy 77.351636 -392.293856) (xy 77.35697 -392.31189)
			(xy 77.374574 -392.33475) (xy 78.691994 -392.33475) (xy 78.692382 -392.311516) (xy 78.698881 -392.265505)
			(xy 78.71176 -392.220857) (xy 78.730764 -392.178452) (xy 78.755518 -392.139126) (xy 78.770226 -392.121136)
			(xy 78.776322 -392.114024) (xy 78.782418 -392.097514) (xy 78.782418 -392.013186) (xy 78.776322 -391.996676)
			(xy 78.770226 -391.989564) (xy 78.755537 -391.97156) (xy 78.730787 -391.932235) (xy 78.711783 -391.889833)
			(xy 78.6989 -391.84519) (xy 78.692391 -391.799183) (xy 78.691994 -391.77595) (xy 78.692504 -391.749963)
			(xy 78.700634 -391.698628) (xy 78.716695 -391.649198) (xy 78.740291 -391.602888) (xy 78.770841 -391.56084)
			(xy 78.807592 -391.524089) (xy 78.84964 -391.493539) (xy 78.89595 -391.469943) (xy 78.94538 -391.453882)
			(xy 78.996715 -391.445752) (xy 79.048689 -391.445752) (xy 79.100024 -391.453882) (xy 79.149454 -391.469943)
			(xy 79.195764 -391.493539) (xy 79.237812 -391.524089) (xy 79.274563 -391.56084) (xy 79.305113 -391.602888)
			(xy 79.328709 -391.649198) (xy 79.34477 -391.698628) (xy 79.3529 -391.749963) (xy 79.35341 -391.77595)
			(xy 79.353022 -391.799184) (xy 79.346522 -391.845195) (xy 79.333643 -391.889843) (xy 79.31464 -391.932248)
			(xy 79.289886 -391.971574) (xy 79.275178 -391.989564) (xy 79.269082 -391.996676) (xy 79.262986 -392.013186)
			(xy 79.262986 -392.097514) (xy 79.269082 -392.114024) (xy 79.275178 -392.121136) (xy 79.289868 -392.13914)
			(xy 79.314618 -392.178465) (xy 79.333621 -392.220867) (xy 79.346504 -392.26551) (xy 79.353013 -392.311517)
			(xy 79.35341 -392.33475) (xy 79.3529 -392.360737) (xy 79.34477 -392.412072) (xy 79.328709 -392.461502)
			(xy 79.305113 -392.507812) (xy 79.274563 -392.54986) (xy 79.237812 -392.586611) (xy 79.195764 -392.617161)
			(xy 79.149454 -392.640757) (xy 79.100024 -392.656818) (xy 79.048689 -392.664948) (xy 78.996715 -392.664948)
			(xy 78.94538 -392.656818) (xy 78.89595 -392.640757) (xy 78.84964 -392.617161) (xy 78.807592 -392.586611)
			(xy 78.770841 -392.54986) (xy 78.740291 -392.507812) (xy 78.716695 -392.461502) (xy 78.700634 -392.412072)
			(xy 78.692504 -392.360737) (xy 78.691994 -392.33475) (xy 77.374574 -392.33475) (xy 77.410564 -392.381486)
			(xy 77.42682 -392.391138) (xy 77.436218 -392.392916) (xy 77.462371 -392.39802) (xy 77.513047 -392.414482)
			(xy 77.560939 -392.437837) (xy 77.605115 -392.46763) (xy 77.644714 -392.503281) (xy 77.678967 -392.544097)
			(xy 77.707205 -392.589282) (xy 77.72888 -392.637957) (xy 77.743569 -392.689176) (xy 77.750987 -392.74194)
			(xy 77.751432 -392.768582) (xy 77.750946 -392.795833) (xy 77.74319 -392.849781) (xy 77.727835 -392.902076)
			(xy 77.705193 -392.951653) (xy 77.675727 -392.997503) (xy 77.640036 -393.038694) (xy 77.598845 -393.074385)
			(xy 77.552995 -393.103851) (xy 77.503418 -393.126493) (xy 77.451123 -393.141848) (xy 77.397175 -393.149604)
			(xy 77.342673 -393.149604) (xy 77.288725 -393.141848) (xy 77.23643 -393.126493) (xy 77.186853 -393.103851)
			(xy 77.141003 -393.074385) (xy 77.099812 -393.038694) (xy 77.064121 -392.997503) (xy 77.034655 -392.951653)
			(xy 77.012013 -392.902076) (xy 76.996658 -392.849781) (xy 76.988902 -392.795833) (xy 76.988416 -392.768582)
			(xy 76.989686 -392.736324) (xy 76.990702 -392.726672) (xy 76.985368 -392.708638) (xy 76.931774 -392.639042)
			(xy 76.915518 -392.62939) (xy 76.90612 -392.627612) (xy 76.879958 -392.622548) (xy 76.829277 -392.606087)
			(xy 76.78138 -392.582731) (xy 76.737201 -392.552935) (xy 76.6976 -392.517279) (xy 76.663347 -392.476458)
			(xy 76.635111 -392.431267) (xy 76.61344 -392.382585) (xy 76.598756 -392.33136) (xy 76.591346 -392.27859)
			(xy 76.590906 -392.251946) (xy 76.305742 -392.251946) (xy 76.305741 -392.278294) (xy 76.297909 -392.332475)
			(xy 76.28241 -392.384979) (xy 76.259562 -392.434726) (xy 76.229834 -392.480695) (xy 76.212192 -392.501628)
			(xy 76.206096 -392.50874) (xy 76.199746 -392.525758) (xy 76.199746 -392.611102) (xy 76.206096 -392.62812)
			(xy 76.212192 -392.635232) (xy 76.229861 -392.656141) (xy 76.259583 -392.702114) (xy 76.282426 -392.751864)
			(xy 76.297919 -392.804369) (xy 76.305744 -392.858551) (xy 76.305741 -392.913294) (xy 76.297909 -392.967475)
			(xy 76.28241 -393.019979) (xy 76.259562 -393.069726) (xy 76.229834 -393.115695) (xy 76.212192 -393.136628)
			(xy 76.206096 -393.14374) (xy 76.199746 -393.160758) (xy 76.199746 -393.246102) (xy 76.206096 -393.26312)
			(xy 76.212192 -393.270232) (xy 76.229811 -393.29118) (xy 76.259526 -393.337148) (xy 76.282366 -393.386892)
			(xy 76.297862 -393.439389) (xy 76.305695 -393.493562) (xy 76.306172 -393.52093) (xy 76.305773 -393.548185)
			(xy 76.298011 -393.60214) (xy 76.282649 -393.654442) (xy 76.260001 -393.704024) (xy 76.230526 -393.749879)
			(xy 76.194826 -393.791072) (xy 76.153626 -393.826766) (xy 76.107766 -393.856232) (xy 76.05818 -393.878872)
			(xy 76.005876 -393.894225) (xy 75.951919 -393.901978) (xy 75.924664 -393.902438) (xy 79.958184 -393.902438)
			(xy 79.958719 -393.874153) (xy 79.967032 -393.818198) (xy 79.983468 -393.764069) (xy 80.007673 -393.712939)
			(xy 80.039121 -393.665916) (xy 80.057752 -393.644628) (xy 80.063667 -393.637445) (xy 80.070447 -393.620135)
			(xy 80.07096 -393.610846) (xy 80.071214 -393.579604) (xy 80.070799 -393.570268) (xy 80.064161 -393.552815)
			(xy 80.05826 -393.545568) (xy 80.040343 -393.52453) (xy 80.010129 -393.478263) (xy 79.986907 -393.428121)
			(xy 79.971164 -393.375153) (xy 79.963228 -393.320468) (xy 79.962756 -393.292838) (xy 79.962756 -392.429238)
			(xy 79.963224 -392.402892) (xy 79.970453 -392.350698) (xy 79.984792 -392.299995) (xy 80.005968 -392.251746)
			(xy 80.03358 -392.206868) (xy 80.067102 -392.166214) (xy 80.0862 -392.14806) (xy 80.093312 -392.14171)
			(xy 80.10144 -392.124946) (xy 80.109822 -392.038332) (xy 80.104742 -392.020552) (xy 80.099154 -392.012678)
			(xy 80.085004 -391.992831) (xy 80.062547 -391.949572) (xy 80.047234 -391.9033) (xy 80.039454 -391.855184)
			(xy 80.038956 -391.830814) (xy 80.039478 -391.805559) (xy 80.047791 -391.755737) (xy 80.064192 -391.707963)
			(xy 80.088233 -391.66354) (xy 80.119257 -391.62368) (xy 80.156419 -391.58947) (xy 80.198705 -391.561844)
			(xy 80.244961 -391.541554) (xy 80.293926 -391.529154) (xy 80.344264 -391.524983) (xy 80.394602 -391.529154)
			(xy 80.443567 -391.541554) (xy 80.489823 -391.561844) (xy 80.532109 -391.58947) (xy 80.569271 -391.62368)
			(xy 80.600295 -391.66354) (xy 80.624336 -391.707963) (xy 80.640737 -391.755737) (xy 80.64905 -391.805559)
			(xy 80.649572 -391.830814) (xy 80.64909 -391.855186) (xy 80.641331 -391.903309) (xy 80.626015 -391.949584)
			(xy 80.60353 -391.992833) (xy 80.589374 -392.012678) (xy 80.583786 -392.020552) (xy 80.578706 -392.038332)
			(xy 80.587088 -392.124946) (xy 80.595216 -392.14171) (xy 80.602328 -392.14806) (xy 80.621457 -392.166187)
			(xy 80.655 -392.206834) (xy 80.682625 -392.251713) (xy 80.703806 -392.29997) (xy 80.718139 -392.350683)
			(xy 80.72535 -392.402888) (xy 80.725772 -392.429238) (xy 80.725772 -393.292838) (xy 80.725348 -393.320742)
			(xy 80.717254 -393.375958) (xy 80.7012 -393.429406) (xy 80.677529 -393.479944) (xy 80.646747 -393.526493)
			(xy 80.62849 -393.5476) (xy 80.622592 -393.554776) (xy 80.615942 -393.572102) (xy 80.615536 -393.581382)
			(xy 80.615536 -393.612624) (xy 80.615962 -393.621898) (xy 80.622617 -393.639215) (xy 80.62849 -393.646406)
			(xy 80.646821 -393.667628) (xy 80.677724 -393.714421) (xy 80.701493 -393.765211) (xy 80.717624 -393.818918)
			(xy 80.725773 -393.8744) (xy 80.72628 -393.902438) (xy 81.15808 -393.902438) (xy 81.158616 -393.874153)
			(xy 81.166929 -393.818198) (xy 81.183365 -393.764069) (xy 81.207569 -393.712939) (xy 81.239017 -393.665916)
			(xy 81.257648 -393.644628) (xy 81.263562 -393.637445) (xy 81.270343 -393.620135) (xy 81.270856 -393.610846)
			(xy 81.27111 -393.579604) (xy 81.270673 -393.57027) (xy 81.264048 -393.552819) (xy 81.258156 -393.545568)
			(xy 81.240238 -393.524531) (xy 81.210025 -393.478264) (xy 81.186803 -393.428121) (xy 81.171059 -393.375153)
			(xy 81.163124 -393.320468) (xy 81.162652 -393.292838) (xy 81.162652 -392.429238) (xy 81.163121 -392.402892)
			(xy 81.17035 -392.350698) (xy 81.184689 -392.299995) (xy 81.205865 -392.251746) (xy 81.233477 -392.206868)
			(xy 81.266998 -392.166214) (xy 81.286096 -392.14806) (xy 81.293208 -392.141456) (xy 81.30159 -392.124946)
			(xy 81.309718 -392.038078) (xy 81.304892 -392.020298) (xy 81.29905 -392.012678) (xy 81.28494 -391.992813)
			(xy 81.26252 -391.949556) (xy 81.247264 -391.903285) (xy 81.23956 -391.855175) (xy 81.239106 -391.830814)
			(xy 81.239628 -391.805559) (xy 81.247941 -391.755737) (xy 81.264342 -391.707963) (xy 81.288383 -391.66354)
			(xy 81.319407 -391.62368) (xy 81.356569 -391.58947) (xy 81.398855 -391.561844) (xy 81.445111 -391.541554)
			(xy 81.494076 -391.529154) (xy 81.544414 -391.524983) (xy 81.594752 -391.529154) (xy 81.643717 -391.541554)
			(xy 81.689973 -391.561844) (xy 81.732259 -391.58947) (xy 81.769421 -391.62368) (xy 81.800445 -391.66354)
			(xy 81.824486 -391.707963) (xy 81.840887 -391.755737) (xy 81.8492 -391.805559) (xy 81.849722 -391.830814)
			(xy 81.849263 -391.855217) (xy 81.841503 -391.903402) (xy 81.826181 -391.94974) (xy 81.803687 -391.993054)
			(xy 81.789524 -392.012932) (xy 81.783936 -392.020552) (xy 81.778856 -392.038332) (xy 81.786984 -392.1252)
			(xy 81.795366 -392.14171) (xy 81.802478 -392.148314) (xy 81.82156 -392.166446) (xy 81.855039 -392.207067)
			(xy 81.882609 -392.251908) (xy 81.903748 -392.300116) (xy 81.918051 -392.350774) (xy 81.925248 -392.402918)
			(xy 81.925668 -392.429238) (xy 81.925668 -393.292838) (xy 81.92522 -393.32074) (xy 81.917128 -393.375955)
			(xy 81.901079 -393.429401) (xy 81.877414 -393.479939) (xy 81.846639 -393.526491) (xy 81.828386 -393.5476)
			(xy 81.822487 -393.554776) (xy 81.815838 -393.572102) (xy 81.815432 -393.581382) (xy 81.815432 -393.612624)
			(xy 81.815858 -393.621898) (xy 81.822512 -393.639215) (xy 81.828386 -393.646406) (xy 81.846717 -393.667628)
			(xy 81.877619 -393.714422) (xy 81.901389 -393.765211) (xy 81.91752 -393.818918) (xy 81.925669 -393.8744)
			(xy 81.926176 -393.902438) (xy 81.925723 -393.927838) (xy 82.358484 -393.927838) (xy 82.358924 -393.900148)
			(xy 82.366822 -393.845336) (xy 82.382517 -393.792229) (xy 82.405683 -393.741929) (xy 82.43584 -393.695482)
			(xy 82.453734 -393.674346) (xy 82.460084 -393.667488) (xy 82.466434 -393.65047) (xy 82.466942 -393.56538)
			(xy 82.460592 -393.548362) (xy 82.454496 -393.54125) (xy 82.437249 -393.520389) (xy 82.408166 -393.474742)
			(xy 82.385826 -393.425443) (xy 82.370677 -393.373481) (xy 82.363023 -393.3199) (xy 82.362548 -393.292838)
			(xy 82.362548 -392.429238) (xy 82.363025 -392.402882) (xy 82.370288 -392.350673) (xy 82.384668 -392.299961)
			(xy 82.40589 -392.25171) (xy 82.43355 -392.206839) (xy 82.467123 -392.166202) (xy 82.486246 -392.14806)
			(xy 82.493358 -392.14171) (xy 82.501486 -392.124946) (xy 82.509868 -392.038332) (xy 82.504788 -392.020552)
			(xy 82.4992 -392.012678) (xy 82.485056 -391.992827) (xy 82.462596 -391.94957) (xy 82.447281 -391.903299)
			(xy 82.439501 -391.855184) (xy 82.439002 -391.830814) (xy 82.439524 -391.805559) (xy 82.447837 -391.755737)
			(xy 82.464238 -391.707963) (xy 82.488279 -391.66354) (xy 82.519303 -391.62368) (xy 82.556465 -391.58947)
			(xy 82.598751 -391.561844) (xy 82.645007 -391.541554) (xy 82.693972 -391.529154) (xy 82.74431 -391.524983)
			(xy 82.794648 -391.529154) (xy 82.843613 -391.541554) (xy 82.889869 -391.561844) (xy 82.932155 -391.58947)
			(xy 82.969317 -391.62368) (xy 83.000341 -391.66354) (xy 83.024382 -391.707963) (xy 83.040783 -391.755737)
			(xy 83.049096 -391.805559) (xy 83.049618 -391.830814) (xy 83.049146 -391.855187) (xy 83.041386 -391.90331)
			(xy 83.026067 -391.949586) (xy 83.003578 -391.992834) (xy 82.98942 -392.012678) (xy 82.983832 -392.020552)
			(xy 82.978752 -392.038332) (xy 82.987134 -392.124946) (xy 82.995262 -392.14171) (xy 83.002374 -392.14806)
			(xy 83.021513 -392.166189) (xy 83.055099 -392.206821) (xy 83.082769 -392.251692) (xy 83.103996 -392.299947)
			(xy 83.118374 -392.350665) (xy 83.125629 -392.40288) (xy 83.126072 -392.429238) (xy 83.126072 -393.292838)
			(xy 83.125535 -393.320141) (xy 83.117687 -393.374183) (xy 83.102229 -393.426558) (xy 83.079475 -393.4762)
			(xy 83.049887 -393.522098) (xy 83.032346 -393.543028) (xy 83.02625 -393.55014) (xy 83.0199 -393.567158)
			(xy 83.0199 -393.652248) (xy 83.02625 -393.669266) (xy 83.032346 -393.676378) (xy 83.049962 -393.697409)
			(xy 83.07963 -393.743554) (xy 83.102416 -393.793458) (xy 83.117853 -393.846101) (xy 83.122282 -393.877038)
			(xy 83.55838 -393.877038) (xy 83.558793 -393.850181) (xy 83.566239 -393.796988) (xy 83.581031 -393.745353)
			(xy 83.602882 -393.696286) (xy 83.631363 -393.650746) (xy 83.648296 -393.629896) (xy 83.653675 -393.622928)
			(xy 83.659777 -393.606429) (xy 83.660234 -393.597638) (xy 83.660488 -393.567158) (xy 83.660208 -393.558308)
			(xy 83.654215 -393.541656) (xy 83.648804 -393.534646) (xy 83.632522 -393.514116) (xy 83.605188 -393.469411)
			(xy 83.584227 -393.421386) (xy 83.570033 -393.370946) (xy 83.562873 -393.319038) (xy 83.562444 -393.292838)
			(xy 83.562444 -392.429238) (xy 83.562923 -392.402882) (xy 83.570186 -392.350674) (xy 83.584565 -392.299961)
			(xy 83.605786 -392.25171) (xy 83.633447 -392.206839) (xy 83.667019 -392.166202) (xy 83.686142 -392.14806)
			(xy 83.693254 -392.14171) (xy 83.701382 -392.124946) (xy 83.709764 -392.038332) (xy 83.704684 -392.020552)
			(xy 83.699096 -392.012678) (xy 83.684951 -391.992827) (xy 83.662491 -391.949571) (xy 83.647177 -391.903299)
			(xy 83.639397 -391.855184) (xy 83.638898 -391.830814) (xy 83.63942 -391.805559) (xy 83.647733 -391.755737)
			(xy 83.664134 -391.707963) (xy 83.688175 -391.66354) (xy 83.719199 -391.62368) (xy 83.756361 -391.58947)
			(xy 83.798647 -391.561844) (xy 83.844903 -391.541554) (xy 83.893868 -391.529154) (xy 83.944206 -391.524983)
			(xy 83.994544 -391.529154) (xy 84.043509 -391.541554) (xy 84.089765 -391.561844) (xy 84.132051 -391.58947)
			(xy 84.169213 -391.62368) (xy 84.200237 -391.66354) (xy 84.224278 -391.707963) (xy 84.240679 -391.755737)
			(xy 84.248992 -391.805559) (xy 84.249514 -391.830814) (xy 84.249043 -391.855187) (xy 84.241283 -391.90331)
			(xy 84.225963 -391.949586) (xy 84.203475 -391.992834) (xy 84.189316 -392.012678) (xy 84.183728 -392.020552)
			(xy 84.178648 -392.038332) (xy 84.18703 -392.124946) (xy 84.195158 -392.14171) (xy 84.20227 -392.14806)
			(xy 84.221408 -392.16619) (xy 84.254995 -392.206822) (xy 84.282665 -392.251693) (xy 84.303892 -392.299947)
			(xy 84.31827 -392.350665) (xy 84.325525 -392.40288) (xy 84.325968 -392.429238) (xy 84.325968 -393.292838)
			(xy 84.325458 -393.3193) (xy 84.318114 -393.371712) (xy 84.303614 -393.42261) (xy 84.282233 -393.471023)
			(xy 84.254381 -393.516026) (xy 84.23783 -393.536678) (xy 84.232506 -393.543735) (xy 84.226528 -393.560358)
			(xy 84.226146 -393.56919) (xy 84.226146 -393.59967) (xy 84.226532 -393.608445) (xy 84.232501 -393.624947)
			(xy 84.23783 -393.631928) (xy 84.254429 -393.652698) (xy 84.282331 -393.697959) (xy 84.303731 -393.746631)
			(xy 84.318222 -393.797788) (xy 84.325528 -393.850453) (xy 84.325968 -393.877038) (xy 84.325479 -393.904453)
			(xy 84.322117 -393.927838) (xy 84.758276 -393.927838) (xy 84.758757 -393.90014) (xy 84.766701 -393.845317)
			(xy 84.782444 -393.792206) (xy 84.805658 -393.74191) (xy 84.835862 -393.695473) (xy 84.85378 -393.674346)
			(xy 84.86013 -393.667488) (xy 84.86648 -393.65047) (xy 84.866988 -393.56538) (xy 84.860638 -393.548362)
			(xy 84.854542 -393.54125) (xy 84.837337 -393.520368) (xy 84.808313 -393.474709) (xy 84.786026 -393.425408)
			(xy 84.770924 -393.373455) (xy 84.763307 -393.31989) (xy 84.762848 -393.292838) (xy 84.762848 -392.429238)
			(xy 84.763318 -392.402892) (xy 84.770547 -392.350699) (xy 84.784886 -392.299995) (xy 84.806062 -392.251746)
			(xy 84.833673 -392.206868) (xy 84.867195 -392.166215) (xy 84.886292 -392.14806) (xy 84.893404 -392.14171)
			(xy 84.901532 -392.124946) (xy 84.909914 -392.038332) (xy 84.904834 -392.020552) (xy 84.899246 -392.012678)
			(xy 84.885095 -391.992832) (xy 84.862638 -391.949573) (xy 84.847326 -391.9033) (xy 84.839546 -391.855184)
			(xy 84.839048 -391.830814) (xy 84.83957 -391.805559) (xy 84.847883 -391.755737) (xy 84.864284 -391.707963)
			(xy 84.888325 -391.66354) (xy 84.919349 -391.62368) (xy 84.956511 -391.58947) (xy 84.998797 -391.561844)
			(xy 85.045053 -391.541554) (xy 85.094018 -391.529154) (xy 85.144356 -391.524983) (xy 85.194694 -391.529154)
			(xy 85.243659 -391.541554) (xy 85.289915 -391.561844) (xy 85.332201 -391.58947) (xy 85.369363 -391.62368)
			(xy 85.400387 -391.66354) (xy 85.424428 -391.707963) (xy 85.440829 -391.755737) (xy 85.449142 -391.805559)
			(xy 85.449664 -391.830814) (xy 85.449183 -391.855186) (xy 85.441425 -391.903309) (xy 85.426108 -391.949584)
			(xy 85.403622 -391.992833) (xy 85.389466 -392.012678) (xy 85.383878 -392.020552) (xy 85.378798 -392.038332)
			(xy 85.38718 -392.124946) (xy 85.395308 -392.14171) (xy 85.40242 -392.14806) (xy 85.421548 -392.166188)
			(xy 85.455091 -392.206835) (xy 85.482716 -392.251714) (xy 85.503897 -392.29997) (xy 85.51823 -392.350683)
			(xy 85.525442 -392.402888) (xy 85.525864 -392.429238) (xy 85.525864 -393.292838) (xy 85.525411 -393.320138)
			(xy 85.517633 -393.374181) (xy 85.502228 -393.426562) (xy 85.47951 -393.476212) (xy 85.449944 -393.522113)
			(xy 85.432392 -393.543028) (xy 85.426296 -393.55014) (xy 85.419946 -393.567158) (xy 85.419946 -393.652248)
			(xy 85.426296 -393.669266) (xy 85.432392 -393.676378) (xy 85.450016 -393.697411) (xy 85.479715 -393.743553)
			(xy 85.502544 -393.793452) (xy 85.51804 -393.846092) (xy 85.525887 -393.900402) (xy 85.526372 -393.927838)
			(xy 85.958172 -393.927838) (xy 85.958654 -393.90014) (xy 85.966598 -393.845318) (xy 85.982341 -393.792206)
			(xy 86.005555 -393.74191) (xy 86.035758 -393.695473) (xy 86.053676 -393.674346) (xy 86.060026 -393.667488)
			(xy 86.066376 -393.65047) (xy 86.066884 -393.56538) (xy 86.060534 -393.548362) (xy 86.054438 -393.54125)
			(xy 86.037232 -393.520369) (xy 86.008208 -393.474709) (xy 85.985922 -393.425408) (xy 85.97082 -393.373455)
			(xy 85.963203 -393.31989) (xy 85.962744 -393.292838) (xy 85.962744 -392.429238) (xy 85.963216 -392.402892)
			(xy 85.970444 -392.350699) (xy 85.984783 -392.299996) (xy 86.005959 -392.251746) (xy 86.03357 -392.206868)
			(xy 86.067091 -392.166215) (xy 86.086188 -392.14806) (xy 86.0933 -392.14171) (xy 86.101428 -392.124946)
			(xy 86.10981 -392.038332) (xy 86.10473 -392.020552) (xy 86.099142 -392.012678) (xy 86.084991 -391.992832)
			(xy 86.062534 -391.949573) (xy 86.047222 -391.9033) (xy 86.039442 -391.855184) (xy 86.038944 -391.830814)
			(xy 86.039466 -391.805559) (xy 86.047779 -391.755737) (xy 86.06418 -391.707963) (xy 86.088221 -391.66354)
			(xy 86.119245 -391.62368) (xy 86.156407 -391.58947) (xy 86.198693 -391.561844) (xy 86.244949 -391.541554)
			(xy 86.293914 -391.529154) (xy 86.344252 -391.524983) (xy 86.39459 -391.529154) (xy 86.443555 -391.541554)
			(xy 86.489811 -391.561844) (xy 86.532097 -391.58947) (xy 86.569259 -391.62368) (xy 86.600283 -391.66354)
			(xy 86.624324 -391.707963) (xy 86.640725 -391.755737) (xy 86.649038 -391.805559) (xy 86.64956 -391.830814)
			(xy 86.64908 -391.855186) (xy 86.641321 -391.903309) (xy 86.626004 -391.949585) (xy 86.603519 -391.992833)
			(xy 86.589362 -392.012678) (xy 86.583774 -392.020552) (xy 86.578694 -392.038332) (xy 86.587076 -392.124946)
			(xy 86.595204 -392.14171) (xy 86.602316 -392.14806) (xy 86.621443 -392.166189) (xy 86.654986 -392.206835)
			(xy 86.682612 -392.251714) (xy 86.703793 -392.29997) (xy 86.718126 -392.350683) (xy 86.725338 -392.402888)
			(xy 86.72576 -392.429238) (xy 86.72576 -393.292838) (xy 86.725308 -393.320138) (xy 86.71753 -393.374181)
			(xy 86.702125 -393.426563) (xy 86.679407 -393.476212) (xy 86.649841 -393.522114) (xy 86.632288 -393.543028)
			(xy 86.626192 -393.55014) (xy 86.619842 -393.567158) (xy 86.619842 -393.652248) (xy 86.626192 -393.669266)
			(xy 86.632288 -393.676378) (xy 86.649911 -393.697412) (xy 86.67961 -393.743554) (xy 86.70244 -393.793452)
			(xy 86.717936 -393.846092) (xy 86.722407 -393.877038) (xy 87.158576 -393.877038) (xy 87.15899 -393.850182)
			(xy 87.166436 -393.796988) (xy 87.181228 -393.745353) (xy 87.203078 -393.696286) (xy 87.231559 -393.650746)
			(xy 87.248492 -393.629896) (xy 87.25387 -393.622927) (xy 87.259973 -393.606429) (xy 87.26043 -393.597638)
			(xy 87.260684 -393.567158) (xy 87.260405 -393.558308) (xy 87.254411 -393.541656) (xy 87.249 -393.534646)
			(xy 87.232717 -393.514116) (xy 87.205384 -393.469411) (xy 87.184423 -393.421386) (xy 87.170229 -393.370946)
			(xy 87.163069 -393.319038) (xy 87.16264 -393.292838) (xy 87.16264 -392.429238) (xy 87.16312 -392.402882)
			(xy 87.170383 -392.350674) (xy 87.184762 -392.299962) (xy 87.205983 -392.251711) (xy 87.233643 -392.20684)
			(xy 87.267215 -392.166202) (xy 87.286338 -392.14806) (xy 87.29345 -392.14171) (xy 87.301578 -392.124946)
			(xy 87.30996 -392.038332) (xy 87.30488 -392.020552) (xy 87.299292 -392.012678) (xy 87.285147 -391.992828)
			(xy 87.262687 -391.949571) (xy 87.247373 -391.903299) (xy 87.239593 -391.855184) (xy 87.239094 -391.830814)
			(xy 87.239616 -391.805559) (xy 87.247929 -391.755737) (xy 87.26433 -391.707963) (xy 87.288371 -391.66354)
			(xy 87.319395 -391.62368) (xy 87.356557 -391.58947) (xy 87.398843 -391.561844) (xy 87.445099 -391.541554)
			(xy 87.494064 -391.529154) (xy 87.544402 -391.524983) (xy 87.59474 -391.529154) (xy 87.643705 -391.541554)
			(xy 87.689961 -391.561844) (xy 87.732247 -391.58947) (xy 87.769409 -391.62368) (xy 87.800433 -391.66354)
			(xy 87.824474 -391.707963) (xy 87.840875 -391.755737) (xy 87.849188 -391.805559) (xy 87.84971 -391.830814)
			(xy 87.84924 -391.855187) (xy 87.84148 -391.903311) (xy 87.82616 -391.949586) (xy 87.803671 -391.992834)
			(xy 87.789512 -392.012678) (xy 87.783924 -392.020552) (xy 87.778844 -392.038332) (xy 87.787226 -392.124946)
			(xy 87.795354 -392.14171) (xy 87.802466 -392.14806) (xy 87.821603 -392.166191) (xy 87.85519 -392.206822)
			(xy 87.882861 -392.251693) (xy 87.904087 -392.299947) (xy 87.918466 -392.350665) (xy 87.925721 -392.40288)
			(xy 87.926164 -392.429238) (xy 87.926164 -393.292838) (xy 87.925655 -393.3193) (xy 87.918311 -393.371712)
			(xy 87.90381 -393.42261) (xy 87.882429 -393.471023) (xy 87.854577 -393.516026) (xy 87.838026 -393.536678)
			(xy 87.832701 -393.543735) (xy 87.826724 -393.560358) (xy 87.826342 -393.56919) (xy 87.826342 -393.59967)
			(xy 87.826729 -393.608444) (xy 87.832698 -393.624947) (xy 87.838026 -393.631928) (xy 87.854625 -393.652699)
			(xy 87.882527 -393.697959) (xy 87.903927 -393.746631) (xy 87.918418 -393.797788) (xy 87.925724 -393.850453)
			(xy 87.926164 -393.877038) (xy 87.925711 -393.902438) (xy 88.358472 -393.902438) (xy 88.358957 -393.874163)
			(xy 88.367242 -393.818222) (xy 88.383639 -393.764101) (xy 88.407794 -393.712968) (xy 88.439185 -393.665929)
			(xy 88.457786 -393.644628) (xy 88.463705 -393.637448) (xy 88.470482 -393.620136) (xy 88.470994 -393.610846)
			(xy 88.471248 -393.579604) (xy 88.470825 -393.570269) (xy 88.464191 -393.552816) (xy 88.458294 -393.545568)
			(xy 88.440322 -393.524562) (xy 88.410045 -393.478308) (xy 88.386768 -393.428165) (xy 88.370982 -393.375185)
			(xy 88.363017 -393.320479) (xy 88.362536 -393.292838) (xy 88.362536 -392.429238) (xy 88.363017 -392.402882)
			(xy 88.37028 -392.350674) (xy 88.384659 -392.299962) (xy 88.40588 -392.251711) (xy 88.43354 -392.20684)
			(xy 88.467112 -392.166202) (xy 88.486234 -392.14806) (xy 88.493346 -392.14171) (xy 88.501474 -392.124946)
			(xy 88.509856 -392.038332) (xy 88.504776 -392.020552) (xy 88.499188 -392.012678) (xy 88.485042 -391.992828)
			(xy 88.462583 -391.949571) (xy 88.447269 -391.903299) (xy 88.439489 -391.855184) (xy 88.43899 -391.830814)
			(xy 88.439512 -391.805559) (xy 88.447825 -391.755737) (xy 88.464226 -391.707963) (xy 88.488267 -391.66354)
			(xy 88.519291 -391.62368) (xy 88.556453 -391.58947) (xy 88.598739 -391.561844) (xy 88.644995 -391.541554)
			(xy 88.69396 -391.529154) (xy 88.744298 -391.524983) (xy 88.794636 -391.529154) (xy 88.843601 -391.541554)
			(xy 88.889857 -391.561844) (xy 88.932143 -391.58947) (xy 88.969305 -391.62368) (xy 89.000329 -391.66354)
			(xy 89.02437 -391.707963) (xy 89.040771 -391.755737) (xy 89.049084 -391.805559) (xy 89.049606 -391.830814)
			(xy 89.049136 -391.855187) (xy 89.041376 -391.903311) (xy 89.026056 -391.949586) (xy 89.003567 -391.992834)
			(xy 88.989408 -392.012678) (xy 88.98382 -392.020552) (xy 88.97874 -392.038332) (xy 88.987122 -392.124946)
			(xy 88.99525 -392.14171) (xy 89.002362 -392.14806) (xy 89.021498 -392.166192) (xy 89.055086 -392.206823)
			(xy 89.082756 -392.251693) (xy 89.103983 -392.299947) (xy 89.118362 -392.350665) (xy 89.125617 -392.40288)
			(xy 89.12606 -392.429238) (xy 89.12606 -393.292838) (xy 89.125578 -393.320749) (xy 89.117439 -393.375975)
			(xy 89.10134 -393.429425) (xy 89.077625 -393.47996) (xy 89.046801 -393.5265) (xy 89.028524 -393.5476)
			(xy 89.02263 -393.55478) (xy 89.015977 -393.572103) (xy 89.01557 -393.581382) (xy 89.01557 -393.612624)
			(xy 89.015988 -393.621899) (xy 89.022647 -393.639217) (xy 89.028524 -393.646406) (xy 89.046817 -393.667646)
			(xy 89.077661 -393.714453) (xy 89.101376 -393.765245) (xy 89.117459 -393.818944) (xy 89.125569 -393.87441)
			(xy 89.12606 -393.902438) (xy 89.125607 -393.927838) (xy 89.558368 -393.927838) (xy 89.558851 -393.90014)
			(xy 89.566795 -393.845318) (xy 89.582537 -393.792206) (xy 89.605751 -393.74191) (xy 89.635954 -393.695473)
			(xy 89.653872 -393.674346) (xy 89.660222 -393.667488) (xy 89.666572 -393.65047) (xy 89.66708 -393.56538)
			(xy 89.66073 -393.548362) (xy 89.654634 -393.54125) (xy 89.637428 -393.520369) (xy 89.608404 -393.474709)
			(xy 89.586118 -393.425409) (xy 89.571015 -393.373455) (xy 89.563399 -393.31989) (xy 89.56294 -393.292838)
			(xy 89.56294 -392.429238) (xy 89.563359 -392.402921) (xy 89.570584 -392.350785) (xy 89.584903 -392.300135)
			(xy 89.606044 -392.251933) (xy 89.633606 -392.207092) (xy 89.667066 -392.166462) (xy 89.68613 -392.148314)
			(xy 89.693242 -392.14171) (xy 89.701624 -392.1252) (xy 89.709752 -392.038332) (xy 89.704672 -392.020552)
			(xy 89.699084 -392.012932) (xy 89.684926 -391.993051) (xy 89.66244 -391.949737) (xy 89.647123 -391.903399)
			(xy 89.639364 -391.855216) (xy 89.638886 -391.830814) (xy 89.639408 -391.805559) (xy 89.647721 -391.755737)
			(xy 89.664122 -391.707963) (xy 89.688163 -391.66354) (xy 89.719187 -391.62368) (xy 89.756349 -391.58947)
			(xy 89.798635 -391.561844) (xy 89.844891 -391.541554) (xy 89.893856 -391.529154) (xy 89.944194 -391.524983)
			(xy 89.994532 -391.529154) (xy 90.043497 -391.541554) (xy 90.089753 -391.561844) (xy 90.132039 -391.58947)
			(xy 90.169201 -391.62368) (xy 90.200225 -391.66354) (xy 90.224266 -391.707963) (xy 90.240667 -391.755737)
			(xy 90.24898 -391.805559) (xy 90.249502 -391.830814) (xy 90.249013 -391.855173) (xy 90.2413 -391.903276)
			(xy 90.226054 -391.949546) (xy 90.203663 -391.992813) (xy 90.189558 -392.012678) (xy 90.183716 -392.020298)
			(xy 90.17889 -392.038078) (xy 90.187018 -392.124946) (xy 90.1954 -392.141456) (xy 90.202512 -392.14806)
			(xy 90.221638 -392.16619) (xy 90.255182 -392.206836) (xy 90.282808 -392.251714) (xy 90.303989 -392.29997)
			(xy 90.318322 -392.350684) (xy 90.325534 -392.402888) (xy 90.325956 -392.429238) (xy 90.325956 -393.292838)
			(xy 90.325505 -393.320138) (xy 90.317727 -393.374181) (xy 90.302322 -393.426563) (xy 90.279603 -393.476212)
			(xy 90.250037 -393.522114) (xy 90.232484 -393.543028) (xy 90.226388 -393.55014) (xy 90.220038 -393.567158)
			(xy 90.220038 -393.652248) (xy 90.226388 -393.669266) (xy 90.232484 -393.676378) (xy 90.250106 -393.697412)
			(xy 90.279806 -393.743554) (xy 90.302636 -393.793452) (xy 90.318132 -393.846092) (xy 90.325979 -393.900402)
			(xy 90.326464 -393.927838) (xy 90.758264 -393.927838) (xy 90.758748 -393.90014) (xy 90.766692 -393.845318)
			(xy 90.782434 -393.792207) (xy 90.805648 -393.74191) (xy 90.835851 -393.695473) (xy 90.853768 -393.674346)
			(xy 90.860118 -393.667488) (xy 90.866468 -393.65047) (xy 90.866976 -393.56538) (xy 90.860626 -393.548362)
			(xy 90.85453 -393.54125) (xy 90.837323 -393.52037) (xy 90.8083 -393.474709) (xy 90.786014 -393.425409)
			(xy 90.770911 -393.373455) (xy 90.763295 -393.31989) (xy 90.762836 -393.292838) (xy 90.762836 -392.429238)
			(xy 90.76331 -392.402892) (xy 90.770539 -392.350699) (xy 90.784877 -392.299996) (xy 90.806052 -392.251747)
			(xy 90.833663 -392.206869) (xy 90.867183 -392.166215) (xy 90.88628 -392.14806) (xy 90.893392 -392.14171)
			(xy 90.90152 -392.124946) (xy 90.909902 -392.038332) (xy 90.904822 -392.020552) (xy 90.899234 -392.012678)
			(xy 90.885082 -391.992833) (xy 90.862625 -391.949573) (xy 90.847314 -391.9033) (xy 90.839534 -391.855184)
			(xy 90.839036 -391.830814) (xy 90.839558 -391.805559) (xy 90.847871 -391.755737) (xy 90.864272 -391.707963)
			(xy 90.888313 -391.66354) (xy 90.919337 -391.62368) (xy 90.956499 -391.58947) (xy 90.998785 -391.561844)
			(xy 91.045041 -391.541554) (xy 91.094006 -391.529154) (xy 91.144344 -391.524983) (xy 91.194682 -391.529154)
			(xy 91.243647 -391.541554) (xy 91.289903 -391.561844) (xy 91.332189 -391.58947) (xy 91.369351 -391.62368)
			(xy 91.400375 -391.66354) (xy 91.424416 -391.707963) (xy 91.440817 -391.755737) (xy 91.44913 -391.805559)
			(xy 91.449652 -391.830814) (xy 91.449173 -391.855186) (xy 91.441415 -391.903309) (xy 91.426097 -391.949585)
			(xy 91.403611 -391.992833) (xy 91.389454 -392.012678) (xy 91.383866 -392.020552) (xy 91.378786 -392.038332)
			(xy 91.387168 -392.124946) (xy 91.395296 -392.14171) (xy 91.402408 -392.14806) (xy 91.421533 -392.166191)
			(xy 91.455077 -392.206836) (xy 91.482703 -392.251715) (xy 91.503885 -392.299971) (xy 91.518218 -392.350684)
			(xy 91.52543 -392.402888) (xy 91.525852 -392.429238) (xy 91.525852 -393.292838) (xy 91.525402 -393.320138)
			(xy 91.517624 -393.374181) (xy 91.502218 -393.426563) (xy 91.4795 -393.476212) (xy 91.449933 -393.522114)
			(xy 91.43238 -393.543028) (xy 91.426284 -393.55014) (xy 91.419934 -393.567158) (xy 91.419934 -393.652248)
			(xy 91.426284 -393.669266) (xy 91.43238 -393.676378) (xy 91.450002 -393.697413) (xy 91.479701 -393.743554)
			(xy 91.502532 -393.793453) (xy 91.518028 -393.846092) (xy 91.525875 -393.900402) (xy 91.52636 -393.927838)
			(xy 91.958668 -393.927838) (xy 91.959112 -393.900149) (xy 91.96701 -393.845337) (xy 91.982704 -393.792229)
			(xy 92.005869 -393.74193) (xy 92.036024 -393.695482) (xy 92.053918 -393.674346) (xy 92.060268 -393.667488)
			(xy 92.066618 -393.65047) (xy 92.067126 -393.56538) (xy 92.060776 -393.548362) (xy 92.05468 -393.54125)
			(xy 92.037431 -393.520391) (xy 92.008349 -393.474743) (xy 91.986009 -393.425443) (xy 91.970861 -393.373482)
			(xy 91.963207 -393.3199) (xy 91.962732 -393.292838) (xy 91.962732 -392.429238) (xy 91.963163 -392.402911)
			(xy 91.970414 -392.350757) (xy 91.984768 -392.300096) (xy 92.005953 -392.251891) (xy 92.033566 -392.207057)
			(xy 92.067083 -392.166447) (xy 92.086176 -392.148314) (xy 92.093288 -392.14171) (xy 92.10167 -392.1252)
			(xy 92.109798 -392.038332) (xy 92.104718 -392.020552) (xy 92.09913 -392.012932) (xy 92.084978 -391.993047)
			(xy 92.062489 -391.949735) (xy 92.04717 -391.903398) (xy 92.03941 -391.855216) (xy 92.038932 -391.830814)
			(xy 92.039454 -391.805559) (xy 92.047767 -391.755737) (xy 92.064168 -391.707963) (xy 92.088209 -391.66354)
			(xy 92.119233 -391.62368) (xy 92.156395 -391.58947) (xy 92.198681 -391.561844) (xy 92.244937 -391.541554)
			(xy 92.293902 -391.529154) (xy 92.34424 -391.524983) (xy 92.394578 -391.529154) (xy 92.443543 -391.541554)
			(xy 92.489799 -391.561844) (xy 92.532085 -391.58947) (xy 92.569247 -391.62368) (xy 92.600271 -391.66354)
			(xy 92.624312 -391.707963) (xy 92.640713 -391.755737) (xy 92.649026 -391.805559) (xy 92.649548 -391.830814)
			(xy 92.649051 -391.855172) (xy 92.641339 -391.903275) (xy 92.626095 -391.949545) (xy 92.603707 -391.992812)
			(xy 92.589604 -392.012678) (xy 92.583762 -392.020298) (xy 92.578936 -392.038078) (xy 92.587064 -392.124946)
			(xy 92.595446 -392.141456) (xy 92.602558 -392.14806) (xy 92.621693 -392.166192) (xy 92.655281 -392.206824)
			(xy 92.682952 -392.251694) (xy 92.704179 -392.299947) (xy 92.718558 -392.350665) (xy 92.725813 -392.40288)
			(xy 92.726256 -392.429238) (xy 92.726256 -393.292838) (xy 92.725746 -393.320143) (xy 92.717897 -393.374189)
			(xy 92.702438 -393.426567) (xy 92.679681 -393.476211) (xy 92.65009 -393.522112) (xy 92.63253 -393.543028)
			(xy 92.626434 -393.55014) (xy 92.620084 -393.567158) (xy 92.620084 -393.652248) (xy 92.626434 -393.669266)
			(xy 92.63253 -393.676378) (xy 92.650144 -393.697411) (xy 92.679813 -393.743555) (xy 92.702599 -393.793459)
			(xy 92.718037 -393.846102) (xy 92.725811 -393.900408) (xy 92.726256 -393.927838) (xy 93.158564 -393.927838)
			(xy 93.159009 -393.900149) (xy 93.166907 -393.845337) (xy 93.182601 -393.79223) (xy 93.205766 -393.74193)
			(xy 93.23592 -393.695482) (xy 93.253814 -393.674346) (xy 93.260164 -393.667488) (xy 93.266514 -393.65047)
			(xy 93.267022 -393.56538) (xy 93.260672 -393.548362) (xy 93.254576 -393.54125) (xy 93.237326 -393.520392)
			(xy 93.208245 -393.474743) (xy 93.185905 -393.425444) (xy 93.170757 -393.373482) (xy 93.163103 -393.3199)
			(xy 93.162628 -393.292838) (xy 93.162628 -392.429238) (xy 93.163112 -392.402883) (xy 93.170374 -392.350674)
			(xy 93.184753 -392.299962) (xy 93.205974 -392.251712) (xy 93.233633 -392.20684) (xy 93.267204 -392.166203)
			(xy 93.286326 -392.14806) (xy 93.293438 -392.14171) (xy 93.301566 -392.124946) (xy 93.309948 -392.038332)
			(xy 93.304868 -392.020552) (xy 93.29928 -392.012678) (xy 93.285133 -391.992829) (xy 93.262674 -391.949571)
			(xy 93.247361 -391.903299) (xy 93.23958 -391.855184) (xy 93.239082 -391.830814) (xy 93.239604 -391.805559)
			(xy 93.247917 -391.755737) (xy 93.264318 -391.707963) (xy 93.288359 -391.66354) (xy 93.319383 -391.62368)
			(xy 93.356545 -391.58947) (xy 93.398831 -391.561844) (xy 93.445087 -391.541554) (xy 93.494052 -391.529154)
			(xy 93.54439 -391.524983) (xy 93.594728 -391.529154) (xy 93.643693 -391.541554) (xy 93.689949 -391.561844)
			(xy 93.732235 -391.58947) (xy 93.769397 -391.62368) (xy 93.800421 -391.66354) (xy 93.824462 -391.707963)
			(xy 93.840863 -391.755737) (xy 93.849176 -391.805559) (xy 93.849698 -391.830814) (xy 93.84923 -391.855187)
			(xy 93.84147 -391.903311) (xy 93.826149 -391.949587) (xy 93.803659 -391.992834) (xy 93.7895 -392.012678)
			(xy 93.783912 -392.020552) (xy 93.778832 -392.038332) (xy 93.787214 -392.124946) (xy 93.795342 -392.14171)
			(xy 93.802454 -392.14806) (xy 93.821589 -392.166193) (xy 93.855176 -392.206824) (xy 93.882848 -392.251694)
			(xy 93.904075 -392.299948) (xy 93.918453 -392.350665) (xy 93.925709 -392.40288) (xy 93.926152 -392.429238)
			(xy 93.926152 -393.292838) (xy 93.925643 -393.320143) (xy 93.917794 -393.374189) (xy 93.902334 -393.426567)
			(xy 93.879577 -393.476212) (xy 93.849987 -393.522112) (xy 93.832426 -393.543028) (xy 93.82633 -393.55014)
			(xy 93.81998 -393.567158) (xy 93.81998 -393.652248) (xy 93.82633 -393.669266) (xy 93.832426 -393.676378)
			(xy 93.850039 -393.697411) (xy 93.879708 -393.743556) (xy 93.902495 -393.793459) (xy 93.917933 -393.846102)
			(xy 93.922362 -393.877038) (xy 94.35846 -393.877038) (xy 94.358878 -393.850182) (xy 94.366323 -393.796988)
			(xy 94.381115 -393.745353) (xy 94.402964 -393.696286) (xy 94.431444 -393.650747) (xy 94.448376 -393.629896)
			(xy 94.453753 -393.622926) (xy 94.459857 -393.606429) (xy 94.460314 -393.597638) (xy 94.460568 -393.567158)
			(xy 94.460271 -393.55831) (xy 94.454288 -393.541659) (xy 94.448884 -393.534646) (xy 94.432599 -393.514118)
			(xy 94.405266 -393.469412) (xy 94.384306 -393.421387) (xy 94.370113 -393.370946) (xy 94.362953 -393.319038)
			(xy 94.362524 -393.292838) (xy 94.362524 -392.429238) (xy 94.363009 -392.402883) (xy 94.370272 -392.350674)
			(xy 94.38465 -392.299963) (xy 94.40587 -392.251712) (xy 94.433529 -392.206841) (xy 94.4671 -392.166203)
			(xy 94.486222 -392.14806) (xy 94.493334 -392.14171) (xy 94.501462 -392.124946) (xy 94.509844 -392.038332)
			(xy 94.504764 -392.020552) (xy 94.499176 -392.012678) (xy 94.485029 -391.992829) (xy 94.46257 -391.949571)
			(xy 94.447257 -391.903299) (xy 94.439476 -391.855184) (xy 94.438978 -391.830814) (xy 94.4395 -391.805559)
			(xy 94.447813 -391.755737) (xy 94.464214 -391.707963) (xy 94.488255 -391.66354) (xy 94.519279 -391.62368)
			(xy 94.556441 -391.58947) (xy 94.598727 -391.561844) (xy 94.644983 -391.541554) (xy 94.693948 -391.529154)
			(xy 94.744286 -391.524983) (xy 94.794624 -391.529154) (xy 94.843589 -391.541554) (xy 94.889845 -391.561844)
			(xy 94.932131 -391.58947) (xy 94.969293 -391.62368) (xy 95.000317 -391.66354) (xy 95.024358 -391.707963)
			(xy 95.040759 -391.755737) (xy 95.049072 -391.805559) (xy 95.049594 -391.830814) (xy 95.049127 -391.855187)
			(xy 95.041366 -391.903311) (xy 95.026046 -391.949587) (xy 95.003555 -391.992834) (xy 94.989396 -392.012678)
			(xy 94.983808 -392.020552) (xy 94.978728 -392.038332) (xy 94.98711 -392.124946) (xy 94.995238 -392.14171)
			(xy 95.00235 -392.14806) (xy 95.021484 -392.166194) (xy 95.055072 -392.206825) (xy 95.082743 -392.251694)
			(xy 95.103971 -392.299948) (xy 95.118349 -392.350665) (xy 95.125605 -392.40288) (xy 95.126048 -392.429238)
			(xy 95.126048 -393.292838) (xy 95.125543 -393.3193) (xy 95.118199 -393.371712) (xy 95.103697 -393.422611)
			(xy 95.082315 -393.471024) (xy 95.054461 -393.516026) (xy 95.03791 -393.536678) (xy 95.032583 -393.543733)
			(xy 95.026608 -393.560358) (xy 95.026226 -393.56919) (xy 95.026226 -393.59967) (xy 95.026616 -393.608444)
			(xy 95.032583 -393.624946) (xy 95.03791 -393.631928) (xy 95.054506 -393.6527) (xy 95.082409 -393.69796)
			(xy 95.10381 -393.746632) (xy 95.118302 -393.797788) (xy 95.125608 -393.850453) (xy 95.126048 -393.877038)
			(xy 95.125559 -393.904453) (xy 95.122197 -393.927838) (xy 95.558356 -393.927838) (xy 95.558779 -393.900148)
			(xy 95.566678 -393.845334) (xy 95.582376 -393.792226) (xy 95.605547 -393.741926) (xy 95.635708 -393.69548)
			(xy 95.653606 -393.674346) (xy 95.659956 -393.667488) (xy 95.666306 -393.65047) (xy 95.666814 -393.56538)
			(xy 95.660464 -393.548362) (xy 95.654368 -393.54125) (xy 95.637117 -393.520393) (xy 95.608036 -393.474744)
			(xy 95.585697 -393.425444) (xy 95.570548 -393.373482) (xy 95.562895 -393.319901) (xy 95.56242 -393.292838)
			(xy 95.56242 -392.429238) (xy 95.562906 -392.402883) (xy 95.570169 -392.350675) (xy 95.584547 -392.299963)
			(xy 95.605767 -392.251712) (xy 95.633426 -392.206841) (xy 95.666996 -392.166203) (xy 95.686118 -392.14806)
			(xy 95.69323 -392.14171) (xy 95.701358 -392.124946) (xy 95.70974 -392.038332) (xy 95.70466 -392.020552)
			(xy 95.699072 -392.012678) (xy 95.684924 -391.992829) (xy 95.662466 -391.949572) (xy 95.647153 -391.903299)
			(xy 95.639372 -391.855184) (xy 95.638874 -391.830814) (xy 95.639396 -391.805559) (xy 95.647709 -391.755737)
			(xy 95.66411 -391.707963) (xy 95.688151 -391.66354) (xy 95.719175 -391.62368) (xy 95.756337 -391.58947)
			(xy 95.798623 -391.561844) (xy 95.844879 -391.541554) (xy 95.893844 -391.529154) (xy 95.944182 -391.524983)
			(xy 95.99452 -391.529154) (xy 96.043485 -391.541554) (xy 96.089741 -391.561844) (xy 96.132027 -391.58947)
			(xy 96.169189 -391.62368) (xy 96.200213 -391.66354) (xy 96.224254 -391.707963) (xy 96.240655 -391.755737)
			(xy 96.248968 -391.805559) (xy 96.24949 -391.830814) (xy 96.249023 -391.855187) (xy 96.241263 -391.903311)
			(xy 96.225942 -391.949587) (xy 96.203452 -391.992834) (xy 96.189292 -392.012678) (xy 96.183704 -392.020552)
			(xy 96.178624 -392.038332) (xy 96.187006 -392.124946) (xy 96.195134 -392.14171) (xy 96.202246 -392.14806)
			(xy 96.221379 -392.166195) (xy 96.254967 -392.206825) (xy 96.282639 -392.251695) (xy 96.303867 -392.299948)
			(xy 96.318245 -392.350665) (xy 96.325501 -392.40288) (xy 96.325944 -392.429238) (xy 96.325944 -393.292838)
			(xy 96.325437 -393.320143) (xy 96.317588 -393.374189) (xy 96.302128 -393.426567) (xy 96.27937 -393.476212)
			(xy 96.249779 -393.522113) (xy 96.232218 -393.543028) (xy 96.226122 -393.55014) (xy 96.219772 -393.567158)
			(xy 96.219772 -393.652248) (xy 96.226122 -393.669266) (xy 96.232218 -393.676378) (xy 96.24983 -393.697412)
			(xy 96.2795 -393.743556) (xy 96.302286 -393.79346) (xy 96.317725 -393.846102) (xy 96.325499 -393.900408)
			(xy 96.325944 -393.927838) (xy 96.758252 -393.927838) (xy 96.758739 -393.90014) (xy 96.766683 -393.845318)
			(xy 96.782424 -393.792207) (xy 96.805637 -393.741911) (xy 96.835839 -393.695473) (xy 96.853756 -393.674346)
			(xy 96.860106 -393.667488) (xy 96.866456 -393.65047) (xy 96.866964 -393.56538) (xy 96.860614 -393.548362)
			(xy 96.854518 -393.54125) (xy 96.837309 -393.520371) (xy 96.808287 -393.47471) (xy 96.786001 -393.425409)
			(xy 96.770899 -393.373456) (xy 96.763283 -393.31989) (xy 96.762824 -393.292838) (xy 96.762824 -392.429238)
			(xy 96.76327 -392.402891) (xy 96.7705 -392.350695) (xy 96.784842 -392.299991) (xy 96.806023 -392.251741)
			(xy 96.833639 -392.206864) (xy 96.867167 -392.166213) (xy 96.886268 -392.14806) (xy 96.89338 -392.14171)
			(xy 96.901508 -392.124946) (xy 96.90989 -392.038332) (xy 96.90481 -392.020552) (xy 96.899222 -392.012678)
			(xy 96.885068 -391.992834) (xy 96.862612 -391.949574) (xy 96.847301 -391.9033) (xy 96.839522 -391.855184)
			(xy 96.839024 -391.830814) (xy 96.839546 -391.805559) (xy 96.847859 -391.755737) (xy 96.86426 -391.707963)
			(xy 96.888301 -391.66354) (xy 96.919325 -391.62368) (xy 96.956487 -391.58947) (xy 96.998773 -391.561844)
			(xy 97.045029 -391.541554) (xy 97.093994 -391.529154) (xy 97.144332 -391.524983) (xy 97.19467 -391.529154)
			(xy 97.243635 -391.541554) (xy 97.289891 -391.561844) (xy 97.332177 -391.58947) (xy 97.369339 -391.62368)
			(xy 97.400363 -391.66354) (xy 97.424404 -391.707963) (xy 97.440805 -391.755737) (xy 97.449118 -391.805559)
			(xy 97.44964 -391.830814) (xy 97.449164 -391.855186) (xy 97.441405 -391.90331) (xy 97.426086 -391.949585)
			(xy 97.403599 -391.992833) (xy 97.389442 -392.012678) (xy 97.383854 -392.020552) (xy 97.378774 -392.038332)
			(xy 97.387156 -392.124946) (xy 97.395284 -392.14171) (xy 97.402396 -392.14806) (xy 97.421519 -392.166193)
			(xy 97.455064 -392.206838) (xy 97.48269 -392.251716) (xy 97.503872 -392.299971) (xy 97.518206 -392.350684)
			(xy 97.525418 -392.402888) (xy 97.52584 -392.429238) (xy 97.52584 -393.292838) (xy 97.525369 -393.320137)
			(xy 97.517593 -393.374179) (xy 97.502191 -393.426559) (xy 97.479477 -393.476208) (xy 97.449917 -393.522112)
			(xy 97.432368 -393.543028) (xy 97.426272 -393.55014) (xy 97.419922 -393.567158) (xy 97.419922 -393.652248)
			(xy 97.426272 -393.669266) (xy 97.432368 -393.676378) (xy 97.449985 -393.697416) (xy 97.479678 -393.743558)
			(xy 97.502503 -393.793457) (xy 97.517995 -393.846095) (xy 97.52584 -393.900403) (xy 97.526348 -393.927838)
			(xy 97.525859 -393.955271) (xy 97.518051 -394.009578) (xy 97.502593 -394.06222) (xy 97.479801 -394.112128)
			(xy 97.450139 -394.158283) (xy 97.41421 -394.199748) (xy 97.372745 -394.235677) (xy 97.32659 -394.265339)
			(xy 97.276682 -394.288131) (xy 97.22404 -394.303589) (xy 97.169733 -394.311397) (xy 97.114867 -394.311397)
			(xy 97.06056 -394.303589) (xy 97.007918 -394.288131) (xy 96.95801 -394.265339) (xy 96.911855 -394.235677)
			(xy 96.87039 -394.199748) (xy 96.834461 -394.158283) (xy 96.804799 -394.112128) (xy 96.782007 -394.06222)
			(xy 96.766549 -394.009578) (xy 96.758741 -393.955271) (xy 96.758252 -393.927838) (xy 96.325944 -393.927838)
			(xy 96.325455 -393.955253) (xy 96.317652 -394.009523) (xy 96.302205 -394.062131) (xy 96.279428 -394.112006)
			(xy 96.249785 -394.158131) (xy 96.21388 -394.199568) (xy 96.172443 -394.235473) (xy 96.126318 -394.265116)
			(xy 96.076443 -394.287893) (xy 96.023835 -394.30334) (xy 95.969565 -394.311143) (xy 95.914735 -394.311143)
			(xy 95.860465 -394.30334) (xy 95.807857 -394.287893) (xy 95.757982 -394.265116) (xy 95.711857 -394.235473)
			(xy 95.67042 -394.199568) (xy 95.634515 -394.158131) (xy 95.604872 -394.112006) (xy 95.582095 -394.062131)
			(xy 95.566648 -394.009523) (xy 95.558845 -393.955253) (xy 95.558356 -393.927838) (xy 95.122197 -393.927838)
			(xy 95.117756 -393.958723) (xy 95.102309 -394.011331) (xy 95.079532 -394.061206) (xy 95.049889 -394.107331)
			(xy 95.013984 -394.148768) (xy 94.972547 -394.184673) (xy 94.926422 -394.214316) (xy 94.876547 -394.237093)
			(xy 94.823939 -394.25254) (xy 94.769669 -394.260343) (xy 94.714839 -394.260343) (xy 94.660569 -394.25254)
			(xy 94.607961 -394.237093) (xy 94.558086 -394.214316) (xy 94.511961 -394.184673) (xy 94.470524 -394.148768)
			(xy 94.434619 -394.107331) (xy 94.404976 -394.061206) (xy 94.382199 -394.011331) (xy 94.366752 -393.958723)
			(xy 94.358949 -393.904453) (xy 94.35846 -393.877038) (xy 93.922362 -393.877038) (xy 93.925707 -393.900408)
			(xy 93.926152 -393.927838) (xy 93.925663 -393.955253) (xy 93.91786 -394.009523) (xy 93.902413 -394.062131)
			(xy 93.879636 -394.112006) (xy 93.849993 -394.158131) (xy 93.814088 -394.199568) (xy 93.772651 -394.235473)
			(xy 93.726526 -394.265116) (xy 93.676651 -394.287893) (xy 93.624043 -394.30334) (xy 93.569773 -394.311143)
			(xy 93.514943 -394.311143) (xy 93.460673 -394.30334) (xy 93.408065 -394.287893) (xy 93.35819 -394.265116)
			(xy 93.312065 -394.235473) (xy 93.270628 -394.199568) (xy 93.234723 -394.158131) (xy 93.20508 -394.112006)
			(xy 93.182303 -394.062131) (xy 93.166856 -394.009523) (xy 93.159053 -393.955253) (xy 93.158564 -393.927838)
			(xy 92.726256 -393.927838) (xy 92.725767 -393.955253) (xy 92.717964 -394.009523) (xy 92.702517 -394.062131)
			(xy 92.67974 -394.112006) (xy 92.650097 -394.158131) (xy 92.614192 -394.199568) (xy 92.572755 -394.235473)
			(xy 92.52663 -394.265116) (xy 92.476755 -394.287893) (xy 92.424147 -394.30334) (xy 92.369877 -394.311143)
			(xy 92.315047 -394.311143) (xy 92.260777 -394.30334) (xy 92.208169 -394.287893) (xy 92.158294 -394.265116)
			(xy 92.112169 -394.235473) (xy 92.070732 -394.199568) (xy 92.034827 -394.158131) (xy 92.005184 -394.112006)
			(xy 91.982407 -394.062131) (xy 91.96696 -394.009523) (xy 91.959157 -393.955253) (xy 91.958668 -393.927838)
			(xy 91.52636 -393.927838) (xy 91.525871 -393.955271) (xy 91.518063 -394.009578) (xy 91.502605 -394.06222)
			(xy 91.479813 -394.112128) (xy 91.450151 -394.158283) (xy 91.414222 -394.199748) (xy 91.372757 -394.235677)
			(xy 91.326602 -394.265339) (xy 91.276694 -394.288131) (xy 91.224052 -394.303589) (xy 91.169745 -394.311397)
			(xy 91.114879 -394.311397) (xy 91.060572 -394.303589) (xy 91.00793 -394.288131) (xy 90.958022 -394.265339)
			(xy 90.911867 -394.235677) (xy 90.870402 -394.199748) (xy 90.834473 -394.158283) (xy 90.804811 -394.112128)
			(xy 90.782019 -394.06222) (xy 90.766561 -394.009578) (xy 90.758753 -393.955271) (xy 90.758264 -393.927838)
			(xy 90.326464 -393.927838) (xy 90.325975 -393.955271) (xy 90.318167 -394.009578) (xy 90.302709 -394.06222)
			(xy 90.279917 -394.112128) (xy 90.250255 -394.158283) (xy 90.214326 -394.199748) (xy 90.172861 -394.235677)
			(xy 90.126706 -394.265339) (xy 90.076798 -394.288131) (xy 90.024156 -394.303589) (xy 89.969849 -394.311397)
			(xy 89.914983 -394.311397) (xy 89.860676 -394.303589) (xy 89.808034 -394.288131) (xy 89.758126 -394.265339)
			(xy 89.711971 -394.235677) (xy 89.670506 -394.199748) (xy 89.634577 -394.158283) (xy 89.604915 -394.112128)
			(xy 89.582123 -394.06222) (xy 89.566665 -394.009578) (xy 89.558857 -393.955271) (xy 89.558368 -393.927838)
			(xy 89.125607 -393.927838) (xy 89.125571 -393.929853) (xy 89.117768 -393.984123) (xy 89.102321 -394.036731)
			(xy 89.079544 -394.086606) (xy 89.049901 -394.132731) (xy 89.013996 -394.174168) (xy 88.972559 -394.210073)
			(xy 88.926434 -394.239716) (xy 88.876559 -394.262493) (xy 88.823951 -394.27794) (xy 88.769681 -394.285743)
			(xy 88.714851 -394.285743) (xy 88.660581 -394.27794) (xy 88.607973 -394.262493) (xy 88.558098 -394.239716)
			(xy 88.511973 -394.210073) (xy 88.470536 -394.174168) (xy 88.434631 -394.132731) (xy 88.404988 -394.086606)
			(xy 88.382211 -394.036731) (xy 88.366764 -393.984123) (xy 88.358961 -393.929853) (xy 88.358472 -393.902438)
			(xy 87.925711 -393.902438) (xy 87.925675 -393.904453) (xy 87.917872 -393.958723) (xy 87.902425 -394.011331)
			(xy 87.879648 -394.061206) (xy 87.850005 -394.107331) (xy 87.8141 -394.148768) (xy 87.772663 -394.184673)
			(xy 87.726538 -394.214316) (xy 87.676663 -394.237093) (xy 87.624055 -394.25254) (xy 87.569785 -394.260343)
			(xy 87.514955 -394.260343) (xy 87.460685 -394.25254) (xy 87.408077 -394.237093) (xy 87.358202 -394.214316)
			(xy 87.312077 -394.184673) (xy 87.27064 -394.148768) (xy 87.234735 -394.107331) (xy 87.205092 -394.061206)
			(xy 87.182315 -394.011331) (xy 87.166868 -393.958723) (xy 87.159065 -393.904453) (xy 87.158576 -393.877038)
			(xy 86.722407 -393.877038) (xy 86.725783 -393.900402) (xy 86.726268 -393.927838) (xy 86.725779 -393.955271)
			(xy 86.717971 -394.009578) (xy 86.702513 -394.06222) (xy 86.679721 -394.112128) (xy 86.650059 -394.158283)
			(xy 86.61413 -394.199748) (xy 86.572665 -394.235677) (xy 86.52651 -394.265339) (xy 86.476602 -394.288131)
			(xy 86.42396 -394.303589) (xy 86.369653 -394.311397) (xy 86.314787 -394.311397) (xy 86.26048 -394.303589)
			(xy 86.207838 -394.288131) (xy 86.15793 -394.265339) (xy 86.111775 -394.235677) (xy 86.07031 -394.199748)
			(xy 86.034381 -394.158283) (xy 86.004719 -394.112128) (xy 85.981927 -394.06222) (xy 85.966469 -394.009578)
			(xy 85.958661 -393.955271) (xy 85.958172 -393.927838) (xy 85.526372 -393.927838) (xy 85.525883 -393.955271)
			(xy 85.518075 -394.009578) (xy 85.502617 -394.06222) (xy 85.479825 -394.112128) (xy 85.450163 -394.158283)
			(xy 85.414234 -394.199748) (xy 85.372769 -394.235677) (xy 85.326614 -394.265339) (xy 85.276706 -394.288131)
			(xy 85.224064 -394.303589) (xy 85.169757 -394.311397) (xy 85.114891 -394.311397) (xy 85.060584 -394.303589)
			(xy 85.007942 -394.288131) (xy 84.958034 -394.265339) (xy 84.911879 -394.235677) (xy 84.870414 -394.199748)
			(xy 84.834485 -394.158283) (xy 84.804823 -394.112128) (xy 84.782031 -394.06222) (xy 84.766573 -394.009578)
			(xy 84.758765 -393.955271) (xy 84.758276 -393.927838) (xy 84.322117 -393.927838) (xy 84.317676 -393.958723)
			(xy 84.302229 -394.011331) (xy 84.279452 -394.061206) (xy 84.249809 -394.107331) (xy 84.213904 -394.148768)
			(xy 84.172467 -394.184673) (xy 84.126342 -394.214316) (xy 84.076467 -394.237093) (xy 84.023859 -394.25254)
			(xy 83.969589 -394.260343) (xy 83.914759 -394.260343) (xy 83.860489 -394.25254) (xy 83.807881 -394.237093)
			(xy 83.758006 -394.214316) (xy 83.711881 -394.184673) (xy 83.670444 -394.148768) (xy 83.634539 -394.107331)
			(xy 83.604896 -394.061206) (xy 83.582119 -394.011331) (xy 83.566672 -393.958723) (xy 83.558869 -393.904453)
			(xy 83.55838 -393.877038) (xy 83.122282 -393.877038) (xy 83.125627 -393.900408) (xy 83.126072 -393.927838)
			(xy 83.125583 -393.955253) (xy 83.11778 -394.009523) (xy 83.102333 -394.062131) (xy 83.079556 -394.112006)
			(xy 83.049913 -394.158131) (xy 83.014008 -394.199568) (xy 82.972571 -394.235473) (xy 82.926446 -394.265116)
			(xy 82.876571 -394.287893) (xy 82.823963 -394.30334) (xy 82.769693 -394.311143) (xy 82.714863 -394.311143)
			(xy 82.660593 -394.30334) (xy 82.607985 -394.287893) (xy 82.55811 -394.265116) (xy 82.511985 -394.235473)
			(xy 82.470548 -394.199568) (xy 82.434643 -394.158131) (xy 82.405 -394.112006) (xy 82.382223 -394.062131)
			(xy 82.366776 -394.009523) (xy 82.358973 -393.955253) (xy 82.358484 -393.927838) (xy 81.925723 -393.927838)
			(xy 81.925687 -393.929871) (xy 81.917879 -393.984178) (xy 81.902421 -394.03682) (xy 81.879629 -394.086728)
			(xy 81.849967 -394.132883) (xy 81.814038 -394.174348) (xy 81.772573 -394.210277) (xy 81.726418 -394.239939)
			(xy 81.67651 -394.262731) (xy 81.623868 -394.278189) (xy 81.569561 -394.285997) (xy 81.514695 -394.285997)
			(xy 81.460388 -394.278189) (xy 81.407746 -394.262731) (xy 81.357838 -394.239939) (xy 81.311683 -394.210277)
			(xy 81.270218 -394.174348) (xy 81.234289 -394.132883) (xy 81.204627 -394.086728) (xy 81.181835 -394.03682)
			(xy 81.166377 -393.984178) (xy 81.158569 -393.929871) (xy 81.15808 -393.902438) (xy 80.72628 -393.902438)
			(xy 80.725791 -393.929871) (xy 80.717983 -393.984178) (xy 80.702525 -394.03682) (xy 80.679733 -394.086728)
			(xy 80.650071 -394.132883) (xy 80.614142 -394.174348) (xy 80.572677 -394.210277) (xy 80.526522 -394.239939)
			(xy 80.476614 -394.262731) (xy 80.423972 -394.278189) (xy 80.369665 -394.285997) (xy 80.314799 -394.285997)
			(xy 80.260492 -394.278189) (xy 80.20785 -394.262731) (xy 80.157942 -394.239939) (xy 80.111787 -394.210277)
			(xy 80.070322 -394.174348) (xy 80.034393 -394.132883) (xy 80.004731 -394.086728) (xy 79.981939 -394.03682)
			(xy 79.966481 -393.984178) (xy 79.958673 -393.929871) (xy 79.958184 -393.902438) (xy 75.924664 -393.902438)
			(xy 75.897292 -393.902008) (xy 75.843111 -393.894184) (xy 75.790607 -393.878687) (xy 75.740861 -393.855837)
			(xy 75.694896 -393.826104) (xy 75.673966 -393.808458) (xy 75.666854 -393.802362) (xy 75.649836 -393.796012)
			(xy 75.564492 -393.796012) (xy 75.547474 -393.802362) (xy 75.540362 -393.808458) (xy 75.519429 -393.826099)
			(xy 75.473461 -393.855823) (xy 75.423715 -393.878669) (xy 75.371213 -393.894165) (xy 75.317035 -393.901994)
			(xy 75.262293 -393.901994) (xy 75.208115 -393.894165) (xy 75.155613 -393.878669) (xy 75.105867 -393.855823)
			(xy 75.059899 -393.826099) (xy 75.038966 -393.808458) (xy 75.031854 -393.802362) (xy 75.014836 -393.796012)
			(xy 74.929492 -393.796012) (xy 74.912474 -393.802362) (xy 74.905362 -393.808458) (xy 74.884429 -393.826099)
			(xy 74.838461 -393.855823) (xy 74.788715 -393.878669) (xy 74.736213 -393.894165) (xy 74.682035 -393.901994)
			(xy 74.627293 -393.901994) (xy 74.573115 -393.894165) (xy 74.520613 -393.878669) (xy 74.470867 -393.855823)
			(xy 74.424899 -393.826099) (xy 74.403966 -393.808458) (xy 74.396854 -393.802362) (xy 74.379836 -393.796012)
			(xy 74.294492 -393.796012) (xy 74.277474 -393.802362) (xy 74.270362 -393.808458) (xy 74.249412 -393.826075)
			(xy 74.203445 -393.855792) (xy 74.153702 -393.878632) (xy 74.101205 -393.894129) (xy 74.047032 -393.901962)
			(xy 74.019664 -393.902438) (xy 73.992413 -393.901956) (xy 73.938467 -393.894195) (xy 73.886174 -393.878837)
			(xy 73.836599 -393.856194) (xy 73.79075 -393.826727) (xy 73.749561 -393.791035) (xy 73.71387 -393.749845)
			(xy 73.684403 -393.703996) (xy 73.661761 -393.65442) (xy 73.646404 -393.602127) (xy 73.638644 -393.548181)
			(xy 73.638156 -393.52093) (xy 72.783192 -393.52093) (xy 72.782772 -393.551662) (xy 72.77536 -393.612678)
			(xy 72.760647 -393.672356) (xy 72.738849 -393.729825) (xy 72.710282 -393.784248) (xy 72.675363 -393.83483)
			(xy 72.634603 -393.880835) (xy 72.588594 -393.921592) (xy 72.538008 -393.956506) (xy 72.483583 -393.985067)
			(xy 72.426112 -394.006861) (xy 72.366433 -394.021568) (xy 72.305416 -394.028975) (xy 72.274684 -394.029438)
			(xy 72.243988 -394.028947) (xy 72.183044 -394.021548) (xy 72.123436 -394.006859) (xy 72.066032 -393.985096)
			(xy 72.011668 -393.956574) (xy 71.98614 -393.939522) (xy 71.977388 -393.934051) (xy 71.957184 -393.929923)
			(xy 71.93698 -393.934051) (xy 71.928228 -393.939522) (xy 71.902703 -393.956577) (xy 71.848332 -393.985085)
			(xy 71.790927 -394.006845) (xy 71.73132 -394.021541) (xy 71.670379 -394.02896) (xy 71.639684 -394.029438)
			(xy 71.608988 -394.028947) (xy 71.548044 -394.021548) (xy 71.488436 -394.006859) (xy 71.431032 -393.985096)
			(xy 71.376668 -393.956574) (xy 71.35114 -393.939522) (xy 71.342388 -393.934051) (xy 71.322184 -393.929923)
			(xy 71.30198 -393.934051) (xy 71.293228 -393.939522) (xy 71.267703 -393.956577) (xy 71.213332 -393.985085)
			(xy 71.155927 -394.006845) (xy 71.09632 -394.021541) (xy 71.035379 -394.02896) (xy 71.004684 -394.029438)
			(xy 70.973988 -394.028947) (xy 70.913044 -394.021548) (xy 70.853436 -394.006859) (xy 70.796032 -393.985096)
			(xy 70.741668 -393.956574) (xy 70.71614 -393.939522) (xy 70.707388 -393.934051) (xy 70.687184 -393.929923)
			(xy 70.66698 -393.934051) (xy 70.658228 -393.939522) (xy 70.632703 -393.956577) (xy 70.578332 -393.985085)
			(xy 70.520927 -394.006845) (xy 70.46132 -394.021541) (xy 70.400379 -394.02896) (xy 70.369684 -394.029438)
			(xy 70.338988 -394.028947) (xy 70.278044 -394.021548) (xy 70.218436 -394.006859) (xy 70.161032 -393.985096)
			(xy 70.106668 -393.956574) (xy 70.08114 -393.939522) (xy 70.072388 -393.934051) (xy 70.052184 -393.929923)
			(xy 70.03198 -393.934051) (xy 70.023228 -393.939522) (xy 69.997703 -393.956577) (xy 69.943332 -393.985085)
			(xy 69.885927 -394.006845) (xy 69.82632 -394.021541) (xy 69.765379 -394.02896) (xy 69.734684 -394.029438)
			(xy 69.703954 -394.028959) (xy 69.642942 -394.021549) (xy 69.583268 -394.00684) (xy 69.525801 -393.985045)
			(xy 69.471381 -393.956483) (xy 69.4208 -393.921569) (xy 69.374796 -393.880814) (xy 69.334039 -393.834811)
			(xy 69.299124 -393.784231) (xy 69.270561 -393.729811) (xy 69.248764 -393.672346) (xy 69.234053 -393.612672)
			(xy 69.226642 -393.55166) (xy 69.226176 -393.52093) (xy 68.948932 -393.52093) (xy 68.948445 -393.521968)
			(xy 68.917672 -393.568481) (xy 68.880455 -393.610018) (xy 68.837587 -393.645693) (xy 68.789981 -393.674747)
			(xy 68.738652 -393.696559) (xy 68.684695 -393.710665) (xy 68.629258 -393.716765) (xy 68.573524 -393.714728)
			(xy 68.518681 -393.704598) (xy 68.465897 -393.686591) (xy 68.416297 -393.66109) (xy 68.370939 -393.628639)
			(xy 68.33079 -393.58993) (xy 68.296704 -393.545787) (xy 68.269408 -393.497152) (xy 68.249485 -393.445061)
			(xy 68.237359 -393.390624) (xy 68.233288 -393.335002) (xy 67.02298 -393.335002) (xy 67.02298 -393.934696)
			(xy 67.04203 -393.961112) (xy 67.057524 -393.966446) (xy 67.08977 -393.977903) (xy 67.151546 -394.007346)
			(xy 67.209427 -394.043857) (xy 67.262607 -394.086927) (xy 67.310348 -394.135958) (xy 67.33159 -394.162788)
			(xy 67.336924 -394.1699) (xy 67.351148 -394.179044) (xy 68.043891 -394.352018) (xy 78.732886 -394.352018)
			(xy 78.736957 -394.296396) (xy 78.749083 -394.241959) (xy 78.769006 -394.189868) (xy 78.796302 -394.141233)
			(xy 78.830388 -394.09709) (xy 78.870537 -394.058381) (xy 78.915895 -394.02593) (xy 78.965495 -394.000429)
			(xy 79.018279 -393.982422) (xy 79.073122 -393.972292) (xy 79.128856 -393.970255) (xy 79.184293 -393.976355)
			(xy 79.23825 -393.990461) (xy 79.289579 -394.012273) (xy 79.337185 -394.041327) (xy 79.380053 -394.077002)
			(xy 79.41727 -394.118539) (xy 79.448043 -394.165052) (xy 79.471715 -394.215549) (xy 79.487783 -394.268956)
			(xy 79.495903 -394.324132) (xy 79.496412 -394.352018) (xy 79.495903 -394.379904) (xy 79.487783 -394.43508)
			(xy 79.471715 -394.488487) (xy 79.448043 -394.538984) (xy 79.41727 -394.585497) (xy 79.380053 -394.627034)
			(xy 79.337185 -394.662709) (xy 79.289579 -394.691763) (xy 79.23825 -394.713575) (xy 79.184293 -394.727681)
			(xy 79.128856 -394.733781) (xy 79.073122 -394.731744) (xy 79.018279 -394.721614) (xy 78.965495 -394.703607)
			(xy 78.915895 -394.678106) (xy 78.870537 -394.645655) (xy 78.830388 -394.606946) (xy 78.796302 -394.562803)
			(xy 78.769006 -394.514168) (xy 78.749083 -394.462077) (xy 78.736957 -394.40764) (xy 78.732886 -394.352018)
			(xy 68.043891 -394.352018) (xy 68.182236 -394.386562) (xy 68.189602 -394.387832) (xy 70.531736 -394.620242)
			(xy 70.547992 -394.616178) (xy 70.555358 -394.611352) (xy 70.583546 -394.59373) (xy 70.643174 -394.56434)
			(xy 70.705774 -394.541965) (xy 70.770523 -394.526898) (xy 70.83657 -394.519339) (xy 70.86981 -394.518896)
			(xy 70.884121 -394.518978) (xy 70.912709 -394.520376) (xy 70.92696 -394.52169) (xy 71.351902 -394.563854)
			(xy 71.384194 -394.567495) (xy 71.447749 -394.581066) (xy 71.509387 -394.60166) (xy 71.568335 -394.629017)
			(xy 71.623854 -394.662795) (xy 71.675248 -394.70257) (xy 71.698866 -394.72489) (xy 71.705216 -394.73124)
			(xy 71.720202 -394.738352) (xy 73.137014 -394.878814) (xy 73.15327 -394.87475) (xy 73.160636 -394.869924)
			(xy 73.188824 -394.852302) (xy 73.248452 -394.822911) (xy 73.311052 -394.800534) (xy 73.375801 -394.785466)
			(xy 73.441848 -394.777905) (xy 73.475088 -394.777468) (xy 73.489399 -394.77755) (xy 73.517987 -394.778947)
			(xy 73.532238 -394.780262) (xy 73.95718 -394.822426) (xy 73.987595 -394.825805) (xy 74.047533 -394.838165)
			(xy 74.105831 -394.856783) (xy 74.161838 -394.881452) (xy 74.188574 -394.89634) (xy 74.194452 -394.89948)
			(xy 74.207314 -394.902946) (xy 74.213974 -394.903198) (xy 77.671676 -394.903198) (xy 77.68174 -394.903635)
			(xy 77.700325 -394.911369) (xy 77.707744 -394.918184) (xy 78.211934 -395.422374) (xy 78.22311 -395.428978)
			(xy 78.229714 -395.430756) (xy 78.263076 -395.440497) (xy 78.327379 -395.466871) (xy 78.388066 -395.500747)
			(xy 78.444266 -395.541638) (xy 78.495172 -395.588957) (xy 78.518004 -395.61516) (xy 78.523592 -395.622018)
			(xy 78.53807 -395.630654) (xy 78.564232 -395.635734) (xy 78.580996 -395.633448) (xy 78.58887 -395.629384)
			(xy 78.619742 -395.614021) (xy 78.684346 -395.589903) (xy 78.751354 -395.573614) (xy 78.819821 -395.565381)
			(xy 78.8543 -395.564868) (xy 78.882683 -395.565238) (xy 78.939173 -395.570834) (xy 78.967076 -395.576044)
			(xy 79.385668 -395.659102) (xy 79.417504 -395.665861) (xy 79.479526 -395.685593) (xy 79.538945 -395.712155)
			(xy 79.59501 -395.745213) (xy 79.647015 -395.784348) (xy 79.694303 -395.829068) (xy 79.715614 -395.853666)
			(xy 79.721202 -395.86027) (xy 79.73568 -395.868906) (xy 80.38592 -395.998192) (xy 80.40243 -395.995906)
			(xy 80.410304 -395.991842) (xy 80.441181 -395.976505) (xy 80.505792 -395.952443) (xy 80.5728 -395.936216)
			(xy 80.641261 -395.928053) (xy 80.675734 -395.92758) (xy 80.704111 -395.927891) (xy 80.7606 -395.933367)
			(xy 80.78851 -395.938502) (xy 81.207356 -396.02156) (xy 81.23919 -396.028323) (xy 81.301207 -396.048062)
			(xy 81.360621 -396.074629) (xy 81.416681 -396.10769) (xy 81.468681 -396.146828) (xy 81.515965 -396.191549)
			(xy 81.537302 -396.216124) (xy 81.54289 -396.222728) (xy 81.557368 -396.231364) (xy 84.320126 -396.78102)
			(xy 84.365593 -396.790482) (xy 84.45501 -396.8156) (xy 84.542185 -396.847645) (xy 84.626581 -396.886422)
			(xy 84.70768 -396.931692) (xy 84.746592 -396.957042) (xy 84.747354 -396.95755) (xy 84.89696 -397.057626)
			(xy 84.913216 -397.06169) (xy 84.921852 -397.060928) (xy 84.933894 -397.059979) (xy 84.958032 -397.058962)
			(xy 84.970112 -397.058896) (xy 85.004249 -397.0594) (xy 85.072049 -397.067444) (xy 85.138431 -397.083408)
			(xy 85.202475 -397.10707) (xy 85.263291 -397.1381) (xy 85.29193 -397.156686) (xy 85.647022 -397.393922)
			(xy 85.673771 -397.412342) (xy 85.723403 -397.454236) (xy 85.768042 -397.501414) (xy 85.807131 -397.553284)
			(xy 85.840179 -397.609197) (xy 85.866774 -397.668452) (xy 85.877146 -397.69923) (xy 85.87994 -397.707866)
			(xy 85.8901 -397.721074) (xy 86.823042 -398.344644) (xy 86.829403 -398.348621) (xy 86.843739 -398.353016)
			(xy 86.851236 -398.35328)
		)
		(stroke
			(width 0)
			(type solid)
		)
		(fill yes)
		(layer "In15.Cu")
		(net "P0V9_CPU1_RT1_2A_2D")
	)
	(gr_poly
		(pts
			(xy 317.425832 -368.749326) (xy 317.4359 -368.748898) (xy 317.454499 -368.741178) (xy 317.4619 -368.73434)
			(xy 318.80556 -367.39068) (xy 318.812303 -367.38331) (xy 318.819895 -367.364848) (xy 318.820292 -367.354866)
			(xy 318.820292 -364.500414) (xy 318.817498 -364.492032) (xy 318.806992 -364.460812) (xy 318.795628 -364.395933)
			(xy 318.794892 -364.363) (xy 318.795378 -364.335749) (xy 318.803134 -364.281801) (xy 318.818489 -364.229506)
			(xy 318.841131 -364.179929) (xy 318.870597 -364.134079) (xy 318.906288 -364.092888) (xy 318.947479 -364.057197)
			(xy 318.993329 -364.027731) (xy 319.042906 -364.005089) (xy 319.095201 -363.989734) (xy 319.149149 -363.981978)
			(xy 319.203651 -363.981978) (xy 319.257599 -363.989734) (xy 319.309894 -364.005089) (xy 319.359471 -364.027731)
			(xy 319.405321 -364.057197) (xy 319.446512 -364.092888) (xy 319.482203 -364.134079) (xy 319.511669 -364.179929)
			(xy 319.534311 -364.229506) (xy 319.549666 -364.281801) (xy 319.557422 -364.335749) (xy 319.557908 -364.363)
			(xy 319.557192 -364.395934) (xy 319.54582 -364.460814) (xy 319.535302 -364.492032) (xy 319.532508 -364.500414)
			(xy 319.532508 -367.523268) (xy 319.53194 -367.551245) (xy 319.523154 -367.606507) (xy 319.50584 -367.659716)
			(xy 319.480424 -367.709566) (xy 319.44753 -367.754831) (xy 319.428114 -367.774982) (xy 318.540384 -368.662712)
			(xy 318.533687 -368.670153) (xy 318.526085 -368.688652) (xy 318.526105 -368.708651) (xy 318.529462 -368.718084)
			(xy 318.535304 -368.732308) (xy 318.560704 -368.749326) (xy 326.963278 -368.749326) (xy 326.973329 -368.748821)
			(xy 326.99189 -368.7411) (xy 326.999346 -368.73434) (xy 331.249528 -364.484158) (xy 331.256925 -364.47731)
			(xy 331.275524 -364.469576) (xy 331.285596 -364.469172) (xy 338.608162 -364.469172) (xy 338.613744 -364.469028)
			(xy 338.62464 -364.466594) (xy 338.629752 -364.464346) (xy 338.658522 -364.451414) (xy 338.718264 -364.431165)
			(xy 338.779853 -364.417531) (xy 338.84256 -364.410674) (xy 338.8741 -364.410244) (xy 362.58246 -364.410244)
			(xy 362.592424 -364.40976) (xy 362.610854 -364.402179) (xy 362.618274 -364.395512) (xy 364.4392 -362.574586)
			(xy 364.446044 -362.567187) (xy 364.453773 -362.548589) (xy 364.454186 -362.538518) (xy 364.454186 -334.121252)
			(xy 364.453754 -334.111186) (xy 364.446026 -334.092596) (xy 364.4392 -334.085184) (xy 360.186986 -329.83297)
			(xy 360.17959 -329.826118) (xy 360.160991 -329.818378) (xy 360.150918 -329.817984) (xy 348.704154 -329.817984)
			(xy 348.694088 -329.817552) (xy 348.675497 -329.809824) (xy 348.668086 -329.802998) (xy 346.542614 -327.677526)
			(xy 346.535502 -327.67016) (xy 346.516706 -327.66254) (xy 314.604654 -327.66254) (xy 314.594588 -327.662973)
			(xy 314.576 -327.670703) (xy 314.568586 -327.677526) (xy 313.554618 -328.691494) (xy 313.547252 -328.698606)
			(xy 313.539632 -328.717402) (xy 313.539632 -334.703674) (xy 313.539128 -334.713725) (xy 313.531408 -334.732288)
			(xy 313.524646 -334.739742) (xy 312.429398 -335.83499) (xy 312.422 -335.841837) (xy 312.403402 -335.849572)
			(xy 312.39333 -335.849976) (xy 306.4764 -335.849976) (xy 306.463894 -335.850625) (xy 306.441794 -335.862343)
			(xy 306.434236 -335.872328) (xy 306.418951 -335.894153) (xy 306.383296 -335.933746) (xy 306.34248 -335.967995)
			(xy 306.297296 -335.996232) (xy 306.248623 -336.017909) (xy 306.197408 -336.032604) (xy 306.144647 -336.040031)
			(xy 306.118006 -336.040476) (xy 306.090636 -336.040005) (xy 306.036458 -336.032181) (xy 305.983954 -336.016694)
			(xy 305.934203 -335.993861) (xy 305.888227 -335.964152) (xy 305.867308 -335.946496) (xy 305.860196 -335.9404)
			(xy 305.843432 -335.93405) (xy 305.75758 -335.93405) (xy 305.740816 -335.9404) (xy 305.733704 -335.946496)
			(xy 305.712773 -335.964138) (xy 305.666807 -335.993865) (xy 305.61706 -336.016709) (xy 305.564556 -336.0322)
			(xy 305.510377 -336.040019) (xy 305.483006 -336.040476) (xy 305.456364 -336.040033) (xy 305.403599 -336.032617)
			(xy 305.35238 -336.017928) (xy 305.303704 -335.996253) (xy 305.258519 -335.968014) (xy 305.217705 -335.933759)
			(xy 305.182056 -335.894158) (xy 305.166776 -335.872328) (xy 305.159245 -335.862312) (xy 305.137129 -335.850596)
			(xy 305.124612 -335.849976) (xy 304.230786 -335.849976) (xy 304.224346 -335.850163) (xy 304.211873 -335.853371)
			(xy 304.206148 -335.856326) (xy 304.179986 -335.871058) (xy 304.17135 -335.878932) (xy 304.168048 -335.884266)
			(xy 304.152799 -335.906409) (xy 304.117077 -335.94659) (xy 304.076073 -335.981364) (xy 304.030599 -336.010046)
			(xy 303.981552 -336.032068) (xy 303.929901 -336.046995) (xy 303.876668 -336.054531) (xy 303.849786 -336.054954)
			(xy 303.821048 -336.054432) (xy 303.764222 -336.045807) (xy 303.709333 -336.028753) (xy 303.657624 -336.003658)
			(xy 303.610265 -335.971089) (xy 303.588928 -335.95183) (xy 303.581816 -335.944972) (xy 303.564036 -335.938114)
			(xy 303.475136 -335.938114) (xy 303.457356 -335.944972) (xy 303.450244 -335.95183) (xy 303.428916 -335.971098)
			(xy 303.381552 -336.003657) (xy 303.329839 -336.028743) (xy 303.27495 -336.045788) (xy 303.218124 -336.054407)
			(xy 303.189386 -336.054954) (xy 303.176648 -336.054875) (xy 303.151227 -336.053221) (xy 303.138586 -336.051652)
			(xy 303.138586 -336.051906) (xy 303.111727 -336.047822) (xy 303.05945 -336.033042) (xy 303.009796 -336.010999)
			(xy 302.96377 -335.982138) (xy 302.922301 -335.947043) (xy 302.886227 -335.906422) (xy 302.87087 -335.884012)
			(xy 302.867568 -335.878932) (xy 302.858932 -335.870804) (xy 302.833024 -335.856326) (xy 302.8273 -335.853368)
			(xy 302.814827 -335.850153) (xy 302.808386 -335.849976) (xy 266.923774 -335.849976) (xy 266.913705 -335.850403)
			(xy 266.895105 -335.858122) (xy 266.887706 -335.864962) (xy 266.102592 -336.650076) (xy 314.281312 -336.650076)
			(xy 314.28181 -336.622166) (xy 314.289946 -336.566941) (xy 314.306042 -336.513491) (xy 314.329753 -336.462956)
			(xy 314.360573 -336.416415) (xy 314.378848 -336.395314) (xy 314.385198 -336.388202) (xy 314.391802 -336.37093)
			(xy 314.391802 -336.283808) (xy 314.385198 -336.266536) (xy 314.378848 -336.259424) (xy 314.360552 -336.23834)
			(xy 314.329729 -336.191796) (xy 314.306018 -336.141258) (xy 314.289925 -336.087803) (xy 314.281795 -336.032574)
			(xy 314.281312 -336.004662) (xy 314.281798 -335.977411) (xy 314.289554 -335.923463) (xy 314.304909 -335.871168)
			(xy 314.327551 -335.821591) (xy 314.357017 -335.775741) (xy 314.392708 -335.73455) (xy 314.433899 -335.698859)
			(xy 314.479749 -335.669393) (xy 314.529326 -335.646751) (xy 314.581621 -335.631396) (xy 314.635569 -335.62364)
			(xy 314.690071 -335.62364) (xy 314.744019 -335.631396) (xy 314.796314 -335.646751) (xy 314.845891 -335.669393)
			(xy 314.891741 -335.698859) (xy 314.932932 -335.73455) (xy 314.968623 -335.775741) (xy 314.998089 -335.821591)
			(xy 315.020731 -335.871168) (xy 315.036086 -335.923463) (xy 315.043842 -335.977411) (xy 315.044328 -336.004662)
			(xy 315.043868 -336.032574) (xy 315.035725 -336.087801) (xy 315.019621 -336.141252) (xy 314.995902 -336.191786)
			(xy 314.965071 -336.238325) (xy 314.946792 -336.259424) (xy 314.940442 -336.266536) (xy 314.933838 -336.283808)
			(xy 314.933838 -336.37093) (xy 314.940442 -336.388202) (xy 314.946792 -336.395314) (xy 314.965049 -336.416431)
			(xy 314.99588 -336.462964) (xy 315.0196 -336.513494) (xy 315.035701 -336.566942) (xy 315.04384 -336.622166)
			(xy 315.044328 -336.650076) (xy 315.043842 -336.677327) (xy 315.036086 -336.731275) (xy 315.020731 -336.78357)
			(xy 314.998089 -336.833147) (xy 314.968623 -336.878997) (xy 314.932932 -336.920188) (xy 314.891741 -336.955879)
			(xy 314.845891 -336.985345) (xy 314.796314 -337.007987) (xy 314.744019 -337.023342) (xy 314.690071 -337.031098)
			(xy 314.635569 -337.031098) (xy 314.581621 -337.023342) (xy 314.529326 -337.007987) (xy 314.479749 -336.985345)
			(xy 314.433899 -336.955879) (xy 314.392708 -336.920188) (xy 314.357017 -336.878997) (xy 314.327551 -336.833147)
			(xy 314.304909 -336.78357) (xy 314.289554 -336.731275) (xy 314.281798 -336.677327) (xy 314.281312 -336.650076)
			(xy 266.102592 -336.650076) (xy 264.870946 -337.881722) (xy 315.239144 -337.881722) (xy 315.243215 -337.8261)
			(xy 315.255341 -337.771663) (xy 315.275264 -337.719572) (xy 315.30256 -337.670937) (xy 315.336646 -337.626794)
			(xy 315.376795 -337.588085) (xy 315.422153 -337.555634) (xy 315.471753 -337.530133) (xy 315.524537 -337.512126)
			(xy 315.57938 -337.501996) (xy 315.635114 -337.499959) (xy 315.690551 -337.506059) (xy 315.744508 -337.520165)
			(xy 315.795837 -337.541977) (xy 315.843443 -337.571031) (xy 315.886311 -337.606706) (xy 315.923528 -337.648243)
			(xy 315.954301 -337.694756) (xy 315.977973 -337.745253) (xy 315.994041 -337.79866) (xy 316.002161 -337.853836)
			(xy 316.00267 -337.881722) (xy 316.002161 -337.909608) (xy 315.994041 -337.964784) (xy 315.977973 -338.018191)
			(xy 315.954301 -338.068688) (xy 315.923528 -338.115201) (xy 315.886311 -338.156738) (xy 315.843443 -338.192413)
			(xy 315.795837 -338.221467) (xy 315.744508 -338.243279) (xy 315.690551 -338.257385) (xy 315.635114 -338.263485)
			(xy 315.57938 -338.261448) (xy 315.524537 -338.251318) (xy 315.471753 -338.233311) (xy 315.422153 -338.20781)
			(xy 315.376795 -338.175359) (xy 315.336646 -338.13665) (xy 315.30256 -338.092507) (xy 315.275264 -338.043872)
			(xy 315.255341 -337.991781) (xy 315.243215 -337.937344) (xy 315.239144 -337.881722) (xy 264.870946 -337.881722)
			(xy 264.818876 -337.933792) (xy 264.81151 -337.940904) (xy 264.80389 -337.9597) (xy 264.80389 -338.777072)
			(xy 314.660024 -338.777072) (xy 314.664095 -338.72145) (xy 314.676221 -338.667013) (xy 314.696144 -338.614922)
			(xy 314.72344 -338.566287) (xy 314.757526 -338.522144) (xy 314.797675 -338.483435) (xy 314.843033 -338.450984)
			(xy 314.892633 -338.425483) (xy 314.945417 -338.407476) (xy 315.00026 -338.397346) (xy 315.055994 -338.395309)
			(xy 315.111431 -338.401409) (xy 315.165388 -338.415515) (xy 315.216717 -338.437327) (xy 315.264323 -338.466381)
			(xy 315.307191 -338.502056) (xy 315.344408 -338.543593) (xy 315.375181 -338.590106) (xy 315.398853 -338.640603)
			(xy 315.414921 -338.69401) (xy 315.423041 -338.749186) (xy 315.42355 -338.777072) (xy 315.423041 -338.804958)
			(xy 315.414921 -338.860134) (xy 315.398853 -338.913541) (xy 315.375181 -338.964038) (xy 315.344408 -339.010551)
			(xy 315.307191 -339.052088) (xy 315.264323 -339.087763) (xy 315.216717 -339.116817) (xy 315.165388 -339.138629)
			(xy 315.111431 -339.152735) (xy 315.055994 -339.158835) (xy 315.00026 -339.156798) (xy 314.945417 -339.146668)
			(xy 314.892633 -339.128661) (xy 314.843033 -339.10316) (xy 314.797675 -339.070709) (xy 314.757526 -339.032)
			(xy 314.72344 -338.987857) (xy 314.696144 -338.939222) (xy 314.676221 -338.887131) (xy 314.664095 -338.832694)
			(xy 314.660024 -338.777072) (xy 264.80389 -338.777072) (xy 264.80389 -339.452712) (xy 315.99886 -339.452712)
			(xy 315.999363 -339.425238) (xy 316.007253 -339.37086) (xy 316.022869 -339.318178) (xy 316.04589 -339.268285)
			(xy 316.075837 -339.222215) (xy 316.093602 -339.201252) (xy 316.099698 -339.19414) (xy 316.106048 -339.177122)
			(xy 316.106048 -339.09127) (xy 316.099698 -339.074252) (xy 316.093602 -339.06714) (xy 316.075876 -339.046147)
			(xy 316.045945 -339.000074) (xy 316.022925 -338.950187) (xy 316.007291 -338.897517) (xy 315.999364 -338.84315)
			(xy 315.99886 -338.81568) (xy 315.999346 -338.788429) (xy 316.007102 -338.734481) (xy 316.022457 -338.682186)
			(xy 316.045099 -338.632609) (xy 316.074565 -338.586759) (xy 316.110256 -338.545568) (xy 316.151447 -338.509877)
			(xy 316.197297 -338.480411) (xy 316.246874 -338.457769) (xy 316.299169 -338.442414) (xy 316.353117 -338.434658)
			(xy 316.407619 -338.434658) (xy 316.461567 -338.442414) (xy 316.513862 -338.457769) (xy 316.563439 -338.480411)
			(xy 316.609289 -338.509877) (xy 316.65048 -338.545568) (xy 316.686171 -338.586759) (xy 316.715637 -338.632609)
			(xy 316.738279 -338.682186) (xy 316.753634 -338.734481) (xy 316.76139 -338.788429) (xy 316.761876 -338.81568)
			(xy 316.761384 -338.843154) (xy 316.753494 -338.897534) (xy 316.737876 -338.950217) (xy 316.73523 -338.95595)
			(xy 317.003688 -338.95595) (xy 317.003688 -338.90145) (xy 317.011444 -338.847505) (xy 317.026798 -338.795213)
			(xy 317.049437 -338.745639) (xy 317.078901 -338.69979) (xy 317.11459 -338.658601) (xy 317.155777 -338.622911)
			(xy 317.201624 -338.593445) (xy 317.251198 -338.570804) (xy 317.30349 -338.555447) (xy 317.357434 -338.547689)
			(xy 317.384684 -338.547202) (xy 317.409921 -338.547562) (xy 317.459956 -338.554191) (xy 317.508676 -338.567375)
			(xy 317.555227 -338.586882) (xy 317.577216 -338.599272) (xy 317.586868 -338.605114) (xy 317.608966 -338.607146)
			(xy 317.703454 -338.573618) (xy 317.719456 -338.558124) (xy 317.72352 -338.54771) (xy 317.734188 -338.520921)
			(xy 317.762478 -338.470677) (xy 317.798011 -338.425266) (xy 317.839977 -338.385723) (xy 317.887418 -338.352951)
			(xy 317.939254 -338.327695) (xy 317.994301 -338.310533) (xy 318.051306 -338.301856) (xy 318.080136 -338.30133)
			(xy 318.107392 -338.301722) (xy 318.161347 -338.309484) (xy 318.213649 -338.324847) (xy 318.263231 -338.347496)
			(xy 318.309086 -338.376972) (xy 318.35028 -338.412673) (xy 318.385973 -338.453873) (xy 318.415439 -338.499734)
			(xy 318.438079 -338.549321) (xy 318.453431 -338.601625) (xy 318.461184 -338.655582) (xy 318.461644 -338.682838)
			(xy 318.460991 -338.714401) (xy 318.450602 -338.776667) (xy 318.430113 -338.836376) (xy 318.41567 -338.864448)
			(xy 318.410844 -338.873338) (xy 318.408812 -338.892896) (xy 318.434466 -338.981034) (xy 318.446912 -338.996528)
			(xy 318.455802 -339.001608) (xy 318.480891 -339.016175) (xy 318.526773 -339.051676) (xy 318.566749 -339.093717)
			(xy 318.599895 -339.141327) (xy 318.625448 -339.193409) (xy 318.642817 -339.24876) (xy 318.651603 -339.306104)
			(xy 318.652144 -339.33511) (xy 318.651658 -339.362361) (xy 318.643902 -339.416309) (xy 318.628547 -339.468604)
			(xy 318.605905 -339.518181) (xy 318.576439 -339.564031) (xy 318.540748 -339.605222) (xy 318.499557 -339.640913)
			(xy 318.453707 -339.670379) (xy 318.40413 -339.693021) (xy 318.351835 -339.708376) (xy 318.297887 -339.716132)
			(xy 318.243385 -339.716132) (xy 318.189437 -339.708376) (xy 318.137142 -339.693021) (xy 318.087565 -339.670379)
			(xy 318.041715 -339.640913) (xy 318.000524 -339.605222) (xy 317.964833 -339.564031) (xy 317.935367 -339.518181)
			(xy 317.912725 -339.468604) (xy 317.89737 -339.416309) (xy 317.889614 -339.362361) (xy 317.889128 -339.33511)
			(xy 317.889764 -339.303546) (xy 317.900161 -339.24128) (xy 317.920656 -339.181572) (xy 317.935102 -339.1535)
			(xy 317.939928 -339.14461) (xy 317.94196 -339.125052) (xy 317.916306 -339.036914) (xy 317.90386 -339.02142)
			(xy 317.89497 -339.01634) (xy 317.887604 -339.012276) (xy 317.877952 -339.006434) (xy 317.855854 -339.004402)
			(xy 317.761366 -339.03793) (xy 317.745364 -339.053424) (xy 317.7413 -339.063838) (xy 317.730641 -339.09063)
			(xy 317.702347 -339.140872) (xy 317.666811 -339.186281) (xy 317.624844 -339.225822) (xy 317.577401 -339.258593)
			(xy 317.525566 -339.283849) (xy 317.470518 -339.301011) (xy 317.413514 -339.30969) (xy 317.384684 -339.310218)
			(xy 317.357434 -339.309711) (xy 317.30349 -339.301953) (xy 317.251198 -339.286596) (xy 317.201624 -339.263955)
			(xy 317.155777 -339.234489) (xy 317.11459 -339.198799) (xy 317.078901 -339.15761) (xy 317.049437 -339.111761)
			(xy 317.026798 -339.062187) (xy 317.011444 -339.009895) (xy 317.003688 -338.95595) (xy 316.73523 -338.95595)
			(xy 316.714852 -339.000109) (xy 316.684901 -339.046178) (xy 316.667134 -339.06714) (xy 316.661038 -339.074252)
			(xy 316.654688 -339.09127) (xy 316.654688 -339.177122) (xy 316.661038 -339.19414) (xy 316.667134 -339.201252)
			(xy 316.684862 -339.222243) (xy 316.714791 -339.268318) (xy 316.73781 -339.318204) (xy 316.753444 -339.370875)
			(xy 316.761371 -339.425242) (xy 316.761876 -339.452712) (xy 316.76139 -339.479963) (xy 316.753634 -339.533911)
			(xy 316.738279 -339.586206) (xy 316.715637 -339.635783) (xy 316.686171 -339.681633) (xy 316.65048 -339.722824)
			(xy 316.609289 -339.758515) (xy 316.563439 -339.787981) (xy 316.513862 -339.810623) (xy 316.461567 -339.825978)
			(xy 316.407619 -339.833734) (xy 316.353117 -339.833734) (xy 316.299169 -339.825978) (xy 316.246874 -339.810623)
			(xy 316.197297 -339.787981) (xy 316.151447 -339.758515) (xy 316.110256 -339.722824) (xy 316.074565 -339.681633)
			(xy 316.045099 -339.635783) (xy 316.022457 -339.586206) (xy 316.007102 -339.533911) (xy 315.999346 -339.479963)
			(xy 315.99886 -339.452712) (xy 264.80389 -339.452712) (xy 264.80389 -348.37116) (xy 271.357598 -348.37116)
			(xy 271.358065 -348.343248) (xy 271.366205 -348.288021) (xy 271.382307 -348.23457) (xy 271.406025 -348.184036)
			(xy 271.436855 -348.137497) (xy 271.455134 -348.116398) (xy 271.461484 -348.109286) (xy 271.468088 -348.092014)
			(xy 271.468088 -348.004892) (xy 271.461484 -347.98762) (xy 271.455134 -347.980508) (xy 271.436828 -347.959432)
			(xy 271.406007 -347.912886) (xy 271.382298 -347.862345) (xy 271.366208 -347.808889) (xy 271.35808 -347.753659)
			(xy 271.357598 -347.725746) (xy 271.358084 -347.698495) (xy 271.36584 -347.644547) (xy 271.381195 -347.592252)
			(xy 271.403837 -347.542675) (xy 271.433303 -347.496825) (xy 271.468994 -347.455634) (xy 271.510185 -347.419943)
			(xy 271.556035 -347.390477) (xy 271.605612 -347.367835) (xy 271.657907 -347.35248) (xy 271.711855 -347.344724)
			(xy 271.766357 -347.344724) (xy 271.820305 -347.35248) (xy 271.8726 -347.367835) (xy 271.922177 -347.390477)
			(xy 271.968027 -347.419943) (xy 272.009218 -347.455634) (xy 272.044909 -347.496825) (xy 272.074375 -347.542675)
			(xy 272.097017 -347.592252) (xy 272.112372 -347.644547) (xy 272.120128 -347.698495) (xy 272.120614 -347.725746)
			(xy 272.120148 -347.753658) (xy 272.112007 -347.808885) (xy 272.095905 -347.862336) (xy 272.072186 -347.91287)
			(xy 272.041357 -347.959409) (xy 272.023078 -347.980508) (xy 272.016728 -347.98762) (xy 272.010124 -348.004892)
			(xy 272.010124 -348.092014) (xy 272.016728 -348.109286) (xy 272.023078 -348.116398) (xy 272.041326 -348.137523)
			(xy 272.072158 -348.184054) (xy 272.09588 -348.234582) (xy 272.111983 -348.288028) (xy 272.120125 -348.34325)
			(xy 272.120614 -348.37116) (xy 272.120128 -348.398411) (xy 272.112372 -348.452359) (xy 272.097017 -348.504654)
			(xy 272.074375 -348.554231) (xy 272.044909 -348.600081) (xy 272.009218 -348.641272) (xy 271.968027 -348.676963)
			(xy 271.922177 -348.706429) (xy 271.8726 -348.729071) (xy 271.820305 -348.744426) (xy 271.766357 -348.752182)
			(xy 271.711855 -348.752182) (xy 271.657907 -348.744426) (xy 271.605612 -348.729071) (xy 271.556035 -348.706429)
			(xy 271.510185 -348.676963) (xy 271.468994 -348.641272) (xy 271.433303 -348.600081) (xy 271.403837 -348.554231)
			(xy 271.381195 -348.504654) (xy 271.36584 -348.452359) (xy 271.358084 -348.398411) (xy 271.357598 -348.37116)
			(xy 264.80389 -348.37116) (xy 264.80389 -349.088456) (xy 275.551392 -349.088456) (xy 275.551392 -346.994988)
			(xy 275.551838 -346.985017) (xy 275.559433 -346.966581) (xy 275.566124 -346.959174) (xy 275.730208 -346.79509)
			(xy 275.737595 -346.788346) (xy 275.756033 -346.780638) (xy 275.766022 -346.780104) (xy 278.952452 -346.780104)
			(xy 278.962456 -346.780567) (xy 278.980918 -346.788286) (xy 278.988266 -346.79509) (xy 279.194514 -347.001338)
			(xy 279.201272 -347.008715) (xy 279.208972 -347.02716) (xy 279.2095 -347.037152) (xy 279.2095 -348.211394)
			(xy 279.209872 -348.22144) (xy 279.217457 -348.240037) (xy 279.224232 -348.247462) (xy 279.466802 -348.490032)
			(xy 279.474517 -348.497083) (xy 279.493951 -348.504725) (xy 279.51482 -348.503982) (xy 279.52446 -348.499938)
			(xy 279.625552 -348.452186) (xy 279.6413 -348.4245) (xy 279.639776 -348.408244) (xy 279.637998 -348.37116)
			(xy 279.638465 -348.343248) (xy 279.646605 -348.288021) (xy 279.662707 -348.23457) (xy 279.686425 -348.184036)
			(xy 279.717255 -348.137497) (xy 279.735534 -348.116398) (xy 279.741884 -348.109286) (xy 279.748488 -348.092014)
			(xy 279.748488 -348.004892) (xy 279.741884 -347.98762) (xy 279.735534 -347.980508) (xy 279.717228 -347.959432)
			(xy 279.686407 -347.912886) (xy 279.662698 -347.862345) (xy 279.646608 -347.808889) (xy 279.63848 -347.753659)
			(xy 279.637998 -347.725746) (xy 279.638484 -347.698495) (xy 279.64624 -347.644547) (xy 279.661595 -347.592252)
			(xy 279.684237 -347.542675) (xy 279.713703 -347.496825) (xy 279.749394 -347.455634) (xy 279.790585 -347.419943)
			(xy 279.836435 -347.390477) (xy 279.886012 -347.367835) (xy 279.938307 -347.35248) (xy 279.992255 -347.344724)
			(xy 280.046757 -347.344724) (xy 280.100705 -347.35248) (xy 280.153 -347.367835) (xy 280.202577 -347.390477)
			(xy 280.248427 -347.419943) (xy 280.289618 -347.455634) (xy 280.325309 -347.496825) (xy 280.354775 -347.542675)
			(xy 280.377417 -347.592252) (xy 280.392772 -347.644547) (xy 280.400528 -347.698495) (xy 280.401014 -347.725746)
			(xy 280.400548 -347.753658) (xy 280.392407 -347.808885) (xy 280.376305 -347.862336) (xy 280.352586 -347.91287)
			(xy 280.321757 -347.959409) (xy 280.303478 -347.980508) (xy 280.297128 -347.98762) (xy 280.290524 -348.004892)
			(xy 280.290524 -348.092014) (xy 280.297128 -348.109286) (xy 280.303478 -348.116398) (xy 280.321726 -348.137523)
			(xy 280.352558 -348.184054) (xy 280.37628 -348.234582) (xy 280.392383 -348.288028) (xy 280.400525 -348.34325)
			(xy 280.401014 -348.37116) (xy 280.400508 -348.398412) (xy 280.392756 -348.452361) (xy 280.377405 -348.504657)
			(xy 280.354768 -348.554237) (xy 280.325305 -348.60009) (xy 280.289616 -348.641283) (xy 280.248427 -348.676977)
			(xy 280.202577 -348.706446) (xy 280.153001 -348.729089) (xy 280.100706 -348.744446) (xy 280.046758 -348.752204)
			(xy 280.019506 -348.752668) (xy 279.994888 -348.752288) (xy 279.946064 -348.745925) (xy 279.898466 -348.73333)
			(xy 279.852885 -348.714713) (xy 279.831292 -348.702884) (xy 279.819354 -348.69628) (xy 279.79243 -348.69628)
			(xy 279.7048 -348.747334) (xy 279.697254 -348.752052) (xy 279.685808 -348.765666) (xy 279.679729 -348.782382)
			(xy 279.6794 -348.791276) (xy 279.6794 -349.602806) (xy 280.59583 -349.602806) (xy 280.599901 -349.547184)
			(xy 280.612027 -349.492747) (xy 280.63195 -349.440656) (xy 280.659246 -349.392021) (xy 280.693332 -349.347878)
			(xy 280.733481 -349.309169) (xy 280.778839 -349.276718) (xy 280.828439 -349.251217) (xy 280.881223 -349.23321)
			(xy 280.936066 -349.22308) (xy 280.9918 -349.221043) (xy 281.047237 -349.227143) (xy 281.101194 -349.241249)
			(xy 281.152523 -349.263061) (xy 281.200129 -349.292115) (xy 281.242997 -349.32779) (xy 281.280214 -349.369327)
			(xy 281.310987 -349.41584) (xy 281.334659 -349.466337) (xy 281.350727 -349.519744) (xy 281.358847 -349.57492)
			(xy 281.359356 -349.602806) (xy 281.358847 -349.630692) (xy 281.350727 -349.685868) (xy 281.334659 -349.739275)
			(xy 281.310987 -349.789772) (xy 281.280214 -349.836285) (xy 281.242997 -349.877822) (xy 281.200129 -349.913497)
			(xy 281.152523 -349.942551) (xy 281.101194 -349.964363) (xy 281.047237 -349.978469) (xy 280.9918 -349.984569)
			(xy 280.936066 -349.982532) (xy 280.881223 -349.972402) (xy 280.828439 -349.954395) (xy 280.778839 -349.928894)
			(xy 280.733481 -349.896443) (xy 280.693332 -349.857734) (xy 280.659246 -349.813591) (xy 280.63195 -349.764956)
			(xy 280.612027 -349.712865) (xy 280.599901 -349.658428) (xy 280.59583 -349.602806) (xy 279.6794 -349.602806)
			(xy 279.6794 -350.498156) (xy 280.01671 -350.498156) (xy 280.020781 -350.442534) (xy 280.032907 -350.388097)
			(xy 280.05283 -350.336006) (xy 280.080126 -350.287371) (xy 280.114212 -350.243228) (xy 280.154361 -350.204519)
			(xy 280.199719 -350.172068) (xy 280.249319 -350.146567) (xy 280.302103 -350.12856) (xy 280.356946 -350.11843)
			(xy 280.41268 -350.116393) (xy 280.468117 -350.122493) (xy 280.522074 -350.136599) (xy 280.573403 -350.158411)
			(xy 280.621009 -350.187465) (xy 280.663877 -350.22314) (xy 280.701094 -350.264677) (xy 280.731867 -350.31119)
			(xy 280.755539 -350.361687) (xy 280.771607 -350.415094) (xy 280.779727 -350.47027) (xy 280.780236 -350.498156)
			(xy 280.779727 -350.526042) (xy 280.771607 -350.581218) (xy 280.755539 -350.634625) (xy 280.731867 -350.685122)
			(xy 280.701094 -350.731635) (xy 280.663877 -350.773172) (xy 280.621009 -350.808847) (xy 280.573403 -350.837901)
			(xy 280.522074 -350.859713) (xy 280.468117 -350.873819) (xy 280.41268 -350.879919) (xy 280.356946 -350.877882)
			(xy 280.302103 -350.867752) (xy 280.249319 -350.849745) (xy 280.199719 -350.824244) (xy 280.154361 -350.791793)
			(xy 280.114212 -350.753084) (xy 280.080126 -350.708941) (xy 280.05283 -350.660306) (xy 280.032907 -350.608215)
			(xy 280.020781 -350.553778) (xy 280.01671 -350.498156) (xy 279.6794 -350.498156) (xy 279.6794 -351.173796)
			(xy 281.355546 -351.173796) (xy 281.356019 -351.146321) (xy 281.363912 -351.09194) (xy 281.379535 -351.039257)
			(xy 281.402563 -350.989365) (xy 281.432518 -350.943297) (xy 281.450288 -350.922336) (xy 281.456384 -350.915224)
			(xy 281.462734 -350.898206) (xy 281.462734 -350.812354) (xy 281.456384 -350.795336) (xy 281.450288 -350.788224)
			(xy 281.432552 -350.767239) (xy 281.402624 -350.721163) (xy 281.379606 -350.671275) (xy 281.363973 -350.618603)
			(xy 281.356049 -350.564235) (xy 281.355546 -350.536764) (xy 281.356032 -350.509513) (xy 281.363788 -350.455565)
			(xy 281.379143 -350.40327) (xy 281.401785 -350.353693) (xy 281.431251 -350.307843) (xy 281.466942 -350.266652)
			(xy 281.508133 -350.230961) (xy 281.553983 -350.201495) (xy 281.60356 -350.178853) (xy 281.655855 -350.163498)
			(xy 281.709803 -350.155742) (xy 281.764305 -350.155742) (xy 281.818253 -350.163498) (xy 281.870548 -350.178853)
			(xy 281.920125 -350.201495) (xy 281.965975 -350.230961) (xy 282.007166 -350.266652) (xy 282.042857 -350.307843)
			(xy 282.072323 -350.353693) (xy 282.094965 -350.40327) (xy 282.11032 -350.455565) (xy 282.118076 -350.509513)
			(xy 282.118562 -350.536764) (xy 282.118064 -350.564238) (xy 282.110176 -350.618618) (xy 282.094559 -350.6713)
			(xy 282.091906 -350.67705) (xy 282.360372 -350.67705) (xy 282.360372 -350.62255) (xy 282.368128 -350.568604)
			(xy 282.383481 -350.516311) (xy 282.406121 -350.466735) (xy 282.435585 -350.420885) (xy 282.471274 -350.379695)
			(xy 282.512461 -350.344003) (xy 282.558308 -350.314535) (xy 282.607882 -350.291892) (xy 282.660174 -350.276534)
			(xy 282.71412 -350.268774) (xy 282.74137 -350.268286) (xy 282.766606 -350.268654) (xy 282.816641 -350.275281)
			(xy 282.865362 -350.288463) (xy 282.911912 -350.307967) (xy 282.933902 -350.320356) (xy 282.943554 -350.326198)
			(xy 282.965652 -350.32823) (xy 283.06014 -350.294702) (xy 283.076142 -350.279208) (xy 283.080206 -350.268794)
			(xy 283.090877 -350.242007) (xy 283.119168 -350.191764) (xy 283.154701 -350.146354) (xy 283.196666 -350.106811)
			(xy 283.244107 -350.074039) (xy 283.295942 -350.048783) (xy 283.350989 -350.03162) (xy 283.407992 -350.022941)
			(xy 283.436822 -350.022414) (xy 283.464075 -350.022857) (xy 283.518025 -350.030617) (xy 283.570322 -350.045977)
			(xy 283.619901 -350.068622) (xy 283.665752 -350.098092) (xy 283.706943 -350.133788) (xy 283.742634 -350.174983)
			(xy 283.772099 -350.220838) (xy 283.794739 -350.270419) (xy 283.810092 -350.322718) (xy 283.817846 -350.376669)
			(xy 283.81833 -350.403922) (xy 283.81766 -350.435484) (xy 283.807276 -350.497749) (xy 283.786795 -350.557459)
			(xy 283.772356 -350.585532) (xy 283.76753 -350.594422) (xy 283.765498 -350.61398) (xy 283.791152 -350.702118)
			(xy 283.803598 -350.717612) (xy 283.812488 -350.722692) (xy 283.837611 -350.737205) (xy 283.883494 -350.772714)
			(xy 283.923468 -350.814763) (xy 283.956612 -350.862383) (xy 283.982159 -350.914474) (xy 283.99952 -350.969834)
			(xy 284.008295 -351.027185) (xy 284.00883 -351.056194) (xy 284.008344 -351.083445) (xy 284.000588 -351.137393)
			(xy 283.985233 -351.189688) (xy 283.962591 -351.239265) (xy 283.933125 -351.285115) (xy 283.897434 -351.326306)
			(xy 283.856243 -351.361997) (xy 283.810393 -351.391463) (xy 283.760816 -351.414105) (xy 283.708521 -351.42946)
			(xy 283.654573 -351.437216) (xy 283.600071 -351.437216) (xy 283.546123 -351.42946) (xy 283.493828 -351.414105)
			(xy 283.444251 -351.391463) (xy 283.398401 -351.361997) (xy 283.35721 -351.326306) (xy 283.321519 -351.285115)
			(xy 283.292053 -351.239265) (xy 283.269411 -351.189688) (xy 283.254056 -351.137393) (xy 283.2463 -351.083445)
			(xy 283.245814 -351.056194) (xy 283.246485 -351.024632) (xy 283.256867 -350.962367) (xy 283.277349 -350.902657)
			(xy 283.291788 -350.874584) (xy 283.296614 -350.865694) (xy 283.298646 -350.846136) (xy 283.272992 -350.757998)
			(xy 283.260546 -350.742504) (xy 283.251656 -350.737424) (xy 283.24429 -350.73336) (xy 283.234638 -350.727518)
			(xy 283.21254 -350.725486) (xy 283.118052 -350.759014) (xy 283.10205 -350.774508) (xy 283.097986 -350.784922)
			(xy 283.08733 -350.811715) (xy 283.059037 -350.861958) (xy 283.023501 -350.907368) (xy 282.981533 -350.94691)
			(xy 282.93409 -350.979681) (xy 282.882254 -351.004936) (xy 282.827205 -351.022098) (xy 282.770201 -351.030775)
			(xy 282.74137 -351.031302) (xy 282.71412 -351.030826) (xy 282.660174 -351.023066) (xy 282.607882 -351.007708)
			(xy 282.558308 -350.985065) (xy 282.512461 -350.955597) (xy 282.471274 -350.919905) (xy 282.435585 -350.878715)
			(xy 282.406121 -350.832865) (xy 282.383481 -350.783289) (xy 282.368128 -350.730996) (xy 282.360372 -350.67705)
			(xy 282.091906 -350.67705) (xy 282.071537 -350.721193) (xy 282.041587 -350.767262) (xy 282.02382 -350.788224)
			(xy 282.017724 -350.795336) (xy 282.011374 -350.812354) (xy 282.011374 -350.898206) (xy 282.017724 -350.915224)
			(xy 282.02382 -350.922336) (xy 282.041585 -350.943297) (xy 282.071509 -350.98938) (xy 282.094521 -351.039274)
			(xy 282.110147 -351.091951) (xy 282.118063 -351.146324) (xy 282.118562 -351.173796) (xy 282.118076 -351.201047)
			(xy 282.11032 -351.254995) (xy 282.094965 -351.30729) (xy 282.072323 -351.356867) (xy 282.042857 -351.402717)
			(xy 282.007166 -351.443908) (xy 281.965975 -351.479599) (xy 281.920125 -351.509065) (xy 281.870548 -351.531707)
			(xy 281.818253 -351.547062) (xy 281.764305 -351.554818) (xy 281.709803 -351.554818) (xy 281.655855 -351.547062)
			(xy 281.60356 -351.531707) (xy 281.553983 -351.509065) (xy 281.508133 -351.479599) (xy 281.466942 -351.443908)
			(xy 281.431251 -351.402717) (xy 281.401785 -351.356867) (xy 281.379143 -351.30729) (xy 281.363788 -351.254995)
			(xy 281.356032 -351.201047) (xy 281.355546 -351.173796) (xy 279.6794 -351.173796) (xy 279.6794 -351.798382)
			(xy 279.679808 -351.808454) (xy 279.687538 -351.827053) (xy 279.694386 -351.83445) (xy 280.226008 -352.366072)
			(xy 280.233492 -352.372761) (xy 280.252049 -352.380353) (xy 280.262076 -352.380804) (xy 284.528768 -352.380804)
			(xy 284.538818 -352.380469) (xy 284.557415 -352.372858) (xy 284.564836 -352.366072) (xy 284.720792 -352.210116)
			(xy 284.727517 -352.20266) (xy 284.735088 -352.184081) (xy 284.735524 -352.174048) (xy 284.735524 -350.072452)
			(xy 284.735174 -350.062404) (xy 284.727573 -350.043807) (xy 284.720792 -350.036384) (xy 283.846524 -349.162116)
			(xy 283.839837 -349.154711) (xy 283.832267 -349.13627) (xy 283.831792 -349.126302) (xy 283.831792 -347.007688)
			(xy 283.832238 -346.997717) (xy 283.839833 -346.979281) (xy 283.846524 -346.971874) (xy 284.033468 -346.78493)
			(xy 284.040874 -346.778209) (xy 284.059297 -346.770486) (xy 284.069282 -346.769944) (xy 287.182052 -346.769944)
			(xy 287.192058 -346.770397) (xy 287.21052 -346.778121) (xy 287.217866 -346.78493) (xy 287.525714 -347.092778)
			(xy 287.532446 -347.100175) (xy 287.540161 -347.118605) (xy 287.5407 -347.128592) (xy 287.5407 -348.305374)
			(xy 287.54103 -348.315424) (xy 287.548644 -348.334021) (xy 287.555432 -348.341442) (xy 287.58515 -348.37116)
			(xy 287.943798 -348.37116) (xy 287.944265 -348.343248) (xy 287.952405 -348.288021) (xy 287.968507 -348.23457)
			(xy 287.992225 -348.184036) (xy 288.023055 -348.137497) (xy 288.041334 -348.116398) (xy 288.047684 -348.109286)
			(xy 288.054288 -348.092014) (xy 288.054288 -348.004892) (xy 288.047684 -347.98762) (xy 288.041334 -347.980508)
			(xy 288.023028 -347.959432) (xy 287.992207 -347.912886) (xy 287.968498 -347.862345) (xy 287.952408 -347.808889)
			(xy 287.94428 -347.753659) (xy 287.943798 -347.725746) (xy 287.944284 -347.698495) (xy 287.95204 -347.644547)
			(xy 287.967395 -347.592252) (xy 287.990037 -347.542675) (xy 288.019503 -347.496825) (xy 288.055194 -347.455634)
			(xy 288.096385 -347.419943) (xy 288.142235 -347.390477) (xy 288.191812 -347.367835) (xy 288.244107 -347.35248)
			(xy 288.298055 -347.344724) (xy 288.352557 -347.344724) (xy 288.406505 -347.35248) (xy 288.4588 -347.367835)
			(xy 288.508377 -347.390477) (xy 288.554227 -347.419943) (xy 288.595418 -347.455634) (xy 288.631109 -347.496825)
			(xy 288.660575 -347.542675) (xy 288.683217 -347.592252) (xy 288.698572 -347.644547) (xy 288.706328 -347.698495)
			(xy 288.706814 -347.725746) (xy 288.706348 -347.753658) (xy 288.698207 -347.808885) (xy 288.682105 -347.862336)
			(xy 288.658386 -347.91287) (xy 288.627557 -347.959409) (xy 288.609278 -347.980508) (xy 288.602928 -347.98762)
			(xy 288.596324 -348.004892) (xy 288.596324 -348.092014) (xy 288.602928 -348.109286) (xy 288.609278 -348.116398)
			(xy 288.627526 -348.137523) (xy 288.658358 -348.184054) (xy 288.68208 -348.234582) (xy 288.698183 -348.288028)
			(xy 288.706325 -348.34325) (xy 288.706814 -348.37116) (xy 288.706328 -348.398411) (xy 288.698572 -348.452359)
			(xy 288.683217 -348.504654) (xy 288.660575 -348.554231) (xy 288.631109 -348.600081) (xy 288.595418 -348.641272)
			(xy 288.554227 -348.676963) (xy 288.508377 -348.706429) (xy 288.4588 -348.729071) (xy 288.406505 -348.744426)
			(xy 288.352557 -348.752182) (xy 288.298055 -348.752182) (xy 288.244107 -348.744426) (xy 288.191812 -348.729071)
			(xy 288.142235 -348.706429) (xy 288.096385 -348.676963) (xy 288.055194 -348.641272) (xy 288.019503 -348.600081)
			(xy 287.990037 -348.554231) (xy 287.967395 -348.504654) (xy 287.95204 -348.452359) (xy 287.944284 -348.398411)
			(xy 287.943798 -348.37116) (xy 287.58515 -348.37116) (xy 287.945068 -348.731078) (xy 287.951751 -348.738486)
			(xy 287.959324 -348.756925) (xy 287.9598 -348.766892) (xy 287.9598 -349.602806) (xy 288.90163 -349.602806)
			(xy 288.905701 -349.547184) (xy 288.917827 -349.492747) (xy 288.93775 -349.440656) (xy 288.965046 -349.392021)
			(xy 288.999132 -349.347878) (xy 289.039281 -349.309169) (xy 289.084639 -349.276718) (xy 289.134239 -349.251217)
			(xy 289.187023 -349.23321) (xy 289.241866 -349.22308) (xy 289.2976 -349.221043) (xy 289.353037 -349.227143)
			(xy 289.406994 -349.241249) (xy 289.458323 -349.263061) (xy 289.505929 -349.292115) (xy 289.548797 -349.32779)
			(xy 289.586014 -349.369327) (xy 289.616787 -349.41584) (xy 289.640459 -349.466337) (xy 289.656527 -349.519744)
			(xy 289.664647 -349.57492) (xy 289.665156 -349.602806) (xy 289.664647 -349.630692) (xy 289.656527 -349.685868)
			(xy 289.640459 -349.739275) (xy 289.616787 -349.789772) (xy 289.586014 -349.836285) (xy 289.548797 -349.877822)
			(xy 289.505929 -349.913497) (xy 289.458323 -349.942551) (xy 289.406994 -349.964363) (xy 289.353037 -349.978469)
			(xy 289.2976 -349.984569) (xy 289.241866 -349.982532) (xy 289.187023 -349.972402) (xy 289.134239 -349.954395)
			(xy 289.084639 -349.928894) (xy 289.039281 -349.896443) (xy 288.999132 -349.857734) (xy 288.965046 -349.813591)
			(xy 288.93775 -349.764956) (xy 288.917827 -349.712865) (xy 288.905701 -349.658428) (xy 288.90163 -349.602806)
			(xy 287.9598 -349.602806) (xy 287.9598 -350.498156) (xy 288.32251 -350.498156) (xy 288.326581 -350.442534)
			(xy 288.338707 -350.388097) (xy 288.35863 -350.336006) (xy 288.385926 -350.287371) (xy 288.420012 -350.243228)
			(xy 288.460161 -350.204519) (xy 288.505519 -350.172068) (xy 288.555119 -350.146567) (xy 288.607903 -350.12856)
			(xy 288.662746 -350.11843) (xy 288.71848 -350.116393) (xy 288.773917 -350.122493) (xy 288.827874 -350.136599)
			(xy 288.879203 -350.158411) (xy 288.926809 -350.187465) (xy 288.969677 -350.22314) (xy 289.006894 -350.264677)
			(xy 289.037667 -350.31119) (xy 289.061339 -350.361687) (xy 289.077407 -350.415094) (xy 289.085527 -350.47027)
			(xy 289.086036 -350.498156) (xy 289.085527 -350.526042) (xy 289.077407 -350.581218) (xy 289.061339 -350.634625)
			(xy 289.037667 -350.685122) (xy 289.006894 -350.731635) (xy 288.969677 -350.773172) (xy 288.926809 -350.808847)
			(xy 288.879203 -350.837901) (xy 288.827874 -350.859713) (xy 288.773917 -350.873819) (xy 288.71848 -350.879919)
			(xy 288.662746 -350.877882) (xy 288.607903 -350.867752) (xy 288.555119 -350.849745) (xy 288.505519 -350.824244)
			(xy 288.460161 -350.791793) (xy 288.420012 -350.753084) (xy 288.385926 -350.708941) (xy 288.35863 -350.660306)
			(xy 288.338707 -350.608215) (xy 288.326581 -350.553778) (xy 288.32251 -350.498156) (xy 287.9598 -350.498156)
			(xy 287.9598 -351.173796) (xy 289.661346 -351.173796) (xy 289.661819 -351.146321) (xy 289.669712 -351.09194)
			(xy 289.685335 -351.039257) (xy 289.708363 -350.989365) (xy 289.738318 -350.943297) (xy 289.756088 -350.922336)
			(xy 289.762184 -350.915224) (xy 289.768534 -350.898206) (xy 289.768534 -350.812354) (xy 289.762184 -350.795336)
			(xy 289.756088 -350.788224) (xy 289.738352 -350.767239) (xy 289.708424 -350.721163) (xy 289.685406 -350.671275)
			(xy 289.669773 -350.618603) (xy 289.661849 -350.564235) (xy 289.661346 -350.536764) (xy 289.661832 -350.509513)
			(xy 289.669588 -350.455565) (xy 289.684943 -350.40327) (xy 289.707585 -350.353693) (xy 289.737051 -350.307843)
			(xy 289.772742 -350.266652) (xy 289.813933 -350.230961) (xy 289.859783 -350.201495) (xy 289.90936 -350.178853)
			(xy 289.961655 -350.163498) (xy 290.015603 -350.155742) (xy 290.070105 -350.155742) (xy 290.124053 -350.163498)
			(xy 290.176348 -350.178853) (xy 290.225925 -350.201495) (xy 290.271775 -350.230961) (xy 290.312966 -350.266652)
			(xy 290.348657 -350.307843) (xy 290.378123 -350.353693) (xy 290.400765 -350.40327) (xy 290.41612 -350.455565)
			(xy 290.423876 -350.509513) (xy 290.424362 -350.536764) (xy 290.423864 -350.564238) (xy 290.415976 -350.618618)
			(xy 290.400359 -350.6713) (xy 290.397706 -350.67705) (xy 290.666172 -350.67705) (xy 290.666172 -350.62255)
			(xy 290.673928 -350.568604) (xy 290.689281 -350.516311) (xy 290.711921 -350.466735) (xy 290.741385 -350.420885)
			(xy 290.777074 -350.379695) (xy 290.818261 -350.344003) (xy 290.864108 -350.314535) (xy 290.913682 -350.291892)
			(xy 290.965974 -350.276534) (xy 291.01992 -350.268774) (xy 291.04717 -350.268286) (xy 291.072406 -350.268654)
			(xy 291.122441 -350.275281) (xy 291.171162 -350.288463) (xy 291.217712 -350.307967) (xy 291.239702 -350.320356)
			(xy 291.249354 -350.326198) (xy 291.271452 -350.32823) (xy 291.36594 -350.294702) (xy 291.381942 -350.279208)
			(xy 291.386006 -350.268794) (xy 291.396677 -350.242007) (xy 291.424968 -350.191764) (xy 291.460501 -350.146354)
			(xy 291.502466 -350.106811) (xy 291.549907 -350.074039) (xy 291.601742 -350.048783) (xy 291.656789 -350.03162)
			(xy 291.713792 -350.022941) (xy 291.742622 -350.022414) (xy 291.769875 -350.022857) (xy 291.823825 -350.030617)
			(xy 291.876122 -350.045977) (xy 291.925701 -350.068622) (xy 291.971552 -350.098092) (xy 292.012743 -350.133788)
			(xy 292.048434 -350.174983) (xy 292.077899 -350.220838) (xy 292.100539 -350.270419) (xy 292.115892 -350.322718)
			(xy 292.123646 -350.376669) (xy 292.12413 -350.403922) (xy 292.12346 -350.435484) (xy 292.113076 -350.497749)
			(xy 292.092595 -350.557459) (xy 292.078156 -350.585532) (xy 292.07333 -350.594422) (xy 292.071298 -350.61398)
			(xy 292.096952 -350.702118) (xy 292.109398 -350.717612) (xy 292.118288 -350.722692) (xy 292.143411 -350.737205)
			(xy 292.189294 -350.772714) (xy 292.229268 -350.814763) (xy 292.262412 -350.862383) (xy 292.287959 -350.914474)
			(xy 292.30532 -350.969834) (xy 292.314095 -351.027185) (xy 292.31463 -351.056194) (xy 292.314144 -351.083445)
			(xy 292.306388 -351.137393) (xy 292.291033 -351.189688) (xy 292.268391 -351.239265) (xy 292.238925 -351.285115)
			(xy 292.203234 -351.326306) (xy 292.162043 -351.361997) (xy 292.116193 -351.391463) (xy 292.066616 -351.414105)
			(xy 292.014321 -351.42946) (xy 291.960373 -351.437216) (xy 291.905871 -351.437216) (xy 291.851923 -351.42946)
			(xy 291.799628 -351.414105) (xy 291.750051 -351.391463) (xy 291.704201 -351.361997) (xy 291.66301 -351.326306)
			(xy 291.627319 -351.285115) (xy 291.597853 -351.239265) (xy 291.575211 -351.189688) (xy 291.559856 -351.137393)
			(xy 291.5521 -351.083445) (xy 291.551614 -351.056194) (xy 291.552285 -351.024632) (xy 291.562667 -350.962367)
			(xy 291.583149 -350.902657) (xy 291.597588 -350.874584) (xy 291.602414 -350.865694) (xy 291.604446 -350.846136)
			(xy 291.578792 -350.757998) (xy 291.566346 -350.742504) (xy 291.557456 -350.737424) (xy 291.55009 -350.73336)
			(xy 291.540438 -350.727518) (xy 291.51834 -350.725486) (xy 291.423852 -350.759014) (xy 291.40785 -350.774508)
			(xy 291.403786 -350.784922) (xy 291.39313 -350.811715) (xy 291.364837 -350.861958) (xy 291.329301 -350.907368)
			(xy 291.287333 -350.94691) (xy 291.23989 -350.979681) (xy 291.188054 -351.004936) (xy 291.133005 -351.022098)
			(xy 291.076001 -351.030775) (xy 291.04717 -351.031302) (xy 291.01992 -351.030826) (xy 290.965974 -351.023066)
			(xy 290.913682 -351.007708) (xy 290.864108 -350.985065) (xy 290.818261 -350.955597) (xy 290.777074 -350.919905)
			(xy 290.741385 -350.878715) (xy 290.711921 -350.832865) (xy 290.689281 -350.783289) (xy 290.673928 -350.730996)
			(xy 290.666172 -350.67705) (xy 290.397706 -350.67705) (xy 290.377337 -350.721193) (xy 290.347387 -350.767262)
			(xy 290.32962 -350.788224) (xy 290.323524 -350.795336) (xy 290.317174 -350.812354) (xy 290.317174 -350.898206)
			(xy 290.323524 -350.915224) (xy 290.32962 -350.922336) (xy 290.347385 -350.943297) (xy 290.377309 -350.98938)
			(xy 290.400321 -351.039274) (xy 290.415947 -351.091951) (xy 290.423863 -351.146324) (xy 290.424362 -351.173796)
			(xy 290.423876 -351.201047) (xy 290.41612 -351.254995) (xy 290.400765 -351.30729) (xy 290.378123 -351.356867)
			(xy 290.348657 -351.402717) (xy 290.312966 -351.443908) (xy 290.271775 -351.479599) (xy 290.225925 -351.509065)
			(xy 290.176348 -351.531707) (xy 290.124053 -351.547062) (xy 290.070105 -351.554818) (xy 290.015603 -351.554818)
			(xy 289.961655 -351.547062) (xy 289.90936 -351.531707) (xy 289.859783 -351.509065) (xy 289.813933 -351.479599)
			(xy 289.772742 -351.443908) (xy 289.737051 -351.402717) (xy 289.707585 -351.356867) (xy 289.684943 -351.30729)
			(xy 289.669588 -351.254995) (xy 289.661832 -351.201047) (xy 289.661346 -351.173796) (xy 287.9598 -351.173796)
			(xy 287.9598 -351.737422) (xy 287.960187 -351.747496) (xy 287.967932 -351.766095) (xy 287.974786 -351.77349)
			(xy 288.663888 -352.462592) (xy 288.671343 -352.469319) (xy 288.689922 -352.476888) (xy 288.699956 -352.477324)
			(xy 292.68928 -352.477324) (xy 292.69933 -352.476991) (xy 292.717926 -352.469378) (xy 292.725348 -352.462592)
			(xy 293.008812 -352.179128) (xy 293.015521 -352.171659) (xy 293.023103 -352.153091) (xy 293.023544 -352.14306)
			(xy 293.023544 -350.067372) (xy 293.023178 -350.057326) (xy 293.015588 -350.038729) (xy 293.008812 -350.031304)
			(xy 292.152324 -349.174816) (xy 292.145637 -349.167411) (xy 292.138067 -349.14897) (xy 292.137592 -349.139002)
			(xy 292.137592 -346.977208) (xy 292.138048 -346.967239) (xy 292.145636 -346.948802) (xy 292.152324 -346.941394)
			(xy 292.329108 -346.76461) (xy 292.336498 -346.757869) (xy 292.354933 -346.750158) (xy 292.364922 -346.749624)
			(xy 295.4401 -346.749624) (xy 295.450108 -346.750057) (xy 295.46857 -346.757796) (xy 295.475914 -346.76461)
			(xy 295.803574 -347.09227) (xy 295.810296 -347.099675) (xy 295.818018 -347.118099) (xy 295.81856 -347.128084)
			(xy 295.81856 -348.252034) (xy 295.818922 -348.26208) (xy 295.826515 -348.280677) (xy 295.833292 -348.288102)
			(xy 295.91635 -348.37116) (xy 296.300398 -348.37116) (xy 296.300865 -348.343248) (xy 296.309005 -348.288021)
			(xy 296.325107 -348.23457) (xy 296.348825 -348.184036) (xy 296.379655 -348.137497) (xy 296.397934 -348.116398)
			(xy 296.404284 -348.109286) (xy 296.410888 -348.092014) (xy 296.410888 -348.004892) (xy 296.404284 -347.98762)
			(xy 296.397934 -347.980508) (xy 296.379628 -347.959432) (xy 296.348807 -347.912886) (xy 296.325098 -347.862345)
			(xy 296.309008 -347.808889) (xy 296.30088 -347.753659) (xy 296.300398 -347.725746) (xy 296.300884 -347.698495)
			(xy 296.30864 -347.644547) (xy 296.323995 -347.592252) (xy 296.346637 -347.542675) (xy 296.376103 -347.496825)
			(xy 296.411794 -347.455634) (xy 296.452985 -347.419943) (xy 296.498835 -347.390477) (xy 296.548412 -347.367835)
			(xy 296.600707 -347.35248) (xy 296.654655 -347.344724) (xy 296.709157 -347.344724) (xy 296.763105 -347.35248)
			(xy 296.8154 -347.367835) (xy 296.864977 -347.390477) (xy 296.910827 -347.419943) (xy 296.952018 -347.455634)
			(xy 296.987709 -347.496825) (xy 297.017175 -347.542675) (xy 297.039817 -347.592252) (xy 297.055172 -347.644547)
			(xy 297.062928 -347.698495) (xy 297.063414 -347.725746) (xy 297.062948 -347.753658) (xy 297.054807 -347.808885)
			(xy 297.038705 -347.862336) (xy 297.014986 -347.91287) (xy 296.984157 -347.959409) (xy 296.965878 -347.980508)
			(xy 296.959528 -347.98762) (xy 296.952924 -348.004892) (xy 296.952924 -348.092014) (xy 296.959528 -348.109286)
			(xy 296.965878 -348.116398) (xy 296.984126 -348.137523) (xy 297.014958 -348.184054) (xy 297.03868 -348.234582)
			(xy 297.054783 -348.288028) (xy 297.062925 -348.34325) (xy 297.063414 -348.37116) (xy 297.062928 -348.398411)
			(xy 297.055172 -348.452359) (xy 297.039817 -348.504654) (xy 297.017175 -348.554231) (xy 296.987709 -348.600081)
			(xy 296.952018 -348.641272) (xy 296.910827 -348.676963) (xy 296.864977 -348.706429) (xy 296.8154 -348.729071)
			(xy 296.763105 -348.744426) (xy 296.709157 -348.752182) (xy 296.654655 -348.752182) (xy 296.600707 -348.744426)
			(xy 296.548412 -348.729071) (xy 296.498835 -348.706429) (xy 296.452985 -348.676963) (xy 296.411794 -348.641272)
			(xy 296.376103 -348.600081) (xy 296.346637 -348.554231) (xy 296.323995 -348.504654) (xy 296.30864 -348.452359)
			(xy 296.300884 -348.398411) (xy 296.300398 -348.37116) (xy 295.91635 -348.37116) (xy 296.276268 -348.731078)
			(xy 296.282951 -348.738486) (xy 296.290524 -348.756925) (xy 296.291 -348.766892) (xy 296.291 -349.602806)
			(xy 297.25823 -349.602806) (xy 297.262301 -349.547184) (xy 297.274427 -349.492747) (xy 297.29435 -349.440656)
			(xy 297.321646 -349.392021) (xy 297.355732 -349.347878) (xy 297.395881 -349.309169) (xy 297.441239 -349.276718)
			(xy 297.490839 -349.251217) (xy 297.543623 -349.23321) (xy 297.598466 -349.22308) (xy 297.6542 -349.221043)
			(xy 297.709637 -349.227143) (xy 297.763594 -349.241249) (xy 297.814923 -349.263061) (xy 297.862529 -349.292115)
			(xy 297.905397 -349.32779) (xy 297.942614 -349.369327) (xy 297.973387 -349.41584) (xy 297.997059 -349.466337)
			(xy 298.013127 -349.519744) (xy 298.021247 -349.57492) (xy 298.021756 -349.602806) (xy 298.021247 -349.630692)
			(xy 298.013127 -349.685868) (xy 297.997059 -349.739275) (xy 297.973387 -349.789772) (xy 297.942614 -349.836285)
			(xy 297.905397 -349.877822) (xy 297.862529 -349.913497) (xy 297.814923 -349.942551) (xy 297.763594 -349.964363)
			(xy 297.709637 -349.978469) (xy 297.6542 -349.984569) (xy 297.598466 -349.982532) (xy 297.543623 -349.972402)
			(xy 297.490839 -349.954395) (xy 297.441239 -349.928894) (xy 297.395881 -349.896443) (xy 297.355732 -349.857734)
			(xy 297.321646 -349.813591) (xy 297.29435 -349.764956) (xy 297.274427 -349.712865) (xy 297.262301 -349.658428)
			(xy 297.25823 -349.602806) (xy 296.291 -349.602806) (xy 296.291 -350.498156) (xy 296.67911 -350.498156)
			(xy 296.683181 -350.442534) (xy 296.695307 -350.388097) (xy 296.71523 -350.336006) (xy 296.742526 -350.287371)
			(xy 296.776612 -350.243228) (xy 296.816761 -350.204519) (xy 296.862119 -350.172068) (xy 296.911719 -350.146567)
			(xy 296.964503 -350.12856) (xy 297.019346 -350.11843) (xy 297.07508 -350.116393) (xy 297.130517 -350.122493)
			(xy 297.184474 -350.136599) (xy 297.235803 -350.158411) (xy 297.283409 -350.187465) (xy 297.326277 -350.22314)
			(xy 297.363494 -350.264677) (xy 297.394267 -350.31119) (xy 297.417939 -350.361687) (xy 297.434007 -350.415094)
			(xy 297.442127 -350.47027) (xy 297.442636 -350.498156) (xy 297.442127 -350.526042) (xy 297.434007 -350.581218)
			(xy 297.417939 -350.634625) (xy 297.394267 -350.685122) (xy 297.363494 -350.731635) (xy 297.326277 -350.773172)
			(xy 297.283409 -350.808847) (xy 297.235803 -350.837901) (xy 297.184474 -350.859713) (xy 297.130517 -350.873819)
			(xy 297.07508 -350.879919) (xy 297.019346 -350.877882) (xy 296.964503 -350.867752) (xy 296.911719 -350.849745)
			(xy 296.862119 -350.824244) (xy 296.816761 -350.791793) (xy 296.776612 -350.753084) (xy 296.742526 -350.708941)
			(xy 296.71523 -350.660306) (xy 296.695307 -350.608215) (xy 296.683181 -350.553778) (xy 296.67911 -350.498156)
			(xy 296.291 -350.498156) (xy 296.291 -351.173796) (xy 298.017946 -351.173796) (xy 298.018419 -351.146321)
			(xy 298.026312 -351.09194) (xy 298.041935 -351.039257) (xy 298.064963 -350.989365) (xy 298.094918 -350.943297)
			(xy 298.112688 -350.922336) (xy 298.118784 -350.915224) (xy 298.125134 -350.898206) (xy 298.125134 -350.812354)
			(xy 298.118784 -350.795336) (xy 298.112688 -350.788224) (xy 298.094952 -350.767239) (xy 298.065024 -350.721163)
			(xy 298.042006 -350.671275) (xy 298.026373 -350.618603) (xy 298.018449 -350.564235) (xy 298.017946 -350.536764)
			(xy 298.018432 -350.509513) (xy 298.026188 -350.455565) (xy 298.041543 -350.40327) (xy 298.064185 -350.353693)
			(xy 298.093651 -350.307843) (xy 298.129342 -350.266652) (xy 298.170533 -350.230961) (xy 298.216383 -350.201495)
			(xy 298.26596 -350.178853) (xy 298.318255 -350.163498) (xy 298.372203 -350.155742) (xy 298.426705 -350.155742)
			(xy 298.480653 -350.163498) (xy 298.532948 -350.178853) (xy 298.582525 -350.201495) (xy 298.628375 -350.230961)
			(xy 298.669566 -350.266652) (xy 298.705257 -350.307843) (xy 298.734723 -350.353693) (xy 298.757365 -350.40327)
			(xy 298.77272 -350.455565) (xy 298.780476 -350.509513) (xy 298.780962 -350.536764) (xy 298.780464 -350.564238)
			(xy 298.772576 -350.618618) (xy 298.756959 -350.6713) (xy 298.754306 -350.67705) (xy 299.022772 -350.67705)
			(xy 299.022772 -350.62255) (xy 299.030528 -350.568604) (xy 299.045881 -350.516311) (xy 299.068521 -350.466735)
			(xy 299.097985 -350.420885) (xy 299.133674 -350.379695) (xy 299.174861 -350.344003) (xy 299.220708 -350.314535)
			(xy 299.270282 -350.291892) (xy 299.322574 -350.276534) (xy 299.37652 -350.268774) (xy 299.40377 -350.268286)
			(xy 299.429006 -350.268654) (xy 299.479041 -350.275281) (xy 299.527762 -350.288463) (xy 299.574312 -350.307967)
			(xy 299.596302 -350.320356) (xy 299.605954 -350.326198) (xy 299.628052 -350.32823) (xy 299.72254 -350.294702)
			(xy 299.738542 -350.279208) (xy 299.742606 -350.268794) (xy 299.753277 -350.242007) (xy 299.781568 -350.191764)
			(xy 299.817101 -350.146354) (xy 299.859066 -350.106811) (xy 299.906507 -350.074039) (xy 299.958342 -350.048783)
			(xy 300.013389 -350.03162) (xy 300.070392 -350.022941) (xy 300.099222 -350.022414) (xy 300.126475 -350.022857)
			(xy 300.180425 -350.030617) (xy 300.232722 -350.045977) (xy 300.282301 -350.068622) (xy 300.328152 -350.098092)
			(xy 300.369343 -350.133788) (xy 300.405034 -350.174983) (xy 300.434499 -350.220838) (xy 300.457139 -350.270419)
			(xy 300.472492 -350.322718) (xy 300.480246 -350.376669) (xy 300.48073 -350.403922) (xy 300.48006 -350.435484)
			(xy 300.469676 -350.497749) (xy 300.449195 -350.557459) (xy 300.434756 -350.585532) (xy 300.42993 -350.594422)
			(xy 300.427898 -350.61398) (xy 300.453552 -350.702118) (xy 300.465998 -350.717612) (xy 300.474888 -350.722692)
			(xy 300.500011 -350.737205) (xy 300.545894 -350.772714) (xy 300.585868 -350.814763) (xy 300.619012 -350.862383)
			(xy 300.644559 -350.914474) (xy 300.66192 -350.969834) (xy 300.670695 -351.027185) (xy 300.67123 -351.056194)
			(xy 300.670744 -351.083445) (xy 300.662988 -351.137393) (xy 300.647633 -351.189688) (xy 300.624991 -351.239265)
			(xy 300.595525 -351.285115) (xy 300.559834 -351.326306) (xy 300.518643 -351.361997) (xy 300.472793 -351.391463)
			(xy 300.423216 -351.414105) (xy 300.370921 -351.42946) (xy 300.316973 -351.437216) (xy 300.262471 -351.437216)
			(xy 300.208523 -351.42946) (xy 300.156228 -351.414105) (xy 300.106651 -351.391463) (xy 300.060801 -351.361997)
			(xy 300.01961 -351.326306) (xy 299.983919 -351.285115) (xy 299.954453 -351.239265) (xy 299.931811 -351.189688)
			(xy 299.916456 -351.137393) (xy 299.9087 -351.083445) (xy 299.908214 -351.056194) (xy 299.908885 -351.024632)
			(xy 299.919267 -350.962367) (xy 299.939749 -350.902657) (xy 299.954188 -350.874584) (xy 299.959014 -350.865694)
			(xy 299.961046 -350.846136) (xy 299.935392 -350.757998) (xy 299.922946 -350.742504) (xy 299.914056 -350.737424)
			(xy 299.90669 -350.73336) (xy 299.897038 -350.727518) (xy 299.87494 -350.725486) (xy 299.780452 -350.759014)
			(xy 299.76445 -350.774508) (xy 299.760386 -350.784922) (xy 299.74973 -350.811715) (xy 299.721437 -350.861958)
			(xy 299.685901 -350.907368) (xy 299.643933 -350.94691) (xy 299.59649 -350.979681) (xy 299.544654 -351.004936)
			(xy 299.489605 -351.022098) (xy 299.432601 -351.030775) (xy 299.40377 -351.031302) (xy 299.37652 -351.030826)
			(xy 299.322574 -351.023066) (xy 299.270282 -351.007708) (xy 299.220708 -350.985065) (xy 299.174861 -350.955597)
			(xy 299.133674 -350.919905) (xy 299.097985 -350.878715) (xy 299.068521 -350.832865) (xy 299.045881 -350.783289)
			(xy 299.030528 -350.730996) (xy 299.022772 -350.67705) (xy 298.754306 -350.67705) (xy 298.733937 -350.721193)
			(xy 298.703987 -350.767262) (xy 298.68622 -350.788224) (xy 298.680124 -350.795336) (xy 298.673774 -350.812354)
			(xy 298.673774 -350.898206) (xy 298.680124 -350.915224) (xy 298.68622 -350.922336) (xy 298.703985 -350.943297)
			(xy 298.733909 -350.98938) (xy 298.756921 -351.039274) (xy 298.772547 -351.091951) (xy 298.780463 -351.146324)
			(xy 298.780962 -351.173796) (xy 298.780476 -351.201047) (xy 298.77272 -351.254995) (xy 298.757365 -351.30729)
			(xy 298.734723 -351.356867) (xy 298.705257 -351.402717) (xy 298.669566 -351.443908) (xy 298.628375 -351.479599)
			(xy 298.582525 -351.509065) (xy 298.532948 -351.531707) (xy 298.480653 -351.547062) (xy 298.426705 -351.554818)
			(xy 298.372203 -351.554818) (xy 298.318255 -351.547062) (xy 298.26596 -351.531707) (xy 298.216383 -351.509065)
			(xy 298.170533 -351.479599) (xy 298.129342 -351.443908) (xy 298.093651 -351.402717) (xy 298.064185 -351.356867)
			(xy 298.041543 -351.30729) (xy 298.026188 -351.254995) (xy 298.018432 -351.201047) (xy 298.017946 -351.173796)
			(xy 296.291 -351.173796) (xy 296.291 -351.701862) (xy 296.291419 -351.711933) (xy 296.299141 -351.730532)
			(xy 296.305986 -351.73793) (xy 296.949368 -352.381312) (xy 296.956839 -352.388019) (xy 296.975406 -352.395603)
			(xy 296.985436 -352.396044) (xy 301.1551 -352.396044) (xy 301.165144 -352.395664) (xy 301.183741 -352.388083)
			(xy 301.191168 -352.381312) (xy 301.380652 -352.191828) (xy 301.387367 -352.184363) (xy 301.394944 -352.165791)
			(xy 301.395384 -352.15576) (xy 301.395384 -350.041972) (xy 301.395008 -350.031927) (xy 301.387424 -350.013331)
			(xy 301.380652 -350.005904) (xy 300.508924 -349.134176) (xy 300.502263 -349.126751) (xy 300.494677 -349.108325)
			(xy 300.494192 -349.098362) (xy 300.494192 -346.949268) (xy 300.494628 -346.939296) (xy 300.50223 -346.92086)
			(xy 300.508924 -346.913454) (xy 300.683168 -346.73921) (xy 300.690571 -346.732486) (xy 300.708997 -346.724765)
			(xy 300.718982 -346.724224) (xy 303.869852 -346.724224) (xy 303.879857 -346.724682) (xy 303.898319 -346.732404)
			(xy 303.905666 -346.73921) (xy 304.183034 -347.016578) (xy 304.189769 -347.023973) (xy 304.197482 -347.042405)
			(xy 304.19802 -347.052392) (xy 304.19802 -348.267274) (xy 304.198372 -348.277321) (xy 304.205973 -348.295917)
			(xy 304.212752 -348.303342) (xy 304.28057 -348.37116) (xy 304.631598 -348.37116) (xy 304.632065 -348.343248)
			(xy 304.640205 -348.288021) (xy 304.656307 -348.23457) (xy 304.680025 -348.184036) (xy 304.710855 -348.137497)
			(xy 304.729134 -348.116398) (xy 304.735484 -348.109286) (xy 304.742088 -348.092014) (xy 304.742088 -348.004892)
			(xy 304.735484 -347.98762) (xy 304.729134 -347.980508) (xy 304.710828 -347.959432) (xy 304.680007 -347.912886)
			(xy 304.656298 -347.862345) (xy 304.640208 -347.808889) (xy 304.63208 -347.753659) (xy 304.631598 -347.725746)
			(xy 304.632084 -347.698495) (xy 304.63984 -347.644547) (xy 304.655195 -347.592252) (xy 304.677837 -347.542675)
			(xy 304.707303 -347.496825) (xy 304.742994 -347.455634) (xy 304.784185 -347.419943) (xy 304.830035 -347.390477)
			(xy 304.879612 -347.367835) (xy 304.931907 -347.35248) (xy 304.985855 -347.344724) (xy 305.040357 -347.344724)
			(xy 305.094305 -347.35248) (xy 305.1466 -347.367835) (xy 305.196177 -347.390477) (xy 305.242027 -347.419943)
			(xy 305.283218 -347.455634) (xy 305.318909 -347.496825) (xy 305.348375 -347.542675) (xy 305.371017 -347.592252)
			(xy 305.386372 -347.644547) (xy 305.394128 -347.698495) (xy 305.394614 -347.725746) (xy 305.394148 -347.753658)
			(xy 305.386007 -347.808885) (xy 305.369905 -347.862336) (xy 305.346186 -347.91287) (xy 305.315357 -347.959409)
			(xy 305.297078 -347.980508) (xy 305.290728 -347.98762) (xy 305.284124 -348.004892) (xy 305.284124 -348.092014)
			(xy 305.290728 -348.109286) (xy 305.297078 -348.116398) (xy 305.315326 -348.137523) (xy 305.346158 -348.184054)
			(xy 305.36988 -348.234582) (xy 305.385983 -348.288028) (xy 305.394125 -348.34325) (xy 305.394614 -348.37116)
			(xy 305.394128 -348.398411) (xy 305.386372 -348.452359) (xy 305.371017 -348.504654) (xy 305.348375 -348.554231)
			(xy 305.318909 -348.600081) (xy 305.283218 -348.641272) (xy 305.242027 -348.676963) (xy 305.196177 -348.706429)
			(xy 305.1466 -348.729071) (xy 305.094305 -348.744426) (xy 305.040357 -348.752182) (xy 304.985855 -348.752182)
			(xy 304.931907 -348.744426) (xy 304.879612 -348.729071) (xy 304.830035 -348.706429) (xy 304.784185 -348.676963)
			(xy 304.742994 -348.641272) (xy 304.707303 -348.600081) (xy 304.677837 -348.554231) (xy 304.655195 -348.504654)
			(xy 304.63984 -348.452359) (xy 304.632084 -348.398411) (xy 304.631598 -348.37116) (xy 304.28057 -348.37116)
			(xy 304.632868 -348.723458) (xy 304.639543 -348.730873) (xy 304.647121 -348.749307) (xy 304.6476 -348.759272)
			(xy 304.6476 -349.602806) (xy 305.58943 -349.602806) (xy 305.593501 -349.547184) (xy 305.605627 -349.492747)
			(xy 305.62555 -349.440656) (xy 305.652846 -349.392021) (xy 305.686932 -349.347878) (xy 305.727081 -349.309169)
			(xy 305.772439 -349.276718) (xy 305.822039 -349.251217) (xy 305.874823 -349.23321) (xy 305.929666 -349.22308)
			(xy 305.9854 -349.221043) (xy 306.040837 -349.227143) (xy 306.094794 -349.241249) (xy 306.146123 -349.263061)
			(xy 306.193729 -349.292115) (xy 306.236597 -349.32779) (xy 306.273814 -349.369327) (xy 306.304587 -349.41584)
			(xy 306.328259 -349.466337) (xy 306.344327 -349.519744) (xy 306.352447 -349.57492) (xy 306.352794 -349.593916)
			(xy 308.898036 -349.593916) (xy 308.898036 -347.326458) (xy 308.898472 -347.302461) (xy 308.905944 -347.255053)
			(xy 308.920759 -347.209404) (xy 308.94255 -347.166643) (xy 308.970778 -347.127829) (xy 308.987444 -347.110558)
			(xy 309.266082 -346.83192) (xy 309.266844 -346.831412) (xy 309.30215 -346.794836) (xy 309.305902 -346.791155)
			(xy 309.314611 -346.78527) (xy 309.319422 -346.783152) (xy 309.41518 -346.74429) (xy 309.419748 -346.742539)
			(xy 309.42934 -346.740618) (xy 309.43423 -346.74048) (xy 310.172354 -346.74048) (xy 310.174132 -346.738956)
			(xy 315.408818 -346.738956) (xy 315.418788 -346.739409) (xy 315.437223 -346.747) (xy 315.444632 -346.753688)
			(xy 316.609476 -347.918532) (xy 316.616942 -347.925245) (xy 316.635513 -347.932824) (xy 316.645544 -347.933264)
			(xy 319.450212 -347.933264) (xy 319.460256 -347.932884) (xy 319.478853 -347.925303) (xy 319.48628 -347.918532)
			(xy 321.222624 -346.182188) (xy 321.229308 -346.174699) (xy 321.236905 -346.156146) (xy 321.237356 -346.14612)
			(xy 321.237356 -343.551764) (xy 321.236991 -343.541718) (xy 321.2294 -343.523121) (xy 321.222624 -343.515696)
			(xy 320.128392 -342.421718) (xy 320.127884 -342.420956) (xy 320.091308 -342.38565) (xy 320.087623 -342.381901)
			(xy 320.081741 -342.37319) (xy 320.079624 -342.368378) (xy 320.040762 -342.27262) (xy 320.03901 -342.268052)
			(xy 320.03709 -342.25846) (xy 320.036952 -342.25357) (xy 320.036952 -340.791546) (xy 320.036598 -340.781499)
			(xy 320.028999 -340.762902) (xy 320.02222 -340.755478) (xy 319.467738 -340.20125) (xy 319.46723 -340.200488)
			(xy 319.430654 -340.165182) (xy 319.426981 -340.161422) (xy 319.421091 -340.152719) (xy 319.41897 -340.14791)
			(xy 319.380108 -340.052152) (xy 319.378403 -340.047578) (xy 319.376606 -340.037983) (xy 319.376552 -340.033102)
			(xy 319.376552 -338.319872) (xy 319.376154 -338.309799) (xy 319.368415 -338.291201) (xy 319.361566 -338.283804)
			(xy 318.564768 -337.48726) (xy 318.56426 -337.486498) (xy 318.527684 -337.451192) (xy 318.524016 -337.447427)
			(xy 318.518123 -337.438728) (xy 318.516 -337.43392) (xy 318.477138 -337.338162) (xy 318.475373 -337.333598)
			(xy 318.473461 -337.324003) (xy 318.473328 -337.319112) (xy 318.473328 -335.36001) (xy 318.473453 -335.355119)
			(xy 318.475379 -335.345526) (xy 318.477138 -335.34096) (xy 318.516 -335.245202) (xy 318.518094 -335.240378)
			(xy 318.523985 -335.231668) (xy 318.527684 -335.22793) (xy 318.56426 -335.192624) (xy 318.564768 -335.191862)
			(xy 318.619124 -335.137506) (xy 318.636409 -335.120846) (xy 318.675221 -335.092595) (xy 318.717974 -335.070764)
			(xy 318.763615 -335.055888) (xy 318.811022 -335.048336) (xy 318.835024 -335.047844) (xy 321.776598 -335.047844)
			(xy 321.800604 -335.048281) (xy 321.848019 -335.05583) (xy 321.893667 -335.07071) (xy 321.936422 -335.092554)
			(xy 321.97523 -335.120823) (xy 321.992498 -335.137506) (xy 322.120514 -335.265522) (xy 322.121022 -335.266284)
			(xy 322.157598 -335.30159) (xy 322.161272 -335.305349) (xy 322.167161 -335.314053) (xy 322.169282 -335.318862)
			(xy 322.208144 -335.41462) (xy 322.209844 -335.419196) (xy 322.211643 -335.428789) (xy 322.2117 -335.43367)
			(xy 322.2117 -336.588354) (xy 322.212123 -336.598424) (xy 322.219843 -336.617023) (xy 322.226686 -336.624422)
			(xy 322.245242 -336.642964) (xy 322.636896 -336.642964) (xy 322.637366 -336.615052) (xy 322.645505 -336.559825)
			(xy 322.661606 -336.506374) (xy 322.685324 -336.45584) (xy 322.716153 -336.409301) (xy 322.734432 -336.388202)
			(xy 322.740782 -336.38109) (xy 322.747386 -336.363818) (xy 322.747386 -336.276696) (xy 322.740782 -336.259424)
			(xy 322.734432 -336.252312) (xy 322.716127 -336.231235) (xy 322.685306 -336.184689) (xy 322.661597 -336.134149)
			(xy 322.645507 -336.080693) (xy 322.637378 -336.025463) (xy 322.636896 -335.99755) (xy 322.637382 -335.970299)
			(xy 322.645138 -335.916351) (xy 322.660493 -335.864056) (xy 322.683135 -335.814479) (xy 322.712601 -335.768629)
			(xy 322.748292 -335.727438) (xy 322.789483 -335.691747) (xy 322.835333 -335.662281) (xy 322.88491 -335.639639)
			(xy 322.937205 -335.624284) (xy 322.991153 -335.616528) (xy 323.045655 -335.616528) (xy 323.099603 -335.624284)
			(xy 323.151898 -335.639639) (xy 323.201475 -335.662281) (xy 323.247325 -335.691747) (xy 323.288516 -335.727438)
			(xy 323.324207 -335.768629) (xy 323.353673 -335.814479) (xy 323.376315 -335.864056) (xy 323.39167 -335.916351)
			(xy 323.399426 -335.970299) (xy 323.399912 -335.99755) (xy 323.399449 -336.025462) (xy 323.391307 -336.080689)
			(xy 323.375205 -336.13414) (xy 323.351485 -336.184674) (xy 323.320655 -336.231213) (xy 323.302376 -336.252312)
			(xy 323.296026 -336.259424) (xy 323.289422 -336.276696) (xy 323.289422 -336.363818) (xy 323.296026 -336.38109)
			(xy 323.302376 -336.388202) (xy 323.320625 -336.409326) (xy 323.351457 -336.455857) (xy 323.375179 -336.506385)
			(xy 323.391282 -336.559832) (xy 323.399423 -336.615054) (xy 323.399912 -336.642964) (xy 323.399426 -336.670215)
			(xy 323.39167 -336.724163) (xy 323.376315 -336.776458) (xy 323.353673 -336.826035) (xy 323.324207 -336.871885)
			(xy 323.288516 -336.913076) (xy 323.247325 -336.948767) (xy 323.201475 -336.978233) (xy 323.151898 -337.000875)
			(xy 323.099603 -337.01623) (xy 323.045655 -337.023986) (xy 322.991153 -337.023986) (xy 322.937205 -337.01623)
			(xy 322.88491 -337.000875) (xy 322.835333 -336.978233) (xy 322.789483 -336.948767) (xy 322.748292 -336.913076)
			(xy 322.712601 -336.871885) (xy 322.683135 -336.826035) (xy 322.660493 -336.776458) (xy 322.645138 -336.724163)
			(xy 322.637382 -336.670215) (xy 322.636896 -336.642964) (xy 322.245242 -336.642964) (xy 322.567808 -336.96529)
			(xy 322.568316 -336.966052) (xy 322.604892 -337.001358) (xy 322.608578 -337.005105) (xy 322.61446 -337.013818)
			(xy 322.616576 -337.01863) (xy 322.655438 -337.114388) (xy 322.657192 -337.118955) (xy 322.659111 -337.128547)
			(xy 322.659248 -337.133438) (xy 322.659248 -337.87461) (xy 323.594728 -337.87461) (xy 323.598799 -337.818988)
			(xy 323.610925 -337.764551) (xy 323.630848 -337.71246) (xy 323.658144 -337.663825) (xy 323.69223 -337.619682)
			(xy 323.732379 -337.580973) (xy 323.777737 -337.548522) (xy 323.827337 -337.523021) (xy 323.880121 -337.505014)
			(xy 323.934964 -337.494884) (xy 323.990698 -337.492847) (xy 324.046135 -337.498947) (xy 324.100092 -337.513053)
			(xy 324.151421 -337.534865) (xy 324.199027 -337.563919) (xy 324.241895 -337.599594) (xy 324.279112 -337.641131)
			(xy 324.309885 -337.687644) (xy 324.333557 -337.738141) (xy 324.349625 -337.791548) (xy 324.357745 -337.846724)
			(xy 324.358254 -337.87461) (xy 324.357745 -337.902496) (xy 324.349625 -337.957672) (xy 324.333557 -338.011079)
			(xy 324.309885 -338.061576) (xy 324.279112 -338.108089) (xy 324.241895 -338.149626) (xy 324.199027 -338.185301)
			(xy 324.151421 -338.214355) (xy 324.100092 -338.236167) (xy 324.046135 -338.250273) (xy 323.990698 -338.256373)
			(xy 323.934964 -338.254336) (xy 323.880121 -338.244206) (xy 323.827337 -338.226199) (xy 323.777737 -338.200698)
			(xy 323.732379 -338.168247) (xy 323.69223 -338.129538) (xy 323.658144 -338.085395) (xy 323.630848 -338.03676)
			(xy 323.610925 -337.984669) (xy 323.598799 -337.930232) (xy 323.594728 -337.87461) (xy 322.659248 -337.87461)
			(xy 322.659248 -338.76996) (xy 323.015608 -338.76996) (xy 323.019679 -338.714338) (xy 323.031805 -338.659901)
			(xy 323.051728 -338.60781) (xy 323.079024 -338.559175) (xy 323.11311 -338.515032) (xy 323.153259 -338.476323)
			(xy 323.198617 -338.443872) (xy 323.248217 -338.418371) (xy 323.301001 -338.400364) (xy 323.355844 -338.390234)
			(xy 323.411578 -338.388197) (xy 323.467015 -338.394297) (xy 323.520972 -338.408403) (xy 323.572301 -338.430215)
			(xy 323.619907 -338.459269) (xy 323.662775 -338.494944) (xy 323.699992 -338.536481) (xy 323.730765 -338.582994)
			(xy 323.754437 -338.633491) (xy 323.770505 -338.686898) (xy 323.778625 -338.742074) (xy 323.779134 -338.76996)
			(xy 323.778625 -338.797846) (xy 323.770505 -338.853022) (xy 323.754437 -338.906429) (xy 323.730765 -338.956926)
			(xy 323.699992 -339.003439) (xy 323.662775 -339.044976) (xy 323.619907 -339.080651) (xy 323.572301 -339.109705)
			(xy 323.520972 -339.131517) (xy 323.467015 -339.145623) (xy 323.411578 -339.151723) (xy 323.355844 -339.149686)
			(xy 323.301001 -339.139556) (xy 323.248217 -339.121549) (xy 323.198617 -339.096048) (xy 323.153259 -339.063597)
			(xy 323.11311 -339.024888) (xy 323.079024 -338.980745) (xy 323.051728 -338.93211) (xy 323.031805 -338.880019)
			(xy 323.019679 -338.825582) (xy 323.015608 -338.76996) (xy 322.659248 -338.76996) (xy 322.659248 -339.4456)
			(xy 324.354444 -339.4456) (xy 324.35492 -339.418125) (xy 324.362812 -339.363744) (xy 324.378434 -339.311061)
			(xy 324.401462 -339.261169) (xy 324.431417 -339.215101) (xy 324.449186 -339.19414) (xy 324.455282 -339.187028)
			(xy 324.461632 -339.17001) (xy 324.461632 -339.084158) (xy 324.455282 -339.06714) (xy 324.449186 -339.060028)
			(xy 324.431452 -339.039042) (xy 324.401523 -338.992966) (xy 324.378505 -338.943078) (xy 324.362872 -338.890407)
			(xy 324.354947 -338.836039) (xy 324.354444 -338.808568) (xy 324.35493 -338.781317) (xy 324.362686 -338.727369)
			(xy 324.378041 -338.675074) (xy 324.400683 -338.625497) (xy 324.430149 -338.579647) (xy 324.46584 -338.538456)
			(xy 324.507031 -338.502765) (xy 324.552881 -338.473299) (xy 324.602458 -338.450657) (xy 324.654753 -338.435302)
			(xy 324.708701 -338.427546) (xy 324.763203 -338.427546) (xy 324.817151 -338.435302) (xy 324.869446 -338.450657)
			(xy 324.919023 -338.473299) (xy 324.964873 -338.502765) (xy 325.006064 -338.538456) (xy 325.041755 -338.579647)
			(xy 325.071221 -338.625497) (xy 325.093863 -338.675074) (xy 325.109218 -338.727369) (xy 325.116974 -338.781317)
			(xy 325.11746 -338.808568) (xy 325.116965 -338.836042) (xy 325.109076 -338.890422) (xy 325.093459 -338.943105)
			(xy 325.090808 -338.94885) (xy 325.359276 -338.94885) (xy 325.359276 -338.89435) (xy 325.367031 -338.840405)
			(xy 325.382385 -338.788112) (xy 325.405024 -338.738537) (xy 325.434487 -338.692688) (xy 325.470176 -338.651498)
			(xy 325.511362 -338.615807) (xy 325.557209 -338.586339) (xy 325.606782 -338.563696) (xy 325.659074 -338.548338)
			(xy 325.713018 -338.540578) (xy 325.740268 -338.54009) (xy 325.765504 -338.540458) (xy 325.815539 -338.547085)
			(xy 325.86426 -338.560267) (xy 325.91081 -338.579771) (xy 325.9328 -338.59216) (xy 325.942452 -338.598002)
			(xy 325.96455 -338.600034) (xy 326.059038 -338.566506) (xy 326.07504 -338.551012) (xy 326.079104 -338.540598)
			(xy 326.089779 -338.513812) (xy 326.118069 -338.46357) (xy 326.153601 -338.418159) (xy 326.195566 -338.378617)
			(xy 326.243007 -338.345844) (xy 326.294841 -338.320588) (xy 326.349887 -338.303424) (xy 326.40689 -338.294745)
			(xy 326.43572 -338.294218) (xy 326.462975 -338.294636) (xy 326.516928 -338.302397) (xy 326.569229 -338.317757)
			(xy 326.618811 -338.340403) (xy 326.664665 -338.369876) (xy 326.705858 -338.405574) (xy 326.741552 -338.446772)
			(xy 326.771019 -338.49263) (xy 326.793659 -338.542214) (xy 326.809013 -338.594517) (xy 326.816767 -338.648471)
			(xy 326.817228 -338.675726) (xy 326.81656 -338.707288) (xy 326.806176 -338.769553) (xy 326.785693 -338.829263)
			(xy 326.771254 -338.857336) (xy 326.766428 -338.866226) (xy 326.764396 -338.885784) (xy 326.79005 -338.973922)
			(xy 326.802496 -338.989416) (xy 326.811386 -338.994496) (xy 326.83651 -339.009007) (xy 326.882393 -339.044516)
			(xy 326.922368 -339.086566) (xy 326.955511 -339.134186) (xy 326.981058 -339.186277) (xy 326.998419 -339.241637)
			(xy 327.007193 -339.298989) (xy 327.007728 -339.327998) (xy 327.007242 -339.355249) (xy 326.999486 -339.409197)
			(xy 326.984131 -339.461492) (xy 326.961489 -339.511069) (xy 326.932023 -339.556919) (xy 326.896332 -339.59811)
			(xy 326.855141 -339.633801) (xy 326.809291 -339.663267) (xy 326.759714 -339.685909) (xy 326.707419 -339.701264)
			(xy 326.653471 -339.70902) (xy 326.598969 -339.70902) (xy 326.545021 -339.701264) (xy 326.492726 -339.685909)
			(xy 326.443149 -339.663267) (xy 326.397299 -339.633801) (xy 326.356108 -339.59811) (xy 326.320417 -339.556919)
			(xy 326.290951 -339.511069) (xy 326.268309 -339.461492) (xy 326.252954 -339.409197) (xy 326.245198 -339.355249)
			(xy 326.244712 -339.327998) (xy 326.245385 -339.296436) (xy 326.255766 -339.234171) (xy 326.276247 -339.174461)
			(xy 326.290686 -339.146388) (xy 326.295512 -339.137498) (xy 326.297544 -339.11794) (xy 326.27189 -339.029802)
			(xy 326.259444 -339.014308) (xy 326.250554 -339.009228) (xy 326.243188 -339.005164) (xy 326.233536 -338.999322)
			(xy 326.211438 -338.99729) (xy 326.11695 -339.030818) (xy 326.100948 -339.046312) (xy 326.096884 -339.056726)
			(xy 326.086232 -339.083521) (xy 326.057938 -339.133764) (xy 326.022402 -339.179173) (xy 325.980433 -339.218715)
			(xy 325.93299 -339.251486) (xy 325.881153 -339.276741) (xy 325.826104 -339.293902) (xy 325.769099 -339.30258)
			(xy 325.740268 -339.303106) (xy 325.713018 -339.302622) (xy 325.659074 -339.294862) (xy 325.606782 -339.279504)
			(xy 325.557209 -339.256861) (xy 325.511362 -339.227393) (xy 325.470176 -339.191702) (xy 325.434487 -339.150512)
			(xy 325.405024 -339.104663) (xy 325.382385 -339.055088) (xy 325.367031 -339.002795) (xy 325.359276 -338.94885)
			(xy 325.090808 -338.94885) (xy 325.070436 -338.992998) (xy 325.040485 -339.039066) (xy 325.022718 -339.060028)
			(xy 325.016622 -339.06714) (xy 325.010272 -339.084158) (xy 325.010272 -339.17001) (xy 325.016622 -339.187028)
			(xy 325.022718 -339.19414) (xy 325.040484 -339.2151) (xy 325.070408 -339.261183) (xy 325.09342 -339.311077)
			(xy 325.109046 -339.363755) (xy 325.116961 -339.418127) (xy 325.11746 -339.4456) (xy 325.116974 -339.472851)
			(xy 325.109218 -339.526799) (xy 325.093863 -339.579094) (xy 325.071221 -339.628671) (xy 325.041755 -339.674521)
			(xy 325.006064 -339.715712) (xy 324.964873 -339.751403) (xy 324.919023 -339.780869) (xy 324.869446 -339.803511)
			(xy 324.817151 -339.818866) (xy 324.763203 -339.826622) (xy 324.708701 -339.826622) (xy 324.654753 -339.818866)
			(xy 324.602458 -339.803511) (xy 324.552881 -339.780869) (xy 324.507031 -339.751403) (xy 324.46584 -339.715712)
			(xy 324.430149 -339.674521) (xy 324.400683 -339.628671) (xy 324.378041 -339.579094) (xy 324.362686 -339.526799)
			(xy 324.35493 -339.472851) (xy 324.354444 -339.4456) (xy 322.659248 -339.4456) (xy 322.659248 -340.068662)
			(xy 322.659598 -340.07871) (xy 322.6672 -340.097306) (xy 322.67398 -340.10473) (xy 323.21881 -340.64956)
			(xy 323.226295 -340.656248) (xy 323.244851 -340.663841) (xy 323.254878 -340.664292) (xy 327.479914 -340.664292)
			(xy 327.489958 -340.663906) (xy 327.508554 -340.656328) (xy 327.515982 -340.64956) (xy 327.710546 -340.454996)
			(xy 327.717387 -340.447597) (xy 327.725105 -340.428997) (xy 327.725532 -340.418928) (xy 327.725532 -338.294472)
			(xy 327.725139 -338.284399) (xy 327.717398 -338.2658) (xy 327.710546 -338.258404) (xy 326.920352 -337.468464)
			(xy 326.919844 -337.467702) (xy 326.883268 -337.432396) (xy 326.879599 -337.428632) (xy 326.873707 -337.419932)
			(xy 326.871584 -337.415124) (xy 326.832722 -337.319366) (xy 326.830958 -337.314802) (xy 326.829045 -337.305207)
			(xy 326.828912 -337.300316) (xy 326.828912 -335.28381) (xy 326.829038 -335.278919) (xy 326.830964 -335.269326)
			(xy 326.832722 -335.26476) (xy 326.871584 -335.169002) (xy 326.873681 -335.164179) (xy 326.87957 -335.155469)
			(xy 326.883268 -335.15173) (xy 326.919844 -335.116424) (xy 326.920352 -335.115662) (xy 326.928988 -335.107026)
			(xy 326.946293 -335.090387) (xy 326.985098 -335.062133) (xy 327.027846 -335.040297) (xy 327.073484 -335.025417)
			(xy 327.120887 -335.01786) (xy 327.144888 -335.017364) (xy 330.102718 -335.017364) (xy 330.126723 -335.017812)
			(xy 330.174137 -335.025362) (xy 330.219784 -335.04024) (xy 330.262539 -335.062081) (xy 330.301348 -335.090346)
			(xy 330.318618 -335.107026) (xy 330.469494 -335.257902) (xy 330.470002 -335.258664) (xy 330.506578 -335.29397)
			(xy 330.510265 -335.297717) (xy 330.516146 -335.30643) (xy 330.518262 -335.311242) (xy 330.557124 -335.407)
			(xy 330.558845 -335.411569) (xy 330.560631 -335.421167) (xy 330.56068 -335.42605) (xy 330.56068 -336.583782)
			(xy 330.561094 -336.593853) (xy 330.56882 -336.612452) (xy 330.575666 -336.61985) (xy 330.584311 -336.628486)
			(xy 330.994512 -336.628486) (xy 330.995016 -336.600576) (xy 331.003151 -336.545351) (xy 331.019245 -336.491901)
			(xy 331.042954 -336.441367) (xy 331.073774 -336.394825) (xy 331.092048 -336.373724) (xy 331.098398 -336.366612)
			(xy 331.105002 -336.34934) (xy 331.105002 -336.262218) (xy 331.098398 -336.244946) (xy 331.092048 -336.237834)
			(xy 331.073756 -336.216746) (xy 331.042933 -336.170204) (xy 331.019221 -336.119666) (xy 331.003127 -336.066212)
			(xy 330.994996 -336.010984) (xy 330.994512 -335.983072) (xy 330.994998 -335.955821) (xy 331.002754 -335.901873)
			(xy 331.018109 -335.849578) (xy 331.040751 -335.800001) (xy 331.070217 -335.754151) (xy 331.105908 -335.71296)
			(xy 331.147099 -335.677269) (xy 331.192949 -335.647803) (xy 331.242526 -335.625161) (xy 331.294821 -335.609806)
			(xy 331.348769 -335.60205) (xy 331.403271 -335.60205) (xy 331.457219 -335.609806) (xy 331.509514 -335.625161)
			(xy 331.559091 -335.647803) (xy 331.604941 -335.677269) (xy 331.646132 -335.71296) (xy 331.681823 -335.754151)
			(xy 331.711289 -335.800001) (xy 331.733931 -335.849578) (xy 331.749286 -335.901873) (xy 331.757042 -335.955821)
			(xy 331.757528 -335.983072) (xy 331.757074 -336.010984) (xy 331.748929 -336.066211) (xy 331.732825 -336.119663)
			(xy 331.709103 -336.170197) (xy 331.678272 -336.216735) (xy 331.659992 -336.237834) (xy 331.653642 -336.244946)
			(xy 331.647038 -336.262218) (xy 331.647038 -336.34934) (xy 331.653642 -336.366612) (xy 331.659992 -336.373724)
			(xy 331.678254 -336.394837) (xy 331.709084 -336.441371) (xy 331.732803 -336.491903) (xy 331.748903 -336.545351)
			(xy 331.757041 -336.600576) (xy 331.757528 -336.628486) (xy 331.757042 -336.655737) (xy 331.749286 -336.709685)
			(xy 331.733931 -336.76198) (xy 331.711289 -336.811557) (xy 331.681823 -336.857407) (xy 331.646132 -336.898598)
			(xy 331.604941 -336.934289) (xy 331.559091 -336.963755) (xy 331.509514 -336.986397) (xy 331.457219 -337.001752)
			(xy 331.403271 -337.009508) (xy 331.348769 -337.009508) (xy 331.294821 -337.001752) (xy 331.242526 -336.986397)
			(xy 331.192949 -336.963755) (xy 331.147099 -336.934289) (xy 331.105908 -336.898598) (xy 331.070217 -336.857407)
			(xy 331.040751 -336.811557) (xy 331.018109 -336.76198) (xy 331.002754 -336.709685) (xy 330.994998 -336.655737)
			(xy 330.994512 -336.628486) (xy 330.584311 -336.628486) (xy 330.82992 -336.87385) (xy 330.830428 -336.874612)
			(xy 330.867004 -336.909918) (xy 330.870684 -336.913671) (xy 330.876569 -336.922379) (xy 330.878688 -336.92719)
			(xy 330.91755 -337.022948) (xy 330.91929 -337.02752) (xy 330.921218 -337.037109) (xy 330.92136 -337.041998)
			(xy 330.92136 -337.860132) (xy 331.952344 -337.860132) (xy 331.956415 -337.80451) (xy 331.968541 -337.750073)
			(xy 331.988464 -337.697982) (xy 332.01576 -337.649347) (xy 332.049846 -337.605204) (xy 332.089995 -337.566495)
			(xy 332.135353 -337.534044) (xy 332.184953 -337.508543) (xy 332.237737 -337.490536) (xy 332.29258 -337.480406)
			(xy 332.348314 -337.478369) (xy 332.403751 -337.484469) (xy 332.457708 -337.498575) (xy 332.509037 -337.520387)
			(xy 332.556643 -337.549441) (xy 332.599511 -337.585116) (xy 332.636728 -337.626653) (xy 332.667501 -337.673166)
			(xy 332.691173 -337.723663) (xy 332.707241 -337.77707) (xy 332.715361 -337.832246) (xy 332.71587 -337.860132)
			(xy 332.715361 -337.888018) (xy 332.707241 -337.943194) (xy 332.691173 -337.996601) (xy 332.667501 -338.047098)
			(xy 332.636728 -338.093611) (xy 332.599511 -338.135148) (xy 332.556643 -338.170823) (xy 332.509037 -338.199877)
			(xy 332.457708 -338.221689) (xy 332.403751 -338.235795) (xy 332.348314 -338.241895) (xy 332.29258 -338.239858)
			(xy 332.237737 -338.229728) (xy 332.184953 -338.211721) (xy 332.135353 -338.18622) (xy 332.089995 -338.153769)
			(xy 332.049846 -338.11506) (xy 332.01576 -338.070917) (xy 331.988464 -338.022282) (xy 331.968541 -337.970191)
			(xy 331.956415 -337.915754) (xy 331.952344 -337.860132) (xy 330.92136 -337.860132) (xy 330.92136 -338.755482)
			(xy 331.373224 -338.755482) (xy 331.377295 -338.69986) (xy 331.389421 -338.645423) (xy 331.409344 -338.593332)
			(xy 331.43664 -338.544697) (xy 331.470726 -338.500554) (xy 331.510875 -338.461845) (xy 331.556233 -338.429394)
			(xy 331.605833 -338.403893) (xy 331.658617 -338.385886) (xy 331.71346 -338.375756) (xy 331.769194 -338.373719)
			(xy 331.824631 -338.379819) (xy 331.878588 -338.393925) (xy 331.929917 -338.415737) (xy 331.977523 -338.444791)
			(xy 332.020391 -338.480466) (xy 332.057608 -338.522003) (xy 332.088381 -338.568516) (xy 332.112053 -338.619013)
			(xy 332.128121 -338.67242) (xy 332.136241 -338.727596) (xy 332.13675 -338.755482) (xy 332.136241 -338.783368)
			(xy 332.128121 -338.838544) (xy 332.112053 -338.891951) (xy 332.088381 -338.942448) (xy 332.057608 -338.988961)
			(xy 332.020391 -339.030498) (xy 331.977523 -339.066173) (xy 331.929917 -339.095227) (xy 331.878588 -339.117039)
			(xy 331.824631 -339.131145) (xy 331.769194 -339.137245) (xy 331.71346 -339.135208) (xy 331.658617 -339.125078)
			(xy 331.605833 -339.107071) (xy 331.556233 -339.08157) (xy 331.510875 -339.049119) (xy 331.470726 -339.01041)
			(xy 331.43664 -338.966267) (xy 331.409344 -338.917632) (xy 331.389421 -338.865541) (xy 331.377295 -338.811104)
			(xy 331.373224 -338.755482) (xy 330.92136 -338.755482) (xy 330.92136 -339.431122) (xy 332.71206 -339.431122)
			(xy 332.712569 -339.403648) (xy 332.720457 -339.34927) (xy 332.736072 -339.296588) (xy 332.759092 -339.246695)
			(xy 332.789037 -339.200625) (xy 332.806802 -339.179662) (xy 332.812898 -339.17255) (xy 332.819248 -339.155532)
			(xy 332.819248 -339.06968) (xy 332.812898 -339.052662) (xy 332.806802 -339.04555) (xy 332.789034 -339.024591)
			(xy 332.75911 -338.978509) (xy 332.736098 -338.928613) (xy 332.720473 -338.875936) (xy 332.712558 -338.821563)
			(xy 332.71206 -338.79409) (xy 332.712546 -338.766839) (xy 332.720302 -338.712891) (xy 332.735657 -338.660596)
			(xy 332.758299 -338.611019) (xy 332.787765 -338.565169) (xy 332.823456 -338.523978) (xy 332.864647 -338.488287)
			(xy 332.910497 -338.458821) (xy 332.960074 -338.436179) (xy 333.012369 -338.420824) (xy 333.066317 -338.413068)
			(xy 333.120819 -338.413068) (xy 333.174767 -338.420824) (xy 333.227062 -338.436179) (xy 333.276639 -338.458821)
			(xy 333.322489 -338.488287) (xy 333.36368 -338.523978) (xy 333.399371 -338.565169) (xy 333.428837 -338.611019)
			(xy 333.451479 -338.660596) (xy 333.466834 -338.712891) (xy 333.47459 -338.766839) (xy 333.475076 -338.79409)
			(xy 333.47459 -338.821565) (xy 333.466699 -338.875945) (xy 333.451079 -338.928627) (xy 333.448438 -338.934349)
			(xy 333.716898 -338.934349) (xy 333.716898 -338.879851) (xy 333.724654 -338.825908) (xy 333.740007 -338.773617)
			(xy 333.762646 -338.724043) (xy 333.792109 -338.678196) (xy 333.827797 -338.637009) (xy 333.868983 -338.601319)
			(xy 333.914829 -338.571854) (xy 333.964402 -338.549213) (xy 334.016692 -338.533857) (xy 334.070635 -338.526099)
			(xy 334.097884 -338.525612) (xy 334.123121 -338.52597) (xy 334.173156 -338.5326) (xy 334.221876 -338.545784)
			(xy 334.268427 -338.565292) (xy 334.290416 -338.577682) (xy 334.300068 -338.583524) (xy 334.322166 -338.585556)
			(xy 334.416654 -338.552028) (xy 334.432656 -338.536534) (xy 334.43672 -338.52612) (xy 334.447394 -338.499334)
			(xy 334.475682 -338.449089) (xy 334.511214 -338.403678) (xy 334.553179 -338.364135) (xy 334.60062 -338.331361)
			(xy 334.652455 -338.306106) (xy 334.707502 -338.288944) (xy 334.764506 -338.280266) (xy 334.793336 -338.27974)
			(xy 334.820592 -338.280122) (xy 334.874548 -338.287885) (xy 334.926851 -338.303248) (xy 334.976434 -338.325898)
			(xy 335.02229 -338.355374) (xy 335.063483 -338.391076) (xy 335.099176 -338.432278) (xy 335.128642 -338.47814)
			(xy 335.151282 -338.527728) (xy 335.166633 -338.580034) (xy 335.174384 -338.633992) (xy 335.174844 -338.661248)
			(xy 335.174195 -338.692811) (xy 335.163804 -338.755077) (xy 335.143314 -338.814786) (xy 335.12887 -338.842858)
			(xy 335.124044 -338.851748) (xy 335.122012 -338.871306) (xy 335.147666 -338.959444) (xy 335.160112 -338.974938)
			(xy 335.169002 -338.980018) (xy 335.194096 -338.994578) (xy 335.239978 -339.03008) (xy 335.279953 -339.072122)
			(xy 335.313099 -339.119734) (xy 335.338651 -339.171817) (xy 335.356019 -339.227169) (xy 335.364803 -339.284513)
			(xy 335.365344 -339.31352) (xy 335.364858 -339.340771) (xy 335.357102 -339.394719) (xy 335.341747 -339.447014)
			(xy 335.319105 -339.496591) (xy 335.289639 -339.542441) (xy 335.253948 -339.583632) (xy 335.212757 -339.619323)
			(xy 335.166907 -339.648789) (xy 335.11733 -339.671431) (xy 335.065035 -339.686786) (xy 335.011087 -339.694542)
			(xy 334.956585 -339.694542) (xy 334.902637 -339.686786) (xy 334.850342 -339.671431) (xy 334.800765 -339.648789)
			(xy 334.754915 -339.619323) (xy 334.713724 -339.583632) (xy 334.678033 -339.542441) (xy 334.648567 -339.496591)
			(xy 334.625925 -339.447014) (xy 334.61057 -339.394719) (xy 334.602814 -339.340771) (xy 334.602328 -339.31352)
			(xy 334.602968 -339.281956) (xy 334.613363 -339.21969) (xy 334.633857 -339.159982) (xy 334.648302 -339.13191)
			(xy 334.653128 -339.12302) (xy 334.65516 -339.103462) (xy 334.629506 -339.015324) (xy 334.61706 -338.99983)
			(xy 334.60817 -338.99475) (xy 334.600804 -338.990686) (xy 334.591152 -338.984844) (xy 334.569054 -338.982812)
			(xy 334.474566 -339.01634) (xy 334.458564 -339.031834) (xy 334.4545 -339.042248) (xy 334.443846 -339.069042)
			(xy 334.415551 -339.119284) (xy 334.380014 -339.164692) (xy 334.338046 -339.204233) (xy 334.290603 -339.237004)
			(xy 334.238767 -339.262259) (xy 334.183719 -339.279421) (xy 334.126715 -339.2881) (xy 334.097884 -339.288628)
			(xy 334.070635 -339.288101) (xy 334.016692 -339.280343) (xy 333.964402 -339.264987) (xy 333.914829 -339.242346)
			(xy 333.868983 -339.212881) (xy 333.827797 -339.177191) (xy 333.792109 -339.136004) (xy 333.762646 -339.090157)
			(xy 333.740007 -339.040583) (xy 333.724654 -338.988292) (xy 333.716898 -338.934349) (xy 333.448438 -338.934349)
			(xy 333.428054 -338.97852) (xy 333.398102 -339.024588) (xy 333.380334 -339.04555) (xy 333.374238 -339.052662)
			(xy 333.367888 -339.06968) (xy 333.367888 -339.155532) (xy 333.374238 -339.17255) (xy 333.380334 -339.179662)
			(xy 333.398066 -339.20065) (xy 333.427995 -339.246725) (xy 333.451013 -339.296613) (xy 333.466646 -339.349284)
			(xy 333.474572 -339.403651) (xy 333.475076 -339.431122) (xy 333.47459 -339.458373) (xy 333.466834 -339.512321)
			(xy 333.451479 -339.564616) (xy 333.428837 -339.614193) (xy 333.399371 -339.660043) (xy 333.36368 -339.701234)
			(xy 333.322489 -339.736925) (xy 333.276639 -339.766391) (xy 333.227062 -339.789033) (xy 333.174767 -339.804388)
			(xy 333.120819 -339.812144) (xy 333.066317 -339.812144) (xy 333.012369 -339.804388) (xy 332.960074 -339.789033)
			(xy 332.910497 -339.766391) (xy 332.864647 -339.736925) (xy 332.823456 -339.701234) (xy 332.787765 -339.660043)
			(xy 332.758299 -339.614193) (xy 332.735657 -339.564616) (xy 332.720302 -339.512321) (xy 332.712546 -339.458373)
			(xy 332.71206 -339.431122) (xy 330.92136 -339.431122) (xy 330.92136 -339.913214) (xy 330.921732 -339.923259)
			(xy 330.929318 -339.941856) (xy 330.936092 -339.949282) (xy 331.61859 -340.63178) (xy 331.626046 -340.638506)
			(xy 331.644625 -340.646076) (xy 331.654658 -340.646512) (xy 335.841594 -340.646512) (xy 335.851639 -340.646137)
			(xy 335.870236 -340.638554) (xy 335.877662 -340.63178) (xy 336.046826 -340.462616) (xy 336.053655 -340.455208)
			(xy 336.061381 -340.436615) (xy 336.061812 -340.426548) (xy 336.061812 -338.228432) (xy 336.061393 -338.218362)
			(xy 336.05367 -338.199763) (xy 336.046826 -338.192364) (xy 335.277968 -337.42376) (xy 335.27746 -337.422998)
			(xy 335.240884 -337.387692) (xy 335.237216 -337.383927) (xy 335.231323 -337.375228) (xy 335.2292 -337.37042)
			(xy 335.190338 -337.274662) (xy 335.188573 -337.270098) (xy 335.186661 -337.260503) (xy 335.186528 -337.255612)
			(xy 335.186528 -335.251044) (xy 335.186662 -335.246153) (xy 335.188582 -335.236561) (xy 335.190338 -335.231994)
			(xy 335.2292 -335.136236) (xy 335.231302 -335.131415) (xy 335.237187 -335.122704) (xy 335.240884 -335.118964)
			(xy 335.27746 -335.083658) (xy 335.277968 -335.082896) (xy 335.303876 -335.056988) (xy 335.321174 -335.040358)
			(xy 335.360005 -335.012173) (xy 335.402762 -334.9904) (xy 335.448396 -334.975574) (xy 335.495785 -334.968059)
			(xy 335.519776 -334.96758) (xy 338.444332 -334.96758) (xy 338.46833 -334.96801) (xy 338.515738 -334.975481)
			(xy 338.561388 -334.990297) (xy 338.604149 -335.01209) (xy 338.642962 -335.040321) (xy 338.660232 -335.056988)
			(xy 338.815934 -335.21269) (xy 338.816442 -335.213452) (xy 338.853018 -335.248758) (xy 338.856695 -335.252514)
			(xy 338.862583 -335.26122) (xy 338.864702 -335.26603) (xy 338.903564 -335.361788) (xy 338.905283 -335.366358)
			(xy 338.90707 -335.375956) (xy 338.90712 -335.380838) (xy 338.90712 -336.558382) (xy 338.90755 -336.568451)
			(xy 338.915267 -336.587049) (xy 338.922106 -336.59445) (xy 339.007024 -336.679286) (xy 339.325712 -336.679286)
			(xy 339.326216 -336.651376) (xy 339.334351 -336.596151) (xy 339.350445 -336.542701) (xy 339.374154 -336.492167)
			(xy 339.404974 -336.445625) (xy 339.423248 -336.424524) (xy 339.429598 -336.417412) (xy 339.436202 -336.40014)
			(xy 339.436202 -336.313018) (xy 339.429598 -336.295746) (xy 339.423248 -336.288634) (xy 339.404956 -336.267546)
			(xy 339.374133 -336.221004) (xy 339.350421 -336.170466) (xy 339.334327 -336.117012) (xy 339.326196 -336.061784)
			(xy 339.325712 -336.033872) (xy 339.326198 -336.006621) (xy 339.333954 -335.952673) (xy 339.349309 -335.900378)
			(xy 339.371951 -335.850801) (xy 339.401417 -335.804951) (xy 339.437108 -335.76376) (xy 339.478299 -335.728069)
			(xy 339.524149 -335.698603) (xy 339.573726 -335.675961) (xy 339.626021 -335.660606) (xy 339.679969 -335.65285)
			(xy 339.734471 -335.65285) (xy 339.788419 -335.660606) (xy 339.840714 -335.675961) (xy 339.890291 -335.698603)
			(xy 339.936141 -335.728069) (xy 339.977332 -335.76376) (xy 340.013023 -335.804951) (xy 340.042489 -335.850801)
			(xy 340.065131 -335.900378) (xy 340.080486 -335.952673) (xy 340.088242 -336.006621) (xy 340.088728 -336.033872)
			(xy 340.088274 -336.061784) (xy 340.080129 -336.117011) (xy 340.064025 -336.170463) (xy 340.040303 -336.220997)
			(xy 340.009472 -336.267535) (xy 339.991192 -336.288634) (xy 339.984842 -336.295746) (xy 339.978238 -336.313018)
			(xy 339.978238 -336.40014) (xy 339.984842 -336.417412) (xy 339.991192 -336.424524) (xy 340.009454 -336.445637)
			(xy 340.040284 -336.492171) (xy 340.064003 -336.542703) (xy 340.080103 -336.596151) (xy 340.088241 -336.651376)
			(xy 340.088728 -336.679286) (xy 340.088242 -336.706537) (xy 340.080486 -336.760485) (xy 340.065131 -336.81278)
			(xy 340.042489 -336.862357) (xy 340.013023 -336.908207) (xy 339.977332 -336.949398) (xy 339.936141 -336.985089)
			(xy 339.890291 -337.014555) (xy 339.840714 -337.037197) (xy 339.788419 -337.052552) (xy 339.734471 -337.060308)
			(xy 339.679969 -337.060308) (xy 339.626021 -337.052552) (xy 339.573726 -337.037197) (xy 339.524149 -337.014555)
			(xy 339.478299 -336.985089) (xy 339.437108 -336.949398) (xy 339.401417 -336.908207) (xy 339.371951 -336.862357)
			(xy 339.349309 -336.81278) (xy 339.333954 -336.760485) (xy 339.326198 -336.706537) (xy 339.325712 -336.679286)
			(xy 339.007024 -336.679286) (xy 339.18652 -336.85861) (xy 339.187028 -336.859372) (xy 339.223604 -336.894678)
			(xy 339.227276 -336.898438) (xy 339.233166 -336.907141) (xy 339.235288 -336.91195) (xy 339.27415 -337.007708)
			(xy 339.275906 -337.012274) (xy 339.277824 -337.021867) (xy 339.27796 -337.026758) (xy 339.27796 -337.910932)
			(xy 340.283544 -337.910932) (xy 340.287615 -337.85531) (xy 340.299741 -337.800873) (xy 340.319664 -337.748782)
			(xy 340.34696 -337.700147) (xy 340.381046 -337.656004) (xy 340.421195 -337.617295) (xy 340.466553 -337.584844)
			(xy 340.516153 -337.559343) (xy 340.568937 -337.541336) (xy 340.62378 -337.531206) (xy 340.679514 -337.529169)
			(xy 340.734951 -337.535269) (xy 340.788908 -337.549375) (xy 340.840237 -337.571187) (xy 340.887843 -337.600241)
			(xy 340.930711 -337.635916) (xy 340.967928 -337.677453) (xy 340.998701 -337.723966) (xy 341.022373 -337.774463)
			(xy 341.038441 -337.82787) (xy 341.046561 -337.883046) (xy 341.04707 -337.910932) (xy 341.046561 -337.938818)
			(xy 341.038441 -337.993994) (xy 341.022373 -338.047401) (xy 340.998701 -338.097898) (xy 340.967928 -338.144411)
			(xy 340.930711 -338.185948) (xy 340.887843 -338.221623) (xy 340.840237 -338.250677) (xy 340.788908 -338.272489)
			(xy 340.734951 -338.286595) (xy 340.679514 -338.292695) (xy 340.62378 -338.290658) (xy 340.568937 -338.280528)
			(xy 340.516153 -338.262521) (xy 340.466553 -338.23702) (xy 340.421195 -338.204569) (xy 340.381046 -338.16586)
			(xy 340.34696 -338.121717) (xy 340.319664 -338.073082) (xy 340.299741 -338.020991) (xy 340.287615 -337.966554)
			(xy 340.283544 -337.910932) (xy 339.27796 -337.910932) (xy 339.27796 -338.806282) (xy 339.704424 -338.806282)
			(xy 339.708495 -338.75066) (xy 339.720621 -338.696223) (xy 339.740544 -338.644132) (xy 339.76784 -338.595497)
			(xy 339.801926 -338.551354) (xy 339.842075 -338.512645) (xy 339.887433 -338.480194) (xy 339.937033 -338.454693)
			(xy 339.989817 -338.436686) (xy 340.04466 -338.426556) (xy 340.100394 -338.424519) (xy 340.155831 -338.430619)
			(xy 340.209788 -338.444725) (xy 340.261117 -338.466537) (xy 340.308723 -338.495591) (xy 340.351591 -338.531266)
			(xy 340.388808 -338.572803) (xy 340.419581 -338.619316) (xy 340.443253 -338.669813) (xy 340.459321 -338.72322)
			(xy 340.467441 -338.778396) (xy 340.46795 -338.806282) (xy 340.467441 -338.834168) (xy 340.459321 -338.889344)
			(xy 340.443253 -338.942751) (xy 340.419581 -338.993248) (xy 340.388808 -339.039761) (xy 340.351591 -339.081298)
			(xy 340.308723 -339.116973) (xy 340.261117 -339.146027) (xy 340.209788 -339.167839) (xy 340.155831 -339.181945)
			(xy 340.100394 -339.188045) (xy 340.04466 -339.186008) (xy 339.989817 -339.175878) (xy 339.937033 -339.157871)
			(xy 339.887433 -339.13237) (xy 339.842075 -339.099919) (xy 339.801926 -339.06121) (xy 339.76784 -339.017067)
			(xy 339.740544 -338.968432) (xy 339.720621 -338.916341) (xy 339.708495 -338.861904) (xy 339.704424 -338.806282)
			(xy 339.27796 -338.806282) (xy 339.27796 -339.481922) (xy 341.04326 -339.481922) (xy 341.043769 -339.454448)
			(xy 341.051657 -339.40007) (xy 341.067272 -339.347388) (xy 341.090292 -339.297495) (xy 341.120237 -339.251425)
			(xy 341.138002 -339.230462) (xy 341.144098 -339.22335) (xy 341.150448 -339.206332) (xy 341.150448 -339.12048)
			(xy 341.144098 -339.103462) (xy 341.138002 -339.09635) (xy 341.120234 -339.075391) (xy 341.09031 -339.029309)
			(xy 341.067298 -338.979413) (xy 341.051673 -338.926736) (xy 341.043758 -338.872363) (xy 341.04326 -338.84489)
			(xy 341.043746 -338.817639) (xy 341.051502 -338.763691) (xy 341.066857 -338.711396) (xy 341.089499 -338.661819)
			(xy 341.118965 -338.615969) (xy 341.154656 -338.574778) (xy 341.195847 -338.539087) (xy 341.241697 -338.509621)
			(xy 341.291274 -338.486979) (xy 341.343569 -338.471624) (xy 341.397517 -338.463868) (xy 341.452019 -338.463868)
			(xy 341.505967 -338.471624) (xy 341.558262 -338.486979) (xy 341.607839 -338.509621) (xy 341.653689 -338.539087)
			(xy 341.69488 -338.574778) (xy 341.730571 -338.615969) (xy 341.760037 -338.661819) (xy 341.782679 -338.711396)
			(xy 341.798034 -338.763691) (xy 341.80579 -338.817639) (xy 341.806276 -338.84489) (xy 341.80579 -338.872365)
			(xy 341.797899 -338.926745) (xy 341.782279 -338.979427) (xy 341.779638 -338.985149) (xy 342.048098 -338.985149)
			(xy 342.048098 -338.930651) (xy 342.055854 -338.876708) (xy 342.071207 -338.824417) (xy 342.093846 -338.774843)
			(xy 342.123309 -338.728996) (xy 342.158997 -338.687809) (xy 342.200183 -338.652119) (xy 342.246029 -338.622654)
			(xy 342.295602 -338.600013) (xy 342.347892 -338.584657) (xy 342.401835 -338.576899) (xy 342.429084 -338.576412)
			(xy 342.454321 -338.57677) (xy 342.504356 -338.5834) (xy 342.553076 -338.596584) (xy 342.599627 -338.616092)
			(xy 342.621616 -338.628482) (xy 342.631268 -338.634324) (xy 342.653366 -338.636356) (xy 342.747854 -338.602828)
			(xy 342.763856 -338.587334) (xy 342.76792 -338.57692) (xy 342.778594 -338.550134) (xy 342.806882 -338.499889)
			(xy 342.842414 -338.454478) (xy 342.884379 -338.414935) (xy 342.93182 -338.382161) (xy 342.983655 -338.356906)
			(xy 343.038702 -338.339744) (xy 343.095706 -338.331066) (xy 343.124536 -338.33054) (xy 343.151792 -338.330922)
			(xy 343.205748 -338.338685) (xy 343.258051 -338.354048) (xy 343.307634 -338.376698) (xy 343.35349 -338.406174)
			(xy 343.394683 -338.441876) (xy 343.430376 -338.483078) (xy 343.459842 -338.52894) (xy 343.482482 -338.578528)
			(xy 343.497833 -338.630834) (xy 343.505584 -338.684792) (xy 343.506044 -338.712048) (xy 343.505395 -338.743611)
			(xy 343.495004 -338.805877) (xy 343.474514 -338.865586) (xy 343.46007 -338.893658) (xy 343.455244 -338.902548)
			(xy 343.453212 -338.922106) (xy 343.478866 -339.010244) (xy 343.491312 -339.025738) (xy 343.500202 -339.030818)
			(xy 343.525296 -339.045378) (xy 343.571178 -339.08088) (xy 343.611153 -339.122922) (xy 343.644299 -339.170534)
			(xy 343.669851 -339.222617) (xy 343.687219 -339.277969) (xy 343.696003 -339.335313) (xy 343.696544 -339.36432)
			(xy 343.696058 -339.391571) (xy 343.688302 -339.445519) (xy 343.672947 -339.497814) (xy 343.650305 -339.547391)
			(xy 343.620839 -339.593241) (xy 343.585148 -339.634432) (xy 343.543957 -339.670123) (xy 343.498107 -339.699589)
			(xy 343.44853 -339.722231) (xy 343.396235 -339.737586) (xy 343.342287 -339.745342) (xy 343.287785 -339.745342)
			(xy 343.233837 -339.737586) (xy 343.181542 -339.722231) (xy 343.131965 -339.699589) (xy 343.086115 -339.670123)
			(xy 343.044924 -339.634432) (xy 343.009233 -339.593241) (xy 342.979767 -339.547391) (xy 342.957125 -339.497814)
			(xy 342.94177 -339.445519) (xy 342.934014 -339.391571) (xy 342.933528 -339.36432) (xy 342.934168 -339.332756)
			(xy 342.944563 -339.27049) (xy 342.965057 -339.210782) (xy 342.979502 -339.18271) (xy 342.984328 -339.17382)
			(xy 342.98636 -339.154262) (xy 342.960706 -339.066124) (xy 342.94826 -339.05063) (xy 342.93937 -339.04555)
			(xy 342.932004 -339.041486) (xy 342.922352 -339.035644) (xy 342.900254 -339.033612) (xy 342.805766 -339.06714)
			(xy 342.789764 -339.082634) (xy 342.7857 -339.093048) (xy 342.775046 -339.119842) (xy 342.746751 -339.170084)
			(xy 342.711214 -339.215492) (xy 342.669246 -339.255033) (xy 342.621803 -339.287804) (xy 342.569967 -339.313059)
			(xy 342.514919 -339.330221) (xy 342.457915 -339.3389) (xy 342.429084 -339.339428) (xy 342.401835 -339.338901)
			(xy 342.347892 -339.331143) (xy 342.295602 -339.315787) (xy 342.246029 -339.293146) (xy 342.200183 -339.263681)
			(xy 342.158997 -339.227991) (xy 342.123309 -339.186804) (xy 342.093846 -339.140957) (xy 342.071207 -339.091383)
			(xy 342.055854 -339.039092) (xy 342.048098 -338.985149) (xy 341.779638 -338.985149) (xy 341.759254 -339.02932)
			(xy 341.729302 -339.075388) (xy 341.711534 -339.09635) (xy 341.705438 -339.103462) (xy 341.699088 -339.12048)
			(xy 341.699088 -339.206332) (xy 341.705438 -339.22335) (xy 341.711534 -339.230462) (xy 341.729266 -339.25145)
			(xy 341.759195 -339.297525) (xy 341.782213 -339.347413) (xy 341.797846 -339.400084) (xy 341.805772 -339.454451)
			(xy 341.806276 -339.481922) (xy 341.80579 -339.509173) (xy 341.798034 -339.563121) (xy 341.782679 -339.615416)
			(xy 341.760037 -339.664993) (xy 341.730571 -339.710843) (xy 341.69488 -339.752034) (xy 341.653689 -339.787725)
			(xy 341.607839 -339.817191) (xy 341.558262 -339.839833) (xy 341.505967 -339.855188) (xy 341.452019 -339.862944)
			(xy 341.397517 -339.862944) (xy 341.343569 -339.855188) (xy 341.291274 -339.839833) (xy 341.241697 -339.817191)
			(xy 341.195847 -339.787725) (xy 341.154656 -339.752034) (xy 341.118965 -339.710843) (xy 341.089499 -339.664993)
			(xy 341.066857 -339.615416) (xy 341.051502 -339.563121) (xy 341.043746 -339.509173) (xy 341.04326 -339.481922)
			(xy 339.27796 -339.481922) (xy 339.27796 -339.908134) (xy 339.278322 -339.91818) (xy 339.285915 -339.936777)
			(xy 339.292692 -339.944202) (xy 340.01837 -340.66988) (xy 340.025832 -340.676597) (xy 340.044406 -340.684172)
			(xy 340.054438 -340.684612) (xy 344.315034 -340.684612) (xy 344.325081 -340.684258) (xy 344.343679 -340.67666)
			(xy 344.351102 -340.66988) (xy 344.405966 -340.615016) (xy 344.412787 -340.6076) (xy 344.420519 -340.589013)
			(xy 344.420952 -340.578948) (xy 344.420952 -338.398612) (xy 344.420533 -338.388542) (xy 344.412809 -338.369943)
			(xy 344.405966 -338.362544) (xy 343.609168 -337.566) (xy 343.60866 -337.565238) (xy 343.572084 -337.529932)
			(xy 343.568405 -337.526178) (xy 343.562519 -337.517471) (xy 343.5604 -337.51266) (xy 343.521538 -337.416902)
			(xy 343.519784 -337.412335) (xy 343.517865 -337.402743) (xy 343.517728 -337.397852) (xy 343.517728 -335.335118)
			(xy 343.517855 -335.330227) (xy 343.51978 -335.320634) (xy 343.521538 -335.316068) (xy 343.5604 -335.22031)
			(xy 343.562496 -335.215487) (xy 343.568386 -335.206777) (xy 343.572084 -335.203038) (xy 343.60866 -335.167732)
			(xy 343.609168 -335.16697) (xy 343.631012 -335.145126) (xy 343.64829 -335.128457) (xy 343.687102 -335.100202)
			(xy 343.729856 -335.078366) (xy 343.775499 -335.063488) (xy 343.822909 -335.055933) (xy 343.846912 -335.055464)
			(xy 347.27769 -335.055464) (xy 347.282719 -335.055625) (xy 347.292568 -335.05768) (xy 347.297248 -335.059528)
			(xy 347.39072 -335.098644) (xy 347.395291 -335.10064) (xy 347.403611 -335.106135) (xy 347.40723 -335.109566)
			(xy 347.58122 -335.283556) (xy 347.581728 -335.284318) (xy 347.618304 -335.319624) (xy 347.621985 -335.323376)
			(xy 347.62787 -335.332085) (xy 347.629988 -335.336896) (xy 347.66885 -335.432654) (xy 347.670592 -335.437226)
			(xy 347.672519 -335.446814) (xy 347.67266 -335.451704) (xy 347.67266 -339.983572) (xy 347.672205 -340.007577)
			(xy 347.664661 -340.054991) (xy 347.649785 -340.100639) (xy 347.627945 -340.143395) (xy 347.599679 -340.182203)
			(xy 347.582998 -340.199472) (xy 347.582744 -340.199472) (xy 347.235526 -340.54669) (xy 347.228702 -340.554103)
			(xy 347.220972 -340.572692) (xy 347.22054 -340.582758) (xy 347.22054 -341.58936) (xy 347.60154 -341.58936)
			(xy 347.602021 -341.561449) (xy 347.610161 -341.506223) (xy 347.626259 -341.452773) (xy 347.649974 -341.402238)
			(xy 347.680799 -341.355698) (xy 347.699076 -341.334598) (xy 347.705426 -341.327486) (xy 347.71203 -341.310214)
			(xy 347.71203 -341.223092) (xy 347.705426 -341.20582) (xy 347.699076 -341.198708) (xy 347.680777 -341.177626)
			(xy 347.649953 -341.131083) (xy 347.626242 -341.080543) (xy 347.610151 -341.027088) (xy 347.602022 -340.971858)
			(xy 347.60154 -340.943946) (xy 347.602026 -340.916695) (xy 347.609782 -340.862747) (xy 347.625137 -340.810452)
			(xy 347.647779 -340.760875) (xy 347.677245 -340.715025) (xy 347.712936 -340.673834) (xy 347.754127 -340.638143)
			(xy 347.799977 -340.608677) (xy 347.849554 -340.586035) (xy 347.901849 -340.57068) (xy 347.955797 -340.562924)
			(xy 348.010299 -340.562924) (xy 348.064247 -340.57068) (xy 348.116542 -340.586035) (xy 348.166119 -340.608677)
			(xy 348.211969 -340.638143) (xy 348.25316 -340.673834) (xy 348.288851 -340.715025) (xy 348.318317 -340.760875)
			(xy 348.340959 -340.810452) (xy 348.356314 -340.862747) (xy 348.36407 -340.916695) (xy 348.364556 -340.943946)
			(xy 348.364079 -340.971857) (xy 348.355939 -341.027083) (xy 348.339839 -341.080534) (xy 348.316123 -341.131068)
			(xy 348.285297 -341.177608) (xy 348.26702 -341.198708) (xy 348.26067 -341.20582) (xy 348.254066 -341.223092)
			(xy 348.254066 -341.310214) (xy 348.26067 -341.327486) (xy 348.26702 -341.334598) (xy 348.285274 -341.355717)
			(xy 348.316105 -341.40225) (xy 348.339824 -341.45278) (xy 348.355926 -341.506227) (xy 348.364067 -341.56145)
			(xy 348.364556 -341.58936) (xy 348.36407 -341.616611) (xy 348.356314 -341.670559) (xy 348.340959 -341.722854)
			(xy 348.318317 -341.772431) (xy 348.288851 -341.818281) (xy 348.25316 -341.859472) (xy 348.211969 -341.895163)
			(xy 348.166119 -341.924629) (xy 348.116542 -341.947271) (xy 348.064247 -341.962626) (xy 348.010299 -341.970382)
			(xy 347.955797 -341.970382) (xy 347.901849 -341.962626) (xy 347.849554 -341.947271) (xy 347.799977 -341.924629)
			(xy 347.754127 -341.895163) (xy 347.712936 -341.859472) (xy 347.677245 -341.818281) (xy 347.647779 -341.772431)
			(xy 347.625137 -341.722854) (xy 347.609782 -341.670559) (xy 347.602026 -341.616611) (xy 347.60154 -341.58936)
			(xy 347.22054 -341.58936) (xy 347.22054 -342.161368) (xy 347.220972 -342.171437) (xy 347.228687 -342.190035)
			(xy 347.235526 -342.197436) (xy 347.58122 -342.542876) (xy 347.581728 -342.543638) (xy 347.618304 -342.578944)
			(xy 347.621989 -342.582693) (xy 347.627871 -342.591404) (xy 347.629988 -342.596216) (xy 347.66885 -342.691974)
			(xy 347.670597 -342.696544) (xy 347.672521 -342.706134) (xy 347.67266 -342.711024) (xy 347.67266 -342.821006)
			(xy 348.559372 -342.821006) (xy 348.563443 -342.765384) (xy 348.575569 -342.710947) (xy 348.595492 -342.658856)
			(xy 348.622788 -342.610221) (xy 348.656874 -342.566078) (xy 348.697023 -342.527369) (xy 348.742381 -342.494918)
			(xy 348.791981 -342.469417) (xy 348.844765 -342.45141) (xy 348.899608 -342.44128) (xy 348.955342 -342.439243)
			(xy 349.010779 -342.445343) (xy 349.064736 -342.459449) (xy 349.116065 -342.481261) (xy 349.163671 -342.510315)
			(xy 349.206539 -342.54599) (xy 349.243756 -342.587527) (xy 349.274529 -342.63404) (xy 349.298201 -342.684537)
			(xy 349.314269 -342.737944) (xy 349.322389 -342.79312) (xy 349.322898 -342.821006) (xy 349.322389 -342.848892)
			(xy 349.314269 -342.904068) (xy 349.298201 -342.957475) (xy 349.274529 -343.007972) (xy 349.243756 -343.054485)
			(xy 349.206539 -343.096022) (xy 349.163671 -343.131697) (xy 349.116065 -343.160751) (xy 349.064736 -343.182563)
			(xy 349.010779 -343.196669) (xy 348.955342 -343.202769) (xy 348.899608 -343.200732) (xy 348.844765 -343.190602)
			(xy 348.791981 -343.172595) (xy 348.742381 -343.147094) (xy 348.697023 -343.114643) (xy 348.656874 -343.075934)
			(xy 348.622788 -343.031791) (xy 348.595492 -342.983156) (xy 348.575569 -342.931065) (xy 348.563443 -342.876628)
			(xy 348.559372 -342.821006) (xy 347.67266 -342.821006) (xy 347.67266 -343.716356) (xy 347.980252 -343.716356)
			(xy 347.984323 -343.660734) (xy 347.996449 -343.606297) (xy 348.016372 -343.554206) (xy 348.043668 -343.505571)
			(xy 348.077754 -343.461428) (xy 348.117903 -343.422719) (xy 348.163261 -343.390268) (xy 348.212861 -343.364767)
			(xy 348.265645 -343.34676) (xy 348.320488 -343.33663) (xy 348.376222 -343.334593) (xy 348.431659 -343.340693)
			(xy 348.485616 -343.354799) (xy 348.536945 -343.376611) (xy 348.584551 -343.405665) (xy 348.627419 -343.44134)
			(xy 348.664636 -343.482877) (xy 348.695409 -343.52939) (xy 348.719081 -343.579887) (xy 348.735149 -343.633294)
			(xy 348.743269 -343.68847) (xy 348.743778 -343.716356) (xy 348.743269 -343.744242) (xy 348.735149 -343.799418)
			(xy 348.719081 -343.852825) (xy 348.695409 -343.903322) (xy 348.664636 -343.949835) (xy 348.627419 -343.991372)
			(xy 348.584551 -344.027047) (xy 348.536945 -344.056101) (xy 348.485616 -344.077913) (xy 348.431659 -344.092019)
			(xy 348.376222 -344.098119) (xy 348.320488 -344.096082) (xy 348.265645 -344.085952) (xy 348.212861 -344.067945)
			(xy 348.163261 -344.042444) (xy 348.117903 -344.009993) (xy 348.077754 -343.971284) (xy 348.043668 -343.927141)
			(xy 348.016372 -343.878506) (xy 347.996449 -343.826415) (xy 347.984323 -343.771978) (xy 347.980252 -343.716356)
			(xy 347.67266 -343.716356) (xy 347.67266 -344.391996) (xy 349.319088 -344.391996) (xy 349.319575 -344.364521)
			(xy 349.327467 -344.310142) (xy 349.343087 -344.25746) (xy 349.366112 -344.207567) (xy 349.396063 -344.161498)
			(xy 349.41383 -344.140536) (xy 349.419926 -344.133424) (xy 349.426276 -344.116406) (xy 349.426276 -344.030554)
			(xy 349.419926 -344.013536) (xy 349.41383 -344.006424) (xy 349.396085 -343.985446) (xy 349.36616 -343.939368)
			(xy 349.343145 -343.889477) (xy 349.327514 -343.836804) (xy 349.319591 -343.782435) (xy 349.319088 -343.754964)
			(xy 349.319574 -343.727713) (xy 349.32733 -343.673765) (xy 349.342685 -343.62147) (xy 349.365327 -343.571893)
			(xy 349.394793 -343.526043) (xy 349.430484 -343.484852) (xy 349.471675 -343.449161) (xy 349.517525 -343.419695)
			(xy 349.567102 -343.397053) (xy 349.619397 -343.381698) (xy 349.673345 -343.373942) (xy 349.727847 -343.373942)
			(xy 349.781795 -343.381698) (xy 349.83409 -343.397053) (xy 349.883667 -343.419695) (xy 349.929517 -343.449161)
			(xy 349.970708 -343.484852) (xy 350.006399 -343.526043) (xy 350.035865 -343.571893) (xy 350.058507 -343.62147)
			(xy 350.073862 -343.673765) (xy 350.081618 -343.727713) (xy 350.082104 -343.754964) (xy 350.081596 -343.782438)
			(xy 350.073709 -343.836816) (xy 350.058094 -343.889498) (xy 350.055438 -343.895254) (xy 350.323849 -343.895254)
			(xy 350.323849 -343.840746) (xy 350.331607 -343.786793) (xy 350.346964 -343.734494) (xy 350.369607 -343.684912)
			(xy 350.399077 -343.639058) (xy 350.434772 -343.597864) (xy 350.475967 -343.56217) (xy 350.521823 -343.532702)
			(xy 350.571405 -343.510059) (xy 350.623705 -343.494704) (xy 350.677658 -343.486949) (xy 350.704912 -343.486486)
			(xy 350.730147 -343.48688) (xy 350.780181 -343.493499) (xy 350.828902 -343.506673) (xy 350.875454 -343.526171)
			(xy 350.897444 -343.538556) (xy 350.907096 -343.544398) (xy 350.929194 -343.54643) (xy 351.023682 -343.512902)
			(xy 351.039684 -343.497408) (xy 351.043748 -343.486994) (xy 351.054468 -343.460228) (xy 351.082752 -343.409987)
			(xy 351.118279 -343.364577) (xy 351.160237 -343.325035) (xy 351.207671 -343.29226) (xy 351.259499 -343.267)
			(xy 351.314539 -343.249831) (xy 351.371536 -343.241145) (xy 351.400364 -343.240614) (xy 351.427617 -343.241089)
			(xy 351.481569 -343.248842) (xy 351.533868 -343.264194) (xy 351.583449 -343.286834) (xy 351.629303 -343.3163)
			(xy 351.670497 -343.351993) (xy 351.706191 -343.393185) (xy 351.735659 -343.439039) (xy 351.758301 -343.488619)
			(xy 351.773656 -343.540918) (xy 351.78141 -343.594869) (xy 351.781872 -343.622122) (xy 351.781209 -343.653685)
			(xy 351.770824 -343.71595) (xy 351.750339 -343.775659) (xy 351.735898 -343.803732) (xy 351.731072 -343.812622)
			(xy 351.72904 -343.83218) (xy 351.754694 -343.920318) (xy 351.76714 -343.935812) (xy 351.77603 -343.940892)
			(xy 351.801163 -343.955389) (xy 351.847044 -343.990902) (xy 351.887016 -344.032955) (xy 351.920157 -344.080578)
			(xy 351.945703 -344.132671) (xy 351.963063 -344.188032) (xy 351.971837 -344.245384) (xy 351.972372 -344.274394)
			(xy 351.971886 -344.301645) (xy 351.96413 -344.355593) (xy 351.948775 -344.407888) (xy 351.926133 -344.457465)
			(xy 351.896667 -344.503315) (xy 351.860976 -344.544506) (xy 351.819785 -344.580197) (xy 351.773935 -344.609663)
			(xy 351.724358 -344.632305) (xy 351.672063 -344.64766) (xy 351.618115 -344.655416) (xy 351.563613 -344.655416)
			(xy 351.509665 -344.64766) (xy 351.45737 -344.632305) (xy 351.407793 -344.609663) (xy 351.361943 -344.580197)
			(xy 351.320752 -344.544506) (xy 351.285061 -344.503315) (xy 351.255595 -344.457465) (xy 351.232953 -344.407888)
			(xy 351.217598 -344.355593) (xy 351.209842 -344.301645) (xy 351.209356 -344.274394) (xy 351.210022 -344.242831)
			(xy 351.220406 -344.180566) (xy 351.240889 -344.120857) (xy 351.25533 -344.092784) (xy 351.260156 -344.083894)
			(xy 351.262188 -344.064336) (xy 351.236534 -343.976198) (xy 351.224088 -343.960704) (xy 351.215198 -343.955624)
			(xy 351.207832 -343.95156) (xy 351.19818 -343.945718) (xy 351.176082 -343.943686) (xy 351.081594 -343.977214)
			(xy 351.065592 -343.992708) (xy 351.061528 -344.003122) (xy 351.050837 -344.0299) (xy 351.022548 -344.080142)
			(xy 350.987017 -344.125551) (xy 350.945054 -344.165093) (xy 350.897616 -344.197866) (xy 350.845785 -344.223124)
			(xy 350.790741 -344.24029) (xy 350.733741 -344.248972) (xy 350.704912 -344.249502) (xy 350.677658 -344.249051)
			(xy 350.623705 -344.241296) (xy 350.571405 -344.225941) (xy 350.521823 -344.203298) (xy 350.475967 -344.17383)
			(xy 350.434772 -344.138136) (xy 350.399077 -344.096942) (xy 350.369607 -344.051088) (xy 350.346964 -344.001506)
			(xy 350.331607 -343.949207) (xy 350.323849 -343.895254) (xy 350.055438 -343.895254) (xy 350.035074 -343.939392)
			(xy 350.005127 -343.985461) (xy 349.987362 -344.006424) (xy 349.981266 -344.013536) (xy 349.974916 -344.030554)
			(xy 349.974916 -344.116406) (xy 349.981266 -344.133424) (xy 349.987362 -344.140536) (xy 350.005133 -344.161492)
			(xy 350.035055 -344.207576) (xy 350.058065 -344.257472) (xy 350.07369 -344.31015) (xy 350.081605 -344.364523)
			(xy 350.082104 -344.391996) (xy 350.081618 -344.419247) (xy 350.073862 -344.473195) (xy 350.058507 -344.52549)
			(xy 350.035865 -344.575067) (xy 350.006399 -344.620917) (xy 349.970708 -344.662108) (xy 349.929517 -344.697799)
			(xy 349.883667 -344.727265) (xy 349.83409 -344.749907) (xy 349.781795 -344.765262) (xy 349.727847 -344.773018)
			(xy 349.673345 -344.773018) (xy 349.619397 -344.765262) (xy 349.567102 -344.749907) (xy 349.517525 -344.727265)
			(xy 349.471675 -344.697799) (xy 349.430484 -344.662108) (xy 349.394793 -344.620917) (xy 349.365327 -344.575067)
			(xy 349.342685 -344.52549) (xy 349.32733 -344.473195) (xy 349.319574 -344.419247) (xy 349.319088 -344.391996)
			(xy 347.67266 -344.391996) (xy 347.67266 -344.923618) (xy 347.672147 -344.949194) (xy 347.663607 -344.999628)
			(xy 347.646771 -345.047929) (xy 347.622109 -345.092743) (xy 347.60662 -345.113102) (xy 347.598079 -345.124479)
			(xy 347.585791 -345.150131) (xy 347.579523 -345.177874) (xy 347.579188 -345.192096) (xy 347.579689 -345.207878)
			(xy 347.587449 -345.238474) (xy 347.60247 -345.266235) (xy 347.623837 -345.289467) (xy 347.650247 -345.306754)
			(xy 347.680088 -345.317042) (xy 347.695774 -345.318842) (xy 347.738954 -345.323922) (xy 347.743023 -345.324448)
			(xy 347.750935 -345.326615) (xy 347.754702 -345.32824) (xy 347.792548 -345.345766) (xy 347.816428 -345.357573)
			(xy 347.859988 -345.388232) (xy 347.879162 -345.406726) (xy 348.145608 -345.673172) (xy 348.153092 -345.679861)
			(xy 348.171649 -345.687453) (xy 348.181676 -345.687904) (xy 352.371914 -345.687904) (xy 352.381961 -345.687541)
			(xy 352.400558 -345.67995) (xy 352.407982 -345.673172) (xy 352.676206 -345.404948) (xy 352.683018 -345.397526)
			(xy 352.690754 -345.378944) (xy 352.691192 -345.36888) (xy 352.691192 -343.290652) (xy 352.690741 -343.280586)
			(xy 352.683038 -343.261987) (xy 352.676206 -343.254584) (xy 351.884996 -342.463628) (xy 351.884488 -342.462866)
			(xy 351.847912 -342.42756) (xy 351.844229 -342.423809) (xy 351.838346 -342.415099) (xy 351.836228 -342.410288)
			(xy 351.797366 -342.31453) (xy 351.795617 -342.309961) (xy 351.793695 -342.30037) (xy 351.793556 -342.29548)
			(xy 351.793556 -340.272624) (xy 351.79369 -340.267733) (xy 351.795611 -340.258141) (xy 351.797366 -340.253574)
			(xy 351.836228 -340.157816) (xy 351.83832 -340.152991) (xy 351.844212 -340.144282) (xy 351.847912 -340.140544)
			(xy 351.884488 -340.105238) (xy 351.884996 -340.104476) (xy 351.906586 -340.082886) (xy 351.923885 -340.066241)
			(xy 351.962693 -340.037989) (xy 352.005442 -340.016155) (xy 352.051081 -340.001276) (xy 352.098485 -339.993719)
			(xy 352.122486 -339.993224) (xy 356.708964 -339.993224) (xy 356.713855 -339.993356) (xy 356.723447 -339.995278)
			(xy 356.728014 -339.997034) (xy 356.823772 -340.035896) (xy 356.828593 -340.037996) (xy 356.837304 -340.043883)
			(xy 356.841044 -340.04758) (xy 356.87635 -340.084156) (xy 356.877112 -340.084664) (xy 357.210106 -340.417912)
			(xy 357.225528 -340.433867) (xy 357.252045 -340.469446) (xy 357.262938 -340.488778) (xy 357.266494 -340.495128)
			(xy 357.274622 -340.50351) (xy 357.27752 -340.5065) (xy 357.282369 -340.513269) (xy 357.284274 -340.516972)
			(xy 357.321866 -340.593172) (xy 357.32367 -340.597035) (xy 357.326096 -340.605207) (xy 357.326692 -340.609428)
			(xy 357.331772 -340.651084) (xy 357.331772 -340.651592) (xy 357.34185 -340.725569) (xy 357.3693 -340.872342)
			(xy 357.386636 -340.944962) (xy 357.388414 -340.952582) (xy 357.391208 -340.968076) (xy 357.391462 -340.970616)
			(xy 357.395526 -341.000334) (xy 357.39578 -341.006938) (xy 357.39578 -351.6122) (xy 357.395341 -351.636197)
			(xy 357.387874 -351.683606) (xy 357.373061 -351.729256) (xy 357.351269 -351.772017) (xy 357.323039 -351.81083)
			(xy 357.306372 -351.8281) (xy 352.848418 -356.286054) (xy 352.847656 -356.286562) (xy 352.81235 -356.323138)
			(xy 352.808595 -356.326816) (xy 352.799888 -356.332703) (xy 352.795078 -356.334822) (xy 352.69932 -356.373684)
			(xy 352.69475 -356.375402) (xy 352.685152 -356.37719) (xy 352.68027 -356.37724) (xy 319.399158 -356.37724)
			(xy 319.375161 -356.376811) (xy 319.327752 -356.369338) (xy 319.282102 -356.354522) (xy 319.239342 -356.332729)
			(xy 319.200529 -356.304499) (xy 319.183258 -356.287832) (xy 319.183258 -356.287578) (xy 314.1472 -351.25152)
			(xy 314.139714 -351.244833) (xy 314.121158 -351.23724) (xy 314.111132 -351.236788) (xy 310.590184 -351.236788)
			(xy 310.566178 -351.236353) (xy 310.518763 -351.228802) (xy 310.473115 -351.213921) (xy 310.43036 -351.192077)
			(xy 310.391553 -351.163808) (xy 310.374284 -351.147126) (xy 308.989222 -349.762064) (xy 308.988714 -349.761302)
			(xy 308.952138 -349.725996) (xy 308.948465 -349.722236) (xy 308.942575 -349.713533) (xy 308.940454 -349.708724)
			(xy 308.901592 -349.612966) (xy 308.89989 -349.60839) (xy 308.898092 -349.598797) (xy 308.898036 -349.593916)
			(xy 306.352794 -349.593916) (xy 306.352956 -349.602806) (xy 306.352447 -349.630692) (xy 306.344327 -349.685868)
			(xy 306.328259 -349.739275) (xy 306.304587 -349.789772) (xy 306.273814 -349.836285) (xy 306.236597 -349.877822)
			(xy 306.193729 -349.913497) (xy 306.146123 -349.942551) (xy 306.094794 -349.964363) (xy 306.040837 -349.978469)
			(xy 305.9854 -349.984569) (xy 305.929666 -349.982532) (xy 305.874823 -349.972402) (xy 305.822039 -349.954395)
			(xy 305.772439 -349.928894) (xy 305.727081 -349.896443) (xy 305.686932 -349.857734) (xy 305.652846 -349.813591)
			(xy 305.62555 -349.764956) (xy 305.605627 -349.712865) (xy 305.593501 -349.658428) (xy 305.58943 -349.602806)
			(xy 304.6476 -349.602806) (xy 304.6476 -350.498156) (xy 305.01031 -350.498156) (xy 305.014381 -350.442534)
			(xy 305.026507 -350.388097) (xy 305.04643 -350.336006) (xy 305.073726 -350.287371) (xy 305.107812 -350.243228)
			(xy 305.147961 -350.204519) (xy 305.193319 -350.172068) (xy 305.242919 -350.146567) (xy 305.295703 -350.12856)
			(xy 305.350546 -350.11843) (xy 305.40628 -350.116393) (xy 305.461717 -350.122493) (xy 305.515674 -350.136599)
			(xy 305.567003 -350.158411) (xy 305.614609 -350.187465) (xy 305.657477 -350.22314) (xy 305.694694 -350.264677)
			(xy 305.725467 -350.31119) (xy 305.749139 -350.361687) (xy 305.765207 -350.415094) (xy 305.773327 -350.47027)
			(xy 305.773836 -350.498156) (xy 305.773327 -350.526042) (xy 305.765207 -350.581218) (xy 305.749139 -350.634625)
			(xy 305.725467 -350.685122) (xy 305.694694 -350.731635) (xy 305.657477 -350.773172) (xy 305.614609 -350.808847)
			(xy 305.567003 -350.837901) (xy 305.515674 -350.859713) (xy 305.461717 -350.873819) (xy 305.40628 -350.879919)
			(xy 305.350546 -350.877882) (xy 305.295703 -350.867752) (xy 305.242919 -350.849745) (xy 305.193319 -350.824244)
			(xy 305.147961 -350.791793) (xy 305.107812 -350.753084) (xy 305.073726 -350.708941) (xy 305.04643 -350.660306)
			(xy 305.026507 -350.608215) (xy 305.014381 -350.553778) (xy 305.01031 -350.498156) (xy 304.6476 -350.498156)
			(xy 304.6476 -351.173796) (xy 306.349146 -351.173796) (xy 306.349619 -351.146321) (xy 306.357512 -351.09194)
			(xy 306.373135 -351.039257) (xy 306.396163 -350.989365) (xy 306.426118 -350.943297) (xy 306.443888 -350.922336)
			(xy 306.449984 -350.915224) (xy 306.456334 -350.898206) (xy 306.456334 -350.812354) (xy 306.449984 -350.795336)
			(xy 306.443888 -350.788224) (xy 306.426152 -350.767239) (xy 306.396224 -350.721163) (xy 306.373206 -350.671275)
			(xy 306.357573 -350.618603) (xy 306.349649 -350.564235) (xy 306.349146 -350.536764) (xy 306.349632 -350.509513)
			(xy 306.357388 -350.455565) (xy 306.372743 -350.40327) (xy 306.395385 -350.353693) (xy 306.424851 -350.307843)
			(xy 306.460542 -350.266652) (xy 306.501733 -350.230961) (xy 306.547583 -350.201495) (xy 306.59716 -350.178853)
			(xy 306.649455 -350.163498) (xy 306.703403 -350.155742) (xy 306.757905 -350.155742) (xy 306.811853 -350.163498)
			(xy 306.864148 -350.178853) (xy 306.913725 -350.201495) (xy 306.959575 -350.230961) (xy 307.000766 -350.266652)
			(xy 307.036457 -350.307843) (xy 307.065923 -350.353693) (xy 307.088565 -350.40327) (xy 307.10392 -350.455565)
			(xy 307.111676 -350.509513) (xy 307.112162 -350.536764) (xy 307.111664 -350.564238) (xy 307.103776 -350.618618)
			(xy 307.088159 -350.6713) (xy 307.085506 -350.67705) (xy 307.353972 -350.67705) (xy 307.353972 -350.62255)
			(xy 307.361728 -350.568604) (xy 307.377081 -350.516311) (xy 307.399721 -350.466735) (xy 307.429185 -350.420885)
			(xy 307.464874 -350.379695) (xy 307.506061 -350.344003) (xy 307.551908 -350.314535) (xy 307.601482 -350.291892)
			(xy 307.653774 -350.276534) (xy 307.70772 -350.268774) (xy 307.73497 -350.268286) (xy 307.760206 -350.268654)
			(xy 307.810241 -350.275281) (xy 307.858962 -350.288463) (xy 307.905512 -350.307967) (xy 307.927502 -350.320356)
			(xy 307.937154 -350.326198) (xy 307.959252 -350.32823) (xy 308.05374 -350.294702) (xy 308.069742 -350.279208)
			(xy 308.073806 -350.268794) (xy 308.084477 -350.242007) (xy 308.112768 -350.191764) (xy 308.148301 -350.146354)
			(xy 308.190266 -350.106811) (xy 308.237707 -350.074039) (xy 308.289542 -350.048783) (xy 308.344589 -350.03162)
			(xy 308.401592 -350.022941) (xy 308.430422 -350.022414) (xy 308.457675 -350.022857) (xy 308.511625 -350.030617)
			(xy 308.563922 -350.045977) (xy 308.613501 -350.068622) (xy 308.659352 -350.098092) (xy 308.700543 -350.133788)
			(xy 308.736234 -350.174983) (xy 308.765699 -350.220838) (xy 308.788339 -350.270419) (xy 308.803692 -350.322718)
			(xy 308.811446 -350.376669) (xy 308.81193 -350.403922) (xy 308.81126 -350.435484) (xy 308.800876 -350.497749)
			(xy 308.780395 -350.557459) (xy 308.765956 -350.585532) (xy 308.76113 -350.594422) (xy 308.759098 -350.61398)
			(xy 308.784752 -350.702118) (xy 308.797198 -350.717612) (xy 308.806088 -350.722692) (xy 308.831211 -350.737205)
			(xy 308.877094 -350.772714) (xy 308.917068 -350.814763) (xy 308.950212 -350.862383) (xy 308.975759 -350.914474)
			(xy 308.99312 -350.969834) (xy 309.001895 -351.027185) (xy 309.00243 -351.056194) (xy 309.001944 -351.083445)
			(xy 308.994188 -351.137393) (xy 308.978833 -351.189688) (xy 308.956191 -351.239265) (xy 308.926725 -351.285115)
			(xy 308.891034 -351.326306) (xy 308.849843 -351.361997) (xy 308.803993 -351.391463) (xy 308.754416 -351.414105)
			(xy 308.702121 -351.42946) (xy 308.648173 -351.437216) (xy 308.593671 -351.437216) (xy 308.539723 -351.42946)
			(xy 308.487428 -351.414105) (xy 308.437851 -351.391463) (xy 308.392001 -351.361997) (xy 308.35081 -351.326306)
			(xy 308.315119 -351.285115) (xy 308.285653 -351.239265) (xy 308.263011 -351.189688) (xy 308.247656 -351.137393)
			(xy 308.2399 -351.083445) (xy 308.239414 -351.056194) (xy 308.240085 -351.024632) (xy 308.250467 -350.962367)
			(xy 308.270949 -350.902657) (xy 308.285388 -350.874584) (xy 308.290214 -350.865694) (xy 308.292246 -350.846136)
			(xy 308.266592 -350.757998) (xy 308.254146 -350.742504) (xy 308.245256 -350.737424) (xy 308.23789 -350.73336)
			(xy 308.228238 -350.727518) (xy 308.20614 -350.725486) (xy 308.111652 -350.759014) (xy 308.09565 -350.774508)
			(xy 308.091586 -350.784922) (xy 308.08093 -350.811715) (xy 308.052637 -350.861958) (xy 308.017101 -350.907368)
			(xy 307.975133 -350.94691) (xy 307.92769 -350.979681) (xy 307.875854 -351.004936) (xy 307.820805 -351.022098)
			(xy 307.763801 -351.030775) (xy 307.73497 -351.031302) (xy 307.70772 -351.030826) (xy 307.653774 -351.023066)
			(xy 307.601482 -351.007708) (xy 307.551908 -350.985065) (xy 307.506061 -350.955597) (xy 307.464874 -350.919905)
			(xy 307.429185 -350.878715) (xy 307.399721 -350.832865) (xy 307.377081 -350.783289) (xy 307.361728 -350.730996)
			(xy 307.353972 -350.67705) (xy 307.085506 -350.67705) (xy 307.065137 -350.721193) (xy 307.035187 -350.767262)
			(xy 307.01742 -350.788224) (xy 307.011324 -350.795336) (xy 307.004974 -350.812354) (xy 307.004974 -350.898206)
			(xy 307.011324 -350.915224) (xy 307.01742 -350.922336) (xy 307.035185 -350.943297) (xy 307.065109 -350.98938)
			(xy 307.088121 -351.039274) (xy 307.103747 -351.091951) (xy 307.111663 -351.146324) (xy 307.112162 -351.173796)
			(xy 307.111676 -351.201047) (xy 307.10392 -351.254995) (xy 307.088565 -351.30729) (xy 307.065923 -351.356867)
			(xy 307.036457 -351.402717) (xy 307.000766 -351.443908) (xy 306.959575 -351.479599) (xy 306.913725 -351.509065)
			(xy 306.864148 -351.531707) (xy 306.811853 -351.547062) (xy 306.757905 -351.554818) (xy 306.703403 -351.554818)
			(xy 306.649455 -351.547062) (xy 306.59716 -351.531707) (xy 306.547583 -351.509065) (xy 306.501733 -351.479599)
			(xy 306.460542 -351.443908) (xy 306.424851 -351.402717) (xy 306.395385 -351.356867) (xy 306.372743 -351.30729)
			(xy 306.357388 -351.254995) (xy 306.349632 -351.201047) (xy 306.349146 -351.173796) (xy 304.6476 -351.173796)
			(xy 304.6476 -352.933) (xy 314.527182 -352.933) (xy 314.531253 -352.877378) (xy 314.543379 -352.822941)
			(xy 314.563302 -352.77085) (xy 314.590598 -352.722215) (xy 314.624684 -352.678072) (xy 314.664833 -352.639363)
			(xy 314.710191 -352.606912) (xy 314.759791 -352.581411) (xy 314.812575 -352.563404) (xy 314.867418 -352.553274)
			(xy 314.923152 -352.551237) (xy 314.978589 -352.557337) (xy 315.032546 -352.571443) (xy 315.083875 -352.593255)
			(xy 315.131481 -352.622309) (xy 315.174349 -352.657984) (xy 315.211566 -352.699521) (xy 315.242339 -352.746034)
			(xy 315.266011 -352.796531) (xy 315.282079 -352.849938) (xy 315.290199 -352.905114) (xy 315.290708 -352.933)
			(xy 315.290199 -352.960886) (xy 315.282079 -353.016062) (xy 315.266011 -353.069469) (xy 315.242339 -353.119966)
			(xy 315.211566 -353.166479) (xy 315.174349 -353.208016) (xy 315.131481 -353.243691) (xy 315.083875 -353.272745)
			(xy 315.032546 -353.294557) (xy 314.978589 -353.308663) (xy 314.923152 -353.314763) (xy 314.867418 -353.312726)
			(xy 314.812575 -353.302596) (xy 314.759791 -353.284589) (xy 314.710191 -353.259088) (xy 314.664833 -353.226637)
			(xy 314.624684 -353.187928) (xy 314.590598 -353.143785) (xy 314.563302 -353.09515) (xy 314.543379 -353.043059)
			(xy 314.531253 -352.988622) (xy 314.527182 -352.933) (xy 304.6476 -352.933) (xy 304.6476 -353.566222)
			(xy 304.647161 -353.576193) (xy 304.639561 -353.59463) (xy 304.634934 -353.59975) (xy 307.212492 -353.59975)
			(xy 307.212978 -353.572499) (xy 307.220734 -353.518551) (xy 307.236089 -353.466256) (xy 307.258731 -353.416679)
			(xy 307.288197 -353.370829) (xy 307.323888 -353.329638) (xy 307.365079 -353.293947) (xy 307.410929 -353.264481)
			(xy 307.460506 -353.241839) (xy 307.512801 -353.226484) (xy 307.566749 -353.218728) (xy 307.621251 -353.218728)
			(xy 307.675199 -353.226484) (xy 307.727494 -353.241839) (xy 307.777071 -353.264481) (xy 307.822921 -353.293947)
			(xy 307.864112 -353.329638) (xy 307.899803 -353.370829) (xy 307.929269 -353.416679) (xy 307.951911 -353.466256)
			(xy 307.967266 -353.518551) (xy 307.975022 -353.572499) (xy 307.975168 -353.5807) (xy 309.409082 -353.5807)
			(xy 309.413153 -353.525078) (xy 309.425279 -353.470641) (xy 309.445202 -353.41855) (xy 309.472498 -353.369915)
			(xy 309.506584 -353.325772) (xy 309.546733 -353.287063) (xy 309.592091 -353.254612) (xy 309.641691 -353.229111)
			(xy 309.694475 -353.211104) (xy 309.749318 -353.200974) (xy 309.805052 -353.198937) (xy 309.860489 -353.205037)
			(xy 309.914446 -353.219143) (xy 309.965775 -353.240955) (xy 310.013381 -353.270009) (xy 310.056249 -353.305684)
			(xy 310.093466 -353.347221) (xy 310.121901 -353.3902) (xy 311.733182 -353.3902) (xy 311.737253 -353.334578)
			(xy 311.749379 -353.280141) (xy 311.769302 -353.22805) (xy 311.796598 -353.179415) (xy 311.830684 -353.135272)
			(xy 311.870833 -353.096563) (xy 311.916191 -353.064112) (xy 311.965791 -353.038611) (xy 312.018575 -353.020604)
			(xy 312.073418 -353.010474) (xy 312.129152 -353.008437) (xy 312.184589 -353.014537) (xy 312.238546 -353.028643)
			(xy 312.289875 -353.050455) (xy 312.337481 -353.079509) (xy 312.380349 -353.115184) (xy 312.417566 -353.156721)
			(xy 312.448339 -353.203234) (xy 312.472011 -353.253731) (xy 312.488079 -353.307138) (xy 312.496199 -353.362314)
			(xy 312.496244 -353.3648) (xy 313.409582 -353.3648) (xy 313.413653 -353.309178) (xy 313.425779 -353.254741)
			(xy 313.445702 -353.20265) (xy 313.472998 -353.154015) (xy 313.507084 -353.109872) (xy 313.547233 -353.071163)
			(xy 313.592591 -353.038712) (xy 313.642191 -353.013211) (xy 313.694975 -352.995204) (xy 313.749818 -352.985074)
			(xy 313.805552 -352.983037) (xy 313.860989 -352.989137) (xy 313.914946 -353.003243) (xy 313.966275 -353.025055)
			(xy 314.013881 -353.054109) (xy 314.056749 -353.089784) (xy 314.093966 -353.131321) (xy 314.124739 -353.177834)
			(xy 314.148411 -353.228331) (xy 314.164479 -353.281738) (xy 314.172599 -353.336914) (xy 314.173108 -353.3648)
			(xy 314.172599 -353.392686) (xy 314.164479 -353.447862) (xy 314.148411 -353.501269) (xy 314.124739 -353.551766)
			(xy 314.093966 -353.598279) (xy 314.056749 -353.639816) (xy 314.013881 -353.675491) (xy 313.966275 -353.704545)
			(xy 313.914946 -353.726357) (xy 313.860989 -353.740463) (xy 313.805552 -353.746563) (xy 313.749818 -353.744526)
			(xy 313.694975 -353.734396) (xy 313.642191 -353.716389) (xy 313.592591 -353.690888) (xy 313.547233 -353.658437)
			(xy 313.507084 -353.619728) (xy 313.472998 -353.575585) (xy 313.445702 -353.52695) (xy 313.425779 -353.474859)
			(xy 313.413653 -353.420422) (xy 313.409582 -353.3648) (xy 312.496244 -353.3648) (xy 312.496708 -353.3902)
			(xy 312.496199 -353.418086) (xy 312.488079 -353.473262) (xy 312.472011 -353.526669) (xy 312.448339 -353.577166)
			(xy 312.417566 -353.623679) (xy 312.380349 -353.665216) (xy 312.337481 -353.700891) (xy 312.289875 -353.729945)
			(xy 312.238546 -353.751757) (xy 312.184589 -353.765863) (xy 312.129152 -353.771963) (xy 312.073418 -353.769926)
			(xy 312.018575 -353.759796) (xy 311.965791 -353.741789) (xy 311.916191 -353.716288) (xy 311.870833 -353.683837)
			(xy 311.830684 -353.645128) (xy 311.796598 -353.600985) (xy 311.769302 -353.55235) (xy 311.749379 -353.500259)
			(xy 311.737253 -353.445822) (xy 311.733182 -353.3902) (xy 310.121901 -353.3902) (xy 310.124239 -353.393734)
			(xy 310.147911 -353.444231) (xy 310.163979 -353.497638) (xy 310.172099 -353.552814) (xy 310.172608 -353.5807)
			(xy 310.172099 -353.608586) (xy 310.163979 -353.663762) (xy 310.147911 -353.717169) (xy 310.124239 -353.767666)
			(xy 310.093466 -353.814179) (xy 310.056249 -353.855716) (xy 310.013381 -353.891391) (xy 309.965775 -353.920445)
			(xy 309.914446 -353.942257) (xy 309.888653 -353.949) (xy 310.564782 -353.949) (xy 310.568853 -353.893378)
			(xy 310.580979 -353.838941) (xy 310.600902 -353.78685) (xy 310.628198 -353.738215) (xy 310.662284 -353.694072)
			(xy 310.702433 -353.655363) (xy 310.747791 -353.622912) (xy 310.797391 -353.597411) (xy 310.850175 -353.579404)
			(xy 310.905018 -353.569274) (xy 310.960752 -353.567237) (xy 311.016189 -353.573337) (xy 311.070146 -353.587443)
			(xy 311.121475 -353.609255) (xy 311.169081 -353.638309) (xy 311.211949 -353.673984) (xy 311.249166 -353.715521)
			(xy 311.279939 -353.762034) (xy 311.303611 -353.812531) (xy 311.319679 -353.865938) (xy 311.327799 -353.921114)
			(xy 311.328308 -353.949) (xy 311.327799 -353.976886) (xy 311.319679 -354.032062) (xy 311.303611 -354.085469)
			(xy 311.279939 -354.135966) (xy 311.249166 -354.182479) (xy 311.211949 -354.224016) (xy 311.169081 -354.259691)
			(xy 311.121475 -354.288745) (xy 311.070146 -354.310557) (xy 311.016189 -354.324663) (xy 310.960752 -354.330763)
			(xy 310.905018 -354.328726) (xy 310.850175 -354.318596) (xy 310.797391 -354.300589) (xy 310.747791 -354.275088)
			(xy 310.702433 -354.242637) (xy 310.662284 -354.203928) (xy 310.628198 -354.159785) (xy 310.600902 -354.11115)
			(xy 310.580979 -354.059059) (xy 310.568853 -354.004622) (xy 310.564782 -353.949) (xy 309.888653 -353.949)
			(xy 309.860489 -353.956363) (xy 309.805052 -353.962463) (xy 309.749318 -353.960426) (xy 309.694475 -353.950296)
			(xy 309.641691 -353.932289) (xy 309.592091 -353.906788) (xy 309.546733 -353.874337) (xy 309.506584 -353.835628)
			(xy 309.472498 -353.791485) (xy 309.445202 -353.74285) (xy 309.425279 -353.690759) (xy 309.413153 -353.636322)
			(xy 309.409082 -353.5807) (xy 307.975168 -353.5807) (xy 307.975508 -353.59975) (xy 307.974903 -353.628935)
			(xy 307.966012 -353.686624) (xy 307.948445 -353.742289) (xy 307.922611 -353.794631) (xy 307.889112 -353.842432)
			(xy 307.848729 -353.884578) (xy 307.825902 -353.902772) (xy 307.815264 -353.911392) (xy 307.798733 -353.933209)
			(xy 307.788603 -353.958638) (xy 307.785606 -353.985847) (xy 307.789959 -354.012871) (xy 307.801346 -354.037763)
			(xy 307.818946 -354.058727) (xy 307.829966 -354.066856) (xy 307.851369 -354.082218) (xy 307.89017 -354.117855)
			(xy 307.923701 -354.158491) (xy 307.951324 -354.203352) (xy 307.972514 -354.251586) (xy 307.986869 -354.302276)
			(xy 307.994115 -354.354458) (xy 307.994558 -354.3808) (xy 307.994072 -354.408051) (xy 307.986316 -354.461999)
			(xy 307.980326 -354.4824) (xy 312.977782 -354.4824) (xy 312.981853 -354.426778) (xy 312.993979 -354.372341)
			(xy 313.013902 -354.32025) (xy 313.041198 -354.271615) (xy 313.075284 -354.227472) (xy 313.115433 -354.188763)
			(xy 313.160791 -354.156312) (xy 313.210391 -354.130811) (xy 313.263175 -354.112804) (xy 313.318018 -354.102674)
			(xy 313.373752 -354.100637) (xy 313.429189 -354.106737) (xy 313.483146 -354.120843) (xy 313.534475 -354.142655)
			(xy 313.582081 -354.171709) (xy 313.624949 -354.207384) (xy 313.662166 -354.248921) (xy 313.692939 -354.295434)
			(xy 313.716611 -354.345931) (xy 313.732679 -354.399338) (xy 313.740799 -354.454514) (xy 313.740844 -354.457)
			(xy 314.120782 -354.457) (xy 314.124853 -354.401378) (xy 314.136979 -354.346941) (xy 314.156902 -354.29485)
			(xy 314.184198 -354.246215) (xy 314.218284 -354.202072) (xy 314.258433 -354.163363) (xy 314.303791 -354.130912)
			(xy 314.353391 -354.105411) (xy 314.406175 -354.087404) (xy 314.461018 -354.077274) (xy 314.516752 -354.075237)
			(xy 314.572189 -354.081337) (xy 314.626146 -354.095443) (xy 314.677475 -354.117255) (xy 314.725081 -354.146309)
			(xy 314.767949 -354.181984) (xy 314.805166 -354.223521) (xy 314.835939 -354.270034) (xy 314.859611 -354.320531)
			(xy 314.875679 -354.373938) (xy 314.883799 -354.429114) (xy 314.884308 -354.457) (xy 314.883799 -354.484886)
			(xy 314.875679 -354.540062) (xy 314.859611 -354.593469) (xy 314.835939 -354.643966) (xy 314.805166 -354.690479)
			(xy 314.767949 -354.732016) (xy 314.725081 -354.767691) (xy 314.677475 -354.796745) (xy 314.626146 -354.818557)
			(xy 314.572189 -354.832663) (xy 314.516752 -354.838763) (xy 314.461018 -354.836726) (xy 314.406175 -354.826596)
			(xy 314.353391 -354.808589) (xy 314.303791 -354.783088) (xy 314.258433 -354.750637) (xy 314.218284 -354.711928)
			(xy 314.184198 -354.667785) (xy 314.156902 -354.61915) (xy 314.136979 -354.567059) (xy 314.124853 -354.512622)
			(xy 314.120782 -354.457) (xy 313.740844 -354.457) (xy 313.741308 -354.4824) (xy 313.740799 -354.510286)
			(xy 313.732679 -354.565462) (xy 313.716611 -354.618869) (xy 313.692939 -354.669366) (xy 313.662166 -354.715879)
			(xy 313.624949 -354.757416) (xy 313.582081 -354.793091) (xy 313.534475 -354.822145) (xy 313.483146 -354.843957)
			(xy 313.429189 -354.858063) (xy 313.373752 -354.864163) (xy 313.318018 -354.862126) (xy 313.263175 -354.851996)
			(xy 313.210391 -354.833989) (xy 313.160791 -354.808488) (xy 313.115433 -354.776037) (xy 313.075284 -354.737328)
			(xy 313.041198 -354.693185) (xy 313.013902 -354.64455) (xy 312.993979 -354.592459) (xy 312.981853 -354.538022)
			(xy 312.977782 -354.4824) (xy 307.980326 -354.4824) (xy 307.970961 -354.514294) (xy 307.948319 -354.563871)
			(xy 307.918853 -354.609721) (xy 307.883162 -354.650912) (xy 307.841971 -354.686603) (xy 307.796121 -354.716069)
			(xy 307.746544 -354.738711) (xy 307.694249 -354.754066) (xy 307.640301 -354.761822) (xy 307.585799 -354.761822)
			(xy 307.531851 -354.754066) (xy 307.479556 -354.738711) (xy 307.429979 -354.716069) (xy 307.384129 -354.686603)
			(xy 307.342938 -354.650912) (xy 307.307247 -354.609721) (xy 307.277781 -354.563871) (xy 307.255139 -354.514294)
			(xy 307.239784 -354.461999) (xy 307.232028 -354.408051) (xy 307.231542 -354.3808) (xy 307.232092 -354.351613)
			(xy 307.240992 -354.29392) (xy 307.258568 -354.238254) (xy 307.284413 -354.185911) (xy 307.317922 -354.138112)
			(xy 307.358316 -354.095969) (xy 307.381148 -354.077778) (xy 307.391729 -354.069096) (xy 307.408252 -354.047292)
			(xy 307.41838 -354.021877) (xy 307.421381 -353.994684) (xy 307.417041 -353.967672) (xy 307.405672 -353.942789)
			(xy 307.388092 -353.921826) (xy 307.377084 -353.913694) (xy 307.355646 -353.898378) (xy 307.316848 -353.862732)
			(xy 307.283322 -353.822087) (xy 307.255704 -353.777219) (xy 307.234519 -353.728978) (xy 307.220171 -353.678281)
			(xy 307.212932 -353.626094) (xy 307.212492 -353.59975) (xy 304.634934 -353.59975) (xy 304.632868 -353.602036)
			(xy 304.121566 -354.113338) (xy 304.114191 -354.120097) (xy 304.095744 -354.127796) (xy 304.085752 -354.128324)
			(xy 303.256442 -354.128324) (xy 303.246395 -354.128683) (xy 303.227799 -354.136279) (xy 303.220374 -354.143056)
			(xy 302.843438 -354.519992) (xy 302.836028 -354.526672) (xy 302.81759 -354.534246) (xy 302.807624 -354.534724)
			(xy 300.829472 -354.534724) (xy 300.8194 -354.535129) (xy 300.800802 -354.542863) (xy 300.793404 -354.54971)
			(xy 300.632114 -354.711) (xy 302.969166 -354.711) (xy 302.973237 -354.655378) (xy 302.985363 -354.600941)
			(xy 303.005286 -354.54885) (xy 303.032582 -354.500215) (xy 303.066668 -354.456072) (xy 303.106817 -354.417363)
			(xy 303.152175 -354.384912) (xy 303.201775 -354.359411) (xy 303.254559 -354.341404) (xy 303.309402 -354.331274)
			(xy 303.365136 -354.329237) (xy 303.420573 -354.335337) (xy 303.47453 -354.349443) (xy 303.525859 -354.371255)
			(xy 303.573465 -354.400309) (xy 303.616333 -354.435984) (xy 303.65355 -354.477521) (xy 303.684323 -354.524034)
			(xy 303.707995 -354.574531) (xy 303.724063 -354.627938) (xy 303.732183 -354.683114) (xy 303.732692 -354.711)
			(xy 303.732183 -354.738886) (xy 303.724063 -354.794062) (xy 303.707995 -354.847469) (xy 303.684323 -354.897966)
			(xy 303.65355 -354.944479) (xy 303.616333 -354.986016) (xy 303.573465 -355.021691) (xy 303.525859 -355.050745)
			(xy 303.47453 -355.072557) (xy 303.420573 -355.086663) (xy 303.365136 -355.092763) (xy 303.309402 -355.090726)
			(xy 303.254559 -355.080596) (xy 303.201775 -355.062589) (xy 303.152175 -355.037088) (xy 303.106817 -355.004637)
			(xy 303.066668 -354.965928) (xy 303.032582 -354.921785) (xy 303.005286 -354.87315) (xy 302.985363 -354.821059)
			(xy 302.973237 -354.766622) (xy 302.969166 -354.711) (xy 300.632114 -354.711) (xy 300.625283 -354.718408)
			(xy 300.617558 -354.737001) (xy 300.617128 -354.747068) (xy 300.617128 -355.3206) (xy 309.370982 -355.3206)
			(xy 309.375053 -355.264978) (xy 309.387179 -355.210541) (xy 309.407102 -355.15845) (xy 309.434398 -355.109815)
			(xy 309.468484 -355.065672) (xy 309.508633 -355.026963) (xy 309.553991 -354.994512) (xy 309.603591 -354.969011)
			(xy 309.656375 -354.951004) (xy 309.711218 -354.940874) (xy 309.766952 -354.938837) (xy 309.822389 -354.944937)
			(xy 309.876346 -354.959043) (xy 309.927675 -354.980855) (xy 309.975281 -355.009909) (xy 310.018149 -355.045584)
			(xy 310.055366 -355.087121) (xy 310.086139 -355.133634) (xy 310.109811 -355.184131) (xy 310.125879 -355.237538)
			(xy 310.133999 -355.292714) (xy 310.134508 -355.3206) (xy 310.133999 -355.348486) (xy 310.125879 -355.403662)
			(xy 310.109811 -355.457069) (xy 310.086139 -355.507566) (xy 310.055366 -355.554079) (xy 310.018149 -355.595616)
			(xy 309.975281 -355.631291) (xy 309.927675 -355.660345) (xy 309.876346 -355.682157) (xy 309.822389 -355.696263)
			(xy 309.766952 -355.702363) (xy 309.711218 -355.700326) (xy 309.656375 -355.690196) (xy 309.603591 -355.672189)
			(xy 309.553991 -355.646688) (xy 309.508633 -355.614237) (xy 309.468484 -355.575528) (xy 309.434398 -355.531385)
			(xy 309.407102 -355.48275) (xy 309.387179 -355.430659) (xy 309.375053 -355.376222) (xy 309.370982 -355.3206)
			(xy 300.617128 -355.3206) (xy 300.617128 -355.854) (xy 302.893982 -355.854) (xy 302.898053 -355.798378)
			(xy 302.910179 -355.743941) (xy 302.930102 -355.69185) (xy 302.957398 -355.643215) (xy 302.991484 -355.599072)
			(xy 303.031633 -355.560363) (xy 303.076991 -355.527912) (xy 303.126591 -355.502411) (xy 303.179375 -355.484404)
			(xy 303.234218 -355.474274) (xy 303.289952 -355.472237) (xy 303.345389 -355.478337) (xy 303.399346 -355.492443)
			(xy 303.450675 -355.514255) (xy 303.498281 -355.543309) (xy 303.541149 -355.578984) (xy 303.578366 -355.620521)
			(xy 303.609139 -355.667034) (xy 303.632811 -355.717531) (xy 303.648879 -355.770938) (xy 303.656999 -355.826114)
			(xy 303.657508 -355.854) (xy 303.656999 -355.881886) (xy 303.648879 -355.937062) (xy 303.632811 -355.990469)
			(xy 303.609139 -356.040966) (xy 303.578366 -356.087479) (xy 303.541149 -356.129016) (xy 303.498281 -356.164691)
			(xy 303.450675 -356.193745) (xy 303.399346 -356.215557) (xy 303.345389 -356.229663) (xy 303.289952 -356.235763)
			(xy 303.234218 -356.233726) (xy 303.179375 -356.223596) (xy 303.126591 -356.205589) (xy 303.076991 -356.180088)
			(xy 303.031633 -356.147637) (xy 302.991484 -356.108928) (xy 302.957398 -356.064785) (xy 302.930102 -356.01615)
			(xy 302.910179 -355.964059) (xy 302.898053 -355.909622) (xy 302.893982 -355.854) (xy 300.617128 -355.854)
			(xy 300.617128 -356.997) (xy 302.986946 -356.997) (xy 302.991017 -356.941378) (xy 303.003143 -356.886941)
			(xy 303.023066 -356.83485) (xy 303.050362 -356.786215) (xy 303.084448 -356.742072) (xy 303.124597 -356.703363)
			(xy 303.169955 -356.670912) (xy 303.219555 -356.645411) (xy 303.272339 -356.627404) (xy 303.327182 -356.617274)
			(xy 303.382916 -356.615237) (xy 303.438353 -356.621337) (xy 303.49231 -356.635443) (xy 303.543639 -356.657255)
			(xy 303.591245 -356.686309) (xy 303.634113 -356.721984) (xy 303.652943 -356.743) (xy 311.276492 -356.743)
			(xy 311.276951 -356.715741) (xy 311.284719 -356.66178) (xy 311.300083 -356.609473) (xy 311.32273 -356.559882)
			(xy 311.352201 -356.514016) (xy 311.387896 -356.472809) (xy 311.429088 -356.437097) (xy 311.451752 -356.421944)
			(xy 311.46368 -356.413664) (xy 311.482686 -356.391729) (xy 311.494742 -356.365328) (xy 311.498873 -356.3366)
			(xy 311.494742 -356.307872) (xy 311.482686 -356.281471) (xy 311.46368 -356.259536) (xy 311.451752 -356.251256)
			(xy 311.429108 -356.236075) (xy 311.387909 -356.200374) (xy 311.352211 -356.159174) (xy 311.322739 -356.113312)
			(xy 311.300094 -356.063724) (xy 311.284736 -356.011417) (xy 311.276978 -355.957457) (xy 311.276492 -355.9302)
			(xy 311.276978 -355.902949) (xy 311.284734 -355.849001) (xy 311.300089 -355.796706) (xy 311.322731 -355.747129)
			(xy 311.352197 -355.701279) (xy 311.387888 -355.660088) (xy 311.429079 -355.624397) (xy 311.474929 -355.594931)
			(xy 311.524506 -355.572289) (xy 311.576801 -355.556934) (xy 311.630749 -355.549178) (xy 311.685251 -355.549178)
			(xy 311.739199 -355.556934) (xy 311.791494 -355.572289) (xy 311.841071 -355.594931) (xy 311.886921 -355.624397)
			(xy 311.928112 -355.660088) (xy 311.963803 -355.701279) (xy 311.993269 -355.747129) (xy 312.015911 -355.796706)
			(xy 312.025276 -355.8286) (xy 314.196982 -355.8286) (xy 314.201053 -355.772978) (xy 314.213179 -355.718541)
			(xy 314.233102 -355.66645) (xy 314.260398 -355.617815) (xy 314.294484 -355.573672) (xy 314.334633 -355.534963)
			(xy 314.379991 -355.502512) (xy 314.429591 -355.477011) (xy 314.482375 -355.459004) (xy 314.537218 -355.448874)
			(xy 314.592952 -355.446837) (xy 314.648389 -355.452937) (xy 314.702346 -355.467043) (xy 314.753675 -355.488855)
			(xy 314.801281 -355.517909) (xy 314.844149 -355.553584) (xy 314.881366 -355.595121) (xy 314.912139 -355.641634)
			(xy 314.935811 -355.692131) (xy 314.951879 -355.745538) (xy 314.959999 -355.800714) (xy 314.960508 -355.8286)
			(xy 314.959999 -355.856486) (xy 314.951879 -355.911662) (xy 314.935811 -355.965069) (xy 314.912139 -356.015566)
			(xy 314.881366 -356.062079) (xy 314.844149 -356.103616) (xy 314.801281 -356.139291) (xy 314.753675 -356.168345)
			(xy 314.702346 -356.190157) (xy 314.648389 -356.204263) (xy 314.592952 -356.210363) (xy 314.537218 -356.208326)
			(xy 314.482375 -356.198196) (xy 314.429591 -356.180189) (xy 314.379991 -356.154688) (xy 314.334633 -356.122237)
			(xy 314.294484 -356.083528) (xy 314.260398 -356.039385) (xy 314.233102 -355.99075) (xy 314.213179 -355.938659)
			(xy 314.201053 -355.884222) (xy 314.196982 -355.8286) (xy 312.025276 -355.8286) (xy 312.031266 -355.849001)
			(xy 312.039022 -355.902949) (xy 312.039508 -355.9302) (xy 312.039049 -355.957459) (xy 312.031281 -356.01142)
			(xy 312.015917 -356.063727) (xy 311.99327 -356.113318) (xy 311.963799 -356.159184) (xy 311.928104 -356.200391)
			(xy 311.886912 -356.236103) (xy 311.864248 -356.251256) (xy 311.85232 -356.259536) (xy 311.833314 -356.281471)
			(xy 311.821258 -356.307872) (xy 311.817127 -356.3366) (xy 311.821258 -356.365328) (xy 311.833314 -356.391729)
			(xy 311.85232 -356.413664) (xy 311.864248 -356.421944) (xy 311.886892 -356.437125) (xy 311.928091 -356.472826)
			(xy 311.963789 -356.514026) (xy 311.993261 -356.559888) (xy 312.015906 -356.609476) (xy 312.031264 -356.661783)
			(xy 312.039022 -356.715743) (xy 312.039055 -356.7176) (xy 313.282582 -356.7176) (xy 313.286653 -356.661978)
			(xy 313.298779 -356.607541) (xy 313.318702 -356.55545) (xy 313.345998 -356.506815) (xy 313.380084 -356.462672)
			(xy 313.420233 -356.423963) (xy 313.465591 -356.391512) (xy 313.515191 -356.366011) (xy 313.567975 -356.348004)
			(xy 313.622818 -356.337874) (xy 313.678552 -356.335837) (xy 313.733989 -356.341937) (xy 313.787946 -356.356043)
			(xy 313.839275 -356.377855) (xy 313.886881 -356.406909) (xy 313.929749 -356.442584) (xy 313.966966 -356.484121)
			(xy 313.970194 -356.489) (xy 315.670182 -356.489) (xy 315.674253 -356.433378) (xy 315.686379 -356.378941)
			(xy 315.706302 -356.32685) (xy 315.733598 -356.278215) (xy 315.767684 -356.234072) (xy 315.807833 -356.195363)
			(xy 315.853191 -356.162912) (xy 315.902791 -356.137411) (xy 315.955575 -356.119404) (xy 316.010418 -356.109274)
			(xy 316.066152 -356.107237) (xy 316.121589 -356.113337) (xy 316.175546 -356.127443) (xy 316.226875 -356.149255)
			(xy 316.274481 -356.178309) (xy 316.317349 -356.213984) (xy 316.354566 -356.255521) (xy 316.385339 -356.302034)
			(xy 316.409011 -356.352531) (xy 316.425079 -356.405938) (xy 316.433199 -356.461114) (xy 316.43336 -356.46995)
			(xy 317.016382 -356.46995) (xy 317.020453 -356.414328) (xy 317.032579 -356.359891) (xy 317.052502 -356.3078)
			(xy 317.079798 -356.259165) (xy 317.113884 -356.215022) (xy 317.154033 -356.176313) (xy 317.199391 -356.143862)
			(xy 317.248991 -356.118361) (xy 317.301775 -356.100354) (xy 317.356618 -356.090224) (xy 317.412352 -356.088187)
			(xy 317.467789 -356.094287) (xy 317.521746 -356.108393) (xy 317.573075 -356.130205) (xy 317.620681 -356.159259)
			(xy 317.663549 -356.194934) (xy 317.700766 -356.236471) (xy 317.731539 -356.282984) (xy 317.755211 -356.333481)
			(xy 317.771279 -356.386888) (xy 317.779399 -356.442064) (xy 317.779908 -356.46995) (xy 317.779399 -356.497836)
			(xy 317.771279 -356.553012) (xy 317.755211 -356.606419) (xy 317.731539 -356.656916) (xy 317.700766 -356.703429)
			(xy 317.663549 -356.744966) (xy 317.620681 -356.780641) (xy 317.573075 -356.809695) (xy 317.521746 -356.831507)
			(xy 317.467789 -356.845613) (xy 317.412352 -356.851713) (xy 317.356618 -356.849676) (xy 317.301775 -356.839546)
			(xy 317.248991 -356.821539) (xy 317.199391 -356.796038) (xy 317.154033 -356.763587) (xy 317.113884 -356.724878)
			(xy 317.079798 -356.680735) (xy 317.052502 -356.6321) (xy 317.032579 -356.580009) (xy 317.020453 -356.525572)
			(xy 317.016382 -356.46995) (xy 316.43336 -356.46995) (xy 316.433708 -356.489) (xy 316.433199 -356.516886)
			(xy 316.425079 -356.572062) (xy 316.409011 -356.625469) (xy 316.385339 -356.675966) (xy 316.354566 -356.722479)
			(xy 316.317349 -356.764016) (xy 316.274481 -356.799691) (xy 316.226875 -356.828745) (xy 316.175546 -356.850557)
			(xy 316.121589 -356.864663) (xy 316.066152 -356.870763) (xy 316.010418 -356.868726) (xy 315.955575 -356.858596)
			(xy 315.902791 -356.840589) (xy 315.853191 -356.815088) (xy 315.807833 -356.782637) (xy 315.767684 -356.743928)
			(xy 315.733598 -356.699785) (xy 315.706302 -356.65115) (xy 315.686379 -356.599059) (xy 315.674253 -356.544622)
			(xy 315.670182 -356.489) (xy 313.970194 -356.489) (xy 313.997739 -356.530634) (xy 314.021411 -356.581131)
			(xy 314.037479 -356.634538) (xy 314.045599 -356.689714) (xy 314.046108 -356.7176) (xy 314.045599 -356.745486)
			(xy 314.037479 -356.800662) (xy 314.021411 -356.854069) (xy 313.997739 -356.904566) (xy 313.966966 -356.951079)
			(xy 313.929749 -356.992616) (xy 313.886881 -357.028291) (xy 313.839275 -357.057345) (xy 313.787946 -357.079157)
			(xy 313.733989 -357.093263) (xy 313.678552 -357.099363) (xy 313.622818 -357.097326) (xy 313.567975 -357.087196)
			(xy 313.515191 -357.069189) (xy 313.465591 -357.043688) (xy 313.420233 -357.011237) (xy 313.380084 -356.972528)
			(xy 313.345998 -356.928385) (xy 313.318702 -356.87975) (xy 313.298779 -356.827659) (xy 313.286653 -356.773222)
			(xy 313.282582 -356.7176) (xy 312.039055 -356.7176) (xy 312.039508 -356.743) (xy 312.039022 -356.770251)
			(xy 312.031266 -356.824199) (xy 312.015911 -356.876494) (xy 311.993269 -356.926071) (xy 311.963803 -356.971921)
			(xy 311.928112 -357.013112) (xy 311.886921 -357.048803) (xy 311.841071 -357.078269) (xy 311.791494 -357.100911)
			(xy 311.739199 -357.116266) (xy 311.685251 -357.124022) (xy 311.630749 -357.124022) (xy 311.576801 -357.116266)
			(xy 311.524506 -357.100911) (xy 311.474929 -357.078269) (xy 311.429079 -357.048803) (xy 311.387888 -357.013112)
			(xy 311.352197 -356.971921) (xy 311.322731 -356.926071) (xy 311.300089 -356.876494) (xy 311.284734 -356.824199)
			(xy 311.276978 -356.770251) (xy 311.276492 -356.743) (xy 303.652943 -356.743) (xy 303.67133 -356.763521)
			(xy 303.702103 -356.810034) (xy 303.725775 -356.860531) (xy 303.741843 -356.913938) (xy 303.749963 -356.969114)
			(xy 303.750472 -356.997) (xy 303.749963 -357.024886) (xy 303.741843 -357.080062) (xy 303.725775 -357.133469)
			(xy 303.702103 -357.183966) (xy 303.67133 -357.230479) (xy 303.634113 -357.272016) (xy 303.591245 -357.307691)
			(xy 303.543639 -357.336745) (xy 303.49231 -357.358557) (xy 303.438353 -357.372663) (xy 303.382916 -357.378763)
			(xy 303.327182 -357.376726) (xy 303.272339 -357.366596) (xy 303.219555 -357.348589) (xy 303.169955 -357.323088)
			(xy 303.124597 -357.290637) (xy 303.084448 -357.251928) (xy 303.050362 -357.207785) (xy 303.023066 -357.15915)
			(xy 303.003143 -357.107059) (xy 302.991017 -357.052622) (xy 302.986946 -356.997) (xy 300.617128 -356.997)
			(xy 300.617128 -357.493062) (xy 305.065174 -357.493062) (xy 305.069245 -357.43744) (xy 305.081371 -357.383003)
			(xy 305.101294 -357.330912) (xy 305.12859 -357.282277) (xy 305.162676 -357.238134) (xy 305.202825 -357.199425)
			(xy 305.248183 -357.166974) (xy 305.297783 -357.141473) (xy 305.350567 -357.123466) (xy 305.40541 -357.113336)
			(xy 305.461144 -357.111299) (xy 305.516581 -357.117399) (xy 305.570538 -357.131505) (xy 305.621867 -357.153317)
			(xy 305.669473 -357.182371) (xy 305.712341 -357.218046) (xy 305.749558 -357.259583) (xy 305.780331 -357.306096)
			(xy 305.804003 -357.356593) (xy 305.820071 -357.41) (xy 305.828191 -357.465176) (xy 305.8287 -357.493062)
			(xy 305.828191 -357.520948) (xy 305.820071 -357.576124) (xy 305.804003 -357.629531) (xy 305.780331 -357.680028)
			(xy 305.749558 -357.726541) (xy 305.712341 -357.768078) (xy 305.669473 -357.803753) (xy 305.621867 -357.832807)
			(xy 305.570538 -357.854619) (xy 305.516581 -357.868725) (xy 305.461144 -357.874825) (xy 305.40541 -357.872788)
			(xy 305.350567 -357.862658) (xy 305.297783 -357.844651) (xy 305.248183 -357.81915) (xy 305.202825 -357.786699)
			(xy 305.162676 -357.74799) (xy 305.12859 -357.703847) (xy 305.101294 -357.655212) (xy 305.081371 -357.603121)
			(xy 305.069245 -357.548684) (xy 305.065174 -357.493062) (xy 300.617128 -357.493062) (xy 300.617128 -358.14)
			(xy 302.875948 -358.14) (xy 302.880019 -358.084378) (xy 302.892145 -358.029941) (xy 302.912068 -357.97785)
			(xy 302.939364 -357.929215) (xy 302.97345 -357.885072) (xy 303.013599 -357.846363) (xy 303.058957 -357.813912)
			(xy 303.108557 -357.788411) (xy 303.161341 -357.770404) (xy 303.216184 -357.760274) (xy 303.271918 -357.758237)
			(xy 303.327355 -357.764337) (xy 303.381312 -357.778443) (xy 303.432641 -357.800255) (xy 303.480247 -357.829309)
			(xy 303.523115 -357.864984) (xy 303.560332 -357.906521) (xy 303.591105 -357.953034) (xy 303.614777 -358.003531)
			(xy 303.630845 -358.056938) (xy 303.638965 -358.112114) (xy 303.639474 -358.14) (xy 303.638965 -358.167886)
			(xy 303.630845 -358.223062) (xy 303.614777 -358.276469) (xy 303.591105 -358.326966) (xy 303.560332 -358.373479)
			(xy 303.523115 -358.415016) (xy 303.480247 -358.450691) (xy 303.432641 -358.479745) (xy 303.381312 -358.501557)
			(xy 303.327355 -358.515663) (xy 303.271918 -358.521763) (xy 303.216184 -358.519726) (xy 303.161341 -358.509596)
			(xy 303.108557 -358.491589) (xy 303.058957 -358.466088) (xy 303.013599 -358.433637) (xy 302.97345 -358.394928)
			(xy 302.939364 -358.350785) (xy 302.912068 -358.30215) (xy 302.892145 -358.250059) (xy 302.880019 -358.195622)
			(xy 302.875948 -358.14) (xy 300.617128 -358.14) (xy 300.617128 -358.763316) (xy 305.14366 -358.763316)
			(xy 305.147731 -358.707694) (xy 305.159857 -358.653257) (xy 305.17978 -358.601166) (xy 305.207076 -358.552531)
			(xy 305.241162 -358.508388) (xy 305.281311 -358.469679) (xy 305.326669 -358.437228) (xy 305.376269 -358.411727)
			(xy 305.429053 -358.39372) (xy 305.483896 -358.38359) (xy 305.53963 -358.381553) (xy 305.595067 -358.387653)
			(xy 305.649024 -358.401759) (xy 305.700353 -358.423571) (xy 305.747959 -358.452625) (xy 305.790827 -358.4883)
			(xy 305.828044 -358.529837) (xy 305.858817 -358.57635) (xy 305.882489 -358.626847) (xy 305.898557 -358.680254)
			(xy 305.906677 -358.73543) (xy 305.907186 -358.763316) (xy 305.906677 -358.791202) (xy 305.898557 -358.846378)
			(xy 305.882489 -358.899785) (xy 305.858817 -358.950282) (xy 305.828044 -358.996795) (xy 305.799188 -359.029)
			(xy 317.905382 -359.029) (xy 317.909453 -358.973378) (xy 317.921579 -358.918941) (xy 317.941502 -358.86685)
			(xy 317.968798 -358.818215) (xy 318.002884 -358.774072) (xy 318.043033 -358.735363) (xy 318.088391 -358.702912)
			(xy 318.137991 -358.677411) (xy 318.190775 -358.659404) (xy 318.245618 -358.649274) (xy 318.301352 -358.647237)
			(xy 318.356789 -358.653337) (xy 318.410746 -358.667443) (xy 318.462075 -358.689255) (xy 318.509681 -358.718309)
			(xy 318.552549 -358.753984) (xy 318.589766 -358.795521) (xy 318.620539 -358.842034) (xy 318.644211 -358.892531)
			(xy 318.660279 -358.945938) (xy 318.668399 -359.001114) (xy 318.668908 -359.029) (xy 318.668399 -359.056886)
			(xy 318.661737 -359.102152) (xy 335.533238 -359.102152) (xy 335.533763 -359.074042) (xy 335.542002 -359.018429)
			(xy 335.558308 -358.964625) (xy 335.582329 -358.913795) (xy 335.613546 -358.867038) (xy 335.632044 -358.845866)
			(xy 335.638648 -358.838754) (xy 335.645252 -358.82199) (xy 335.646522 -358.736138) (xy 335.640426 -358.71912)
			(xy 335.63433 -358.711754) (xy 335.61724 -358.690976) (xy 335.58848 -358.645509) (xy 335.566395 -358.596451)
			(xy 335.551422 -358.544777) (xy 335.54386 -358.491512) (xy 335.543398 -358.464612) (xy 335.543867 -358.437359)
			(xy 335.551622 -358.383408) (xy 335.566977 -358.33111) (xy 335.589618 -358.28153) (xy 335.619086 -358.235676)
			(xy 335.654779 -358.194483) (xy 335.695971 -358.158789) (xy 335.741824 -358.129321) (xy 335.791404 -358.106679)
			(xy 335.843702 -358.091323) (xy 335.897653 -358.083567) (xy 335.924906 -358.083104) (xy 335.953823 -358.083617)
			(xy 336.010995 -358.092347) (xy 336.066194 -358.109606) (xy 336.118155 -358.134998) (xy 336.165689 -358.167943)
			(xy 336.207706 -358.207684) (xy 336.225896 -358.23017) (xy 336.233452 -358.238937) (xy 336.254216 -358.249115)
			(xy 336.265774 -358.249728) (xy 336.346038 -358.249728) (xy 336.357605 -358.249147) (xy 336.378378 -358.238962)
			(xy 336.385916 -358.23017) (xy 336.402669 -358.209387) (xy 336.441023 -358.172257) (xy 336.484177 -358.140835)
			(xy 336.531291 -358.115736) (xy 336.581443 -358.09745) (xy 336.633654 -358.086333) (xy 336.686906 -358.082603)
			(xy 336.740158 -358.086333) (xy 336.792369 -358.09745) (xy 336.842521 -358.115736) (xy 336.889635 -358.140835)
			(xy 336.932789 -358.172257) (xy 336.971143 -358.209387) (xy 336.987896 -358.23017) (xy 336.995452 -358.238937)
			(xy 337.016216 -358.249115) (xy 337.027774 -358.249728) (xy 337.108038 -358.249728) (xy 337.119605 -358.249147)
			(xy 337.140378 -358.238962) (xy 337.147916 -358.23017) (xy 337.16609 -358.207673) (xy 337.208115 -358.16794)
			(xy 337.255653 -358.135003) (xy 337.307618 -358.109617) (xy 337.362818 -358.092364) (xy 337.419989 -358.083638)
			(xy 337.448906 -358.083104) (xy 337.477834 -358.083626) (xy 337.535025 -358.092383) (xy 337.590236 -358.109678)
			(xy 337.642201 -358.135116) (xy 337.689727 -358.168113) (xy 337.731722 -358.207911) (xy 337.749896 -358.230424)
			(xy 337.757262 -358.239568) (xy 337.777582 -358.249728) (xy 337.880452 -358.251252) (xy 337.90128 -358.2416)
			(xy 337.908646 -358.232456) (xy 337.915758 -358.224074) (xy 337.921854 -358.216962) (xy 337.928204 -358.199944)
			(xy 337.928204 -358.1146) (xy 337.921854 -358.097582) (xy 337.915758 -358.09047) (xy 337.898131 -358.069528)
			(xy 337.868419 -358.023557) (xy 337.845581 -357.973812) (xy 337.830087 -357.921314) (xy 337.822254 -357.86714)
			(xy 337.821778 -357.839772) (xy 337.822252 -357.812521) (xy 337.830012 -357.758573) (xy 337.84537 -357.706279)
			(xy 337.868013 -357.656703) (xy 337.897481 -357.610853) (xy 337.933174 -357.569664) (xy 337.974364 -357.533973)
			(xy 338.020215 -357.504506) (xy 338.069792 -357.481865) (xy 338.122087 -357.466509) (xy 338.176035 -357.458751)
			(xy 338.203286 -357.458264) (xy 338.232204 -357.458768) (xy 338.289377 -357.467497) (xy 338.344577 -357.484756)
			(xy 338.396539 -357.51015) (xy 338.444072 -357.543097) (xy 338.486087 -357.582842) (xy 338.504276 -357.60533)
			(xy 338.511847 -357.614082) (xy 338.532599 -357.62427) (xy 338.544154 -357.624888) (xy 338.624418 -357.624888)
			(xy 338.635988 -357.624332) (xy 338.656759 -357.614128) (xy 338.664296 -357.60533) (xy 338.681049 -357.584547)
			(xy 338.719403 -357.547417) (xy 338.762557 -357.515995) (xy 338.809671 -357.490896) (xy 338.859823 -357.47261)
			(xy 338.912034 -357.461493) (xy 338.965286 -357.457763) (xy 339.018538 -357.461493) (xy 339.070749 -357.47261)
			(xy 339.120901 -357.490896) (xy 339.168015 -357.515995) (xy 339.211169 -357.547417) (xy 339.249523 -357.584547)
			(xy 339.266276 -357.60533) (xy 339.273847 -357.614082) (xy 339.294599 -357.62427) (xy 339.306154 -357.624888)
			(xy 339.386418 -357.624888) (xy 339.397988 -357.624332) (xy 339.418759 -357.614128) (xy 339.426296 -357.60533)
			(xy 339.444497 -357.582855) (xy 339.486514 -357.543118) (xy 339.534046 -357.510177) (xy 339.586006 -357.484787)
			(xy 339.641202 -357.467529) (xy 339.69837 -357.458799) (xy 339.727286 -357.458264) (xy 339.754536 -357.458791)
			(xy 339.80848 -357.466545) (xy 339.860773 -357.481897) (xy 339.910348 -357.504534) (xy 339.956197 -357.533997)
			(xy 339.997386 -357.569684) (xy 340.033078 -357.610869) (xy 340.062545 -357.656715) (xy 340.085188 -357.706288)
			(xy 340.100546 -357.758579) (xy 340.108306 -357.812522) (xy 340.108794 -357.839772) (xy 340.108313 -357.867142)
			(xy 340.100499 -357.92132) (xy 340.085013 -357.973823) (xy 340.062175 -358.02357) (xy 340.032454 -358.069538)
			(xy 340.030165 -358.072254) (xy 340.314959 -358.072254) (xy 340.314959 -358.017746) (xy 340.322717 -357.963791)
			(xy 340.338075 -357.911491) (xy 340.360721 -357.861908) (xy 340.390192 -357.816054) (xy 340.42589 -357.77486)
			(xy 340.467087 -357.739167) (xy 340.512945 -357.709701) (xy 340.56253 -357.687061) (xy 340.614833 -357.671708)
			(xy 340.668787 -357.663956) (xy 340.696042 -357.663496) (xy 340.723411 -357.663997) (xy 340.777589 -357.671807)
			(xy 340.830091 -357.687288) (xy 340.879839 -357.710121) (xy 340.925807 -357.739838) (xy 340.94674 -357.757476)
			(xy 340.953852 -357.763572) (xy 340.97087 -357.769922) (xy 341.056214 -357.769922) (xy 341.073232 -357.763572)
			(xy 341.080344 -357.757476) (xy 341.101277 -357.739835) (xy 341.147245 -357.710111) (xy 341.196991 -357.687265)
			(xy 341.249493 -357.671769) (xy 341.303671 -357.66394) (xy 341.358413 -357.66394) (xy 341.412591 -357.671769)
			(xy 341.465093 -357.687265) (xy 341.514839 -357.710111) (xy 341.560807 -357.739835) (xy 341.58174 -357.757476)
			(xy 341.588852 -357.763572) (xy 341.60587 -357.769922) (xy 341.691214 -357.769922) (xy 341.708232 -357.763572)
			(xy 341.715344 -357.757476) (xy 341.736277 -357.739835) (xy 341.782245 -357.710111) (xy 341.831991 -357.687265)
			(xy 341.884493 -357.671769) (xy 341.938671 -357.66394) (xy 341.993413 -357.66394) (xy 342.047591 -357.671769)
			(xy 342.100093 -357.687265) (xy 342.149839 -357.710111) (xy 342.195807 -357.739835) (xy 342.21674 -357.757476)
			(xy 342.223852 -357.763572) (xy 342.24087 -357.769922) (xy 342.326214 -357.769922) (xy 342.343232 -357.763572)
			(xy 342.350344 -357.757476) (xy 342.371283 -357.739846) (xy 342.417254 -357.710134) (xy 342.467 -357.687296)
			(xy 342.519499 -357.671803) (xy 342.573673 -357.663972) (xy 342.601042 -357.663496) (xy 342.628292 -357.663977)
			(xy 342.682235 -357.671738) (xy 342.734526 -357.687097) (xy 342.784098 -357.709741) (xy 342.829944 -357.739209)
			(xy 342.871129 -357.7749) (xy 342.906817 -357.81609) (xy 342.936279 -357.861939) (xy 342.958918 -357.911514)
			(xy 342.974271 -357.963806) (xy 342.982026 -358.01775) (xy 342.982026 -358.07225) (xy 342.974271 -358.126194)
			(xy 342.958918 -358.178486) (xy 342.936279 -358.228061) (xy 342.906817 -358.27391) (xy 342.871129 -358.3151)
			(xy 342.829944 -358.350791) (xy 342.784098 -358.380259) (xy 342.734526 -358.402903) (xy 342.682235 -358.418262)
			(xy 342.628292 -358.426023) (xy 342.601042 -358.426512) (xy 342.573673 -358.426018) (xy 342.519495 -358.418207)
			(xy 342.466992 -358.402724) (xy 342.417245 -358.379888) (xy 342.371277 -358.35017) (xy 342.350344 -358.332532)
			(xy 342.343232 -358.326436) (xy 342.326214 -358.320086) (xy 342.24087 -358.320086) (xy 342.223852 -358.326436)
			(xy 342.21674 -358.332532) (xy 342.195807 -358.350173) (xy 342.149839 -358.379897) (xy 342.100093 -358.402743)
			(xy 342.047591 -358.418239) (xy 341.993413 -358.426068) (xy 341.938671 -358.426068) (xy 341.884493 -358.418239)
			(xy 341.831991 -358.402743) (xy 341.782245 -358.379897) (xy 341.736277 -358.350173) (xy 341.715344 -358.332532)
			(xy 341.708232 -358.326436) (xy 341.691214 -358.320086) (xy 341.60587 -358.320086) (xy 341.588852 -358.326436)
			(xy 341.58174 -358.332532) (xy 341.560807 -358.350173) (xy 341.514839 -358.379897) (xy 341.465093 -358.402743)
			(xy 341.412591 -358.418239) (xy 341.358413 -358.426068) (xy 341.303671 -358.426068) (xy 341.249493 -358.418239)
			(xy 341.196991 -358.402743) (xy 341.147245 -358.379897) (xy 341.101277 -358.350173) (xy 341.080344 -358.332532)
			(xy 341.073232 -358.326436) (xy 341.056214 -358.320086) (xy 340.97087 -358.320086) (xy 340.953852 -358.326436)
			(xy 340.94674 -358.332532) (xy 340.925808 -358.350171) (xy 340.879835 -358.379882) (xy 340.830087 -358.402717)
			(xy 340.777587 -358.418208) (xy 340.723411 -358.426037) (xy 340.696042 -358.426512) (xy 340.668787 -358.426044)
			(xy 340.614833 -358.418292) (xy 340.56253 -358.402939) (xy 340.512945 -358.380299) (xy 340.467087 -358.350833)
			(xy 340.42589 -358.31514) (xy 340.390192 -358.273946) (xy 340.360721 -358.228092) (xy 340.338075 -358.178509)
			(xy 340.322717 -358.126209) (xy 340.314959 -358.072254) (xy 340.030165 -358.072254) (xy 340.014814 -358.09047)
			(xy 340.008718 -358.097582) (xy 340.002368 -358.1146) (xy 340.002368 -358.199944) (xy 340.008718 -358.216962)
			(xy 340.014814 -358.224074) (xy 340.032457 -358.245003) (xy 340.062167 -358.290977) (xy 340.085002 -358.340725)
			(xy 340.100493 -358.393227) (xy 340.10832 -358.447403) (xy 340.108794 -358.474772) (xy 340.1083 -358.502884)
			(xy 340.100057 -358.558499) (xy 340.083744 -358.612304) (xy 340.059716 -358.663133) (xy 340.02849 -358.709888)
			(xy 340.009988 -358.731058) (xy 340.003384 -358.73817) (xy 339.99678 -358.754934) (xy 339.99551 -358.840786)
			(xy 340.001606 -358.857804) (xy 340.007702 -358.86517) (xy 340.024793 -358.885948) (xy 340.053555 -358.931414)
			(xy 340.075641 -358.980471) (xy 340.090613 -359.032146) (xy 340.098173 -359.085412) (xy 340.098634 -359.112312)
			(xy 340.098109 -359.141265) (xy 340.089351 -359.198505) (xy 340.072036 -359.253762) (xy 340.046565 -359.305765)
			(xy 340.013522 -359.353319) (xy 339.993986 -359.374694) (xy 339.987128 -359.38206) (xy 339.980016 -359.400348)
			(xy 339.981286 -359.491534) (xy 339.988906 -359.509568) (xy 339.996018 -359.51668) (xy 340.004582 -359.525305)
			(xy 340.020722 -359.543481) (xy 340.028276 -359.553002) (xy 340.035852 -359.561749) (xy 340.0566 -359.57194)
			(xy 340.068154 -359.57256) (xy 340.148418 -359.57256) (xy 340.159989 -359.572014) (xy 340.180761 -359.561803)
			(xy 340.188296 -359.553002) (xy 340.206705 -359.530327) (xy 340.249229 -359.490296) (xy 340.29736 -359.457215)
			(xy 340.323424 -359.444036) (xy 340.332822 -359.439464) (xy 340.346284 -359.423716) (xy 340.37524 -359.3338)
			(xy 340.373462 -359.313226) (xy 340.368382 -359.304082) (xy 340.353844 -359.27595) (xy 340.333234 -359.216076)
			(xy 340.322781 -359.153624) (xy 340.322154 -359.121964) (xy 340.322644 -359.094714) (xy 340.330405 -359.040768)
			(xy 340.345762 -358.988476) (xy 340.368405 -358.938901) (xy 340.397871 -358.893052) (xy 340.433562 -358.851864)
			(xy 340.474751 -358.816173) (xy 340.520599 -358.786706) (xy 340.570174 -358.764063) (xy 340.622466 -358.748705)
			(xy 340.676412 -358.740944) (xy 340.703662 -358.740456) (xy 340.731032 -358.740931) (xy 340.785211 -358.748744)
			(xy 340.837715 -358.764231) (xy 340.887462 -358.787071) (xy 340.933429 -358.816795) (xy 340.95436 -358.834436)
			(xy 340.961472 -358.840532) (xy 340.97849 -358.846882) (xy 341.063834 -358.846882) (xy 341.080852 -358.840532)
			(xy 341.087964 -358.834436) (xy 341.108897 -358.816795) (xy 341.154865 -358.787071) (xy 341.204611 -358.764225)
			(xy 341.257113 -358.748729) (xy 341.311291 -358.7409) (xy 341.366033 -358.7409) (xy 341.420211 -358.748729)
			(xy 341.472713 -358.764225) (xy 341.522459 -358.787071) (xy 341.568427 -358.816795) (xy 341.58936 -358.834436)
			(xy 341.596472 -358.840532) (xy 341.61349 -358.846882) (xy 341.698834 -358.846882) (xy 341.715852 -358.840532)
			(xy 341.722964 -358.834436) (xy 341.743897 -358.816795) (xy 341.789865 -358.787071) (xy 341.839611 -358.764225)
			(xy 341.892113 -358.748729) (xy 341.946291 -358.7409) (xy 342.001033 -358.7409) (xy 342.055211 -358.748729)
			(xy 342.107713 -358.764225) (xy 342.157459 -358.787071) (xy 342.203427 -358.816795) (xy 342.22436 -358.834436)
			(xy 342.231472 -358.840532) (xy 342.24849 -358.846882) (xy 342.333834 -358.846882) (xy 342.350852 -358.840532)
			(xy 342.357964 -358.834436) (xy 342.378903 -358.816806) (xy 342.424874 -358.787091) (xy 342.474619 -358.764253)
			(xy 342.527118 -358.74876) (xy 342.581293 -358.740931) (xy 342.608662 -358.740456) (xy 342.635912 -358.740991)
			(xy 342.689859 -358.748741) (xy 342.742153 -358.764091) (xy 342.791731 -358.786726) (xy 342.837582 -358.816187)
			(xy 342.878774 -358.851873) (xy 342.914469 -358.893058) (xy 342.943938 -358.938904) (xy 342.966583 -358.988477)
			(xy 342.981943 -359.040769) (xy 342.989704 -359.094714) (xy 342.99017 -359.121964) (xy 342.989735 -359.147938)
			(xy 342.982694 -359.199406) (xy 342.968738 -359.249444) (xy 342.948123 -359.297126) (xy 342.935052 -359.319576)
			(xy 342.929718 -359.328212) (xy 342.92667 -359.348278) (xy 342.949276 -359.43794) (xy 342.961214 -359.454196)
			(xy 342.970104 -359.45953) (xy 342.990317 -359.47195) (xy 343.027799 -359.501031) (xy 343.061396 -359.534525)
			(xy 343.076276 -359.553002) (xy 343.083852 -359.561749) (xy 343.1046 -359.57194) (xy 343.116154 -359.57256)
			(xy 343.196418 -359.57256) (xy 343.207989 -359.572014) (xy 343.228761 -359.561803) (xy 343.236296 -359.553002)
			(xy 343.243109 -359.544383) (xy 343.257596 -359.527862) (xy 343.265252 -359.519982) (xy 343.272364 -359.512616)
			(xy 343.279984 -359.494328) (xy 343.279984 -359.402888) (xy 343.272364 -359.3846) (xy 343.265252 -359.377234)
			(xy 343.244854 -359.3557) (xy 343.210314 -359.307482) (xy 343.183653 -359.254498) (xy 343.165516 -359.198027)
			(xy 343.156339 -359.139428) (xy 343.155778 -359.109772) (xy 343.156209 -359.0824) (xy 343.164032 -359.028219)
			(xy 343.179528 -358.975715) (xy 343.202379 -358.925968) (xy 343.232112 -358.880004) (xy 343.249758 -358.859074)
			(xy 343.255854 -358.851962) (xy 343.262204 -358.834944) (xy 343.262204 -358.7496) (xy 343.255854 -358.732582)
			(xy 343.249758 -358.72547) (xy 343.232089 -358.70456) (xy 343.202363 -358.658589) (xy 343.179517 -358.608839)
			(xy 343.164022 -358.556333) (xy 343.156195 -358.502151) (xy 343.156198 -358.447407) (xy 343.164031 -358.393225)
			(xy 343.179532 -358.340721) (xy 343.202383 -358.290974) (xy 343.232114 -358.245006) (xy 343.249758 -358.224074)
			(xy 343.255854 -358.216962) (xy 343.262204 -358.199944) (xy 343.262204 -358.1146) (xy 343.255854 -358.097582)
			(xy 343.249758 -358.09047) (xy 343.232131 -358.069528) (xy 343.202419 -358.023557) (xy 343.179581 -357.973812)
			(xy 343.164087 -357.921314) (xy 343.156254 -357.86714) (xy 343.155778 -357.839772) (xy 343.156252 -357.812521)
			(xy 343.164012 -357.758573) (xy 343.17937 -357.706279) (xy 343.202013 -357.656703) (xy 343.231481 -357.610853)
			(xy 343.267174 -357.569664) (xy 343.308364 -357.533973) (xy 343.354215 -357.504506) (xy 343.403792 -357.481865)
			(xy 343.456087 -357.466509) (xy 343.510035 -357.458751) (xy 343.537286 -357.458264) (xy 343.566204 -357.458768)
			(xy 343.623377 -357.467497) (xy 343.678577 -357.484756) (xy 343.730539 -357.51015) (xy 343.778072 -357.543097)
			(xy 343.820087 -357.582842) (xy 343.838276 -357.60533) (xy 343.845847 -357.614082) (xy 343.866599 -357.62427)
			(xy 343.878154 -357.624888) (xy 343.958418 -357.624888) (xy 343.969988 -357.624332) (xy 343.990759 -357.614128)
			(xy 343.998296 -357.60533) (xy 344.015049 -357.584547) (xy 344.053403 -357.547417) (xy 344.096557 -357.515995)
			(xy 344.143671 -357.490896) (xy 344.193823 -357.47261) (xy 344.246034 -357.461493) (xy 344.299286 -357.457763)
			(xy 344.352538 -357.461493) (xy 344.404749 -357.47261) (xy 344.454901 -357.490896) (xy 344.502015 -357.515995)
			(xy 344.545169 -357.547417) (xy 344.583523 -357.584547) (xy 344.600276 -357.60533) (xy 344.607847 -357.614082)
			(xy 344.628599 -357.62427) (xy 344.640154 -357.624888) (xy 344.720418 -357.624888) (xy 344.731988 -357.624332)
			(xy 344.752759 -357.614128) (xy 344.760296 -357.60533) (xy 344.778497 -357.582855) (xy 344.820514 -357.543118)
			(xy 344.868046 -357.510177) (xy 344.920006 -357.484787) (xy 344.975202 -357.467529) (xy 345.03237 -357.458799)
			(xy 345.061286 -357.458264) (xy 345.088536 -357.458791) (xy 345.14248 -357.466545) (xy 345.194773 -357.481897)
			(xy 345.244348 -357.504534) (xy 345.290197 -357.533997) (xy 345.331386 -357.569684) (xy 345.367078 -357.610869)
			(xy 345.396545 -357.656715) (xy 345.419188 -357.706288) (xy 345.434546 -357.758579) (xy 345.442306 -357.812522)
			(xy 345.442794 -357.839772) (xy 345.442313 -357.867142) (xy 345.434499 -357.92132) (xy 345.419013 -357.973823)
			(xy 345.396175 -358.02357) (xy 345.366454 -358.069538) (xy 345.348814 -358.09047) (xy 345.342718 -358.097582)
			(xy 345.336368 -358.1146) (xy 345.336368 -358.199944) (xy 345.342718 -358.216962) (xy 345.348814 -358.224074)
			(xy 345.366426 -358.24503) (xy 345.396148 -358.290995) (xy 345.418993 -358.340737) (xy 345.43449 -358.393235)
			(xy 345.44232 -358.44741) (xy 345.442323 -358.502148) (xy 345.434499 -358.556323) (xy 345.419008 -358.608823)
			(xy 345.396169 -358.658568) (xy 345.366451 -358.704536) (xy 345.348814 -358.72547) (xy 345.342718 -358.732582)
			(xy 345.336368 -358.7496) (xy 345.336368 -358.834944) (xy 345.342718 -358.851962) (xy 345.348814 -358.859074)
			(xy 345.366457 -358.880003) (xy 345.396167 -358.925977) (xy 345.419002 -358.975725) (xy 345.434493 -359.028227)
			(xy 345.44232 -359.082403) (xy 345.442794 -359.109772) (xy 345.442239 -359.139428) (xy 345.433051 -359.198023)
			(xy 345.414908 -359.254492) (xy 345.388247 -359.307474) (xy 345.35371 -359.355693) (xy 345.33332 -359.377234)
			(xy 345.326208 -359.3846) (xy 345.318588 -359.402888) (xy 345.318588 -359.494328) (xy 345.326208 -359.512616)
			(xy 345.33332 -359.519982) (xy 345.353721 -359.541514) (xy 345.388262 -359.589732) (xy 345.414922 -359.642716)
			(xy 345.433059 -359.699188) (xy 345.442234 -359.757787) (xy 345.442794 -359.787444) (xy 345.442363 -359.814697)
			(xy 345.4346 -359.868647) (xy 345.419239 -359.920944) (xy 345.396592 -359.970522) (xy 345.367119 -360.016373)
			(xy 345.331422 -360.057563) (xy 345.290227 -360.093254) (xy 345.244371 -360.122719) (xy 345.19479 -360.145359)
			(xy 345.142491 -360.160713) (xy 345.088539 -360.168467) (xy 345.061286 -360.168952) (xy 345.03237 -360.16839)
			(xy 344.975201 -360.159673) (xy 344.920002 -360.142424) (xy 344.86804 -360.117041) (xy 344.820505 -360.084104)
			(xy 344.778487 -360.044369) (xy 344.760296 -360.021886) (xy 344.752734 -360.013125) (xy 344.731975 -360.002942)
			(xy 344.720418 -360.002328) (xy 344.640154 -360.002328) (xy 344.628589 -360.00292) (xy 344.607817 -360.013098)
			(xy 344.600276 -360.021886) (xy 344.588084 -360.036618) (xy 344.581988 -360.04373) (xy 344.575638 -360.061256)
			(xy 344.576908 -360.147616) (xy 344.583766 -360.164888) (xy 344.59037 -360.171746) (xy 344.609168 -360.19302)
			(xy 344.640975 -360.240039) (xy 344.665456 -360.291255) (xy 344.682071 -360.345536) (xy 344.690451 -360.40168)
			(xy 344.690954 -360.430064) (xy 344.690388 -360.457312) (xy 344.682638 -360.511255) (xy 344.66729 -360.563545)
			(xy 344.644656 -360.613119) (xy 344.615198 -360.658967) (xy 344.579515 -360.700157) (xy 344.538333 -360.735849)
			(xy 344.492491 -360.765317) (xy 344.442922 -360.787961) (xy 344.390635 -360.803321) (xy 344.336694 -360.811083)
			(xy 344.309446 -360.811572) (xy 344.28053 -360.811031) (xy 344.223359 -360.802308) (xy 344.16816 -360.785056)
			(xy 344.116198 -360.759668) (xy 344.068664 -360.726728) (xy 344.026646 -360.68699) (xy 344.008456 -360.664506)
			(xy 344.000908 -360.65573) (xy 343.980139 -360.645554) (xy 343.968578 -360.644948) (xy 343.888314 -360.644948)
			(xy 343.876745 -360.64551) (xy 343.855973 -360.655709) (xy 343.848436 -360.664506) (xy 343.836244 -360.679492)
			(xy 343.830148 -360.68635) (xy 343.823798 -360.703876) (xy 343.824814 -360.789728) (xy 343.831418 -360.807)
			(xy 343.837768 -360.814112) (xy 343.856251 -360.835263) (xy 343.887441 -360.881978) (xy 343.911455 -360.932756)
			(xy 343.927775 -360.986503) (xy 343.936051 -361.04206) (xy 343.936574 -361.070144) (xy 343.936163 -361.097398)
			(xy 343.9284 -361.15135) (xy 343.913037 -361.203648) (xy 343.890388 -361.253228) (xy 343.860914 -361.29908)
			(xy 343.825215 -361.34027) (xy 343.784017 -361.375961) (xy 343.738159 -361.405426) (xy 343.688575 -361.428064)
			(xy 343.636274 -361.443416) (xy 343.58232 -361.451169) (xy 343.555066 -361.451652) (xy 343.52615 -361.451104)
			(xy 343.468979 -361.442384) (xy 343.41378 -361.425133) (xy 343.361818 -361.399747) (xy 343.314284 -361.366807)
			(xy 343.272267 -361.32707) (xy 343.254076 -361.304586) (xy 343.246522 -361.295816) (xy 343.225757 -361.285637)
			(xy 343.214198 -361.285028) (xy 343.133934 -361.285028) (xy 343.122367 -361.285608) (xy 343.101596 -361.295795)
			(xy 343.094056 -361.304586) (xy 343.077303 -361.325369) (xy 343.038949 -361.362499) (xy 342.995795 -361.393921)
			(xy 342.948681 -361.41902) (xy 342.898529 -361.437306) (xy 342.846318 -361.448423) (xy 342.793066 -361.452153)
			(xy 342.739814 -361.448423) (xy 342.687603 -361.437306) (xy 342.637451 -361.41902) (xy 342.590337 -361.393921)
			(xy 342.547183 -361.362499) (xy 342.508829 -361.325369) (xy 342.492076 -361.304586) (xy 342.484522 -361.295816)
			(xy 342.463757 -361.285637) (xy 342.452198 -361.285028) (xy 342.371934 -361.285028) (xy 342.360367 -361.285608)
			(xy 342.339596 -361.295795) (xy 342.332056 -361.304586) (xy 342.315303 -361.325369) (xy 342.276949 -361.362499)
			(xy 342.233795 -361.393921) (xy 342.186681 -361.41902) (xy 342.136529 -361.437306) (xy 342.084318 -361.448423)
			(xy 342.031066 -361.452153) (xy 341.977814 -361.448423) (xy 341.925603 -361.437306) (xy 341.875451 -361.41902)
			(xy 341.828337 -361.393921) (xy 341.785183 -361.362499) (xy 341.746829 -361.325369) (xy 341.730076 -361.304586)
			(xy 341.722522 -361.295816) (xy 341.701757 -361.285637) (xy 341.690198 -361.285028) (xy 341.609934 -361.285028)
			(xy 341.598367 -361.285608) (xy 341.577596 -361.295795) (xy 341.570056 -361.304586) (xy 341.553303 -361.325369)
			(xy 341.514949 -361.362499) (xy 341.471795 -361.393921) (xy 341.424681 -361.41902) (xy 341.374529 -361.437306)
			(xy 341.322318 -361.448423) (xy 341.269066 -361.452153) (xy 341.215814 -361.448423) (xy 341.163603 -361.437306)
			(xy 341.113451 -361.41902) (xy 341.066337 -361.393921) (xy 341.023183 -361.362499) (xy 340.984829 -361.325369)
			(xy 340.968076 -361.304586) (xy 340.960522 -361.295816) (xy 340.939757 -361.285637) (xy 340.928198 -361.285028)
			(xy 340.847934 -361.285028) (xy 340.836367 -361.285608) (xy 340.815596 -361.295795) (xy 340.808056 -361.304586)
			(xy 340.791303 -361.325369) (xy 340.752949 -361.362499) (xy 340.709795 -361.393921) (xy 340.662681 -361.41902)
			(xy 340.612529 -361.437306) (xy 340.560318 -361.448423) (xy 340.507066 -361.452153) (xy 340.453814 -361.448423)
			(xy 340.401603 -361.437306) (xy 340.351451 -361.41902) (xy 340.304337 -361.393921) (xy 340.261183 -361.362499)
			(xy 340.222829 -361.325369) (xy 340.206076 -361.304586) (xy 340.198522 -361.295816) (xy 340.177757 -361.285637)
			(xy 340.166198 -361.285028) (xy 340.085934 -361.285028) (xy 340.074367 -361.285608) (xy 340.053596 -361.295795)
			(xy 340.046056 -361.304586) (xy 340.029303 -361.325369) (xy 339.990949 -361.362499) (xy 339.947795 -361.393921)
			(xy 339.900681 -361.41902) (xy 339.850529 -361.437306) (xy 339.798318 -361.448423) (xy 339.745066 -361.452153)
			(xy 339.691814 -361.448423) (xy 339.639603 -361.437306) (xy 339.589451 -361.41902) (xy 339.542337 -361.393921)
			(xy 339.499183 -361.362499) (xy 339.460829 -361.325369) (xy 339.444076 -361.304586) (xy 339.436522 -361.295816)
			(xy 339.415757 -361.285637) (xy 339.404198 -361.285028) (xy 339.323934 -361.285028) (xy 339.312367 -361.285608)
			(xy 339.291596 -361.295795) (xy 339.284056 -361.304586) (xy 339.267303 -361.325369) (xy 339.228949 -361.362499)
			(xy 339.185795 -361.393921) (xy 339.138681 -361.41902) (xy 339.088529 -361.437306) (xy 339.036318 -361.448423)
			(xy 338.983066 -361.452153) (xy 338.929814 -361.448423) (xy 338.877603 -361.437306) (xy 338.827451 -361.41902)
			(xy 338.780337 -361.393921) (xy 338.737183 -361.362499) (xy 338.698829 -361.325369) (xy 338.682076 -361.304586)
			(xy 338.674522 -361.295816) (xy 338.653757 -361.285637) (xy 338.642198 -361.285028) (xy 338.561934 -361.285028)
			(xy 338.550367 -361.285608) (xy 338.529596 -361.295795) (xy 338.522056 -361.304586) (xy 338.503886 -361.327088)
			(xy 338.461863 -361.366822) (xy 338.414323 -361.39976) (xy 338.362358 -361.425145) (xy 338.307156 -361.442397)
			(xy 338.249983 -361.45112) (xy 338.221066 -361.451652) (xy 338.192139 -361.451095) (xy 338.134949 -361.442348)
			(xy 338.079737 -361.425061) (xy 338.027772 -361.399629) (xy 337.980246 -361.366638) (xy 337.93825 -361.326844)
			(xy 337.920076 -361.304332) (xy 337.91271 -361.295188) (xy 337.89239 -361.285028) (xy 337.78952 -361.283504)
			(xy 337.768692 -361.293156) (xy 337.761326 -361.3023) (xy 337.743109 -361.323664) (xy 337.701484 -361.361338)
			(xy 337.654786 -361.392503) (xy 337.604023 -361.416485) (xy 337.550294 -361.432766) (xy 337.494757 -361.440995)
			(xy 337.466686 -361.441492) (xy 337.437771 -361.440915) (xy 337.380603 -361.432199) (xy 337.325405 -361.414953)
			(xy 337.273443 -361.389572) (xy 337.225907 -361.356639) (xy 337.183888 -361.316907) (xy 337.165696 -361.294426)
			(xy 337.158144 -361.285654) (xy 337.137377 -361.275479) (xy 337.125818 -361.274868) (xy 337.045554 -361.274868)
			(xy 337.033987 -361.275446) (xy 337.013214 -361.285633) (xy 337.005676 -361.294426) (xy 336.988923 -361.315209)
			(xy 336.950569 -361.352339) (xy 336.907415 -361.383761) (xy 336.860301 -361.40886) (xy 336.810149 -361.427146)
			(xy 336.757938 -361.438263) (xy 336.704686 -361.441993) (xy 336.651434 -361.438263) (xy 336.599223 -361.427146)
			(xy 336.549071 -361.40886) (xy 336.501957 -361.383761) (xy 336.458803 -361.352339) (xy 336.420449 -361.315209)
			(xy 336.403696 -361.294426) (xy 336.396144 -361.285654) (xy 336.375377 -361.275479) (xy 336.363818 -361.274868)
			(xy 336.283554 -361.274868) (xy 336.271987 -361.275446) (xy 336.251214 -361.285633) (xy 336.243676 -361.294426)
			(xy 336.225505 -361.316926) (xy 336.18348 -361.356659) (xy 336.135941 -361.389596) (xy 336.083976 -361.414981)
			(xy 336.028775 -361.432234) (xy 335.971603 -361.440959) (xy 335.942686 -361.441492) (xy 335.915432 -361.441058)
			(xy 335.861479 -361.433299) (xy 335.80918 -361.41794) (xy 335.759598 -361.395295) (xy 335.713745 -361.365824)
			(xy 335.672552 -361.330127) (xy 335.636858 -361.288931) (xy 335.607391 -361.243075) (xy 335.584749 -361.193492)
			(xy 335.569395 -361.141191) (xy 335.56164 -361.087238) (xy 335.561178 -361.059984) (xy 335.561627 -361.032788)
			(xy 335.569312 -360.978943) (xy 335.584579 -360.926739) (xy 335.607118 -360.877238) (xy 335.63647 -360.831447)
			(xy 335.653888 -360.810556) (xy 335.659984 -360.803698) (xy 335.666334 -360.786172) (xy 335.665318 -360.70032)
			(xy 335.658714 -360.683048) (xy 335.652364 -360.675936) (xy 335.633861 -360.654801) (xy 335.602673 -360.608082)
			(xy 335.578663 -360.5573) (xy 335.562347 -360.50355) (xy 335.554077 -360.44799) (xy 335.553558 -360.419904)
			(xy 335.554016 -360.392735) (xy 335.561743 -360.338949) (xy 335.577025 -360.286804) (xy 335.599554 -360.237356)
			(xy 335.628874 -360.191607) (xy 335.646268 -360.17073) (xy 335.652364 -360.163618) (xy 335.658714 -360.146092)
			(xy 335.657444 -360.059732) (xy 335.650586 -360.04246) (xy 335.643982 -360.035602) (xy 335.625151 -360.014356)
			(xy 335.593351 -359.967329) (xy 335.568877 -359.916105) (xy 335.552269 -359.861819) (xy 335.543897 -359.805669)
			(xy 335.543398 -359.777284) (xy 335.543939 -359.748332) (xy 335.552696 -359.691093) (xy 335.570008 -359.635837)
			(xy 335.595475 -359.583834) (xy 335.628512 -359.536279) (xy 335.648046 -359.514902) (xy 335.654904 -359.507536)
			(xy 335.662016 -359.489248) (xy 335.660746 -359.398062) (xy 335.653126 -359.380028) (xy 335.646014 -359.372916)
			(xy 335.625019 -359.351305) (xy 335.589452 -359.302673) (xy 335.561974 -359.249053) (xy 335.54327 -359.191779)
			(xy 335.533803 -359.132277) (xy 335.533238 -359.102152) (xy 318.661737 -359.102152) (xy 318.660279 -359.112062)
			(xy 318.644211 -359.165469) (xy 318.620539 -359.215966) (xy 318.589766 -359.262479) (xy 318.552549 -359.304016)
			(xy 318.509681 -359.339691) (xy 318.462075 -359.368745) (xy 318.410746 -359.390557) (xy 318.356789 -359.404663)
			(xy 318.301352 -359.410763) (xy 318.245618 -359.408726) (xy 318.190775 -359.398596) (xy 318.137991 -359.380589)
			(xy 318.088391 -359.355088) (xy 318.043033 -359.322637) (xy 318.002884 -359.283928) (xy 317.968798 -359.239785)
			(xy 317.941502 -359.19115) (xy 317.921579 -359.139059) (xy 317.909453 -359.084622) (xy 317.905382 -359.029)
			(xy 305.799188 -359.029) (xy 305.790827 -359.038332) (xy 305.747959 -359.074007) (xy 305.700353 -359.103061)
			(xy 305.649024 -359.124873) (xy 305.595067 -359.138979) (xy 305.53963 -359.145079) (xy 305.483896 -359.143042)
			(xy 305.429053 -359.132912) (xy 305.376269 -359.114905) (xy 305.326669 -359.089404) (xy 305.281311 -359.056953)
			(xy 305.241162 -359.018244) (xy 305.207076 -358.974101) (xy 305.17978 -358.925466) (xy 305.159857 -358.873375)
			(xy 305.147731 -358.818938) (xy 305.14366 -358.763316) (xy 300.617128 -358.763316) (xy 300.617128 -359.283)
			(xy 302.893982 -359.283) (xy 302.898053 -359.227378) (xy 302.910179 -359.172941) (xy 302.930102 -359.12085)
			(xy 302.957398 -359.072215) (xy 302.991484 -359.028072) (xy 303.031633 -358.989363) (xy 303.076991 -358.956912)
			(xy 303.126591 -358.931411) (xy 303.179375 -358.913404) (xy 303.234218 -358.903274) (xy 303.289952 -358.901237)
			(xy 303.345389 -358.907337) (xy 303.399346 -358.921443) (xy 303.450675 -358.943255) (xy 303.498281 -358.972309)
			(xy 303.541149 -359.007984) (xy 303.578366 -359.049521) (xy 303.609139 -359.096034) (xy 303.632811 -359.146531)
			(xy 303.648879 -359.199938) (xy 303.656999 -359.255114) (xy 303.657508 -359.283) (xy 303.656999 -359.310886)
			(xy 303.648879 -359.366062) (xy 303.632811 -359.419469) (xy 303.609139 -359.469966) (xy 303.578366 -359.516479)
			(xy 303.541149 -359.558016) (xy 303.498281 -359.593691) (xy 303.450675 -359.622745) (xy 303.399346 -359.644557)
			(xy 303.345389 -359.658663) (xy 303.289952 -359.664763) (xy 303.234218 -359.662726) (xy 303.179375 -359.652596)
			(xy 303.126591 -359.634589) (xy 303.076991 -359.609088) (xy 303.031633 -359.576637) (xy 302.991484 -359.537928)
			(xy 302.957398 -359.493785) (xy 302.930102 -359.44515) (xy 302.910179 -359.393059) (xy 302.898053 -359.338622)
			(xy 302.893982 -359.283) (xy 300.617128 -359.283) (xy 300.617128 -359.564178) (xy 300.616659 -359.574146)
			(xy 300.60908 -359.592582) (xy 300.602396 -359.599992) (xy 300.172628 -360.02976) (xy 305.24145 -360.02976)
			(xy 305.245521 -359.974138) (xy 305.257647 -359.919701) (xy 305.27757 -359.86761) (xy 305.304866 -359.818975)
			(xy 305.338952 -359.774832) (xy 305.379101 -359.736123) (xy 305.424459 -359.703672) (xy 305.474059 -359.678171)
			(xy 305.526843 -359.660164) (xy 305.581686 -359.650034) (xy 305.63742 -359.647997) (xy 305.692857 -359.654097)
			(xy 305.746814 -359.668203) (xy 305.798143 -359.690015) (xy 305.845749 -359.719069) (xy 305.888617 -359.754744)
			(xy 305.925834 -359.796281) (xy 305.956607 -359.842794) (xy 305.980279 -359.893291) (xy 305.996347 -359.946698)
			(xy 306.004467 -360.001874) (xy 306.004976 -360.02976) (xy 306.004467 -360.057646) (xy 305.996347 -360.112822)
			(xy 305.980279 -360.166229) (xy 305.956607 -360.216726) (xy 305.925834 -360.263239) (xy 305.888617 -360.304776)
			(xy 305.845749 -360.340451) (xy 305.798143 -360.369505) (xy 305.746814 -360.391317) (xy 305.703533 -360.402632)
			(xy 313.480448 -360.402632) (xy 313.484519 -360.34701) (xy 313.496645 -360.292573) (xy 313.516568 -360.240482)
			(xy 313.543864 -360.191847) (xy 313.57795 -360.147704) (xy 313.618099 -360.108995) (xy 313.663457 -360.076544)
			(xy 313.713057 -360.051043) (xy 313.765841 -360.033036) (xy 313.820684 -360.022906) (xy 313.876418 -360.020869)
			(xy 313.931855 -360.026969) (xy 313.985812 -360.041075) (xy 314.037141 -360.062887) (xy 314.084747 -360.091941)
			(xy 314.127615 -360.127616) (xy 314.164832 -360.169153) (xy 314.195605 -360.215666) (xy 314.219277 -360.266163)
			(xy 314.226252 -360.289348) (xy 314.38545 -360.289348) (xy 314.389521 -360.233726) (xy 314.401647 -360.179289)
			(xy 314.42157 -360.127198) (xy 314.448866 -360.078563) (xy 314.482952 -360.03442) (xy 314.523101 -359.995711)
			(xy 314.568459 -359.96326) (xy 314.618059 -359.937759) (xy 314.670843 -359.919752) (xy 314.725686 -359.909622)
			(xy 314.78142 -359.907585) (xy 314.836857 -359.913685) (xy 314.853362 -359.918) (xy 319.046858 -359.918)
			(xy 319.050929 -359.862378) (xy 319.063055 -359.807941) (xy 319.082978 -359.75585) (xy 319.110274 -359.707215)
			(xy 319.14436 -359.663072) (xy 319.184509 -359.624363) (xy 319.229867 -359.591912) (xy 319.279467 -359.566411)
			(xy 319.332251 -359.548404) (xy 319.387094 -359.538274) (xy 319.442828 -359.536237) (xy 319.498265 -359.542337)
			(xy 319.552222 -359.556443) (xy 319.603551 -359.578255) (xy 319.651157 -359.607309) (xy 319.694025 -359.642984)
			(xy 319.731242 -359.684521) (xy 319.762015 -359.731034) (xy 319.785687 -359.781531) (xy 319.801755 -359.834938)
			(xy 319.809875 -359.890114) (xy 319.810384 -359.918) (xy 319.809875 -359.945886) (xy 319.801755 -360.001062)
			(xy 319.785687 -360.054469) (xy 319.762015 -360.104966) (xy 319.731242 -360.151479) (xy 319.694025 -360.193016)
			(xy 319.651157 -360.228691) (xy 319.603551 -360.257745) (xy 319.552222 -360.279557) (xy 319.498265 -360.293663)
			(xy 319.442828 -360.299763) (xy 319.387094 -360.297726) (xy 319.332251 -360.287596) (xy 319.279467 -360.269589)
			(xy 319.229867 -360.244088) (xy 319.184509 -360.211637) (xy 319.14436 -360.172928) (xy 319.110274 -360.128785)
			(xy 319.082978 -360.08015) (xy 319.063055 -360.028059) (xy 319.050929 -359.973622) (xy 319.046858 -359.918)
			(xy 314.853362 -359.918) (xy 314.890814 -359.927791) (xy 314.942143 -359.949603) (xy 314.989749 -359.978657)
			(xy 315.032617 -360.014332) (xy 315.069834 -360.055869) (xy 315.100607 -360.102382) (xy 315.124279 -360.152879)
			(xy 315.140347 -360.206286) (xy 315.148467 -360.261462) (xy 315.148976 -360.289348) (xy 315.148467 -360.317234)
			(xy 315.14188 -360.361992) (xy 322.46265 -360.361992) (xy 322.466721 -360.30637) (xy 322.478847 -360.251933)
			(xy 322.49877 -360.199842) (xy 322.526066 -360.151207) (xy 322.560152 -360.107064) (xy 322.600301 -360.068355)
			(xy 322.645659 -360.035904) (xy 322.695259 -360.010403) (xy 322.748043 -359.992396) (xy 322.802886 -359.982266)
			(xy 322.85862 -359.980229) (xy 322.914057 -359.986329) (xy 322.968014 -360.000435) (xy 323.019343 -360.022247)
			(xy 323.066949 -360.051301) (xy 323.109817 -360.086976) (xy 323.147034 -360.128513) (xy 323.177807 -360.175026)
			(xy 323.201479 -360.225523) (xy 323.217547 -360.27893) (xy 323.225667 -360.334106) (xy 323.226176 -360.361992)
			(xy 323.225667 -360.389878) (xy 323.217547 -360.445054) (xy 323.201479 -360.498461) (xy 323.177807 -360.548958)
			(xy 323.147034 -360.595471) (xy 323.109817 -360.637008) (xy 323.066949 -360.672683) (xy 323.019343 -360.701737)
			(xy 322.968014 -360.723549) (xy 322.914057 -360.737655) (xy 322.85862 -360.743755) (xy 322.802886 -360.741718)
			(xy 322.748043 -360.731588) (xy 322.695259 -360.713581) (xy 322.645659 -360.68808) (xy 322.600301 -360.655629)
			(xy 322.560152 -360.61692) (xy 322.526066 -360.572777) (xy 322.49877 -360.524142) (xy 322.478847 -360.472051)
			(xy 322.466721 -360.417614) (xy 322.46265 -360.361992) (xy 315.14188 -360.361992) (xy 315.140347 -360.37241)
			(xy 315.124279 -360.425817) (xy 315.100607 -360.476314) (xy 315.069834 -360.522827) (xy 315.032617 -360.564364)
			(xy 314.989749 -360.600039) (xy 314.942143 -360.629093) (xy 314.890814 -360.650905) (xy 314.836857 -360.665011)
			(xy 314.78142 -360.671111) (xy 314.725686 -360.669074) (xy 314.670843 -360.658944) (xy 314.618059 -360.640937)
			(xy 314.568459 -360.615436) (xy 314.523101 -360.582985) (xy 314.482952 -360.544276) (xy 314.448866 -360.500133)
			(xy 314.42157 -360.451498) (xy 314.401647 -360.399407) (xy 314.389521 -360.34497) (xy 314.38545 -360.289348)
			(xy 314.226252 -360.289348) (xy 314.235345 -360.31957) (xy 314.243465 -360.374746) (xy 314.243974 -360.402632)
			(xy 314.243465 -360.430518) (xy 314.235345 -360.485694) (xy 314.219277 -360.539101) (xy 314.195605 -360.589598)
			(xy 314.164832 -360.636111) (xy 314.127615 -360.677648) (xy 314.084747 -360.713323) (xy 314.037141 -360.742377)
			(xy 313.985812 -360.764189) (xy 313.931855 -360.778295) (xy 313.876418 -360.784395) (xy 313.820684 -360.782358)
			(xy 313.765841 -360.772228) (xy 313.713057 -360.754221) (xy 313.663457 -360.72872) (xy 313.618099 -360.696269)
			(xy 313.57795 -360.65756) (xy 313.543864 -360.613417) (xy 313.516568 -360.564782) (xy 313.496645 -360.512691)
			(xy 313.484519 -360.458254) (xy 313.480448 -360.402632) (xy 305.703533 -360.402632) (xy 305.692857 -360.405423)
			(xy 305.63742 -360.411523) (xy 305.581686 -360.409486) (xy 305.526843 -360.399356) (xy 305.474059 -360.381349)
			(xy 305.424459 -360.355848) (xy 305.379101 -360.323397) (xy 305.338952 -360.284688) (xy 305.304866 -360.240545)
			(xy 305.27757 -360.19191) (xy 305.257647 -360.139819) (xy 305.245521 -360.085382) (xy 305.24145 -360.02976)
			(xy 300.172628 -360.02976) (xy 300.004226 -360.198162) (xy 299.996821 -360.204885) (xy 299.978397 -360.212607)
			(xy 299.968412 -360.213148) (xy 292.096444 -360.213148) (xy 292.077902 -360.205274) (xy 292.07206 -360.199432)
			(xy 280.813764 -360.199432) (xy 280.803793 -360.198992) (xy 280.785357 -360.191392) (xy 280.77795 -360.1847)
			(xy 276.46249 -355.86924) (xy 276.455767 -355.861836) (xy 276.448046 -355.843411) (xy 276.447504 -355.833426)
			(xy 276.447504 -350.085152) (xy 276.447159 -350.075104) (xy 276.439555 -350.056506) (xy 276.432772 -350.049084)
			(xy 275.573744 -349.190056) (xy 275.567077 -349.182635) (xy 275.559494 -349.164206) (xy 275.559012 -349.154242)
			(xy 275.559012 -349.106744) (xy 275.551392 -349.088456) (xy 264.80389 -349.088456) (xy 264.80389 -349.602806)
			(xy 272.31543 -349.602806) (xy 272.319501 -349.547184) (xy 272.331627 -349.492747) (xy 272.35155 -349.440656)
			(xy 272.378846 -349.392021) (xy 272.412932 -349.347878) (xy 272.453081 -349.309169) (xy 272.498439 -349.276718)
			(xy 272.548039 -349.251217) (xy 272.600823 -349.23321) (xy 272.655666 -349.22308) (xy 272.7114 -349.221043)
			(xy 272.766837 -349.227143) (xy 272.820794 -349.241249) (xy 272.872123 -349.263061) (xy 272.919729 -349.292115)
			(xy 272.962597 -349.32779) (xy 272.999814 -349.369327) (xy 273.030587 -349.41584) (xy 273.054259 -349.466337)
			(xy 273.070327 -349.519744) (xy 273.078447 -349.57492) (xy 273.078956 -349.602806) (xy 273.078447 -349.630692)
			(xy 273.070327 -349.685868) (xy 273.054259 -349.739275) (xy 273.030587 -349.789772) (xy 272.999814 -349.836285)
			(xy 272.962597 -349.877822) (xy 272.919729 -349.913497) (xy 272.872123 -349.942551) (xy 272.820794 -349.964363)
			(xy 272.766837 -349.978469) (xy 272.7114 -349.984569) (xy 272.655666 -349.982532) (xy 272.600823 -349.972402)
			(xy 272.548039 -349.954395) (xy 272.498439 -349.928894) (xy 272.453081 -349.896443) (xy 272.412932 -349.857734)
			(xy 272.378846 -349.813591) (xy 272.35155 -349.764956) (xy 272.331627 -349.712865) (xy 272.319501 -349.658428)
			(xy 272.31543 -349.602806) (xy 264.80389 -349.602806) (xy 264.80389 -350.289368) (xy 264.804359 -350.299241)
			(xy 264.811814 -350.317528) (xy 264.818368 -350.324928) (xy 264.818622 -350.325182) (xy 264.991596 -350.498156)
			(xy 271.73631 -350.498156) (xy 271.740381 -350.442534) (xy 271.752507 -350.388097) (xy 271.77243 -350.336006)
			(xy 271.799726 -350.287371) (xy 271.833812 -350.243228) (xy 271.873961 -350.204519) (xy 271.919319 -350.172068)
			(xy 271.968919 -350.146567) (xy 272.021703 -350.12856) (xy 272.076546 -350.11843) (xy 272.13228 -350.116393)
			(xy 272.187717 -350.122493) (xy 272.241674 -350.136599) (xy 272.293003 -350.158411) (xy 272.340609 -350.187465)
			(xy 272.383477 -350.22314) (xy 272.420694 -350.264677) (xy 272.451467 -350.31119) (xy 272.475139 -350.361687)
			(xy 272.491207 -350.415094) (xy 272.499327 -350.47027) (xy 272.499836 -350.498156) (xy 272.499327 -350.526042)
			(xy 272.491207 -350.581218) (xy 272.475139 -350.634625) (xy 272.451467 -350.685122) (xy 272.420694 -350.731635)
			(xy 272.383477 -350.773172) (xy 272.340609 -350.808847) (xy 272.293003 -350.837901) (xy 272.241674 -350.859713)
			(xy 272.187717 -350.873819) (xy 272.13228 -350.879919) (xy 272.076546 -350.877882) (xy 272.021703 -350.867752)
			(xy 271.968919 -350.849745) (xy 271.919319 -350.824244) (xy 271.873961 -350.791793) (xy 271.833812 -350.753084)
			(xy 271.799726 -350.708941) (xy 271.77243 -350.660306) (xy 271.752507 -350.608215) (xy 271.740381 -350.553778)
			(xy 271.73631 -350.498156) (xy 264.991596 -350.498156) (xy 265.667236 -351.173796) (xy 273.075146 -351.173796)
			(xy 273.075619 -351.146321) (xy 273.083512 -351.09194) (xy 273.099135 -351.039257) (xy 273.122163 -350.989365)
			(xy 273.152118 -350.943297) (xy 273.169888 -350.922336) (xy 273.175984 -350.915224) (xy 273.182334 -350.898206)
			(xy 273.182334 -350.812354) (xy 273.175984 -350.795336) (xy 273.169888 -350.788224) (xy 273.152152 -350.767239)
			(xy 273.122224 -350.721163) (xy 273.099206 -350.671275) (xy 273.083573 -350.618603) (xy 273.075649 -350.564235)
			(xy 273.075146 -350.536764) (xy 273.075632 -350.509513) (xy 273.083388 -350.455565) (xy 273.098743 -350.40327)
			(xy 273.121385 -350.353693) (xy 273.150851 -350.307843) (xy 273.186542 -350.266652) (xy 273.227733 -350.230961)
			(xy 273.273583 -350.201495) (xy 273.32316 -350.178853) (xy 273.375455 -350.163498) (xy 273.429403 -350.155742)
			(xy 273.483905 -350.155742) (xy 273.537853 -350.163498) (xy 273.590148 -350.178853) (xy 273.639725 -350.201495)
			(xy 273.685575 -350.230961) (xy 273.726766 -350.266652) (xy 273.762457 -350.307843) (xy 273.791923 -350.353693)
			(xy 273.814565 -350.40327) (xy 273.82992 -350.455565) (xy 273.837676 -350.509513) (xy 273.838162 -350.536764)
			(xy 273.837664 -350.564238) (xy 273.829776 -350.618618) (xy 273.814159 -350.6713) (xy 273.811506 -350.67705)
			(xy 274.079972 -350.67705) (xy 274.079972 -350.62255) (xy 274.087728 -350.568604) (xy 274.103081 -350.516311)
			(xy 274.125721 -350.466735) (xy 274.155185 -350.420885) (xy 274.190874 -350.379695) (xy 274.232061 -350.344003)
			(xy 274.277908 -350.314535) (xy 274.327482 -350.291892) (xy 274.379774 -350.276534) (xy 274.43372 -350.268774)
			(xy 274.46097 -350.268286) (xy 274.486206 -350.268654) (xy 274.536241 -350.275281) (xy 274.584962 -350.288463)
			(xy 274.631512 -350.307967) (xy 274.653502 -350.320356) (xy 274.663154 -350.326198) (xy 274.685252 -350.32823)
			(xy 274.77974 -350.294702) (xy 274.795742 -350.279208) (xy 274.799806 -350.268794) (xy 274.810477 -350.242007)
			(xy 274.838768 -350.191764) (xy 274.874301 -350.146354) (xy 274.916266 -350.106811) (xy 274.963707 -350.074039)
			(xy 275.015542 -350.048783) (xy 275.070589 -350.03162) (xy 275.127592 -350.022941) (xy 275.156422 -350.022414)
			(xy 275.183675 -350.022857) (xy 275.237625 -350.030617) (xy 275.289922 -350.045977) (xy 275.339501 -350.068622)
			(xy 275.385352 -350.098092) (xy 275.426543 -350.133788) (xy 275.462234 -350.174983) (xy 275.491699 -350.220838)
			(xy 275.514339 -350.270419) (xy 275.529692 -350.322718) (xy 275.537446 -350.376669) (xy 275.53793 -350.403922)
			(xy 275.53726 -350.435484) (xy 275.526876 -350.497749) (xy 275.506395 -350.557459) (xy 275.491956 -350.585532)
			(xy 275.48713 -350.594422) (xy 275.485098 -350.61398) (xy 275.510752 -350.702118) (xy 275.523198 -350.717612)
			(xy 275.532088 -350.722692) (xy 275.557211 -350.737205) (xy 275.603094 -350.772714) (xy 275.643068 -350.814763)
			(xy 275.676212 -350.862383) (xy 275.701759 -350.914474) (xy 275.71912 -350.969834) (xy 275.727895 -351.027185)
			(xy 275.72843 -351.056194) (xy 275.727944 -351.083445) (xy 275.720188 -351.137393) (xy 275.704833 -351.189688)
			(xy 275.682191 -351.239265) (xy 275.652725 -351.285115) (xy 275.617034 -351.326306) (xy 275.575843 -351.361997)
			(xy 275.529993 -351.391463) (xy 275.480416 -351.414105) (xy 275.428121 -351.42946) (xy 275.374173 -351.437216)
			(xy 275.319671 -351.437216) (xy 275.265723 -351.42946) (xy 275.213428 -351.414105) (xy 275.163851 -351.391463)
			(xy 275.118001 -351.361997) (xy 275.07681 -351.326306) (xy 275.041119 -351.285115) (xy 275.011653 -351.239265)
			(xy 274.989011 -351.189688) (xy 274.973656 -351.137393) (xy 274.9659 -351.083445) (xy 274.965414 -351.056194)
			(xy 274.966085 -351.024632) (xy 274.976467 -350.962367) (xy 274.996949 -350.902657) (xy 275.011388 -350.874584)
			(xy 275.016214 -350.865694) (xy 275.018246 -350.846136) (xy 274.992592 -350.757998) (xy 274.980146 -350.742504)
			(xy 274.971256 -350.737424) (xy 274.96389 -350.73336) (xy 274.954238 -350.727518) (xy 274.93214 -350.725486)
			(xy 274.837652 -350.759014) (xy 274.82165 -350.774508) (xy 274.817586 -350.784922) (xy 274.80693 -350.811715)
			(xy 274.778637 -350.861958) (xy 274.743101 -350.907368) (xy 274.701133 -350.94691) (xy 274.65369 -350.979681)
			(xy 274.601854 -351.004936) (xy 274.546805 -351.022098) (xy 274.489801 -351.030775) (xy 274.46097 -351.031302)
			(xy 274.43372 -351.030826) (xy 274.379774 -351.023066) (xy 274.327482 -351.007708) (xy 274.277908 -350.985065)
			(xy 274.232061 -350.955597) (xy 274.190874 -350.919905) (xy 274.155185 -350.878715) (xy 274.125721 -350.832865)
			(xy 274.103081 -350.783289) (xy 274.087728 -350.730996) (xy 274.079972 -350.67705) (xy 273.811506 -350.67705)
			(xy 273.791137 -350.721193) (xy 273.761187 -350.767262) (xy 273.74342 -350.788224) (xy 273.737324 -350.795336)
			(xy 273.730974 -350.812354) (xy 273.730974 -350.898206) (xy 273.737324 -350.915224) (xy 273.74342 -350.922336)
			(xy 273.761185 -350.943297) (xy 273.791109 -350.98938) (xy 273.814121 -351.039274) (xy 273.829747 -351.091951)
			(xy 273.837663 -351.146324) (xy 273.838162 -351.173796) (xy 273.837676 -351.201047) (xy 273.82992 -351.254995)
			(xy 273.814565 -351.30729) (xy 273.791923 -351.356867) (xy 273.762457 -351.402717) (xy 273.726766 -351.443908)
			(xy 273.685575 -351.479599) (xy 273.639725 -351.509065) (xy 273.590148 -351.531707) (xy 273.537853 -351.547062)
			(xy 273.483905 -351.554818) (xy 273.429403 -351.554818) (xy 273.375455 -351.547062) (xy 273.32316 -351.531707)
			(xy 273.273583 -351.509065) (xy 273.227733 -351.479599) (xy 273.186542 -351.443908) (xy 273.150851 -351.402717)
			(xy 273.121385 -351.356867) (xy 273.098743 -351.30729) (xy 273.083388 -351.254995) (xy 273.075632 -351.201047)
			(xy 273.075146 -351.173796) (xy 265.667236 -351.173796) (xy 274.073874 -359.580434) (xy 274.074382 -359.580942)
			(xy 274.081764 -359.587521) (xy 274.100063 -359.594962) (xy 274.109942 -359.59542) (xy 276.32914 -359.59542)
			(xy 276.339207 -359.595851) (xy 276.357799 -359.603578) (xy 276.365208 -359.610406) (xy 278.320754 -361.565952)
			(xy 285.209742 -361.565952) (xy 285.21011 -361.538696) (xy 285.217875 -361.484739) (xy 285.23324 -361.432436)
			(xy 285.255892 -361.382852) (xy 285.285369 -361.336997) (xy 285.321073 -361.295803) (xy 285.362276 -361.26011)
			(xy 285.408138 -361.230645) (xy 285.457728 -361.208006) (xy 285.510035 -361.192654) (xy 285.563994 -361.184903)
			(xy 285.59125 -361.184444) (xy 285.61862 -361.184929) (xy 285.672798 -361.19274) (xy 285.725302 -361.208224)
			(xy 285.775049 -361.231062) (xy 285.821016 -361.260784) (xy 285.841948 -361.278424) (xy 285.84906 -361.28452)
			(xy 285.866078 -361.29087) (xy 285.951422 -361.29087) (xy 285.96844 -361.28452) (xy 285.975552 -361.278424)
			(xy 285.996494 -361.260798) (xy 286.042464 -361.231083) (xy 286.092209 -361.208244) (xy 286.144707 -361.19275)
			(xy 286.198881 -361.184919) (xy 286.22625 -361.184444) (xy 286.252898 -361.184913) (xy 286.305674 -361.192349)
			(xy 286.356902 -361.207056) (xy 286.405586 -361.228747) (xy 286.450777 -361.257001) (xy 286.491599 -361.291268)
			(xy 286.527255 -361.330882) (xy 286.557053 -361.375071) (xy 286.56915 -361.39882) (xy 286.57423 -361.409234)
			(xy 286.592264 -361.423458) (xy 286.692594 -361.446064) (xy 286.714946 -361.44073) (xy 286.72409 -361.433618)
			(xy 286.744487 -361.417796) (xy 286.788733 -361.391204) (xy 286.836157 -361.370812) (xy 286.885894 -361.356991)
			(xy 286.937039 -361.349993) (xy 286.96285 -361.349544) (xy 286.99022 -361.350029) (xy 287.044398 -361.35784)
			(xy 287.096902 -361.373324) (xy 287.146649 -361.396162) (xy 287.192616 -361.425884) (xy 287.213548 -361.443524)
			(xy 287.22066 -361.44962) (xy 287.237678 -361.45597) (xy 287.323022 -361.45597) (xy 287.34004 -361.44962)
			(xy 287.347152 -361.443524) (xy 287.368085 -361.425883) (xy 287.414053 -361.396159) (xy 287.463799 -361.373313)
			(xy 287.516301 -361.357817) (xy 287.570479 -361.349988) (xy 287.625221 -361.349988) (xy 287.679399 -361.357817)
			(xy 287.731901 -361.373313) (xy 287.781647 -361.396159) (xy 287.827615 -361.425883) (xy 287.848548 -361.443524)
			(xy 287.85566 -361.44962) (xy 287.872678 -361.45597) (xy 287.958022 -361.45597) (xy 287.97504 -361.44962)
			(xy 287.982152 -361.443524) (xy 288.003085 -361.425883) (xy 288.049053 -361.396159) (xy 288.098799 -361.373313)
			(xy 288.151301 -361.357817) (xy 288.205479 -361.349988) (xy 288.260221 -361.349988) (xy 288.314399 -361.357817)
			(xy 288.366901 -361.373313) (xy 288.416647 -361.396159) (xy 288.462615 -361.425883) (xy 288.483548 -361.443524)
			(xy 288.49066 -361.44962) (xy 288.507678 -361.45597) (xy 288.593022 -361.45597) (xy 288.61004 -361.44962)
			(xy 288.617152 -361.443524) (xy 288.638094 -361.425898) (xy 288.684064 -361.396183) (xy 288.733809 -361.373344)
			(xy 288.786307 -361.35785) (xy 288.840481 -361.350019) (xy 288.86785 -361.349544) (xy 288.893663 -361.35)
			(xy 288.944816 -361.356964) (xy 288.994561 -361.370771) (xy 289.041985 -361.391168) (xy 289.086222 -361.417781)
			(xy 289.10661 -361.433618) (xy 289.115754 -361.44073) (xy 289.138106 -361.446064) (xy 289.238436 -361.423458)
			(xy 289.25647 -361.409234) (xy 289.26155 -361.39882) (xy 289.273615 -361.375051) (xy 289.303402 -361.330844)
			(xy 289.339054 -361.291217) (xy 289.379878 -361.256941) (xy 289.425077 -361.228684) (xy 289.473771 -361.206996)
			(xy 289.525011 -361.192301) (xy 289.577797 -361.184885) (xy 289.60445 -361.184444) (xy 289.63182 -361.184929)
			(xy 289.685998 -361.19274) (xy 289.738502 -361.208224) (xy 289.788249 -361.231062) (xy 289.834216 -361.260784)
			(xy 289.855148 -361.278424) (xy 289.86226 -361.28452) (xy 289.879278 -361.29087) (xy 289.964622 -361.29087)
			(xy 289.98164 -361.28452) (xy 289.988752 -361.278424) (xy 290.009694 -361.260798) (xy 290.055664 -361.231083)
			(xy 290.105409 -361.208244) (xy 290.157907 -361.19275) (xy 290.212081 -361.184919) (xy 290.23945 -361.184444)
			(xy 290.265295 -361.184875) (xy 290.316511 -361.19186) (xy 290.366315 -361.205696) (xy 290.413795 -361.226128)
			(xy 290.458082 -361.252783) (xy 290.498365 -361.285173) (xy 290.533907 -361.322705) (xy 290.54933 -361.343448)
			(xy 290.556442 -361.353354) (xy 290.57727 -361.364276) (xy 290.682934 -361.366816) (xy 290.70427 -361.356656)
			(xy 290.71189 -361.347004) (xy 290.73011 -361.324759) (xy 290.772036 -361.285413) (xy 290.819395 -361.25281)
			(xy 290.871113 -361.227688) (xy 290.926017 -361.210617) (xy 290.982862 -361.201984) (xy 291.01161 -361.201462)
			(xy 291.03886 -361.201968) (xy 291.092806 -361.209725) (xy 291.145098 -361.22508) (xy 291.194673 -361.24772)
			(xy 291.240522 -361.277185) (xy 291.28086 -361.312136) (xy 295.410886 -361.312136) (xy 295.410886 -361.22744)
			(xy 295.418937 -361.143126) (xy 295.434966 -361.05996) (xy 295.458827 -360.978693) (xy 295.490306 -360.900063)
			(xy 295.529117 -360.824782) (xy 295.574907 -360.75353) (xy 295.627263 -360.686954) (xy 295.685711 -360.625656)
			(xy 295.749721 -360.570191) (xy 295.818713 -360.521062) (xy 295.892063 -360.478713) (xy 295.969106 -360.443529)
			(xy 296.049145 -360.415827) (xy 296.131454 -360.395859) (xy 296.215289 -360.383806) (xy 296.29989 -360.379776)
			(xy 296.384491 -360.383806) (xy 296.468326 -360.395859) (xy 296.550635 -360.415827) (xy 296.630674 -360.443529)
			(xy 296.707717 -360.478713) (xy 296.781067 -360.521062) (xy 296.850059 -360.570191) (xy 296.914069 -360.625656)
			(xy 296.917448 -360.6292) (xy 301.369982 -360.6292) (xy 301.374053 -360.573578) (xy 301.386179 -360.519141)
			(xy 301.406102 -360.46705) (xy 301.433398 -360.418415) (xy 301.467484 -360.374272) (xy 301.507633 -360.335563)
			(xy 301.552991 -360.303112) (xy 301.602591 -360.277611) (xy 301.655375 -360.259604) (xy 301.710218 -360.249474)
			(xy 301.765952 -360.247437) (xy 301.821389 -360.253537) (xy 301.875346 -360.267643) (xy 301.926675 -360.289455)
			(xy 301.974281 -360.318509) (xy 302.017149 -360.354184) (xy 302.054366 -360.395721) (xy 302.085139 -360.442234)
			(xy 302.108811 -360.492731) (xy 302.124879 -360.546138) (xy 302.132999 -360.601314) (xy 302.133508 -360.6292)
			(xy 302.132999 -360.657086) (xy 302.124879 -360.712262) (xy 302.108811 -360.765669) (xy 302.085139 -360.816166)
			(xy 302.054366 -360.862679) (xy 302.017149 -360.904216) (xy 301.974281 -360.939891) (xy 301.926675 -360.968945)
			(xy 301.875346 -360.990757) (xy 301.821389 -361.004863) (xy 301.765952 -361.010963) (xy 301.710218 -361.008926)
			(xy 301.655375 -360.998796) (xy 301.602591 -360.980789) (xy 301.552991 -360.955288) (xy 301.507633 -360.922837)
			(xy 301.467484 -360.884128) (xy 301.433398 -360.839985) (xy 301.406102 -360.79135) (xy 301.386179 -360.739259)
			(xy 301.374053 -360.684822) (xy 301.369982 -360.6292) (xy 296.917448 -360.6292) (xy 296.972517 -360.686954)
			(xy 297.024873 -360.75353) (xy 297.070663 -360.824782) (xy 297.109474 -360.900063) (xy 297.140953 -360.978693)
			(xy 297.164814 -361.05996) (xy 297.180843 -361.143126) (xy 297.188894 -361.22744) (xy 297.189398 -361.269788)
			(xy 297.188894 -361.312136) (xy 297.180843 -361.39645) (xy 297.176959 -361.4166) (xy 300.099982 -361.4166)
			(xy 300.104053 -361.360978) (xy 300.116179 -361.306541) (xy 300.136102 -361.25445) (xy 300.163398 -361.205815)
			(xy 300.197484 -361.161672) (xy 300.237633 -361.122963) (xy 300.282991 -361.090512) (xy 300.332591 -361.065011)
			(xy 300.385375 -361.047004) (xy 300.440218 -361.036874) (xy 300.495952 -361.034837) (xy 300.551389 -361.040937)
			(xy 300.605346 -361.055043) (xy 300.619364 -361.061) (xy 304.113182 -361.061) (xy 304.117253 -361.005378)
			(xy 304.129379 -360.950941) (xy 304.149302 -360.89885) (xy 304.176598 -360.850215) (xy 304.210684 -360.806072)
			(xy 304.250833 -360.767363) (xy 304.296191 -360.734912) (xy 304.345791 -360.709411) (xy 304.398575 -360.691404)
			(xy 304.453418 -360.681274) (xy 304.509152 -360.679237) (xy 304.564589 -360.685337) (xy 304.618546 -360.699443)
			(xy 304.669875 -360.721255) (xy 304.717481 -360.750309) (xy 304.760349 -360.785984) (xy 304.797566 -360.827521)
			(xy 304.828339 -360.874034) (xy 304.852011 -360.924531) (xy 304.868079 -360.977938) (xy 304.876199 -361.033114)
			(xy 304.876708 -361.061) (xy 304.876199 -361.088886) (xy 304.868079 -361.144062) (xy 304.852011 -361.197469)
			(xy 304.828339 -361.247966) (xy 304.797566 -361.294479) (xy 304.790103 -361.302808) (xy 305.2097 -361.302808)
			(xy 305.213771 -361.247186) (xy 305.225897 -361.192749) (xy 305.24582 -361.140658) (xy 305.273116 -361.092023)
			(xy 305.307202 -361.04788) (xy 305.347351 -361.009171) (xy 305.392709 -360.97672) (xy 305.442309 -360.951219)
			(xy 305.495093 -360.933212) (xy 305.549936 -360.923082) (xy 305.60567 -360.921045) (xy 305.661107 -360.927145)
			(xy 305.715064 -360.941251) (xy 305.766393 -360.963063) (xy 305.813999 -360.992117) (xy 305.856867 -361.027792)
			(xy 305.894084 -361.069329) (xy 305.924857 -361.115842) (xy 305.948529 -361.166339) (xy 305.964597 -361.219746)
			(xy 305.972717 -361.274922) (xy 305.972809 -361.279948) (xy 314.255656 -361.279948) (xy 314.259727 -361.224326)
			(xy 314.271853 -361.169889) (xy 314.291776 -361.117798) (xy 314.319072 -361.069163) (xy 314.353158 -361.02502)
			(xy 314.393307 -360.986311) (xy 314.438665 -360.95386) (xy 314.488265 -360.928359) (xy 314.541049 -360.910352)
			(xy 314.595892 -360.900222) (xy 314.651626 -360.898185) (xy 314.707063 -360.904285) (xy 314.76102 -360.918391)
			(xy 314.812349 -360.940203) (xy 314.859955 -360.969257) (xy 314.902823 -361.004932) (xy 314.94004 -361.046469)
			(xy 314.970813 -361.092982) (xy 314.994485 -361.143479) (xy 315.010553 -361.196886) (xy 315.018673 -361.252062)
			(xy 315.019182 -361.279948) (xy 315.018673 -361.307834) (xy 315.010553 -361.36301) (xy 314.994485 -361.416417)
			(xy 314.970813 -361.466914) (xy 314.94004 -361.513427) (xy 314.902823 -361.554964) (xy 314.859955 -361.590639)
			(xy 314.846717 -361.598718) (xy 321.434966 -361.598718) (xy 321.439037 -361.543096) (xy 321.451163 -361.488659)
			(xy 321.471086 -361.436568) (xy 321.498382 -361.387933) (xy 321.532468 -361.34379) (xy 321.572617 -361.305081)
			(xy 321.617975 -361.27263) (xy 321.667575 -361.247129) (xy 321.720359 -361.229122) (xy 321.775202 -361.218992)
			(xy 321.830936 -361.216955) (xy 321.886373 -361.223055) (xy 321.94033 -361.237161) (xy 321.991659 -361.258973)
			(xy 322.039265 -361.288027) (xy 322.082133 -361.323702) (xy 322.11935 -361.365239) (xy 322.150123 -361.411752)
			(xy 322.173795 -361.462249) (xy 322.175345 -361.4674) (xy 326.668382 -361.4674) (xy 326.672453 -361.411778)
			(xy 326.684579 -361.357341) (xy 326.704502 -361.30525) (xy 326.731798 -361.256615) (xy 326.765884 -361.212472)
			(xy 326.806033 -361.173763) (xy 326.851391 -361.141312) (xy 326.900991 -361.115811) (xy 326.953775 -361.097804)
			(xy 327.008618 -361.087674) (xy 327.064352 -361.085637) (xy 327.119789 -361.091737) (xy 327.173746 -361.105843)
			(xy 327.225075 -361.127655) (xy 327.240715 -361.1372) (xy 328.725782 -361.1372) (xy 328.729853 -361.081578)
			(xy 328.741979 -361.027141) (xy 328.761902 -360.97505) (xy 328.789198 -360.926415) (xy 328.823284 -360.882272)
			(xy 328.863433 -360.843563) (xy 328.908791 -360.811112) (xy 328.958391 -360.785611) (xy 329.011175 -360.767604)
			(xy 329.066018 -360.757474) (xy 329.121752 -360.755437) (xy 329.177189 -360.761537) (xy 329.231146 -360.775643)
			(xy 329.282475 -360.797455) (xy 329.330081 -360.826509) (xy 329.372949 -360.862184) (xy 329.410166 -360.903721)
			(xy 329.440939 -360.950234) (xy 329.464611 -361.000731) (xy 329.480679 -361.054138) (xy 329.488799 -361.109314)
			(xy 329.489308 -361.1372) (xy 330.021182 -361.1372) (xy 330.025253 -361.081578) (xy 330.037379 -361.027141)
			(xy 330.057302 -360.97505) (xy 330.084598 -360.926415) (xy 330.118684 -360.882272) (xy 330.158833 -360.843563)
			(xy 330.204191 -360.811112) (xy 330.253791 -360.785611) (xy 330.306575 -360.767604) (xy 330.361418 -360.757474)
			(xy 330.417152 -360.755437) (xy 330.472589 -360.761537) (xy 330.526546 -360.775643) (xy 330.577875 -360.797455)
			(xy 330.625481 -360.826509) (xy 330.668349 -360.862184) (xy 330.705566 -360.903721) (xy 330.736339 -360.950234)
			(xy 330.760011 -361.000731) (xy 330.776079 -361.054138) (xy 330.784199 -361.109314) (xy 330.784708 -361.1372)
			(xy 330.784199 -361.165086) (xy 330.776079 -361.220262) (xy 330.760011 -361.273669) (xy 330.736339 -361.324166)
			(xy 330.705566 -361.370679) (xy 330.668349 -361.412216) (xy 330.625481 -361.447891) (xy 330.577875 -361.476945)
			(xy 330.526546 -361.498757) (xy 330.472589 -361.512863) (xy 330.417152 -361.518963) (xy 330.361418 -361.516926)
			(xy 330.306575 -361.506796) (xy 330.253791 -361.488789) (xy 330.204191 -361.463288) (xy 330.158833 -361.430837)
			(xy 330.118684 -361.392128) (xy 330.084598 -361.347985) (xy 330.057302 -361.29935) (xy 330.037379 -361.247259)
			(xy 330.025253 -361.192822) (xy 330.021182 -361.1372) (xy 329.489308 -361.1372) (xy 329.488799 -361.165086)
			(xy 329.480679 -361.220262) (xy 329.464611 -361.273669) (xy 329.440939 -361.324166) (xy 329.410166 -361.370679)
			(xy 329.372949 -361.412216) (xy 329.330081 -361.447891) (xy 329.282475 -361.476945) (xy 329.231146 -361.498757)
			(xy 329.177189 -361.512863) (xy 329.121752 -361.518963) (xy 329.066018 -361.516926) (xy 329.011175 -361.506796)
			(xy 328.958391 -361.488789) (xy 328.908791 -361.463288) (xy 328.863433 -361.430837) (xy 328.823284 -361.392128)
			(xy 328.789198 -361.347985) (xy 328.761902 -361.29935) (xy 328.741979 -361.247259) (xy 328.729853 -361.192822)
			(xy 328.725782 -361.1372) (xy 327.240715 -361.1372) (xy 327.272681 -361.156709) (xy 327.315549 -361.192384)
			(xy 327.352766 -361.233921) (xy 327.383539 -361.280434) (xy 327.407211 -361.330931) (xy 327.423279 -361.384338)
			(xy 327.431399 -361.439514) (xy 327.431908 -361.4674) (xy 327.431399 -361.495286) (xy 327.423279 -361.550462)
			(xy 327.407211 -361.603869) (xy 327.383539 -361.654366) (xy 327.352766 -361.700879) (xy 327.315549 -361.742416)
			(xy 327.272681 -361.778091) (xy 327.225075 -361.807145) (xy 327.173746 -361.828957) (xy 327.119789 -361.843063)
			(xy 327.064352 -361.849163) (xy 327.008618 -361.847126) (xy 326.953775 -361.836996) (xy 326.900991 -361.818989)
			(xy 326.851391 -361.793488) (xy 326.806033 -361.761037) (xy 326.765884 -361.722328) (xy 326.731798 -361.678185)
			(xy 326.704502 -361.62955) (xy 326.684579 -361.577459) (xy 326.672453 -361.523022) (xy 326.668382 -361.4674)
			(xy 322.175345 -361.4674) (xy 322.189863 -361.515656) (xy 322.197983 -361.570832) (xy 322.198492 -361.598718)
			(xy 322.197983 -361.626604) (xy 322.189863 -361.68178) (xy 322.173795 -361.735187) (xy 322.150123 -361.785684)
			(xy 322.11935 -361.832197) (xy 322.082133 -361.873734) (xy 322.039265 -361.909409) (xy 321.991659 -361.938463)
			(xy 321.94033 -361.960275) (xy 321.886373 -361.974381) (xy 321.830936 -361.980481) (xy 321.775202 -361.978444)
			(xy 321.720359 -361.968314) (xy 321.667575 -361.950307) (xy 321.617975 -361.924806) (xy 321.572617 -361.892355)
			(xy 321.532468 -361.853646) (xy 321.498382 -361.809503) (xy 321.471086 -361.760868) (xy 321.451163 -361.708777)
			(xy 321.439037 -361.65434) (xy 321.434966 -361.598718) (xy 314.846717 -361.598718) (xy 314.812349 -361.619693)
			(xy 314.76102 -361.641505) (xy 314.707063 -361.655611) (xy 314.651626 -361.661711) (xy 314.595892 -361.659674)
			(xy 314.541049 -361.649544) (xy 314.488265 -361.631537) (xy 314.438665 -361.606036) (xy 314.393307 -361.573585)
			(xy 314.353158 -361.534876) (xy 314.319072 -361.490733) (xy 314.291776 -361.442098) (xy 314.271853 -361.390007)
			(xy 314.259727 -361.33557) (xy 314.255656 -361.279948) (xy 305.972809 -361.279948) (xy 305.973226 -361.302808)
			(xy 305.972717 -361.330694) (xy 305.964597 -361.38587) (xy 305.948529 -361.439277) (xy 305.924857 -361.489774)
			(xy 305.894084 -361.536287) (xy 305.856867 -361.577824) (xy 305.813999 -361.613499) (xy 305.766393 -361.642553)
			(xy 305.715064 -361.664365) (xy 305.661107 -361.678471) (xy 305.60567 -361.684571) (xy 305.549936 -361.682534)
			(xy 305.495093 -361.672404) (xy 305.442309 -361.654397) (xy 305.392709 -361.628896) (xy 305.347351 -361.596445)
			(xy 305.307202 -361.557736) (xy 305.273116 -361.513593) (xy 305.24582 -361.464958) (xy 305.225897 -361.412867)
			(xy 305.213771 -361.35843) (xy 305.2097 -361.302808) (xy 304.790103 -361.302808) (xy 304.760349 -361.336016)
			(xy 304.717481 -361.371691) (xy 304.669875 -361.400745) (xy 304.618546 -361.422557) (xy 304.564589 -361.436663)
			(xy 304.509152 -361.442763) (xy 304.453418 -361.440726) (xy 304.398575 -361.430596) (xy 304.345791 -361.412589)
			(xy 304.296191 -361.387088) (xy 304.250833 -361.354637) (xy 304.210684 -361.315928) (xy 304.176598 -361.271785)
			(xy 304.149302 -361.22315) (xy 304.129379 -361.171059) (xy 304.117253 -361.116622) (xy 304.113182 -361.061)
			(xy 300.619364 -361.061) (xy 300.656675 -361.076855) (xy 300.704281 -361.105909) (xy 300.747149 -361.141584)
			(xy 300.784366 -361.183121) (xy 300.815139 -361.229634) (xy 300.838811 -361.280131) (xy 300.854879 -361.333538)
			(xy 300.862999 -361.388714) (xy 300.863508 -361.4166) (xy 300.862999 -361.444486) (xy 300.854879 -361.499662)
			(xy 300.838811 -361.553069) (xy 300.815139 -361.603566) (xy 300.784366 -361.650079) (xy 300.747149 -361.691616)
			(xy 300.741881 -361.696) (xy 302.893982 -361.696) (xy 302.898053 -361.640378) (xy 302.910179 -361.585941)
			(xy 302.930102 -361.53385) (xy 302.957398 -361.485215) (xy 302.991484 -361.441072) (xy 303.031633 -361.402363)
			(xy 303.076991 -361.369912) (xy 303.126591 -361.344411) (xy 303.179375 -361.326404) (xy 303.234218 -361.316274)
			(xy 303.289952 -361.314237) (xy 303.345389 -361.320337) (xy 303.399346 -361.334443) (xy 303.450675 -361.356255)
			(xy 303.498281 -361.385309) (xy 303.541149 -361.420984) (xy 303.578366 -361.462521) (xy 303.609139 -361.509034)
			(xy 303.632811 -361.559531) (xy 303.648879 -361.612938) (xy 303.656999 -361.668114) (xy 303.657508 -361.696)
			(xy 303.656999 -361.723886) (xy 303.648879 -361.779062) (xy 303.632811 -361.832469) (xy 303.609139 -361.882966)
			(xy 303.578366 -361.929479) (xy 303.541149 -361.971016) (xy 303.498281 -362.006691) (xy 303.450675 -362.035745)
			(xy 303.399346 -362.057557) (xy 303.345389 -362.071663) (xy 303.289952 -362.077763) (xy 303.234218 -362.075726)
			(xy 303.179375 -362.065596) (xy 303.126591 -362.047589) (xy 303.076991 -362.022088) (xy 303.031633 -361.989637)
			(xy 302.991484 -361.950928) (xy 302.957398 -361.906785) (xy 302.930102 -361.85815) (xy 302.910179 -361.806059)
			(xy 302.898053 -361.751622) (xy 302.893982 -361.696) (xy 300.741881 -361.696) (xy 300.704281 -361.727291)
			(xy 300.656675 -361.756345) (xy 300.605346 -361.778157) (xy 300.551389 -361.792263) (xy 300.495952 -361.798363)
			(xy 300.440218 -361.796326) (xy 300.385375 -361.786196) (xy 300.332591 -361.768189) (xy 300.282991 -361.742688)
			(xy 300.237633 -361.710237) (xy 300.197484 -361.671528) (xy 300.163398 -361.627385) (xy 300.136102 -361.57875)
			(xy 300.116179 -361.526659) (xy 300.104053 -361.472222) (xy 300.099982 -361.4166) (xy 297.176959 -361.4166)
			(xy 297.164814 -361.479616) (xy 297.140953 -361.560883) (xy 297.109474 -361.639513) (xy 297.070663 -361.714794)
			(xy 297.024873 -361.786046) (xy 296.972517 -361.852622) (xy 296.914069 -361.91392) (xy 296.850059 -361.969385)
			(xy 296.781067 -362.018514) (xy 296.707717 -362.060863) (xy 296.630674 -362.096047) (xy 296.550635 -362.123749)
			(xy 296.468326 -362.143717) (xy 296.384491 -362.15577) (xy 296.29989 -362.159801) (xy 296.215289 -362.15577)
			(xy 296.131454 -362.143717) (xy 296.049145 -362.123749) (xy 295.969106 -362.096047) (xy 295.892063 -362.060863)
			(xy 295.818713 -362.018514) (xy 295.749721 -361.969385) (xy 295.685711 -361.91392) (xy 295.627263 -361.852622)
			(xy 295.574907 -361.786046) (xy 295.529117 -361.714794) (xy 295.490306 -361.639513) (xy 295.458827 -361.560883)
			(xy 295.434966 -361.479616) (xy 295.418937 -361.39645) (xy 295.410886 -361.312136) (xy 291.28086 -361.312136)
			(xy 291.281712 -361.312874) (xy 291.317403 -361.354062) (xy 291.34687 -361.399909) (xy 291.369513 -361.449483)
			(xy 291.38487 -361.501775) (xy 291.39263 -361.55572) (xy 291.393118 -361.58297) (xy 291.3926 -361.612245)
			(xy 291.383625 -361.670104) (xy 291.365911 -361.725911) (xy 291.339876 -361.778355) (xy 291.306131 -361.826203)
			(xy 291.286184 -361.847638) (xy 291.279072 -361.855004) (xy 291.27196 -361.873546) (xy 291.27323 -361.965494)
			(xy 291.281104 -361.983782) (xy 291.28847 -361.990894) (xy 291.30629 -362.008912) (xy 291.33752 -362.048822)
			(xy 291.36319 -362.092515) (xy 291.38285 -362.139223) (xy 291.393562 -362.1786) (xy 302.131982 -362.1786)
			(xy 302.136053 -362.122978) (xy 302.148179 -362.068541) (xy 302.168102 -362.01645) (xy 302.195398 -361.967815)
			(xy 302.229484 -361.923672) (xy 302.269633 -361.884963) (xy 302.314991 -361.852512) (xy 302.364591 -361.827011)
			(xy 302.417375 -361.809004) (xy 302.472218 -361.798874) (xy 302.527952 -361.796837) (xy 302.583389 -361.802937)
			(xy 302.637346 -361.817043) (xy 302.688675 -361.838855) (xy 302.736281 -361.867909) (xy 302.779149 -361.903584)
			(xy 302.816366 -361.945121) (xy 302.847139 -361.991634) (xy 302.870811 -362.042131) (xy 302.886879 -362.095538)
			(xy 302.894999 -362.150714) (xy 302.895508 -362.1786) (xy 302.894999 -362.206486) (xy 302.886879 -362.261662)
			(xy 302.870811 -362.315069) (xy 302.847139 -362.365566) (xy 302.816366 -362.412079) (xy 302.779149 -362.453616)
			(xy 302.736281 -362.489291) (xy 302.688675 -362.518345) (xy 302.637346 -362.540157) (xy 302.583389 -362.554263)
			(xy 302.527952 -362.560363) (xy 302.472218 -362.558326) (xy 302.417375 -362.548196) (xy 302.364591 -362.530189)
			(xy 302.314991 -362.504688) (xy 302.269633 -362.472237) (xy 302.229484 -362.433528) (xy 302.195398 -362.389385)
			(xy 302.168102 -362.34075) (xy 302.148179 -362.288659) (xy 302.136053 -362.234222) (xy 302.131982 -362.1786)
			(xy 291.393562 -362.1786) (xy 291.396152 -362.188122) (xy 291.402863 -362.238352) (xy 291.403278 -362.26369)
			(xy 291.402811 -362.29106) (xy 291.394995 -362.34524) (xy 291.379506 -362.397743) (xy 291.356664 -362.44749)
			(xy 291.326939 -362.493456) (xy 291.309298 -362.514388) (xy 291.303202 -362.5215) (xy 291.296852 -362.538518)
			(xy 291.296852 -362.623862) (xy 291.303202 -362.64088) (xy 291.309298 -362.647992) (xy 291.326928 -362.668933)
			(xy 291.356651 -362.7149) (xy 291.379496 -362.764645) (xy 291.394992 -362.817146) (xy 291.39815 -362.839)
			(xy 300.582582 -362.839) (xy 300.586653 -362.783378) (xy 300.598779 -362.728941) (xy 300.618702 -362.67685)
			(xy 300.645998 -362.628215) (xy 300.680084 -362.584072) (xy 300.720233 -362.545363) (xy 300.765591 -362.512912)
			(xy 300.815191 -362.487411) (xy 300.867975 -362.469404) (xy 300.922818 -362.459274) (xy 300.978552 -362.457237)
			(xy 301.033989 -362.463337) (xy 301.087946 -362.477443) (xy 301.139275 -362.499255) (xy 301.186881 -362.528309)
			(xy 301.227533 -362.56214) (xy 305.030376 -362.56214) (xy 305.034447 -362.506518) (xy 305.046573 -362.452081)
			(xy 305.066496 -362.39999) (xy 305.093792 -362.351355) (xy 305.127878 -362.307212) (xy 305.168027 -362.268503)
			(xy 305.213385 -362.236052) (xy 305.262985 -362.210551) (xy 305.315769 -362.192544) (xy 305.370612 -362.182414)
			(xy 305.426346 -362.180377) (xy 305.481783 -362.186477) (xy 305.53574 -362.200583) (xy 305.587069 -362.222395)
			(xy 305.634675 -362.251449) (xy 305.677543 -362.287124) (xy 305.71476 -362.328661) (xy 305.745533 -362.375174)
			(xy 305.769205 -362.425671) (xy 305.785273 -362.479078) (xy 305.793393 -362.534254) (xy 305.793902 -362.56214)
			(xy 305.793393 -362.590026) (xy 305.785273 -362.645202) (xy 305.769205 -362.698609) (xy 305.745533 -362.749106)
			(xy 305.719164 -362.788962) (xy 320.244722 -362.788962) (xy 320.248793 -362.73334) (xy 320.260919 -362.678903)
			(xy 320.280842 -362.626812) (xy 320.308138 -362.578177) (xy 320.342224 -362.534034) (xy 320.382373 -362.495325)
			(xy 320.427731 -362.462874) (xy 320.477331 -362.437373) (xy 320.530115 -362.419366) (xy 320.584958 -362.409236)
			(xy 320.640692 -362.407199) (xy 320.696129 -362.413299) (xy 320.750086 -362.427405) (xy 320.801415 -362.449217)
			(xy 320.849021 -362.478271) (xy 320.891889 -362.513946) (xy 320.929106 -362.555483) (xy 320.959879 -362.601996)
			(xy 320.963819 -362.6104) (xy 326.668382 -362.6104) (xy 326.672453 -362.554778) (xy 326.684579 -362.500341)
			(xy 326.704502 -362.44825) (xy 326.731798 -362.399615) (xy 326.765884 -362.355472) (xy 326.806033 -362.316763)
			(xy 326.851391 -362.284312) (xy 326.900991 -362.258811) (xy 326.953775 -362.240804) (xy 327.008618 -362.230674)
			(xy 327.064352 -362.228637) (xy 327.119789 -362.234737) (xy 327.173746 -362.248843) (xy 327.225075 -362.270655)
			(xy 327.272681 -362.299709) (xy 327.315549 -362.335384) (xy 327.352766 -362.376921) (xy 327.383539 -362.423434)
			(xy 327.407211 -362.473931) (xy 327.423279 -362.527338) (xy 327.431399 -362.582514) (xy 327.431908 -362.6104)
			(xy 327.431444 -362.6358) (xy 328.801982 -362.6358) (xy 328.806053 -362.580178) (xy 328.818179 -362.525741)
			(xy 328.838102 -362.47365) (xy 328.865398 -362.425015) (xy 328.899484 -362.380872) (xy 328.939633 -362.342163)
			(xy 328.984991 -362.309712) (xy 329.034591 -362.284211) (xy 329.087375 -362.266204) (xy 329.142218 -362.256074)
			(xy 329.197952 -362.254037) (xy 329.253389 -362.260137) (xy 329.307346 -362.274243) (xy 329.358675 -362.296055)
			(xy 329.406281 -362.325109) (xy 329.449149 -362.360784) (xy 329.486366 -362.402321) (xy 329.517139 -362.448834)
			(xy 329.540811 -362.499331) (xy 329.556879 -362.552738) (xy 329.564999 -362.607914) (xy 329.565508 -362.6358)
			(xy 330.300582 -362.6358) (xy 330.304653 -362.580178) (xy 330.316779 -362.525741) (xy 330.336702 -362.47365)
			(xy 330.363998 -362.425015) (xy 330.398084 -362.380872) (xy 330.438233 -362.342163) (xy 330.483591 -362.309712)
			(xy 330.533191 -362.284211) (xy 330.585975 -362.266204) (xy 330.640818 -362.256074) (xy 330.696552 -362.254037)
			(xy 330.751989 -362.260137) (xy 330.805946 -362.274243) (xy 330.857275 -362.296055) (xy 330.904881 -362.325109)
			(xy 330.947749 -362.360784) (xy 330.984966 -362.402321) (xy 331.015739 -362.448834) (xy 331.039411 -362.499331)
			(xy 331.055479 -362.552738) (xy 331.063599 -362.607914) (xy 331.064108 -362.6358) (xy 331.063599 -362.663686)
			(xy 331.055479 -362.718862) (xy 331.039411 -362.772269) (xy 331.015739 -362.822766) (xy 330.984966 -362.869279)
			(xy 330.947749 -362.910816) (xy 330.904881 -362.946491) (xy 330.857275 -362.975545) (xy 330.805946 -362.997357)
			(xy 330.751989 -363.011463) (xy 330.696552 -363.017563) (xy 330.640818 -363.015526) (xy 330.585975 -363.005396)
			(xy 330.533191 -362.987389) (xy 330.483591 -362.961888) (xy 330.438233 -362.929437) (xy 330.398084 -362.890728)
			(xy 330.363998 -362.846585) (xy 330.336702 -362.79795) (xy 330.316779 -362.745859) (xy 330.304653 -362.691422)
			(xy 330.300582 -362.6358) (xy 329.565508 -362.6358) (xy 329.564999 -362.663686) (xy 329.556879 -362.718862)
			(xy 329.540811 -362.772269) (xy 329.517139 -362.822766) (xy 329.486366 -362.869279) (xy 329.449149 -362.910816)
			(xy 329.406281 -362.946491) (xy 329.358675 -362.975545) (xy 329.307346 -362.997357) (xy 329.253389 -363.011463)
			(xy 329.197952 -363.017563) (xy 329.142218 -363.015526) (xy 329.087375 -363.005396) (xy 329.034591 -362.987389)
			(xy 328.984991 -362.961888) (xy 328.939633 -362.929437) (xy 328.899484 -362.890728) (xy 328.865398 -362.846585)
			(xy 328.838102 -362.79795) (xy 328.818179 -362.745859) (xy 328.806053 -362.691422) (xy 328.801982 -362.6358)
			(xy 327.431444 -362.6358) (xy 327.431399 -362.638286) (xy 327.423279 -362.693462) (xy 327.407211 -362.746869)
			(xy 327.383539 -362.797366) (xy 327.352766 -362.843879) (xy 327.315549 -362.885416) (xy 327.272681 -362.921091)
			(xy 327.225075 -362.950145) (xy 327.173746 -362.971957) (xy 327.119789 -362.986063) (xy 327.064352 -362.992163)
			(xy 327.008618 -362.990126) (xy 326.953775 -362.979996) (xy 326.900991 -362.961989) (xy 326.851391 -362.936488)
			(xy 326.806033 -362.904037) (xy 326.765884 -362.865328) (xy 326.731798 -362.821185) (xy 326.704502 -362.77255)
			(xy 326.684579 -362.720459) (xy 326.672453 -362.666022) (xy 326.668382 -362.6104) (xy 320.963819 -362.6104)
			(xy 320.983551 -362.652493) (xy 320.999619 -362.7059) (xy 321.007739 -362.761076) (xy 321.008248 -362.788962)
			(xy 321.007739 -362.816848) (xy 320.999619 -362.872024) (xy 320.983551 -362.925431) (xy 320.959879 -362.975928)
			(xy 320.929106 -363.022441) (xy 320.891889 -363.063978) (xy 320.849021 -363.099653) (xy 320.801415 -363.128707)
			(xy 320.750086 -363.150519) (xy 320.696129 -363.164625) (xy 320.640692 -363.170725) (xy 320.584958 -363.168688)
			(xy 320.530115 -363.158558) (xy 320.477331 -363.140551) (xy 320.427731 -363.11505) (xy 320.382373 -363.082599)
			(xy 320.342224 -363.04389) (xy 320.308138 -362.999747) (xy 320.280842 -362.951112) (xy 320.260919 -362.899021)
			(xy 320.248793 -362.844584) (xy 320.244722 -362.788962) (xy 305.719164 -362.788962) (xy 305.71476 -362.795619)
			(xy 305.677543 -362.837156) (xy 305.634675 -362.872831) (xy 305.587069 -362.901885) (xy 305.53574 -362.923697)
			(xy 305.481783 -362.937803) (xy 305.426346 -362.943903) (xy 305.370612 -362.941866) (xy 305.315769 -362.931736)
			(xy 305.262985 -362.913729) (xy 305.213385 -362.888228) (xy 305.168027 -362.855777) (xy 305.127878 -362.817068)
			(xy 305.093792 -362.772925) (xy 305.066496 -362.72429) (xy 305.046573 -362.672199) (xy 305.034447 -362.617762)
			(xy 305.030376 -362.56214) (xy 301.227533 -362.56214) (xy 301.229749 -362.563984) (xy 301.266966 -362.605521)
			(xy 301.297739 -362.652034) (xy 301.321411 -362.702531) (xy 301.337479 -362.755938) (xy 301.345599 -362.811114)
			(xy 301.346108 -362.839) (xy 301.345599 -362.866886) (xy 301.337479 -362.922062) (xy 301.321411 -362.975469)
			(xy 301.297739 -363.025966) (xy 301.266966 -363.072479) (xy 301.229749 -363.114016) (xy 301.186881 -363.149691)
			(xy 301.139275 -363.178745) (xy 301.087946 -363.200557) (xy 301.033989 -363.214663) (xy 300.978552 -363.220763)
			(xy 300.922818 -363.218726) (xy 300.867975 -363.208596) (xy 300.815191 -363.190589) (xy 300.765591 -363.165088)
			(xy 300.720233 -363.132637) (xy 300.680084 -363.093928) (xy 300.645998 -363.049785) (xy 300.618702 -363.00115)
			(xy 300.598779 -362.949059) (xy 300.586653 -362.894622) (xy 300.582582 -362.839) (xy 291.39815 -362.839)
			(xy 291.402821 -362.871323) (xy 291.402822 -362.926062) (xy 291.394995 -362.98024) (xy 291.379501 -363.032741)
			(xy 291.356658 -363.082487) (xy 291.326937 -363.128455) (xy 291.309298 -363.149388) (xy 291.303202 -363.1565)
			(xy 291.296852 -363.173518) (xy 291.296852 -363.23905) (xy 318.698878 -363.23905) (xy 318.702949 -363.183428)
			(xy 318.715075 -363.128991) (xy 318.734998 -363.0769) (xy 318.762294 -363.028265) (xy 318.79638 -362.984122)
			(xy 318.836529 -362.945413) (xy 318.881887 -362.912962) (xy 318.931487 -362.887461) (xy 318.984271 -362.869454)
			(xy 319.039114 -362.859324) (xy 319.094848 -362.857287) (xy 319.150285 -362.863387) (xy 319.204242 -362.877493)
			(xy 319.255571 -362.899305) (xy 319.303177 -362.928359) (xy 319.346045 -362.964034) (xy 319.383262 -363.005571)
			(xy 319.414035 -363.052084) (xy 319.437707 -363.102581) (xy 319.453775 -363.155988) (xy 319.461895 -363.211164)
			(xy 319.462154 -363.225334) (xy 356.693976 -363.225334) (xy 356.698047 -363.169712) (xy 356.710173 -363.115275)
			(xy 356.730096 -363.063184) (xy 356.757392 -363.014549) (xy 356.791478 -362.970406) (xy 356.831627 -362.931697)
			(xy 356.876985 -362.899246) (xy 356.926585 -362.873745) (xy 356.979369 -362.855738) (xy 357.034212 -362.845608)
			(xy 357.089946 -362.843571) (xy 357.145383 -362.849671) (xy 357.19934 -362.863777) (xy 357.250669 -362.885589)
			(xy 357.298275 -362.914643) (xy 357.341143 -362.950318) (xy 357.37836 -362.991855) (xy 357.409133 -363.038368)
			(xy 357.432805 -363.088865) (xy 357.448873 -363.142272) (xy 357.456993 -363.197448) (xy 357.457502 -363.225334)
			(xy 357.456993 -363.25322) (xy 357.448873 -363.308396) (xy 357.432805 -363.361803) (xy 357.409133 -363.4123)
			(xy 357.37836 -363.458813) (xy 357.341143 -363.50035) (xy 357.298275 -363.536025) (xy 357.250669 -363.565079)
			(xy 357.19934 -363.586891) (xy 357.145383 -363.600997) (xy 357.089946 -363.607097) (xy 357.034212 -363.60506)
			(xy 356.979369 -363.59493) (xy 356.926585 -363.576923) (xy 356.876985 -363.551422) (xy 356.831627 -363.518971)
			(xy 356.791478 -363.480262) (xy 356.757392 -363.436119) (xy 356.730096 -363.387484) (xy 356.710173 -363.335393)
			(xy 356.698047 -363.280956) (xy 356.693976 -363.225334) (xy 319.462154 -363.225334) (xy 319.462404 -363.23905)
			(xy 319.461895 -363.266936) (xy 319.453775 -363.322112) (xy 319.437707 -363.375519) (xy 319.414035 -363.426016)
			(xy 319.383262 -363.472529) (xy 319.346045 -363.514066) (xy 319.303177 -363.549741) (xy 319.255571 -363.578795)
			(xy 319.204242 -363.600607) (xy 319.150285 -363.614713) (xy 319.094848 -363.620813) (xy 319.039114 -363.618776)
			(xy 318.984271 -363.608646) (xy 318.931487 -363.590639) (xy 318.881887 -363.565138) (xy 318.836529 -363.532687)
			(xy 318.79638 -363.493978) (xy 318.762294 -363.449835) (xy 318.734998 -363.4012) (xy 318.715075 -363.349109)
			(xy 318.702949 -363.294672) (xy 318.698878 -363.23905) (xy 291.296852 -363.23905) (xy 291.296852 -363.258862)
			(xy 291.303202 -363.27588) (xy 291.309298 -363.282992) (xy 291.326928 -363.303933) (xy 291.356651 -363.3499)
			(xy 291.379496 -363.399645) (xy 291.394992 -363.452146) (xy 291.402821 -363.506323) (xy 291.402822 -363.561062)
			(xy 291.394995 -363.61524) (xy 291.379501 -363.667741) (xy 291.356658 -363.717487) (xy 291.326937 -363.763455)
			(xy 291.309298 -363.784388) (xy 291.303202 -363.7915) (xy 291.296852 -363.808518) (xy 291.296852 -363.846872)
			(xy 305.046632 -363.846872) (xy 305.050703 -363.79125) (xy 305.062829 -363.736813) (xy 305.082752 -363.684722)
			(xy 305.110048 -363.636087) (xy 305.144134 -363.591944) (xy 305.184283 -363.553235) (xy 305.229641 -363.520784)
			(xy 305.279241 -363.495283) (xy 305.332025 -363.477276) (xy 305.386868 -363.467146) (xy 305.442602 -363.465109)
			(xy 305.498039 -363.471209) (xy 305.551996 -363.485315) (xy 305.603325 -363.507127) (xy 305.650931 -363.536181)
			(xy 305.693799 -363.571856) (xy 305.731016 -363.613393) (xy 305.761789 -363.659906) (xy 305.785461 -363.710403)
			(xy 305.798954 -363.755251) (xy 323.849978 -363.755251) (xy 323.849978 -363.700749) (xy 323.857734 -363.646801)
			(xy 323.873089 -363.594506) (xy 323.895731 -363.544929) (xy 323.925197 -363.499079) (xy 323.960888 -363.457888)
			(xy 324.002079 -363.422197) (xy 324.047929 -363.392731) (xy 324.097506 -363.370089) (xy 324.149801 -363.354734)
			(xy 324.203749 -363.346978) (xy 324.231 -363.346492) (xy 324.260231 -363.347055) (xy 324.318006 -363.355987)
			(xy 324.373743 -363.373627) (xy 324.426137 -363.399561) (xy 324.473962 -363.433183) (xy 324.5161 -363.473706)
			(xy 324.534276 -363.496606) (xy 324.542714 -363.507003) (xy 324.563918 -363.52334) (xy 324.588637 -363.533613)
			(xy 324.615175 -363.537118) (xy 324.641713 -363.533613) (xy 324.666432 -363.52334) (xy 324.687636 -363.507003)
			(xy 324.696074 -363.496606) (xy 324.714223 -363.473681) (xy 324.756356 -363.433141) (xy 324.804183 -363.399509)
			(xy 324.856584 -363.373571) (xy 324.912331 -363.355937) (xy 324.970115 -363.347019) (xy 324.99935 -363.346492)
			(xy 325.026605 -363.346952) (xy 325.080562 -363.354703) (xy 325.132865 -363.370055) (xy 325.182452 -363.392694)
			(xy 325.228311 -363.422161) (xy 325.26951 -363.457855) (xy 325.305209 -363.499049) (xy 325.334682 -363.544904)
			(xy 325.357328 -363.594488) (xy 325.372686 -363.64679) (xy 325.373406 -363.6518) (xy 326.693782 -363.6518)
			(xy 326.697853 -363.596178) (xy 326.709979 -363.541741) (xy 326.729902 -363.48965) (xy 326.757198 -363.441015)
			(xy 326.791284 -363.396872) (xy 326.831433 -363.358163) (xy 326.876791 -363.325712) (xy 326.926391 -363.300211)
			(xy 326.979175 -363.282204) (xy 327.034018 -363.272074) (xy 327.089752 -363.270037) (xy 327.145189 -363.276137)
			(xy 327.199146 -363.290243) (xy 327.250475 -363.312055) (xy 327.298081 -363.341109) (xy 327.340949 -363.376784)
			(xy 327.378166 -363.418321) (xy 327.408939 -363.464834) (xy 327.432611 -363.515331) (xy 327.448679 -363.568738)
			(xy 327.456799 -363.623914) (xy 327.457308 -363.6518) (xy 327.709782 -363.6518) (xy 327.713853 -363.596178)
			(xy 327.725979 -363.541741) (xy 327.745902 -363.48965) (xy 327.773198 -363.441015) (xy 327.807284 -363.396872)
			(xy 327.847433 -363.358163) (xy 327.892791 -363.325712) (xy 327.942391 -363.300211) (xy 327.995175 -363.282204)
			(xy 328.050018 -363.272074) (xy 328.105752 -363.270037) (xy 328.161189 -363.276137) (xy 328.215146 -363.290243)
			(xy 328.266475 -363.312055) (xy 328.314081 -363.341109) (xy 328.356949 -363.376784) (xy 328.394166 -363.418321)
			(xy 328.424939 -363.464834) (xy 328.448611 -363.515331) (xy 328.464679 -363.568738) (xy 328.472799 -363.623914)
			(xy 328.473308 -363.6518) (xy 328.472799 -363.679686) (xy 328.464679 -363.734862) (xy 328.448611 -363.788269)
			(xy 328.424939 -363.838766) (xy 328.394166 -363.885279) (xy 328.356949 -363.926816) (xy 328.314081 -363.962491)
			(xy 328.266475 -363.991545) (xy 328.215146 -364.013357) (xy 328.161189 -364.027463) (xy 328.105752 -364.033563)
			(xy 328.050018 -364.031526) (xy 327.995175 -364.021396) (xy 327.942391 -364.003389) (xy 327.892791 -363.977888)
			(xy 327.847433 -363.945437) (xy 327.807284 -363.906728) (xy 327.773198 -363.862585) (xy 327.745902 -363.81395)
			(xy 327.725979 -363.761859) (xy 327.713853 -363.707422) (xy 327.709782 -363.6518) (xy 327.457308 -363.6518)
			(xy 327.456799 -363.679686) (xy 327.448679 -363.734862) (xy 327.432611 -363.788269) (xy 327.408939 -363.838766)
			(xy 327.378166 -363.885279) (xy 327.340949 -363.926816) (xy 327.298081 -363.962491) (xy 327.250475 -363.991545)
			(xy 327.199146 -364.013357) (xy 327.145189 -364.027463) (xy 327.089752 -364.033563) (xy 327.034018 -364.031526)
			(xy 326.979175 -364.021396) (xy 326.926391 -364.003389) (xy 326.876791 -363.977888) (xy 326.831433 -363.945437)
			(xy 326.791284 -363.906728) (xy 326.757198 -363.862585) (xy 326.729902 -363.81395) (xy 326.709979 -363.761859)
			(xy 326.697853 -363.707422) (xy 326.693782 -363.6518) (xy 325.373406 -363.6518) (xy 325.380445 -363.700745)
			(xy 325.380445 -363.755255) (xy 325.372686 -363.80921) (xy 325.357328 -363.861512) (xy 325.334682 -363.911096)
			(xy 325.305209 -363.956951) (xy 325.26951 -363.998145) (xy 325.228311 -364.033839) (xy 325.182452 -364.063306)
			(xy 325.132865 -364.085945) (xy 325.080562 -364.101297) (xy 325.026605 -364.109048) (xy 324.99935 -364.109508)
			(xy 324.970118 -364.108981) (xy 324.912341 -364.100041) (xy 324.856604 -364.082395) (xy 324.80421 -364.056454)
			(xy 324.756385 -364.022825) (xy 324.714249 -363.982296) (xy 324.696074 -363.959394) (xy 324.687663 -363.948953)
			(xy 324.666477 -363.932535) (xy 324.641745 -363.922206) (xy 324.615175 -363.918682) (xy 324.588605 -363.922206)
			(xy 324.563873 -363.932535) (xy 324.542687 -363.948953) (xy 324.534276 -363.959394) (xy 324.516077 -363.982276)
			(xy 324.473954 -364.022814) (xy 324.426136 -364.056447) (xy 324.373744 -364.082387) (xy 324.318007 -364.100025)
			(xy 324.260231 -364.108949) (xy 324.231 -364.109508) (xy 324.203749 -364.109022) (xy 324.149801 -364.101266)
			(xy 324.097506 -364.085911) (xy 324.047929 -364.063269) (xy 324.002079 -364.033803) (xy 323.960888 -363.998112)
			(xy 323.925197 -363.956921) (xy 323.895731 -363.911071) (xy 323.873089 -363.861494) (xy 323.857734 -363.809199)
			(xy 323.849978 -363.755251) (xy 305.798954 -363.755251) (xy 305.801529 -363.76381) (xy 305.809649 -363.818986)
			(xy 305.810158 -363.846872) (xy 305.809649 -363.874758) (xy 305.801529 -363.929934) (xy 305.785461 -363.983341)
			(xy 305.761789 -364.033838) (xy 305.731016 -364.080351) (xy 305.693799 -364.121888) (xy 305.650931 -364.157563)
			(xy 305.603325 -364.186617) (xy 305.551996 -364.208429) (xy 305.498039 -364.222535) (xy 305.442602 -364.228635)
			(xy 305.386868 -364.226598) (xy 305.332025 -364.216468) (xy 305.279241 -364.198461) (xy 305.229641 -364.17296)
			(xy 305.184283 -364.140509) (xy 305.144134 -364.1018) (xy 305.110048 -364.057657) (xy 305.082752 -364.009022)
			(xy 305.062829 -363.956931) (xy 305.050703 -363.902494) (xy 305.046632 -363.846872) (xy 291.296852 -363.846872)
			(xy 291.296852 -363.893862) (xy 291.303202 -363.91088) (xy 291.309298 -363.917992) (xy 291.326946 -363.938917)
			(xy 291.356657 -363.984891) (xy 291.379491 -364.034641) (xy 291.39498 -364.087143) (xy 291.402805 -364.14132)
			(xy 291.403278 -364.16869) (xy 291.402835 -364.195944) (xy 291.395079 -364.249897) (xy 291.379723 -364.302197)
			(xy 291.357079 -364.351779) (xy 291.327609 -364.397634) (xy 291.291913 -364.438828) (xy 291.250718 -364.474521)
			(xy 291.204862 -364.503989) (xy 291.155278 -364.52663) (xy 291.102978 -364.541983) (xy 291.049024 -364.549737)
			(xy 291.02177 -364.550198) (xy 290.995926 -364.549734) (xy 290.944713 -364.542753) (xy 290.89491 -364.528922)
			(xy 290.847431 -364.508494) (xy 290.803143 -364.481845) (xy 290.762859 -364.44946) (xy 290.727315 -364.411934)
			(xy 290.71189 -364.391194) (xy 290.704778 -364.381288) (xy 290.68395 -364.370366) (xy 290.578286 -364.367826)
			(xy 290.55695 -364.377986) (xy 290.54933 -364.387638) (xy 290.531166 -364.40993) (xy 290.489227 -364.449271)
			(xy 290.441856 -364.481868) (xy 290.390127 -364.506981) (xy 290.335214 -364.524042) (xy 290.278361 -364.532664)
			(xy 290.24961 -364.53318) (xy 290.22224 -364.532713) (xy 290.168061 -364.524896) (xy 290.115557 -364.509408)
			(xy 290.06581 -364.486566) (xy 290.019844 -364.456841) (xy 289.998912 -364.4392) (xy 289.9918 -364.433104)
			(xy 289.974782 -364.426754) (xy 289.889438 -364.426754) (xy 289.87242 -364.433104) (xy 289.865308 -364.4392)
			(xy 289.844384 -364.456849) (xy 289.798409 -364.486559) (xy 289.748659 -364.509393) (xy 289.696157 -364.524882)
			(xy 289.64198 -364.532707) (xy 289.61461 -364.53318) (xy 289.587035 -364.532714) (xy 289.532462 -364.524763)
			(xy 289.479602 -364.509038) (xy 289.429556 -364.485868) (xy 289.383366 -364.455735) (xy 289.341996 -364.419267)
			(xy 289.32378 -364.39856) (xy 289.316188 -364.390431) (xy 289.296028 -364.381084) (xy 289.284918 -364.380526)
			(xy 289.207702 -364.380526) (xy 289.196589 -364.381071) (xy 289.17643 -364.390425) (xy 289.16884 -364.39856)
			(xy 289.150602 -364.419247) (xy 289.10924 -364.455721) (xy 289.063056 -364.485857) (xy 289.013013 -364.509027)
			(xy 288.960155 -364.524748) (xy 288.905583 -364.532693) (xy 288.87801 -364.53318) (xy 288.85064 -364.532713)
			(xy 288.796461 -364.524896) (xy 288.743957 -364.509408) (xy 288.69421 -364.486566) (xy 288.648244 -364.456841)
			(xy 288.627312 -364.4392) (xy 288.6202 -364.433104) (xy 288.603182 -364.426754) (xy 288.517838 -364.426754)
			(xy 288.50082 -364.433104) (xy 288.493708 -364.4392) (xy 288.472775 -364.456841) (xy 288.426807 -364.486565)
			(xy 288.377061 -364.509411) (xy 288.324559 -364.524907) (xy 288.270381 -364.532736) (xy 288.215639 -364.532736)
			(xy 288.161461 -364.524907) (xy 288.108959 -364.509411) (xy 288.059213 -364.486565) (xy 288.013245 -364.456841)
			(xy 287.992312 -364.4392) (xy 287.9852 -364.433104) (xy 287.968182 -364.426754) (xy 287.882838 -364.426754)
			(xy 287.86582 -364.433104) (xy 287.858708 -364.4392) (xy 287.837775 -364.456841) (xy 287.791807 -364.486565)
			(xy 287.742061 -364.509411) (xy 287.689559 -364.524907) (xy 287.635381 -364.532736) (xy 287.580639 -364.532736)
			(xy 287.526461 -364.524907) (xy 287.473959 -364.509411) (xy 287.424213 -364.486565) (xy 287.378245 -364.456841)
			(xy 287.357312 -364.4392) (xy 287.3502 -364.433104) (xy 287.333182 -364.426754) (xy 287.247838 -364.426754)
			(xy 287.23082 -364.433104) (xy 287.223708 -364.4392) (xy 287.202784 -364.456849) (xy 287.156809 -364.486559)
			(xy 287.107059 -364.509393) (xy 287.054557 -364.524882) (xy 287.00038 -364.532707) (xy 286.97301 -364.53318)
			(xy 286.945435 -364.532714) (xy 286.890862 -364.524763) (xy 286.838002 -364.509038) (xy 286.787956 -364.485868)
			(xy 286.741766 -364.455735) (xy 286.700396 -364.419267) (xy 286.68218 -364.39856) (xy 286.674588 -364.390431)
			(xy 286.654428 -364.381084) (xy 286.643318 -364.380526) (xy 286.566102 -364.380526) (xy 286.554989 -364.381071)
			(xy 286.53483 -364.390425) (xy 286.52724 -364.39856) (xy 286.509002 -364.419247) (xy 286.46764 -364.455721)
			(xy 286.421456 -364.485857) (xy 286.371413 -364.509027) (xy 286.318555 -364.524748) (xy 286.263983 -364.532693)
			(xy 286.23641 -364.53318) (xy 286.20904 -364.532713) (xy 286.154861 -364.524896) (xy 286.102357 -364.509408)
			(xy 286.05261 -364.486566) (xy 286.006644 -364.456841) (xy 285.985712 -364.4392) (xy 285.9786 -364.433104)
			(xy 285.961582 -364.426754) (xy 285.876238 -364.426754) (xy 285.85922 -364.433104) (xy 285.852108 -364.4392)
			(xy 285.831184 -364.456849) (xy 285.785209 -364.486559) (xy 285.735459 -364.509393) (xy 285.682957 -364.524882)
			(xy 285.62878 -364.532707) (xy 285.60141 -364.53318) (xy 285.574156 -364.532735) (xy 285.520203 -364.524979)
			(xy 285.467903 -364.509623) (xy 285.418321 -364.486979) (xy 285.372467 -364.45751) (xy 285.331273 -364.421814)
			(xy 285.295579 -364.380619) (xy 285.266112 -364.334763) (xy 285.243471 -364.28518) (xy 285.228117 -364.232879)
			(xy 285.220363 -364.178926) (xy 285.219902 -364.151672) (xy 285.220351 -364.124301) (xy 285.228173 -364.070121)
			(xy 285.243666 -364.017618) (xy 285.266511 -363.967871) (xy 285.296239 -363.921905) (xy 285.313882 -363.900974)
			(xy 285.319978 -363.893862) (xy 285.326328 -363.876844) (xy 285.326328 -363.7915) (xy 285.319978 -363.774482)
			(xy 285.313882 -363.76737) (xy 285.296216 -363.746459) (xy 285.266496 -363.700486) (xy 285.243655 -363.650736)
			(xy 285.228162 -363.598231) (xy 285.220337 -363.54405) (xy 285.22034 -363.489308) (xy 285.228171 -363.435128)
			(xy 285.243669 -363.382625) (xy 285.266516 -363.332877) (xy 285.296241 -363.286908) (xy 285.313882 -363.265974)
			(xy 285.319978 -363.258862) (xy 285.326328 -363.241844) (xy 285.326328 -363.1565) (xy 285.319978 -363.139482)
			(xy 285.313882 -363.13237) (xy 285.296216 -363.111459) (xy 285.266496 -363.065486) (xy 285.243655 -363.015736)
			(xy 285.228162 -362.963231) (xy 285.220337 -362.90905) (xy 285.22034 -362.854308) (xy 285.228171 -362.800128)
			(xy 285.243669 -362.747625) (xy 285.266516 -362.697877) (xy 285.296241 -362.651908) (xy 285.313882 -362.630974)
			(xy 285.319978 -362.623862) (xy 285.326328 -362.606844) (xy 285.326328 -362.5215) (xy 285.319978 -362.504482)
			(xy 285.313882 -362.49737) (xy 285.296259 -362.476425) (xy 285.266546 -362.430455) (xy 285.243707 -362.380711)
			(xy 285.228212 -362.328213) (xy 285.220379 -362.27404) (xy 285.219902 -362.246672) (xy 285.22044 -362.217398)
			(xy 285.22941 -362.159539) (xy 285.247118 -362.103732) (xy 285.273149 -362.051288) (xy 285.306891 -362.003439)
			(xy 285.326836 -361.982004) (xy 285.333948 -361.974638) (xy 285.34106 -361.956096) (xy 285.33979 -361.864148)
			(xy 285.331916 -361.84586) (xy 285.32455 -361.838748) (xy 285.306706 -361.820753) (xy 285.275478 -361.780839)
			(xy 285.24981 -361.73714) (xy 285.230155 -361.690428) (xy 285.216858 -361.641525) (xy 285.210153 -361.591291)
			(xy 285.209742 -361.565952) (xy 278.320754 -361.565952) (xy 281.397202 -364.6424) (xy 300.398432 -364.6424)
			(xy 300.402503 -364.586778) (xy 300.414629 -364.532341) (xy 300.434552 -364.48025) (xy 300.461848 -364.431615)
			(xy 300.495934 -364.387472) (xy 300.536083 -364.348763) (xy 300.581441 -364.316312) (xy 300.631041 -364.290811)
			(xy 300.683825 -364.272804) (xy 300.738668 -364.262674) (xy 300.794402 -364.260637) (xy 300.849839 -364.266737)
			(xy 300.903796 -364.280843) (xy 300.955125 -364.302655) (xy 301.002731 -364.331709) (xy 301.045599 -364.367384)
			(xy 301.082816 -364.408921) (xy 301.113589 -364.455434) (xy 301.137261 -364.505931) (xy 301.153329 -364.559338)
			(xy 301.161449 -364.614514) (xy 301.161958 -364.6424) (xy 301.161449 -364.670286) (xy 301.153329 -364.725462)
			(xy 301.137261 -364.778869) (xy 301.113589 -364.829366) (xy 301.082816 -364.875879) (xy 301.045599 -364.917416)
			(xy 301.002731 -364.953091) (xy 300.955125 -364.982145) (xy 300.903796 -365.003957) (xy 300.849839 -365.018063)
			(xy 300.794402 -365.024163) (xy 300.738668 -365.022126) (xy 300.683825 -365.011996) (xy 300.631041 -364.993989)
			(xy 300.581441 -364.968488) (xy 300.536083 -364.936037) (xy 300.495934 -364.897328) (xy 300.461848 -364.853185)
			(xy 300.434552 -364.80455) (xy 300.414629 -364.752459) (xy 300.402503 -364.698022) (xy 300.398432 -364.6424)
			(xy 281.397202 -364.6424) (xy 281.879802 -365.125) (xy 302.893982 -365.125) (xy 302.898053 -365.069378)
			(xy 302.910179 -365.014941) (xy 302.930102 -364.96285) (xy 302.957398 -364.914215) (xy 302.991484 -364.870072)
			(xy 303.031633 -364.831363) (xy 303.076991 -364.798912) (xy 303.126591 -364.773411) (xy 303.179375 -364.755404)
			(xy 303.234218 -364.745274) (xy 303.289952 -364.743237) (xy 303.345389 -364.749337) (xy 303.399346 -364.763443)
			(xy 303.450675 -364.785255) (xy 303.498281 -364.814309) (xy 303.541149 -364.849984) (xy 303.578366 -364.891521)
			(xy 303.609139 -364.938034) (xy 303.632811 -364.988531) (xy 303.648879 -365.041938) (xy 303.656999 -365.097114)
			(xy 303.657508 -365.125) (xy 305.190142 -365.125) (xy 305.194213 -365.069378) (xy 305.206339 -365.014941)
			(xy 305.226262 -364.96285) (xy 305.253558 -364.914215) (xy 305.287644 -364.870072) (xy 305.327793 -364.831363)
			(xy 305.373151 -364.798912) (xy 305.422751 -364.773411) (xy 305.475535 -364.755404) (xy 305.530378 -364.745274)
			(xy 305.586112 -364.743237) (xy 305.641549 -364.749337) (xy 305.695506 -364.763443) (xy 305.746835 -364.785255)
			(xy 305.794441 -364.814309) (xy 305.837309 -364.849984) (xy 305.874526 -364.891521) (xy 305.878979 -364.898251)
			(xy 306.984378 -364.898251) (xy 306.984378 -364.843749) (xy 306.992134 -364.789801) (xy 307.007489 -364.737506)
			(xy 307.030131 -364.687929) (xy 307.059597 -364.642079) (xy 307.095288 -364.600888) (xy 307.136479 -364.565197)
			(xy 307.182329 -364.535731) (xy 307.231906 -364.513089) (xy 307.284201 -364.497734) (xy 307.338149 -364.489978)
			(xy 307.3654 -364.489492) (xy 307.391858 -364.489953) (xy 307.444268 -364.497261) (xy 307.495166 -364.511736)
			(xy 307.543578 -364.533102) (xy 307.566314 -364.546642) (xy 307.579346 -364.554087) (xy 307.608341 -364.561787)
			(xy 307.638322 -364.56074) (xy 307.666709 -364.551035) (xy 307.691056 -364.533507) (xy 307.709267 -364.509668)
			(xy 307.719774 -364.481568) (xy 307.721254 -364.466632) (xy 307.723585 -364.437914) (xy 307.735709 -364.381591)
			(xy 307.756165 -364.327731) (xy 307.78449 -364.277561) (xy 307.820038 -364.232222) (xy 307.862001 -364.192745)
			(xy 307.909424 -364.160029) (xy 307.961228 -364.134817) (xy 308.016235 -364.117684) (xy 308.073193 -364.109019)
			(xy 308.102 -364.108492) (xy 308.129251 -364.108978) (xy 308.183199 -364.116734) (xy 308.235494 -364.132089)
			(xy 308.285071 -364.154731) (xy 308.330921 -364.184197) (xy 308.372112 -364.219888) (xy 308.407803 -364.261079)
			(xy 308.437269 -364.306929) (xy 308.459911 -364.356506) (xy 308.475266 -364.408801) (xy 308.483022 -364.462749)
			(xy 308.483022 -364.517251) (xy 308.475266 -364.571199) (xy 308.459911 -364.623494) (xy 308.437269 -364.673071)
			(xy 308.407803 -364.718921) (xy 308.386073 -364.744) (xy 309.370982 -364.744) (xy 309.375053 -364.688378)
			(xy 309.387179 -364.633941) (xy 309.407102 -364.58185) (xy 309.434398 -364.533215) (xy 309.468484 -364.489072)
			(xy 309.508633 -364.450363) (xy 309.553991 -364.417912) (xy 309.603591 -364.392411) (xy 309.656375 -364.374404)
			(xy 309.711218 -364.364274) (xy 309.766952 -364.362237) (xy 309.822389 -364.368337) (xy 309.876346 -364.382443)
			(xy 309.927675 -364.404255) (xy 309.975281 -364.433309) (xy 310.018149 -364.468984) (xy 310.055366 -364.510521)
			(xy 310.086139 -364.557034) (xy 310.109811 -364.607531) (xy 310.125879 -364.660938) (xy 310.133999 -364.716114)
			(xy 310.134508 -364.744) (xy 310.133999 -364.771886) (xy 310.125879 -364.827062) (xy 310.109811 -364.880469)
			(xy 310.086139 -364.930966) (xy 310.055366 -364.977479) (xy 310.0256 -365.0107) (xy 314.463682 -365.0107)
			(xy 314.467753 -364.955078) (xy 314.479879 -364.900641) (xy 314.499802 -364.84855) (xy 314.527098 -364.799915)
			(xy 314.561184 -364.755772) (xy 314.601333 -364.717063) (xy 314.646691 -364.684612) (xy 314.696291 -364.659111)
			(xy 314.749075 -364.641104) (xy 314.803918 -364.630974) (xy 314.859652 -364.628937) (xy 314.915089 -364.635037)
			(xy 314.969046 -364.649143) (xy 315.020375 -364.670955) (xy 315.067981 -364.700009) (xy 315.110849 -364.735684)
			(xy 315.148066 -364.777221) (xy 315.178839 -364.823734) (xy 315.202511 -364.874231) (xy 315.218579 -364.927638)
			(xy 315.226699 -364.982814) (xy 315.227208 -365.0107) (xy 315.226699 -365.038586) (xy 315.218579 -365.093762)
			(xy 315.202511 -365.147169) (xy 315.178839 -365.197666) (xy 315.148066 -365.244179) (xy 315.110849 -365.285716)
			(xy 315.067981 -365.321391) (xy 315.020375 -365.350445) (xy 314.969046 -365.372257) (xy 314.915089 -365.386363)
			(xy 314.859652 -365.392463) (xy 314.803918 -365.390426) (xy 314.749075 -365.380296) (xy 314.696291 -365.362289)
			(xy 314.646691 -365.336788) (xy 314.601333 -365.304337) (xy 314.561184 -365.265628) (xy 314.527098 -365.221485)
			(xy 314.499802 -365.17285) (xy 314.479879 -365.120759) (xy 314.467753 -365.066322) (xy 314.463682 -365.0107)
			(xy 310.0256 -365.0107) (xy 310.018149 -365.019016) (xy 309.975281 -365.054691) (xy 309.927675 -365.083745)
			(xy 309.876346 -365.105557) (xy 309.822389 -365.119663) (xy 309.766952 -365.125763) (xy 309.711218 -365.123726)
			(xy 309.656375 -365.113596) (xy 309.603591 -365.095589) (xy 309.553991 -365.070088) (xy 309.508633 -365.037637)
			(xy 309.468484 -364.998928) (xy 309.434398 -364.954785) (xy 309.407102 -364.90615) (xy 309.387179 -364.854059)
			(xy 309.375053 -364.799622) (xy 309.370982 -364.744) (xy 308.386073 -364.744) (xy 308.372112 -364.760112)
			(xy 308.330921 -364.795803) (xy 308.285071 -364.825269) (xy 308.235494 -364.847911) (xy 308.183199 -364.863266)
			(xy 308.129251 -364.871022) (xy 308.102 -364.871508) (xy 308.075542 -364.871047) (xy 308.023132 -364.863739)
			(xy 307.972234 -364.849264) (xy 307.923822 -364.827898) (xy 307.901086 -364.814358) (xy 307.888054 -364.806913)
			(xy 307.859059 -364.799213) (xy 307.829078 -364.80026) (xy 307.800691 -364.809965) (xy 307.776344 -364.827493)
			(xy 307.758133 -364.851332) (xy 307.747626 -364.879432) (xy 307.746146 -364.894368) (xy 307.743815 -364.923086)
			(xy 307.731691 -364.979409) (xy 307.711235 -365.033269) (xy 307.68291 -365.083439) (xy 307.647362 -365.128778)
			(xy 307.605399 -365.168255) (xy 307.557976 -365.200971) (xy 307.506172 -365.226183) (xy 307.451165 -365.243316)
			(xy 307.394207 -365.251981) (xy 307.3654 -365.252508) (xy 307.338149 -365.252022) (xy 307.284201 -365.244266)
			(xy 307.231906 -365.228911) (xy 307.182329 -365.206269) (xy 307.136479 -365.176803) (xy 307.095288 -365.141112)
			(xy 307.059597 -365.099921) (xy 307.030131 -365.054071) (xy 307.007489 -365.004494) (xy 306.992134 -364.952199)
			(xy 306.984378 -364.898251) (xy 305.878979 -364.898251) (xy 305.905299 -364.938034) (xy 305.928971 -364.988531)
			(xy 305.945039 -365.041938) (xy 305.953159 -365.097114) (xy 305.953668 -365.125) (xy 305.953159 -365.152886)
			(xy 305.945039 -365.208062) (xy 305.928971 -365.261469) (xy 305.905299 -365.311966) (xy 305.874526 -365.358479)
			(xy 305.837309 -365.400016) (xy 305.794441 -365.435691) (xy 305.746835 -365.464745) (xy 305.695506 -365.486557)
			(xy 305.641549 -365.500663) (xy 305.586112 -365.506763) (xy 305.530378 -365.504726) (xy 305.475535 -365.494596)
			(xy 305.422751 -365.476589) (xy 305.373151 -365.451088) (xy 305.327793 -365.418637) (xy 305.287644 -365.379928)
			(xy 305.253558 -365.335785) (xy 305.226262 -365.28715) (xy 305.206339 -365.235059) (xy 305.194213 -365.180622)
			(xy 305.190142 -365.125) (xy 303.657508 -365.125) (xy 303.656999 -365.152886) (xy 303.648879 -365.208062)
			(xy 303.632811 -365.261469) (xy 303.609139 -365.311966) (xy 303.578366 -365.358479) (xy 303.541149 -365.400016)
			(xy 303.498281 -365.435691) (xy 303.450675 -365.464745) (xy 303.399346 -365.486557) (xy 303.345389 -365.500663)
			(xy 303.289952 -365.506763) (xy 303.234218 -365.504726) (xy 303.179375 -365.494596) (xy 303.126591 -365.476589)
			(xy 303.076991 -365.451088) (xy 303.031633 -365.418637) (xy 302.991484 -365.379928) (xy 302.957398 -365.335785)
			(xy 302.930102 -365.28715) (xy 302.910179 -365.235059) (xy 302.898053 -365.180622) (xy 302.893982 -365.125)
			(xy 281.879802 -365.125) (xy 282.42006 -365.665258) (xy 282.42746 -365.6721) (xy 282.446058 -365.679819)
			(xy 282.456128 -365.680244) (xy 297.219624 -365.680244) (xy 297.229691 -365.680673) (xy 297.248285 -365.688398)
			(xy 297.255692 -365.69523) (xy 297.320454 -365.76) (xy 307.059582 -365.76) (xy 307.063653 -365.704378)
			(xy 307.075779 -365.649941) (xy 307.095702 -365.59785) (xy 307.122998 -365.549215) (xy 307.157084 -365.505072)
			(xy 307.197233 -365.466363) (xy 307.242591 -365.433912) (xy 307.292191 -365.408411) (xy 307.344975 -365.390404)
			(xy 307.399818 -365.380274) (xy 307.455552 -365.378237) (xy 307.510989 -365.384337) (xy 307.564946 -365.398443)
			(xy 307.616275 -365.420255) (xy 307.663881 -365.449309) (xy 307.706749 -365.484984) (xy 307.743966 -365.526521)
			(xy 307.774739 -365.573034) (xy 307.798411 -365.623531) (xy 307.814479 -365.676938) (xy 307.819227 -365.7092)
			(xy 308.202582 -365.7092) (xy 308.206653 -365.653578) (xy 308.218779 -365.599141) (xy 308.238702 -365.54705)
			(xy 308.265998 -365.498415) (xy 308.300084 -365.454272) (xy 308.340233 -365.415563) (xy 308.385591 -365.383112)
			(xy 308.435191 -365.357611) (xy 308.487975 -365.339604) (xy 308.542818 -365.329474) (xy 308.598552 -365.327437)
			(xy 308.653989 -365.333537) (xy 308.707946 -365.347643) (xy 308.759275 -365.369455) (xy 308.806881 -365.398509)
			(xy 308.849749 -365.434184) (xy 308.868579 -365.4552) (xy 309.96458 -365.4552) (xy 309.968651 -365.399578)
			(xy 309.980777 -365.345141) (xy 310.0007 -365.29305) (xy 310.027996 -365.244415) (xy 310.062082 -365.200272)
			(xy 310.102231 -365.161563) (xy 310.147589 -365.129112) (xy 310.197189 -365.103611) (xy 310.249973 -365.085604)
			(xy 310.304816 -365.075474) (xy 310.36055 -365.073437) (xy 310.415987 -365.079537) (xy 310.469944 -365.093643)
			(xy 310.521273 -365.115455) (xy 310.568879 -365.144509) (xy 310.611747 -365.180184) (xy 310.648964 -365.221721)
			(xy 310.679737 -365.268234) (xy 310.703409 -365.318731) (xy 310.719477 -365.372138) (xy 310.727597 -365.427314)
			(xy 310.728106 -365.4552) (xy 310.727597 -365.483086) (xy 310.719477 -365.538262) (xy 310.703409 -365.591669)
			(xy 310.679737 -365.642166) (xy 310.648964 -365.688679) (xy 310.611747 -365.730216) (xy 310.568879 -365.765891)
			(xy 310.521273 -365.794945) (xy 310.469944 -365.816757) (xy 310.415987 -365.830863) (xy 310.36055 -365.836963)
			(xy 310.304816 -365.834926) (xy 310.249973 -365.824796) (xy 310.197189 -365.806789) (xy 310.147589 -365.781288)
			(xy 310.102231 -365.748837) (xy 310.062082 -365.710128) (xy 310.027996 -365.665985) (xy 310.0007 -365.61735)
			(xy 309.980777 -365.565259) (xy 309.968651 -365.510822) (xy 309.96458 -365.4552) (xy 308.868579 -365.4552)
			(xy 308.886966 -365.475721) (xy 308.917739 -365.522234) (xy 308.941411 -365.572731) (xy 308.957479 -365.626138)
			(xy 308.965599 -365.681314) (xy 308.966108 -365.7092) (xy 308.965599 -365.737086) (xy 308.957479 -365.792262)
			(xy 308.941411 -365.845669) (xy 308.917739 -365.896166) (xy 308.886966 -365.942679) (xy 308.849749 -365.984216)
			(xy 308.806881 -366.019891) (xy 308.759275 -366.048945) (xy 308.707946 -366.070757) (xy 308.653989 -366.084863)
			(xy 308.598552 -366.090963) (xy 308.542818 -366.088926) (xy 308.487975 -366.078796) (xy 308.435191 -366.060789)
			(xy 308.385591 -366.035288) (xy 308.340233 -366.002837) (xy 308.300084 -365.964128) (xy 308.265998 -365.919985)
			(xy 308.238702 -365.87135) (xy 308.218779 -365.819259) (xy 308.206653 -365.764822) (xy 308.202582 -365.7092)
			(xy 307.819227 -365.7092) (xy 307.822599 -365.732114) (xy 307.823108 -365.76) (xy 307.822599 -365.787886)
			(xy 307.814479 -365.843062) (xy 307.798411 -365.896469) (xy 307.774739 -365.946966) (xy 307.743966 -365.993479)
			(xy 307.706749 -366.035016) (xy 307.663881 -366.070691) (xy 307.616275 -366.099745) (xy 307.564946 -366.121557)
			(xy 307.510989 -366.135663) (xy 307.455552 -366.141763) (xy 307.399818 -366.139726) (xy 307.344975 -366.129596)
			(xy 307.292191 -366.111589) (xy 307.242591 -366.086088) (xy 307.197233 -366.053637) (xy 307.157084 -366.014928)
			(xy 307.122998 -365.970785) (xy 307.095702 -365.92215) (xy 307.075779 -365.870059) (xy 307.063653 -365.815622)
			(xy 307.059582 -365.76) (xy 297.320454 -365.76) (xy 297.955372 -366.395) (xy 302.893982 -366.395)
			(xy 302.898053 -366.339378) (xy 302.910179 -366.284941) (xy 302.930102 -366.23285) (xy 302.957398 -366.184215)
			(xy 302.991484 -366.140072) (xy 303.031633 -366.101363) (xy 303.076991 -366.068912) (xy 303.126591 -366.043411)
			(xy 303.179375 -366.025404) (xy 303.234218 -366.015274) (xy 303.289952 -366.013237) (xy 303.345389 -366.019337)
			(xy 303.399346 -366.033443) (xy 303.450675 -366.055255) (xy 303.498281 -366.084309) (xy 303.541149 -366.119984)
			(xy 303.578366 -366.161521) (xy 303.609139 -366.208034) (xy 303.632811 -366.258531) (xy 303.63566 -366.268)
			(xy 311.951876 -366.268) (xy 311.955947 -366.212378) (xy 311.968073 -366.157941) (xy 311.987996 -366.10585)
			(xy 312.015292 -366.057215) (xy 312.049378 -366.013072) (xy 312.089527 -365.974363) (xy 312.134885 -365.941912)
			(xy 312.184485 -365.916411) (xy 312.237269 -365.898404) (xy 312.292112 -365.888274) (xy 312.347846 -365.886237)
			(xy 312.403283 -365.892337) (xy 312.45724 -365.906443) (xy 312.508569 -365.928255) (xy 312.556175 -365.957309)
			(xy 312.599043 -365.992984) (xy 312.63626 -366.034521) (xy 312.667033 -366.081034) (xy 312.690705 -366.131531)
			(xy 312.706773 -366.184938) (xy 312.714893 -366.240114) (xy 312.715402 -366.268) (xy 312.714893 -366.295886)
			(xy 312.706773 -366.351062) (xy 312.690705 -366.404469) (xy 312.667033 -366.454966) (xy 312.63626 -366.501479)
			(xy 312.599043 -366.543016) (xy 312.556175 -366.578691) (xy 312.508569 -366.607745) (xy 312.45724 -366.629557)
			(xy 312.403283 -366.643663) (xy 312.347846 -366.649763) (xy 312.292112 -366.647726) (xy 312.237269 -366.637596)
			(xy 312.184485 -366.619589) (xy 312.134885 -366.594088) (xy 312.089527 -366.561637) (xy 312.049378 -366.522928)
			(xy 312.015292 -366.478785) (xy 311.987996 -366.43015) (xy 311.968073 -366.378059) (xy 311.955947 -366.323622)
			(xy 311.951876 -366.268) (xy 303.63566 -366.268) (xy 303.648879 -366.311938) (xy 303.656999 -366.367114)
			(xy 303.657508 -366.395) (xy 303.656999 -366.422886) (xy 303.648879 -366.478062) (xy 303.632811 -366.531469)
			(xy 303.609139 -366.581966) (xy 303.578366 -366.628479) (xy 303.541149 -366.670016) (xy 303.498281 -366.705691)
			(xy 303.450675 -366.734745) (xy 303.399346 -366.756557) (xy 303.345389 -366.770663) (xy 303.289952 -366.776763)
			(xy 303.234218 -366.774726) (xy 303.179375 -366.764596) (xy 303.126591 -366.746589) (xy 303.076991 -366.721088)
			(xy 303.031633 -366.688637) (xy 302.991484 -366.649928) (xy 302.957398 -366.605785) (xy 302.930102 -366.55715)
			(xy 302.910179 -366.505059) (xy 302.898053 -366.450622) (xy 302.893982 -366.395) (xy 297.955372 -366.395)
			(xy 298.412513 -366.8522) (xy 311.072782 -366.8522) (xy 311.076853 -366.796578) (xy 311.088979 -366.742141)
			(xy 311.108902 -366.69005) (xy 311.136198 -366.641415) (xy 311.170284 -366.597272) (xy 311.210433 -366.558563)
			(xy 311.255791 -366.526112) (xy 311.305391 -366.500611) (xy 311.358175 -366.482604) (xy 311.413018 -366.472474)
			(xy 311.468752 -366.470437) (xy 311.524189 -366.476537) (xy 311.578146 -366.490643) (xy 311.629475 -366.512455)
			(xy 311.677081 -366.541509) (xy 311.719949 -366.577184) (xy 311.757166 -366.618721) (xy 311.787939 -366.665234)
			(xy 311.811611 -366.715731) (xy 311.827679 -366.769138) (xy 311.835799 -366.824314) (xy 311.836308 -366.8522)
			(xy 311.835799 -366.880086) (xy 311.827679 -366.935262) (xy 311.811611 -366.988669) (xy 311.787939 -367.039166)
			(xy 311.757166 -367.085679) (xy 311.719949 -367.127216) (xy 311.677081 -367.162891) (xy 311.629475 -367.191945)
			(xy 311.578146 -367.213757) (xy 311.524189 -367.227863) (xy 311.468752 -367.233963) (xy 311.413018 -367.231926)
			(xy 311.358175 -367.221796) (xy 311.305391 -367.203789) (xy 311.255791 -367.178288) (xy 311.210433 -367.145837)
			(xy 311.170284 -367.107128) (xy 311.136198 -367.062985) (xy 311.108902 -367.01435) (xy 311.088979 -366.962259)
			(xy 311.076853 -366.907822) (xy 311.072782 -366.8522) (xy 298.412513 -366.8522) (xy 299.225208 -367.665)
			(xy 302.893982 -367.665) (xy 302.898053 -367.609378) (xy 302.910179 -367.554941) (xy 302.930102 -367.50285)
			(xy 302.957398 -367.454215) (xy 302.991484 -367.410072) (xy 303.031633 -367.371363) (xy 303.076991 -367.338912)
			(xy 303.126591 -367.313411) (xy 303.179375 -367.295404) (xy 303.234218 -367.285274) (xy 303.289952 -367.283237)
			(xy 303.345389 -367.289337) (xy 303.399346 -367.303443) (xy 303.450675 -367.325255) (xy 303.498281 -367.354309)
			(xy 303.50536 -367.3602) (xy 310.183782 -367.3602) (xy 310.187853 -367.304578) (xy 310.199979 -367.250141)
			(xy 310.219902 -367.19805) (xy 310.247198 -367.149415) (xy 310.281284 -367.105272) (xy 310.321433 -367.066563)
			(xy 310.366791 -367.034112) (xy 310.416391 -367.008611) (xy 310.469175 -366.990604) (xy 310.524018 -366.980474)
			(xy 310.579752 -366.978437) (xy 310.635189 -366.984537) (xy 310.689146 -366.998643) (xy 310.740475 -367.020455)
			(xy 310.788081 -367.049509) (xy 310.830949 -367.085184) (xy 310.868166 -367.126721) (xy 310.898939 -367.173234)
			(xy 310.922611 -367.223731) (xy 310.938679 -367.277138) (xy 310.946799 -367.332314) (xy 310.947308 -367.3602)
			(xy 310.946799 -367.388086) (xy 310.938679 -367.443262) (xy 310.922611 -367.496669) (xy 310.898939 -367.547166)
			(xy 310.868166 -367.593679) (xy 310.830949 -367.635216) (xy 310.788081 -367.670891) (xy 310.740475 -367.699945)
			(xy 310.689146 -367.721757) (xy 310.635189 -367.735863) (xy 310.579752 -367.741963) (xy 310.524018 -367.739926)
			(xy 310.469175 -367.729796) (xy 310.416391 -367.711789) (xy 310.366791 -367.686288) (xy 310.321433 -367.653837)
			(xy 310.281284 -367.615128) (xy 310.247198 -367.570985) (xy 310.219902 -367.52235) (xy 310.199979 -367.470259)
			(xy 310.187853 -367.415822) (xy 310.183782 -367.3602) (xy 303.50536 -367.3602) (xy 303.541149 -367.389984)
			(xy 303.578366 -367.431521) (xy 303.609139 -367.478034) (xy 303.632811 -367.528531) (xy 303.648879 -367.581938)
			(xy 303.656999 -367.637114) (xy 303.657508 -367.665) (xy 303.656999 -367.692886) (xy 303.648879 -367.748062)
			(xy 303.632811 -367.801469) (xy 303.609139 -367.851966) (xy 303.578366 -367.898479) (xy 303.541149 -367.940016)
			(xy 303.498281 -367.975691) (xy 303.450675 -368.004745) (xy 303.399346 -368.026557) (xy 303.345389 -368.040663)
			(xy 303.289952 -368.046763) (xy 303.234218 -368.044726) (xy 303.179375 -368.034596) (xy 303.126591 -368.016589)
			(xy 303.076991 -367.991088) (xy 303.031633 -367.958637) (xy 302.991484 -367.919928) (xy 302.957398 -367.875785)
			(xy 302.930102 -367.82715) (xy 302.910179 -367.775059) (xy 302.898053 -367.720622) (xy 302.893982 -367.665)
			(xy 299.225208 -367.665) (xy 299.22724 -367.667032) (xy 299.631608 -368.0714) (xy 309.548782 -368.0714)
			(xy 309.552853 -368.015778) (xy 309.564979 -367.961341) (xy 309.584902 -367.90925) (xy 309.612198 -367.860615)
			(xy 309.646284 -367.816472) (xy 309.686433 -367.777763) (xy 309.731791 -367.745312) (xy 309.781391 -367.719811)
			(xy 309.834175 -367.701804) (xy 309.889018 -367.691674) (xy 309.944752 -367.689637) (xy 310.000189 -367.695737)
			(xy 310.054146 -367.709843) (xy 310.105475 -367.731655) (xy 310.153081 -367.760709) (xy 310.195949 -367.796384)
			(xy 310.233166 -367.837921) (xy 310.263939 -367.884434) (xy 310.287611 -367.934931) (xy 310.303679 -367.988338)
			(xy 310.311799 -368.043514) (xy 310.312308 -368.0714) (xy 310.311799 -368.099286) (xy 310.303679 -368.154462)
			(xy 310.287611 -368.207869) (xy 310.263939 -368.258366) (xy 310.233166 -368.304879) (xy 310.195949 -368.346416)
			(xy 310.153081 -368.382091) (xy 310.105475 -368.411145) (xy 310.054146 -368.432957) (xy 310.000189 -368.447063)
			(xy 309.944752 -368.453163) (xy 309.889018 -368.451126) (xy 309.834175 -368.440996) (xy 309.781391 -368.422989)
			(xy 309.731791 -368.397488) (xy 309.686433 -368.365037) (xy 309.646284 -368.326328) (xy 309.612198 -368.282185)
			(xy 309.584902 -368.23355) (xy 309.564979 -368.181459) (xy 309.552853 -368.127022) (xy 309.548782 -368.0714)
			(xy 299.631608 -368.0714) (xy 300.294548 -368.73434) (xy 300.301946 -368.741185) (xy 300.320545 -368.748912)
			(xy 300.330616 -368.749326)
		)
		(stroke
			(width 0)
			(type solid)
		)
		(fill yes)
		(layer "In15.Cu")
		(net "GND")
	)
	(gr_poly
		(pts
			(xy 103.554276 -190.698628) (xy 103.564149 -190.698158) (xy 103.582435 -190.690703) (xy 103.589836 -190.68415)
			(xy 103.59009 -190.683896) (xy 105.471214 -188.802772) (xy 105.47861 -188.79592) (xy 105.497209 -188.788179)
			(xy 105.507282 -188.787786) (xy 110.184184 -188.787786) (xy 110.194248 -188.788224) (xy 110.212831 -188.795958)
			(xy 110.220252 -188.802772) (xy 110.72368 -189.3062) (xy 110.724188 -189.306708) (xy 110.731569 -189.31329)
			(xy 110.749869 -189.320734) (xy 110.759748 -189.321186) (xy 125.72492 -189.321186) (xy 125.734797 -189.320725)
			(xy 125.753093 -189.31328) (xy 125.76048 -189.306708) (xy 125.760734 -189.306454) (xy 142.731236 -172.335952)
			(xy 142.731744 -172.335444) (xy 142.738327 -172.328063) (xy 142.745778 -172.309764) (xy 142.746222 -172.299884)
			(xy 142.746222 -153.97226) (xy 142.745792 -153.962193) (xy 142.73807 -153.943597) (xy 142.731236 -153.936192)
			(xy 136.240012 -147.444968) (xy 136.233169 -147.437568) (xy 136.225445 -147.41897) (xy 136.225026 -147.4089)
			(xy 136.225026 -145.071846) (xy 136.224594 -145.06178) (xy 136.216868 -145.043187) (xy 136.21004 -145.035778)
			(xy 130.000248 -138.825986) (xy 129.993136 -138.81862) (xy 129.97434 -138.811) (xy 111.585756 -138.811)
			(xy 111.575689 -138.811431) (xy 111.557097 -138.819157) (xy 111.549688 -138.825986) (xy 110.230666 -140.145008)
			(xy 110.223265 -140.151848) (xy 110.204667 -140.159569) (xy 110.194598 -140.159994) (xy 96.988376 -140.159994)
			(xy 96.979677 -140.160349) (xy 96.963283 -140.166171) (xy 96.949778 -140.177138) (xy 96.944942 -140.184378)
			(xy 96.892872 -140.27023) (xy 96.89211 -140.296646) (xy 96.898206 -140.308584) (xy 96.898714 -140.3096)
			(xy 96.898968 -140.310108) (xy 96.90354 -140.318998) (xy 96.908366 -140.329412) (xy 96.926654 -140.34389)
			(xy 97.015808 -140.363956) (xy 97.027288 -140.365968) (xy 97.049927 -140.360545) (xy 97.059242 -140.353542)
			(xy 97.079743 -140.337431) (xy 97.124288 -140.310333) (xy 97.172107 -140.289553) (xy 97.222311 -140.275477)
			(xy 97.273964 -140.268369) (xy 97.300034 -140.267944) (xy 97.307908 -140.267944) (xy 97.336692 -140.269053)
			(xy 97.39345 -140.278868) (xy 97.448085 -140.297109) (xy 97.499355 -140.323363) (xy 97.546091 -140.35703)
			(xy 97.587231 -140.397345) (xy 97.621838 -140.443391) (xy 97.649124 -140.494118) (xy 97.668468 -140.548373)
			(xy 97.67443 -140.576554) (xy 97.676462 -140.58646) (xy 97.68205 -140.594842) (xy 97.684937 -140.599064)
			(xy 97.692101 -140.606363) (xy 97.696274 -140.60932) (xy 97.755964 -140.649198) (xy 97.764631 -140.654315)
			(xy 97.784375 -140.658119) (xy 97.794318 -140.656564) (xy 97.794572 -140.656564) (xy 97.813228 -140.653006)
			(xy 97.851019 -140.649188) (xy 97.87001 -140.648944) (xy 97.870772 -140.648944) (xy 97.89803 -140.649405)
			(xy 97.95199 -140.65716) (xy 98.004298 -140.672515) (xy 98.053888 -140.695159) (xy 98.099751 -140.72463)
			(xy 98.140952 -140.760328) (xy 98.176653 -140.801527) (xy 98.206127 -140.847387) (xy 98.228775 -140.896975)
			(xy 98.240522 -140.93698) (xy 98.420172 -140.93698) (xy 98.424243 -140.881358) (xy 98.436369 -140.826921)
			(xy 98.456292 -140.77483) (xy 98.483588 -140.726195) (xy 98.517674 -140.682052) (xy 98.557823 -140.643343)
			(xy 98.603181 -140.610892) (xy 98.652781 -140.585391) (xy 98.705565 -140.567384) (xy 98.760408 -140.557254)
			(xy 98.816142 -140.555217) (xy 98.871579 -140.561317) (xy 98.925536 -140.575423) (xy 98.976865 -140.597235)
			(xy 99.024471 -140.626289) (xy 99.067339 -140.661964) (xy 99.104556 -140.703501) (xy 99.135329 -140.750014)
			(xy 99.159001 -140.800511) (xy 99.175069 -140.853918) (xy 99.183189 -140.909094) (xy 99.183698 -140.93698)
			(xy 99.183189 -140.964866) (xy 99.175069 -141.020042) (xy 99.159001 -141.073449) (xy 99.135329 -141.123946)
			(xy 99.104556 -141.170459) (xy 99.067339 -141.211996) (xy 99.024471 -141.247671) (xy 98.976865 -141.276725)
			(xy 98.925536 -141.298537) (xy 98.871579 -141.312643) (xy 98.816142 -141.318743) (xy 98.760408 -141.316706)
			(xy 98.705565 -141.306576) (xy 98.652781 -141.288569) (xy 98.603181 -141.263068) (xy 98.557823 -141.230617)
			(xy 98.517674 -141.191908) (xy 98.483588 -141.147765) (xy 98.456292 -141.09913) (xy 98.436369 -141.047039)
			(xy 98.424243 -140.992602) (xy 98.420172 -140.93698) (xy 98.240522 -140.93698) (xy 98.244134 -140.949282)
			(xy 98.251893 -141.003242) (xy 98.251893 -141.057758) (xy 98.244134 -141.111718) (xy 98.228775 -141.164025)
			(xy 98.206127 -141.213613) (xy 98.176653 -141.259473) (xy 98.140952 -141.300672) (xy 98.099751 -141.33637)
			(xy 98.053888 -141.365841) (xy 98.004298 -141.388485) (xy 97.95199 -141.40384) (xy 97.89803 -141.411595)
			(xy 97.870772 -141.41196) (xy 97.844465 -141.411523) (xy 97.79235 -141.4043) (xy 97.741723 -141.389982)
			(xy 97.693545 -141.368841) (xy 97.64873 -141.341277) (xy 97.60813 -141.307814) (xy 97.572515 -141.269088)
			(xy 97.542562 -141.225833) (xy 97.518839 -141.178872) (xy 97.501797 -141.129095) (xy 97.496376 -141.10335)
			(xy 97.494344 -141.093444) (xy 97.488756 -141.085062) (xy 97.48587 -141.080839) (xy 97.478706 -141.07354)
			(xy 97.474532 -141.070584) (xy 97.406206 -141.025118) (xy 97.386648 -141.021308) (xy 97.376488 -141.02334)
			(xy 97.357586 -141.027) (xy 97.319285 -141.030946) (xy 97.300034 -141.031214) (xy 97.273275 -141.030765)
			(xy 97.220281 -141.023288) (xy 97.168853 -141.008477) (xy 97.120001 -140.986621) (xy 97.074683 -140.958152)
			(xy 97.033791 -140.923626) (xy 96.998126 -140.883724) (xy 96.968389 -140.839227) (xy 96.956372 -140.815314)
			(xy 96.951038 -140.804646) (xy 96.933258 -140.790422) (xy 96.832674 -140.76807) (xy 96.810068 -140.773404)
			(xy 96.800924 -140.78077) (xy 96.779397 -140.797679) (xy 96.732437 -140.825805) (xy 96.68194 -140.846932)
			(xy 96.628942 -140.860626) (xy 96.601788 -140.864082) (xy 96.591344 -140.865156) (xy 96.570377 -140.866299)
			(xy 96.559878 -140.866368) (xy 96.53046 -140.865803) (xy 96.472324 -140.856744) (xy 96.416262 -140.838888)
			(xy 96.389698 -140.826236) (xy 96.389444 -140.826236) (xy 96.37944 -140.821779) (xy 96.357578 -140.820985)
			(xy 96.34728 -140.824712) (xy 96.276414 -140.854176) (xy 96.266559 -140.858838) (xy 96.251699 -140.874762)
			(xy 96.247712 -140.88491) (xy 96.247712 -140.885164) (xy 96.238911 -140.910181) (xy 96.215371 -140.957701)
			(xy 96.185483 -141.001507) (xy 96.149822 -141.040757) (xy 96.109074 -141.074697) (xy 96.064022 -141.102673)
			(xy 96.015534 -141.124147) (xy 95.96454 -141.138706) (xy 95.912023 -141.146072) (xy 95.885508 -141.14653)
			(xy 95.858256 -141.146045) (xy 95.804306 -141.138289) (xy 95.752009 -141.122935) (xy 95.702429 -141.100295)
			(xy 95.656576 -141.070829) (xy 95.615383 -141.035138) (xy 95.579689 -140.993948) (xy 95.55022 -140.948097)
			(xy 95.527575 -140.898519) (xy 95.512217 -140.846223) (xy 95.504457 -140.792274) (xy 95.504 -140.765022)
			(xy 95.504 -140.755624) (xy 95.504508 -140.745464) (xy 95.496126 -140.72489) (xy 95.42399 -140.657834)
			(xy 95.403416 -140.650976) (xy 95.392494 -140.651992) (xy 95.35414 -140.654024) (xy 95.326885 -140.653564)
			(xy 95.272929 -140.645812) (xy 95.220625 -140.630459) (xy 95.171039 -140.607819) (xy 95.125179 -140.578352)
			(xy 95.083981 -140.542659) (xy 95.048281 -140.501465) (xy 95.018808 -140.45561) (xy 94.99616 -140.406028)
			(xy 94.9808 -140.353726) (xy 94.97304 -140.299771) (xy 94.972632 -140.272516) (xy 94.972632 -140.26388)
			(xy 94.972388 -140.253732) (xy 94.964919 -140.234874) (xy 94.958154 -140.227304) (xy 94.907608 -140.175234)
			(xy 94.90329 -140.171424) (xy 94.89653 -140.166378) (xy 94.880719 -140.160533) (xy 94.872302 -140.159994)
			(xy 94.83725 -140.159994) (xy 94.827506 -140.160429) (xy 94.809434 -140.16772) (xy 94.795416 -140.181257)
			(xy 94.791022 -140.189966) (xy 94.781116 -140.212064) (xy 94.777522 -140.22091) (xy 94.776482 -140.239961)
			(xy 94.779084 -140.249148) (xy 94.78518 -140.266928) (xy 94.789752 -140.273278) (xy 94.806058 -140.296735)
			(xy 94.832264 -140.347496) (xy 94.850613 -140.401596) (xy 94.860696 -140.457825) (xy 94.862287 -140.514929)
			(xy 94.855352 -140.571633) (xy 94.840045 -140.626671) (xy 94.816709 -140.678813) (xy 94.785863 -140.726896)
			(xy 94.748196 -140.769845) (xy 94.704551 -140.806703) (xy 94.680532 -140.822172) (xy 94.656126 -140.836575)
			(xy 94.603992 -140.858785) (xy 94.549142 -140.873025) (xy 94.52102 -140.876528) (xy 94.511748 -140.87799)
			(xy 94.495082 -140.886592) (xy 94.488508 -140.893292) (xy 94.443296 -140.943838) (xy 94.437428 -140.95103)
			(xy 94.430788 -140.968348) (xy 94.430342 -140.97762) (xy 94.430342 -140.979652) (xy 94.429856 -141.006903)
			(xy 94.4221 -141.060851) (xy 94.406745 -141.113146) (xy 94.384103 -141.162723) (xy 94.354637 -141.208573)
			(xy 94.318946 -141.249764) (xy 94.277755 -141.285455) (xy 94.231905 -141.314921) (xy 94.182328 -141.337563)
			(xy 94.130033 -141.352918) (xy 94.076085 -141.360674) (xy 94.021583 -141.360674) (xy 93.967635 -141.352918)
			(xy 93.91534 -141.337563) (xy 93.865763 -141.314921) (xy 93.819913 -141.285455) (xy 93.778722 -141.249764)
			(xy 93.743031 -141.208573) (xy 93.713565 -141.162723) (xy 93.690923 -141.113146) (xy 93.675568 -141.060851)
			(xy 93.667812 -141.006903) (xy 93.667326 -140.979652) (xy 93.667834 -140.960094) (xy 93.668342 -140.949426)
			(xy 93.66123 -140.930122) (xy 93.603318 -140.868908) (xy 93.595846 -140.861738) (xy 93.576833 -140.853585)
			(xy 93.566488 -140.85316) (xy 93.566234 -140.85316) (xy 93.539215 -140.852686) (xy 93.485719 -140.845053)
			(xy 93.433835 -140.829948) (xy 93.384601 -140.807674) (xy 93.339002 -140.778677) (xy 93.297951 -140.743536)
			(xy 93.262268 -140.702954) (xy 93.232668 -140.657744) (xy 93.209742 -140.608811) (xy 93.19395 -140.557132)
			(xy 93.185607 -140.503742) (xy 93.184726 -140.476732) (xy 93.184726 -140.471398) (xy 93.185248 -140.442873)
			(xy 93.193785 -140.386464) (xy 93.210638 -140.331958) (xy 93.222572 -140.306044) (xy 93.222572 -140.30579)
			(xy 93.226062 -140.297907) (xy 93.228091 -140.280797) (xy 93.224337 -140.263982) (xy 93.220032 -140.256514)
			(xy 93.174312 -140.18387) (xy 93.167454 -140.172694) (xy 93.14434 -140.159994) (xy 93.082618 -140.159994)
			(xy 93.070285 -140.160575) (xy 93.048435 -140.172013) (xy 93.040962 -140.181838) (xy 93.024391 -140.204712)
			(xy 92.985608 -140.245775) (xy 92.941194 -140.28067) (xy 92.89212 -140.308636) (xy 92.839459 -140.329059)
			(xy 92.784362 -140.341495) (xy 92.728034 -140.34567) (xy 92.671706 -140.341495) (xy 92.616609 -140.329059)
			(xy 92.563948 -140.308636) (xy 92.514874 -140.28067) (xy 92.47046 -140.245775) (xy 92.431677 -140.204712)
			(xy 92.415106 -140.181838) (xy 92.407498 -140.172157) (xy 92.385738 -140.160721) (xy 92.37345 -140.159994)
			(xy 89.334848 -140.159994) (xy 89.326466 -140.163042) (xy 89.29445 -140.174154) (xy 89.227759 -140.186167)
			(xy 89.193878 -140.186918) (xy 89.159996 -140.186165) (xy 89.093304 -140.174161) (xy 89.06129 -140.163042)
			(xy 89.052908 -140.159994) (xy 88.496648 -140.159994) (xy 88.486582 -140.160426) (xy 88.46799 -140.168153)
			(xy 88.46058 -140.17498) (xy 87.691976 -140.943584) (xy 88.776554 -140.943584) (xy 88.780625 -140.887962)
			(xy 88.792751 -140.833525) (xy 88.812674 -140.781434) (xy 88.83997 -140.732799) (xy 88.874056 -140.688656)
			(xy 88.914205 -140.649947) (xy 88.959563 -140.617496) (xy 89.009163 -140.591995) (xy 89.061947 -140.573988)
			(xy 89.11679 -140.563858) (xy 89.172524 -140.561821) (xy 89.227961 -140.567921) (xy 89.281918 -140.582027)
			(xy 89.333247 -140.603839) (xy 89.380853 -140.632893) (xy 89.423721 -140.668568) (xy 89.460938 -140.710105)
			(xy 89.491711 -140.756618) (xy 89.515383 -140.807115) (xy 89.531451 -140.860522) (xy 89.539571 -140.915698)
			(xy 89.54008 -140.943584) (xy 89.539571 -140.97147) (xy 89.531451 -141.026646) (xy 89.515383 -141.080053)
			(xy 89.491711 -141.13055) (xy 89.460938 -141.177063) (xy 89.423721 -141.2186) (xy 89.380853 -141.254275)
			(xy 89.333247 -141.283329) (xy 89.281918 -141.305141) (xy 89.227961 -141.319247) (xy 89.172524 -141.325347)
			(xy 89.11679 -141.32331) (xy 89.061947 -141.31318) (xy 89.009163 -141.295173) (xy 88.959563 -141.269672)
			(xy 88.914205 -141.237221) (xy 88.874056 -141.198512) (xy 88.83997 -141.154369) (xy 88.812674 -141.105734)
			(xy 88.792751 -141.053643) (xy 88.780625 -140.999206) (xy 88.776554 -140.943584) (xy 87.691976 -140.943584)
			(xy 87.215218 -141.420342) (xy 92.08592 -141.420342) (xy 92.089991 -141.36472) (xy 92.102117 -141.310283)
			(xy 92.12204 -141.258192) (xy 92.149336 -141.209557) (xy 92.183422 -141.165414) (xy 92.223571 -141.126705)
			(xy 92.268929 -141.094254) (xy 92.318529 -141.068753) (xy 92.371313 -141.050746) (xy 92.426156 -141.040616)
			(xy 92.48189 -141.038579) (xy 92.537327 -141.044679) (xy 92.591284 -141.058785) (xy 92.642613 -141.080597)
			(xy 92.690219 -141.109651) (xy 92.733087 -141.145326) (xy 92.770304 -141.186863) (xy 92.801077 -141.233376)
			(xy 92.824749 -141.283873) (xy 92.840817 -141.33728) (xy 92.848937 -141.392456) (xy 92.849446 -141.420342)
			(xy 92.848937 -141.448228) (xy 92.840817 -141.503404) (xy 92.824749 -141.556811) (xy 92.801077 -141.607308)
			(xy 92.770304 -141.653821) (xy 92.734393 -141.6939) (xy 103.389682 -141.6939) (xy 103.393753 -141.638278)
			(xy 103.405879 -141.583841) (xy 103.425802 -141.53175) (xy 103.453098 -141.483115) (xy 103.487184 -141.438972)
			(xy 103.527333 -141.400263) (xy 103.572691 -141.367812) (xy 103.622291 -141.342311) (xy 103.675075 -141.324304)
			(xy 103.729918 -141.314174) (xy 103.785652 -141.312137) (xy 103.841089 -141.318237) (xy 103.895046 -141.332343)
			(xy 103.946375 -141.354155) (xy 103.993981 -141.383209) (xy 104.036849 -141.418884) (xy 104.074066 -141.460421)
			(xy 104.104839 -141.506934) (xy 104.128511 -141.557431) (xy 104.144579 -141.610838) (xy 104.152699 -141.666014)
			(xy 104.153208 -141.6939) (xy 104.152699 -141.721786) (xy 104.144579 -141.776962) (xy 104.128511 -141.830369)
			(xy 104.104839 -141.880866) (xy 104.074066 -141.927379) (xy 104.036849 -141.968916) (xy 103.993981 -142.004591)
			(xy 103.946375 -142.033645) (xy 103.895046 -142.055457) (xy 103.841089 -142.069563) (xy 103.785652 -142.075663)
			(xy 103.729918 -142.073626) (xy 103.675075 -142.063496) (xy 103.622291 -142.045489) (xy 103.572691 -142.019988)
			(xy 103.527333 -141.987537) (xy 103.487184 -141.948828) (xy 103.453098 -141.904685) (xy 103.425802 -141.85605)
			(xy 103.405879 -141.803959) (xy 103.393753 -141.749522) (xy 103.389682 -141.6939) (xy 92.734393 -141.6939)
			(xy 92.733087 -141.695358) (xy 92.690219 -141.731033) (xy 92.642613 -141.760087) (xy 92.591284 -141.781899)
			(xy 92.537327 -141.796005) (xy 92.48189 -141.802105) (xy 92.426156 -141.800068) (xy 92.371313 -141.789938)
			(xy 92.318529 -141.771931) (xy 92.268929 -141.74643) (xy 92.223571 -141.713979) (xy 92.183422 -141.67527)
			(xy 92.149336 -141.631127) (xy 92.12204 -141.582492) (xy 92.102117 -141.530401) (xy 92.089991 -141.475964)
			(xy 92.08592 -141.420342) (xy 87.215218 -141.420342) (xy 87.186516 -141.449044) (xy 87.179116 -141.455883)
			(xy 87.160517 -141.463596) (xy 87.150448 -141.46403) (xy 82.380836 -141.46403) (xy 82.368769 -141.464704)
			(xy 82.347295 -141.475718) (xy 82.339688 -141.485112) (xy 82.323033 -141.507295) (xy 82.284363 -141.547062)
			(xy 82.240342 -141.58081) (xy 82.191896 -141.607826) (xy 82.140049 -141.627541) (xy 82.085893 -141.639539)
			(xy 82.03057 -141.643566) (xy 81.975247 -141.639539) (xy 81.921091 -141.627541) (xy 81.869244 -141.607826)
			(xy 81.820798 -141.58081) (xy 81.776777 -141.547062) (xy 81.738107 -141.507295) (xy 81.721452 -141.485112)
			(xy 81.713838 -141.475735) (xy 81.692364 -141.464747) (xy 81.680304 -141.46403) (xy 70.941692 -141.46403)
			(xy 70.934326 -141.456664) (xy 58.492136 -141.456664) (xy 58.482072 -141.4571) (xy 58.463491 -141.464838)
			(xy 58.456068 -141.47165) (xy 57.824116 -142.103602) (xy 99.991416 -142.103602) (xy 99.995487 -142.04798)
			(xy 100.007613 -141.993543) (xy 100.027536 -141.941452) (xy 100.054832 -141.892817) (xy 100.088918 -141.848674)
			(xy 100.129067 -141.809965) (xy 100.174425 -141.777514) (xy 100.224025 -141.752013) (xy 100.276809 -141.734006)
			(xy 100.331652 -141.723876) (xy 100.387386 -141.721839) (xy 100.442823 -141.727939) (xy 100.49678 -141.742045)
			(xy 100.548109 -141.763857) (xy 100.595715 -141.792911) (xy 100.638583 -141.828586) (xy 100.6758 -141.870123)
			(xy 100.706573 -141.916636) (xy 100.730245 -141.967133) (xy 100.746313 -142.02054) (xy 100.754433 -142.075716)
			(xy 100.754942 -142.103602) (xy 100.754433 -142.131488) (xy 100.746313 -142.186664) (xy 100.730245 -142.240071)
			(xy 100.706573 -142.290568) (xy 100.6758 -142.337081) (xy 100.638583 -142.378618) (xy 100.595715 -142.414293)
			(xy 100.548109 -142.443347) (xy 100.49678 -142.465159) (xy 100.442823 -142.479265) (xy 100.387386 -142.485365)
			(xy 100.331652 -142.483328) (xy 100.276809 -142.473198) (xy 100.224025 -142.455191) (xy 100.174425 -142.42969)
			(xy 100.129067 -142.397239) (xy 100.088918 -142.35853) (xy 100.054832 -142.314387) (xy 100.027536 -142.265752)
			(xy 100.007613 -142.213661) (xy 99.995487 -142.159224) (xy 99.991416 -142.103602) (xy 57.824116 -142.103602)
			(xy 57.422542 -142.505176) (xy 91.124276 -142.505176) (xy 91.128347 -142.449554) (xy 91.140473 -142.395117)
			(xy 91.160396 -142.343026) (xy 91.187692 -142.294391) (xy 91.221778 -142.250248) (xy 91.261927 -142.211539)
			(xy 91.307285 -142.179088) (xy 91.356885 -142.153587) (xy 91.409669 -142.13558) (xy 91.464512 -142.12545)
			(xy 91.520246 -142.123413) (xy 91.575683 -142.129513) (xy 91.62964 -142.143619) (xy 91.680969 -142.165431)
			(xy 91.728575 -142.194485) (xy 91.771443 -142.23016) (xy 91.80866 -142.271697) (xy 91.839433 -142.31821)
			(xy 91.863105 -142.368707) (xy 91.879173 -142.422114) (xy 91.887293 -142.47729) (xy 91.887802 -142.505176)
			(xy 91.887293 -142.533062) (xy 91.879173 -142.588238) (xy 91.863105 -142.641645) (xy 91.839433 -142.692142)
			(xy 91.80866 -142.738655) (xy 91.771443 -142.780192) (xy 91.728575 -142.815867) (xy 91.680969 -142.844921)
			(xy 91.62964 -142.866733) (xy 91.575683 -142.880839) (xy 91.520246 -142.886939) (xy 91.464512 -142.884902)
			(xy 91.409669 -142.874772) (xy 91.356885 -142.856765) (xy 91.307285 -142.831264) (xy 91.261927 -142.798813)
			(xy 91.221778 -142.760104) (xy 91.187692 -142.715961) (xy 91.160396 -142.667326) (xy 91.140473 -142.615235)
			(xy 91.128347 -142.560798) (xy 91.124276 -142.505176) (xy 57.422542 -142.505176) (xy 56.573166 -143.354552)
			(xy 87.380316 -143.354552) (xy 87.384387 -143.29893) (xy 87.396513 -143.244493) (xy 87.416436 -143.192402)
			(xy 87.443732 -143.143767) (xy 87.477818 -143.099624) (xy 87.517967 -143.060915) (xy 87.563325 -143.028464)
			(xy 87.612925 -143.002963) (xy 87.665709 -142.984956) (xy 87.720552 -142.974826) (xy 87.776286 -142.972789)
			(xy 87.831723 -142.978889) (xy 87.88568 -142.992995) (xy 87.937009 -143.014807) (xy 87.984615 -143.043861)
			(xy 88.027483 -143.079536) (xy 88.0647 -143.121073) (xy 88.095473 -143.167586) (xy 88.119145 -143.218083)
			(xy 88.135213 -143.27149) (xy 88.143333 -143.326666) (xy 88.143842 -143.354552) (xy 88.143513 -143.372586)
			(xy 88.36533 -143.372586) (xy 88.365816 -143.345335) (xy 88.373572 -143.291387) (xy 88.388927 -143.239092)
			(xy 88.411569 -143.189515) (xy 88.441035 -143.143665) (xy 88.476726 -143.102474) (xy 88.517917 -143.066783)
			(xy 88.563767 -143.037317) (xy 88.613344 -143.014675) (xy 88.665639 -142.99932) (xy 88.719587 -142.991564)
			(xy 88.774089 -142.991564) (xy 88.828037 -142.99932) (xy 88.880332 -143.014675) (xy 88.929909 -143.037317)
			(xy 88.975759 -143.066783) (xy 88.997143 -143.085312) (xy 100.117908 -143.085312) (xy 100.121979 -143.02969)
			(xy 100.134105 -142.975253) (xy 100.154028 -142.923162) (xy 100.181324 -142.874527) (xy 100.21541 -142.830384)
			(xy 100.255559 -142.791675) (xy 100.300917 -142.759224) (xy 100.350517 -142.733723) (xy 100.403301 -142.715716)
			(xy 100.458144 -142.705586) (xy 100.513878 -142.703549) (xy 100.569315 -142.709649) (xy 100.623272 -142.723755)
			(xy 100.674601 -142.745567) (xy 100.722207 -142.774621) (xy 100.765075 -142.810296) (xy 100.802292 -142.851833)
			(xy 100.833065 -142.898346) (xy 100.856737 -142.948843) (xy 100.872805 -143.00225) (xy 100.880925 -143.057426)
			(xy 100.881434 -143.085312) (xy 100.880925 -143.113198) (xy 100.872805 -143.168374) (xy 100.856737 -143.221781)
			(xy 100.833065 -143.272278) (xy 100.802292 -143.318791) (xy 100.765075 -143.360328) (xy 100.722207 -143.396003)
			(xy 100.674601 -143.425057) (xy 100.623272 -143.446869) (xy 100.569315 -143.460975) (xy 100.513878 -143.467075)
			(xy 100.458144 -143.465038) (xy 100.403301 -143.454908) (xy 100.350517 -143.436901) (xy 100.300917 -143.4114)
			(xy 100.255559 -143.378949) (xy 100.21541 -143.34024) (xy 100.181324 -143.296097) (xy 100.154028 -143.247462)
			(xy 100.134105 -143.195371) (xy 100.121979 -143.140934) (xy 100.117908 -143.085312) (xy 88.997143 -143.085312)
			(xy 89.01695 -143.102474) (xy 89.052641 -143.143665) (xy 89.082107 -143.189515) (xy 89.104749 -143.239092)
			(xy 89.120104 -143.291387) (xy 89.12786 -143.345335) (xy 89.128346 -143.372586) (xy 89.127829 -143.40195)
			(xy 89.118904 -143.459996) (xy 89.110566 -143.488156) (xy 89.106877 -143.501104) (xy 89.105692 -143.527992)
			(xy 89.111581 -143.554253) (xy 89.124133 -143.578061) (xy 89.142474 -143.597757) (xy 89.165329 -143.61197)
			(xy 89.191105 -143.619711) (xy 89.204546 -143.62049) (xy 89.231285 -143.621742) (xy 89.28406 -143.630677)
			(xy 89.335067 -143.646906) (xy 89.383303 -143.670109) (xy 89.42782 -143.69983) (xy 89.467742 -143.735484)
			(xy 89.502285 -143.776372) (xy 89.53077 -143.82169) (xy 89.552638 -143.870546) (xy 89.567457 -143.92198)
			(xy 89.574937 -143.974981) (xy 89.575386 -144.001744) (xy 89.5749 -144.028995) (xy 89.572922 -144.042754)
			(xy 90.855738 -144.042754) (xy 90.855738 -143.988246) (xy 90.863495 -143.934293) (xy 90.878852 -143.881992)
			(xy 90.901495 -143.83241) (xy 90.930965 -143.786555) (xy 90.96666 -143.74536) (xy 91.007855 -143.709665)
			(xy 91.05371 -143.680195) (xy 91.103292 -143.657552) (xy 91.155593 -143.642195) (xy 91.209546 -143.634438)
			(xy 91.2368 -143.633952) (xy 91.26329 -143.634388) (xy 91.315759 -143.641738) (xy 91.366705 -143.65628)
			(xy 91.415147 -143.677737) (xy 91.460151 -143.705694) (xy 91.500851 -143.739612) (xy 91.518994 -143.75892)
			(xy 91.52822 -143.768469) (xy 91.550551 -143.782819) (xy 91.575827 -143.790926) (xy 91.602338 -143.792242)
			(xy 91.628293 -143.786678) (xy 91.651935 -143.77461) (xy 91.671666 -143.756854) (xy 91.679268 -143.745966)
			(xy 91.694495 -143.723592) (xy 91.730189 -143.682913) (xy 91.771271 -143.647684) (xy 91.816917 -143.618611)
			(xy 91.866212 -143.596277) (xy 91.918167 -143.581129) (xy 91.971741 -143.573471) (xy 91.9988 -143.572992)
			(xy 92.026051 -143.573478) (xy 92.079999 -143.581234) (xy 92.132294 -143.596589) (xy 92.181871 -143.619231)
			(xy 92.227721 -143.648697) (xy 92.228585 -143.649446) (xy 112.505996 -143.649446) (xy 112.510067 -143.593824)
			(xy 112.522193 -143.539387) (xy 112.542116 -143.487296) (xy 112.569412 -143.438661) (xy 112.603498 -143.394518)
			(xy 112.643647 -143.355809) (xy 112.689005 -143.323358) (xy 112.738605 -143.297857) (xy 112.791389 -143.27985)
			(xy 112.846232 -143.26972) (xy 112.901966 -143.267683) (xy 112.957403 -143.273783) (xy 113.01136 -143.287889)
			(xy 113.062689 -143.309701) (xy 113.110295 -143.338755) (xy 113.153163 -143.37443) (xy 113.19038 -143.415967)
			(xy 113.221153 -143.46248) (xy 113.244825 -143.512977) (xy 113.260893 -143.566384) (xy 113.269013 -143.62156)
			(xy 113.269522 -143.649446) (xy 113.269013 -143.677332) (xy 113.260893 -143.732508) (xy 113.244825 -143.785915)
			(xy 113.221153 -143.836412) (xy 113.19038 -143.882925) (xy 113.153163 -143.924462) (xy 113.110295 -143.960137)
			(xy 113.062689 -143.989191) (xy 113.01136 -144.011003) (xy 112.957403 -144.025109) (xy 112.901966 -144.031209)
			(xy 112.846232 -144.029172) (xy 112.791389 -144.019042) (xy 112.738605 -144.001035) (xy 112.689005 -143.975534)
			(xy 112.643647 -143.943083) (xy 112.603498 -143.904374) (xy 112.569412 -143.860231) (xy 112.542116 -143.811596)
			(xy 112.522193 -143.759505) (xy 112.510067 -143.705068) (xy 112.505996 -143.649446) (xy 92.228585 -143.649446)
			(xy 92.268912 -143.684388) (xy 92.304603 -143.725579) (xy 92.334069 -143.771429) (xy 92.356711 -143.821006)
			(xy 92.372066 -143.873301) (xy 92.379822 -143.927249) (xy 92.379822 -143.981751) (xy 92.372066 -144.035699)
			(xy 92.356711 -144.087994) (xy 92.334069 -144.137571) (xy 92.304603 -144.183421) (xy 92.268912 -144.224612)
			(xy 92.227721 -144.260303) (xy 92.181871 -144.289769) (xy 92.132294 -144.312411) (xy 92.079999 -144.327766)
			(xy 92.026051 -144.335522) (xy 91.9988 -144.336008) (xy 91.972309 -144.335585) (xy 91.919839 -144.328235)
			(xy 91.868893 -144.31369) (xy 91.820451 -144.292231) (xy 91.775447 -144.264272) (xy 91.734748 -144.23035)
			(xy 91.716606 -144.21104) (xy 91.705788 -144.199934) (xy 91.679009 -144.184333) (xy 91.648787 -144.177468)
			(xy 91.617896 -144.179968) (xy 91.589172 -144.191605) (xy 91.565251 -144.21131) (xy 91.556332 -144.223994)
			(xy 91.541125 -144.246382) (xy 91.505425 -144.287057) (xy 91.464339 -144.322283) (xy 91.418689 -144.351353)
			(xy 91.369392 -144.373686) (xy 91.317435 -144.388832) (xy 91.26386 -144.396489) (xy 91.2368 -144.396968)
			(xy 91.209546 -144.396562) (xy 91.155593 -144.388805) (xy 91.103292 -144.373448) (xy 91.05371 -144.350805)
			(xy 91.007855 -144.321335) (xy 90.96666 -144.28564) (xy 90.930965 -144.244445) (xy 90.901495 -144.19859)
			(xy 90.878852 -144.149008) (xy 90.863495 -144.096707) (xy 90.855738 -144.042754) (xy 89.572922 -144.042754)
			(xy 89.567144 -144.082943) (xy 89.551789 -144.135238) (xy 89.529147 -144.184815) (xy 89.499681 -144.230665)
			(xy 89.46399 -144.271856) (xy 89.422799 -144.307547) (xy 89.376949 -144.337013) (xy 89.327372 -144.359655)
			(xy 89.275077 -144.37501) (xy 89.221129 -144.382766) (xy 89.166627 -144.382766) (xy 89.112679 -144.37501)
			(xy 89.060384 -144.359655) (xy 89.010807 -144.337013) (xy 88.964957 -144.307547) (xy 88.923766 -144.271856)
			(xy 88.888075 -144.230665) (xy 88.858609 -144.184815) (xy 88.835967 -144.135238) (xy 88.820612 -144.082943)
			(xy 88.812856 -144.028995) (xy 88.81237 -144.001744) (xy 88.812875 -143.972379) (xy 88.821808 -143.914334)
			(xy 88.83015 -143.886174) (xy 88.833789 -143.873214) (xy 88.83498 -143.846333) (xy 88.829098 -143.820077)
			(xy 88.816555 -143.796273) (xy 88.798221 -143.776579) (xy 88.775375 -143.762365) (xy 88.749607 -143.754621)
			(xy 88.73617 -143.75384) (xy 88.709422 -143.752733) (xy 88.656639 -143.743785) (xy 88.605625 -143.727542)
			(xy 88.557385 -143.704324) (xy 88.512866 -143.674588) (xy 88.472943 -143.638918) (xy 88.438402 -143.598015)
			(xy 88.40992 -143.552684) (xy 88.388058 -143.503814) (xy 88.373246 -143.452367) (xy 88.365774 -143.399354)
			(xy 88.36533 -143.372586) (xy 88.143513 -143.372586) (xy 88.143333 -143.382438) (xy 88.135213 -143.437614)
			(xy 88.119145 -143.491021) (xy 88.095473 -143.541518) (xy 88.0647 -143.588031) (xy 88.027483 -143.629568)
			(xy 87.984615 -143.665243) (xy 87.937009 -143.694297) (xy 87.88568 -143.716109) (xy 87.831723 -143.730215)
			(xy 87.776286 -143.736315) (xy 87.720552 -143.734278) (xy 87.665709 -143.724148) (xy 87.612925 -143.706141)
			(xy 87.563325 -143.68064) (xy 87.517967 -143.648189) (xy 87.477818 -143.60948) (xy 87.443732 -143.565337)
			(xy 87.416436 -143.516702) (xy 87.396513 -143.464611) (xy 87.384387 -143.410174) (xy 87.380316 -143.354552)
			(xy 56.573166 -143.354552) (xy 56.141874 -143.785844) (xy 82.07832 -143.785844) (xy 82.082391 -143.730222)
			(xy 82.094517 -143.675785) (xy 82.11444 -143.623694) (xy 82.141736 -143.575059) (xy 82.175822 -143.530916)
			(xy 82.215971 -143.492207) (xy 82.261329 -143.459756) (xy 82.310929 -143.434255) (xy 82.363713 -143.416248)
			(xy 82.418556 -143.406118) (xy 82.47429 -143.404081) (xy 82.529727 -143.410181) (xy 82.583684 -143.424287)
			(xy 82.635013 -143.446099) (xy 82.682619 -143.475153) (xy 82.725487 -143.510828) (xy 82.762704 -143.552365)
			(xy 82.793477 -143.598878) (xy 82.817149 -143.649375) (xy 82.833217 -143.702782) (xy 82.841337 -143.757958)
			(xy 82.841846 -143.785844) (xy 82.841337 -143.81373) (xy 82.833217 -143.868906) (xy 82.817149 -143.922313)
			(xy 82.793477 -143.97281) (xy 82.762704 -144.019323) (xy 82.725487 -144.06086) (xy 82.682619 -144.096535)
			(xy 82.635013 -144.125589) (xy 82.583684 -144.147401) (xy 82.529727 -144.161507) (xy 82.47429 -144.167607)
			(xy 82.418556 -144.16557) (xy 82.363713 -144.15544) (xy 82.310929 -144.137433) (xy 82.261329 -144.111932)
			(xy 82.215971 -144.079481) (xy 82.175822 -144.040772) (xy 82.141736 -143.996629) (xy 82.11444 -143.947994)
			(xy 82.094517 -143.895903) (xy 82.082391 -143.841466) (xy 82.07832 -143.785844) (xy 56.141874 -143.785844)
			(xy 54.901338 -145.02638) (xy 57.174128 -145.02638) (xy 57.178199 -144.970758) (xy 57.190325 -144.916321)
			(xy 57.210248 -144.86423) (xy 57.237544 -144.815595) (xy 57.27163 -144.771452) (xy 57.311779 -144.732743)
			(xy 57.357137 -144.700292) (xy 57.406737 -144.674791) (xy 57.459521 -144.656784) (xy 57.514364 -144.646654)
			(xy 57.570098 -144.644617) (xy 57.625535 -144.650717) (xy 57.679492 -144.664823) (xy 57.730821 -144.686635)
			(xy 57.778427 -144.715689) (xy 57.821295 -144.751364) (xy 57.858512 -144.792901) (xy 57.889285 -144.839414)
			(xy 57.910847 -144.88541) (xy 88.81186 -144.88541) (xy 88.815931 -144.829788) (xy 88.828057 -144.775351)
			(xy 88.84798 -144.72326) (xy 88.875276 -144.674625) (xy 88.909362 -144.630482) (xy 88.949511 -144.591773)
			(xy 88.994869 -144.559322) (xy 89.044469 -144.533821) (xy 89.097253 -144.515814) (xy 89.152096 -144.505684)
			(xy 89.20783 -144.503647) (xy 89.263267 -144.509747) (xy 89.317224 -144.523853) (xy 89.368553 -144.545665)
			(xy 89.416159 -144.574719) (xy 89.459027 -144.610394) (xy 89.496244 -144.651931) (xy 89.527017 -144.698444)
			(xy 89.550689 -144.748941) (xy 89.566757 -144.802348) (xy 89.574877 -144.857524) (xy 89.575386 -144.88541)
			(xy 89.574877 -144.913296) (xy 89.568253 -144.958308) (xy 90.97086 -144.958308) (xy 90.974931 -144.902686)
			(xy 90.987057 -144.848249) (xy 91.00698 -144.796158) (xy 91.034276 -144.747523) (xy 91.068362 -144.70338)
			(xy 91.108511 -144.664671) (xy 91.153869 -144.63222) (xy 91.203469 -144.606719) (xy 91.256253 -144.588712)
			(xy 91.311096 -144.578582) (xy 91.36683 -144.576545) (xy 91.422267 -144.582645) (xy 91.476224 -144.596751)
			(xy 91.527553 -144.618563) (xy 91.575159 -144.647617) (xy 91.618027 -144.683292) (xy 91.655244 -144.724829)
			(xy 91.686017 -144.771342) (xy 91.709689 -144.821839) (xy 91.725757 -144.875246) (xy 91.733877 -144.930422)
			(xy 91.734386 -144.958308) (xy 91.733877 -144.986194) (xy 91.725757 -145.04137) (xy 91.70971 -145.094706)
			(xy 99.562666 -145.094706) (xy 99.563113 -145.068765) (xy 99.570142 -145.017363) (xy 99.584073 -144.967387)
			(xy 99.604648 -144.919759) (xy 99.631486 -144.875359) (xy 99.664094 -144.835006) (xy 99.70187 -144.799444)
			(xy 99.744116 -144.769329) (xy 99.766882 -144.756886) (xy 99.776788 -144.751806) (xy 99.789996 -144.735042)
			(xy 99.813618 -144.639792) (xy 99.809808 -144.61871) (xy 99.803712 -144.609566) (xy 99.788026 -144.585661)
			(xy 99.763183 -144.534166) (xy 99.746289 -144.479544) (xy 99.737722 -144.423015) (xy 99.737164 -144.394428)
			(xy 99.73765 -144.367177) (xy 99.745406 -144.313229) (xy 99.760761 -144.260934) (xy 99.783403 -144.211357)
			(xy 99.812869 -144.165507) (xy 99.84856 -144.124316) (xy 99.889751 -144.088625) (xy 99.935601 -144.059159)
			(xy 99.985178 -144.036517) (xy 100.037473 -144.021162) (xy 100.091421 -144.013406) (xy 100.145923 -144.013406)
			(xy 100.199871 -144.021162) (xy 100.252166 -144.036517) (xy 100.301743 -144.059159) (xy 100.347593 -144.088625)
			(xy 100.365166 -144.103852) (xy 102.455216 -144.103852) (xy 102.459287 -144.04823) (xy 102.471413 -143.993793)
			(xy 102.491336 -143.941702) (xy 102.518632 -143.893067) (xy 102.552718 -143.848924) (xy 102.592867 -143.810215)
			(xy 102.638225 -143.777764) (xy 102.687825 -143.752263) (xy 102.740609 -143.734256) (xy 102.795452 -143.724126)
			(xy 102.851186 -143.722089) (xy 102.906623 -143.728189) (xy 102.96058 -143.742295) (xy 103.011909 -143.764107)
			(xy 103.059515 -143.793161) (xy 103.102383 -143.828836) (xy 103.1396 -143.870373) (xy 103.170373 -143.916886)
			(xy 103.194045 -143.967383) (xy 103.210113 -144.02079) (xy 103.218233 -144.075966) (xy 103.218742 -144.103852)
			(xy 103.218233 -144.131738) (xy 103.210113 -144.186914) (xy 103.194045 -144.240321) (xy 103.170373 -144.290818)
			(xy 103.1396 -144.337331) (xy 103.102383 -144.378868) (xy 103.059515 -144.414543) (xy 103.011909 -144.443597)
			(xy 102.96058 -144.465409) (xy 102.906623 -144.479515) (xy 102.851186 -144.485615) (xy 102.795452 -144.483578)
			(xy 102.740609 -144.473448) (xy 102.687825 -144.455441) (xy 102.638225 -144.42994) (xy 102.592867 -144.397489)
			(xy 102.552718 -144.35878) (xy 102.518632 -144.314637) (xy 102.491336 -144.266002) (xy 102.471413 -144.213911)
			(xy 102.459287 -144.159474) (xy 102.455216 -144.103852) (xy 100.365166 -144.103852) (xy 100.388784 -144.124316)
			(xy 100.424475 -144.165507) (xy 100.453941 -144.211357) (xy 100.476583 -144.260934) (xy 100.491938 -144.313229)
			(xy 100.499694 -144.367177) (xy 100.50018 -144.394428) (xy 100.49979 -144.420371) (xy 100.492755 -144.471777)
			(xy 100.478818 -144.521756) (xy 100.458236 -144.569385) (xy 100.431389 -144.613785) (xy 100.398773 -144.654138)
			(xy 100.360989 -144.689697) (xy 100.318734 -144.719808) (xy 100.295964 -144.732248) (xy 100.286058 -144.737328)
			(xy 100.27285 -144.754092) (xy 100.249228 -144.849342) (xy 100.253038 -144.870424) (xy 100.259134 -144.879568)
			(xy 100.274797 -144.903487) (xy 100.299645 -144.954978) (xy 100.316544 -145.009595) (xy 100.325119 -145.06612)
			(xy 100.325682 -145.094706) (xy 100.325346 -145.117825) (xy 100.31978 -145.163725) (xy 100.308693 -145.208614)
			(xy 100.30079 -145.230342) (xy 100.296218 -145.242026) (xy 100.298758 -145.265902) (xy 100.357178 -145.35531)
			(xy 100.378006 -145.367502) (xy 100.390198 -145.36801) (xy 100.419095 -145.370045) (xy 100.475808 -145.38185)
			(xy 100.530086 -145.402092) (xy 100.58068 -145.430305) (xy 100.626428 -145.465842) (xy 100.66628 -145.507885)
			(xy 100.699318 -145.555469) (xy 100.724785 -145.6075) (xy 100.742094 -145.662782) (xy 100.743666 -145.673064)
			(xy 102.076756 -145.673064) (xy 102.080827 -145.617442) (xy 102.092953 -145.563005) (xy 102.112876 -145.510914)
			(xy 102.140172 -145.462279) (xy 102.174258 -145.418136) (xy 102.214407 -145.379427) (xy 102.259765 -145.346976)
			(xy 102.309365 -145.321475) (xy 102.362149 -145.303468) (xy 102.416992 -145.293338) (xy 102.472726 -145.291301)
			(xy 102.528163 -145.297401) (xy 102.58212 -145.311507) (xy 102.633449 -145.333319) (xy 102.681055 -145.362373)
			(xy 102.723923 -145.398048) (xy 102.76114 -145.439585) (xy 102.763024 -145.442432) (xy 103.786176 -145.442432)
			(xy 103.790247 -145.38681) (xy 103.802373 -145.332373) (xy 103.822296 -145.280282) (xy 103.849592 -145.231647)
			(xy 103.883678 -145.187504) (xy 103.923827 -145.148795) (xy 103.969185 -145.116344) (xy 104.018785 -145.090843)
			(xy 104.071569 -145.072836) (xy 104.126412 -145.062706) (xy 104.182146 -145.060669) (xy 104.237583 -145.066769)
			(xy 104.29154 -145.080875) (xy 104.342869 -145.102687) (xy 104.390475 -145.131741) (xy 104.433343 -145.167416)
			(xy 104.47056 -145.208953) (xy 104.501333 -145.255466) (xy 104.525005 -145.305963) (xy 104.541073 -145.35937)
			(xy 104.549193 -145.414546) (xy 104.549702 -145.442432) (xy 104.549193 -145.470318) (xy 104.541073 -145.525494)
			(xy 104.525005 -145.578901) (xy 104.501333 -145.629398) (xy 104.47056 -145.675911) (xy 104.433343 -145.717448)
			(xy 104.390475 -145.753123) (xy 104.342869 -145.782177) (xy 104.29154 -145.803989) (xy 104.237583 -145.818095)
			(xy 104.182146 -145.824195) (xy 104.126412 -145.822158) (xy 104.071569 -145.812028) (xy 104.018785 -145.794021)
			(xy 103.969185 -145.76852) (xy 103.923827 -145.736069) (xy 103.883678 -145.69736) (xy 103.849592 -145.653217)
			(xy 103.822296 -145.604582) (xy 103.802373 -145.552491) (xy 103.790247 -145.498054) (xy 103.786176 -145.442432)
			(xy 102.763024 -145.442432) (xy 102.791913 -145.486098) (xy 102.815585 -145.536595) (xy 102.831653 -145.590002)
			(xy 102.839773 -145.645178) (xy 102.840282 -145.673064) (xy 102.839773 -145.70095) (xy 102.831653 -145.756126)
			(xy 102.815585 -145.809533) (xy 102.791913 -145.86003) (xy 102.76114 -145.906543) (xy 102.723923 -145.94808)
			(xy 102.681055 -145.983755) (xy 102.633449 -146.012809) (xy 102.58212 -146.034621) (xy 102.528163 -146.048727)
			(xy 102.472726 -146.054827) (xy 102.416992 -146.05279) (xy 102.362149 -146.04266) (xy 102.309365 -146.024653)
			(xy 102.259765 -145.999152) (xy 102.214407 -145.966701) (xy 102.174258 -145.927992) (xy 102.140172 -145.883849)
			(xy 102.112876 -145.835214) (xy 102.092953 -145.783123) (xy 102.080827 -145.728686) (xy 102.076756 -145.673064)
			(xy 100.743666 -145.673064) (xy 100.750849 -145.720046) (xy 100.751386 -145.74901) (xy 100.7509 -145.776261)
			(xy 100.743144 -145.830209) (xy 100.727789 -145.882504) (xy 100.705147 -145.932081) (xy 100.675681 -145.977931)
			(xy 100.63999 -146.019122) (xy 100.598799 -146.054813) (xy 100.552949 -146.084279) (xy 100.503372 -146.106921)
			(xy 100.451077 -146.122276) (xy 100.397129 -146.130032) (xy 100.342627 -146.130032) (xy 100.288679 -146.122276)
			(xy 100.236384 -146.106921) (xy 100.186807 -146.084279) (xy 100.140957 -146.054813) (xy 100.099766 -146.019122)
			(xy 100.064075 -145.977931) (xy 100.034609 -145.932081) (xy 100.011967 -145.882504) (xy 99.996612 -145.830209)
			(xy 99.988856 -145.776261) (xy 99.98837 -145.74901) (xy 99.988678 -145.72589) (xy 99.994255 -145.679989)
			(xy 100.005353 -145.635101) (xy 100.013262 -145.613374) (xy 100.017834 -145.60169) (xy 100.015294 -145.577814)
			(xy 99.956874 -145.488406) (xy 99.936046 -145.476214) (xy 99.923854 -145.475706) (xy 99.894962 -145.47361)
			(xy 99.838252 -145.461813) (xy 99.783976 -145.441579) (xy 99.733382 -145.413373) (xy 99.687633 -145.377844)
			(xy 99.647781 -145.335808) (xy 99.614741 -145.28823) (xy 99.589273 -145.236205) (xy 99.571961 -145.180927)
			(xy 99.563204 -145.123668) (xy 99.562666 -145.094706) (xy 91.70971 -145.094706) (xy 91.709689 -145.094777)
			(xy 91.686017 -145.145274) (xy 91.655244 -145.191787) (xy 91.618027 -145.233324) (xy 91.575159 -145.268999)
			(xy 91.527553 -145.298053) (xy 91.476224 -145.319865) (xy 91.422267 -145.333971) (xy 91.36683 -145.340071)
			(xy 91.311096 -145.338034) (xy 91.256253 -145.327904) (xy 91.203469 -145.309897) (xy 91.153869 -145.284396)
			(xy 91.108511 -145.251945) (xy 91.068362 -145.213236) (xy 91.034276 -145.169093) (xy 91.00698 -145.120458)
			(xy 90.987057 -145.068367) (xy 90.974931 -145.01393) (xy 90.97086 -144.958308) (xy 89.568253 -144.958308)
			(xy 89.566757 -144.968472) (xy 89.550689 -145.021879) (xy 89.527017 -145.072376) (xy 89.496244 -145.118889)
			(xy 89.459027 -145.160426) (xy 89.416159 -145.196101) (xy 89.368553 -145.225155) (xy 89.317224 -145.246967)
			(xy 89.263267 -145.261073) (xy 89.20783 -145.267173) (xy 89.152096 -145.265136) (xy 89.097253 -145.255006)
			(xy 89.044469 -145.236999) (xy 88.994869 -145.211498) (xy 88.949511 -145.179047) (xy 88.909362 -145.140338)
			(xy 88.875276 -145.096195) (xy 88.84798 -145.04756) (xy 88.828057 -144.995469) (xy 88.815931 -144.941032)
			(xy 88.81186 -144.88541) (xy 57.910847 -144.88541) (xy 57.912957 -144.889911) (xy 57.929025 -144.943318)
			(xy 57.937145 -144.998494) (xy 57.937654 -145.02638) (xy 57.937145 -145.054266) (xy 57.929025 -145.109442)
			(xy 57.912957 -145.162849) (xy 57.889285 -145.213346) (xy 57.858512 -145.259859) (xy 57.821295 -145.301396)
			(xy 57.778427 -145.337071) (xy 57.730821 -145.366125) (xy 57.679492 -145.387937) (xy 57.625535 -145.402043)
			(xy 57.570098 -145.408143) (xy 57.514364 -145.406106) (xy 57.459521 -145.395976) (xy 57.406737 -145.377969)
			(xy 57.357137 -145.352468) (xy 57.311779 -145.320017) (xy 57.27163 -145.281308) (xy 57.237544 -145.237165)
			(xy 57.210248 -145.18853) (xy 57.190325 -145.136439) (xy 57.178199 -145.082002) (xy 57.174128 -145.02638)
			(xy 54.901338 -145.02638) (xy 53.954426 -145.973292) (xy 69.238366 -145.973292) (xy 69.242437 -145.91767)
			(xy 69.254563 -145.863233) (xy 69.274486 -145.811142) (xy 69.301782 -145.762507) (xy 69.335868 -145.718364)
			(xy 69.376017 -145.679655) (xy 69.421375 -145.647204) (xy 69.470975 -145.621703) (xy 69.523759 -145.603696)
			(xy 69.578602 -145.593566) (xy 69.634336 -145.591529) (xy 69.689773 -145.597629) (xy 69.74373 -145.611735)
			(xy 69.795059 -145.633547) (xy 69.842665 -145.662601) (xy 69.885533 -145.698276) (xy 69.92275 -145.739813)
			(xy 69.953523 -145.786326) (xy 69.977195 -145.836823) (xy 69.993263 -145.89023) (xy 70.001383 -145.945406)
			(xy 70.001892 -145.973292) (xy 70.001383 -146.001178) (xy 69.993263 -146.056354) (xy 69.987686 -146.074892)
			(xy 73.130916 -146.074892) (xy 73.134987 -146.01927) (xy 73.147113 -145.964833) (xy 73.167036 -145.912742)
			(xy 73.194332 -145.864107) (xy 73.228418 -145.819964) (xy 73.268567 -145.781255) (xy 73.313925 -145.748804)
			(xy 73.363525 -145.723303) (xy 73.416309 -145.705296) (xy 73.471152 -145.695166) (xy 73.526886 -145.693129)
			(xy 73.582323 -145.699229) (xy 73.63628 -145.713335) (xy 73.687609 -145.735147) (xy 73.735215 -145.764201)
			(xy 73.778083 -145.799876) (xy 73.8153 -145.841413) (xy 73.846073 -145.887926) (xy 73.869745 -145.938423)
			(xy 73.873303 -145.95025) (xy 85.577678 -145.95025) (xy 85.577678 -145.89575) (xy 85.585434 -145.841804)
			(xy 85.600788 -145.789511) (xy 85.623428 -145.739935) (xy 85.652892 -145.694085) (xy 85.688581 -145.652895)
			(xy 85.729769 -145.617204) (xy 85.775617 -145.587737) (xy 85.825192 -145.565095) (xy 85.877484 -145.549738)
			(xy 85.93143 -145.541979) (xy 85.95868 -145.541492) (xy 85.984408 -145.541906) (xy 86.035397 -145.548825)
			(xy 86.084992 -145.56254) (xy 86.132291 -145.582801) (xy 86.176435 -145.609241) (xy 86.216621 -145.641379)
			(xy 86.252119 -145.67863) (xy 86.267544 -145.699226) (xy 86.275964 -145.710071) (xy 86.297411 -145.727195)
			(xy 86.322644 -145.737991) (xy 86.34984 -145.741678) (xy 86.377036 -145.737991) (xy 86.402269 -145.727195)
			(xy 86.423716 -145.710071) (xy 86.432136 -145.699226) (xy 86.44755 -145.678622) (xy 86.483053 -145.641377)
			(xy 86.523243 -145.609244) (xy 86.567389 -145.582808) (xy 86.614689 -145.562548) (xy 86.664283 -145.548834)
			(xy 86.715272 -145.541914) (xy 86.741 -145.541492) (xy 86.768251 -145.541978) (xy 86.822199 -145.549734)
			(xy 86.874494 -145.565089) (xy 86.924071 -145.587731) (xy 86.969921 -145.617197) (xy 87.011112 -145.652888)
			(xy 87.046803 -145.694079) (xy 87.076269 -145.739929) (xy 87.098911 -145.789506) (xy 87.114266 -145.841801)
			(xy 87.122022 -145.895749) (xy 87.122022 -145.90141) (xy 90.84386 -145.90141) (xy 90.847931 -145.845788)
			(xy 90.860057 -145.791351) (xy 90.87998 -145.73926) (xy 90.907276 -145.690625) (xy 90.941362 -145.646482)
			(xy 90.981511 -145.607773) (xy 91.026869 -145.575322) (xy 91.076469 -145.549821) (xy 91.129253 -145.531814)
			(xy 91.184096 -145.521684) (xy 91.23983 -145.519647) (xy 91.295267 -145.525747) (xy 91.349224 -145.539853)
			(xy 91.400553 -145.561665) (xy 91.448159 -145.590719) (xy 91.491027 -145.626394) (xy 91.528244 -145.667931)
			(xy 91.559017 -145.714444) (xy 91.582689 -145.764941) (xy 91.598757 -145.818348) (xy 91.606877 -145.873524)
			(xy 91.607386 -145.90141) (xy 91.606877 -145.929296) (xy 91.598757 -145.984472) (xy 91.582689 -146.037879)
			(xy 91.559017 -146.088376) (xy 91.528244 -146.134889) (xy 91.491027 -146.176426) (xy 91.448159 -146.212101)
			(xy 91.400553 -146.241155) (xy 91.349224 -146.262967) (xy 91.295267 -146.277073) (xy 91.23983 -146.283173)
			(xy 91.184096 -146.281136) (xy 91.129253 -146.271006) (xy 91.076469 -146.252999) (xy 91.026869 -146.227498)
			(xy 90.981511 -146.195047) (xy 90.941362 -146.156338) (xy 90.907276 -146.112195) (xy 90.87998 -146.06356)
			(xy 90.860057 -146.011469) (xy 90.847931 -145.957032) (xy 90.84386 -145.90141) (xy 87.122022 -145.90141)
			(xy 87.122022 -145.950251) (xy 87.114266 -146.004199) (xy 87.098911 -146.056494) (xy 87.076269 -146.106071)
			(xy 87.046803 -146.151921) (xy 87.011112 -146.193112) (xy 86.969921 -146.228803) (xy 86.924071 -146.258269)
			(xy 86.874494 -146.280911) (xy 86.822199 -146.296266) (xy 86.768251 -146.304022) (xy 86.741 -146.304508)
			(xy 86.715271 -146.304109) (xy 86.664282 -146.297187) (xy 86.614686 -146.28347) (xy 86.567387 -146.263206)
			(xy 86.523243 -146.236764) (xy 86.483058 -146.204624) (xy 86.44756 -146.167371) (xy 86.432136 -146.146774)
			(xy 86.423716 -146.135929) (xy 86.402269 -146.118805) (xy 86.377036 -146.108009) (xy 86.34984 -146.104322)
			(xy 86.322644 -146.108009) (xy 86.297411 -146.118805) (xy 86.275964 -146.135929) (xy 86.267544 -146.146774)
			(xy 86.252142 -146.167387) (xy 86.216637 -146.204632) (xy 86.176445 -146.236765) (xy 86.132297 -146.2632)
			(xy 86.084995 -146.283457) (xy 86.035399 -146.297169) (xy 85.984409 -146.304087) (xy 85.95868 -146.304508)
			(xy 85.93143 -146.304021) (xy 85.877484 -146.296262) (xy 85.825192 -146.280905) (xy 85.775617 -146.258263)
			(xy 85.729769 -146.228796) (xy 85.688581 -146.193105) (xy 85.652892 -146.151915) (xy 85.623428 -146.106065)
			(xy 85.600788 -146.056489) (xy 85.585434 -146.004196) (xy 85.577678 -145.95025) (xy 73.873303 -145.95025)
			(xy 73.885813 -145.99183) (xy 73.893933 -146.047006) (xy 73.894442 -146.074892) (xy 73.893933 -146.102778)
			(xy 73.885813 -146.157954) (xy 73.869745 -146.211361) (xy 73.846073 -146.261858) (xy 73.8153 -146.308371)
			(xy 73.778083 -146.349908) (xy 73.735215 -146.385583) (xy 73.687609 -146.414637) (xy 73.63628 -146.436449)
			(xy 73.582323 -146.450555) (xy 73.526886 -146.456655) (xy 73.471152 -146.454618) (xy 73.416309 -146.444488)
			(xy 73.363525 -146.426481) (xy 73.313925 -146.40098) (xy 73.268567 -146.368529) (xy 73.228418 -146.32982)
			(xy 73.194332 -146.285677) (xy 73.167036 -146.237042) (xy 73.147113 -146.184951) (xy 73.134987 -146.130514)
			(xy 73.130916 -146.074892) (xy 69.987686 -146.074892) (xy 69.977195 -146.109761) (xy 69.953523 -146.160258)
			(xy 69.92275 -146.206771) (xy 69.885533 -146.248308) (xy 69.842665 -146.283983) (xy 69.795059 -146.313037)
			(xy 69.74373 -146.334849) (xy 69.689773 -146.348955) (xy 69.634336 -146.355055) (xy 69.578602 -146.353018)
			(xy 69.523759 -146.342888) (xy 69.470975 -146.324881) (xy 69.421375 -146.29938) (xy 69.376017 -146.266929)
			(xy 69.335868 -146.22822) (xy 69.301782 -146.184077) (xy 69.274486 -146.135442) (xy 69.254563 -146.083351)
			(xy 69.242437 -146.028914) (xy 69.238366 -145.973292) (xy 53.954426 -145.973292) (xy 53.321966 -146.605752)
			(xy 74.369928 -146.605752) (xy 74.373999 -146.55013) (xy 74.386125 -146.495693) (xy 74.406048 -146.443602)
			(xy 74.433344 -146.394967) (xy 74.46743 -146.350824) (xy 74.507579 -146.312115) (xy 74.552937 -146.279664)
			(xy 74.602537 -146.254163) (xy 74.655321 -146.236156) (xy 74.710164 -146.226026) (xy 74.765898 -146.223989)
			(xy 74.821335 -146.230089) (xy 74.875292 -146.244195) (xy 74.926621 -146.266007) (xy 74.974227 -146.295061)
			(xy 75.017095 -146.330736) (xy 75.054312 -146.372273) (xy 75.085085 -146.418786) (xy 75.108757 -146.469283)
			(xy 75.124825 -146.52269) (xy 75.132945 -146.577866) (xy 75.133454 -146.605752) (xy 75.132945 -146.633638)
			(xy 75.124825 -146.688814) (xy 75.108757 -146.742221) (xy 75.085085 -146.792718) (xy 75.054312 -146.839231)
			(xy 75.017095 -146.880768) (xy 74.974227 -146.916443) (xy 74.937267 -146.939) (xy 86.612982 -146.939)
			(xy 86.617053 -146.883378) (xy 86.629179 -146.828941) (xy 86.649102 -146.77685) (xy 86.676398 -146.728215)
			(xy 86.710484 -146.684072) (xy 86.750633 -146.645363) (xy 86.795991 -146.612912) (xy 86.845591 -146.587411)
			(xy 86.898375 -146.569404) (xy 86.953218 -146.559274) (xy 87.008952 -146.557237) (xy 87.064389 -146.563337)
			(xy 87.118346 -146.577443) (xy 87.169675 -146.599255) (xy 87.217281 -146.628309) (xy 87.260149 -146.663984)
			(xy 87.297366 -146.705521) (xy 87.328139 -146.752034) (xy 87.351811 -146.802531) (xy 87.367879 -146.855938)
			(xy 87.375999 -146.911114) (xy 87.376508 -146.939) (xy 87.375999 -146.966886) (xy 87.367879 -147.022062)
			(xy 87.351811 -147.075469) (xy 87.328139 -147.125966) (xy 87.297366 -147.172479) (xy 87.260149 -147.214016)
			(xy 87.217281 -147.249691) (xy 87.169675 -147.278745) (xy 87.118346 -147.300557) (xy 87.064389 -147.314663)
			(xy 87.008952 -147.320763) (xy 86.953218 -147.318726) (xy 86.898375 -147.308596) (xy 86.845591 -147.290589)
			(xy 86.795991 -147.265088) (xy 86.750633 -147.232637) (xy 86.710484 -147.193928) (xy 86.676398 -147.149785)
			(xy 86.649102 -147.10115) (xy 86.629179 -147.049059) (xy 86.617053 -146.994622) (xy 86.612982 -146.939)
			(xy 74.937267 -146.939) (xy 74.926621 -146.945497) (xy 74.875292 -146.967309) (xy 74.821335 -146.981415)
			(xy 74.765898 -146.987515) (xy 74.710164 -146.985478) (xy 74.655321 -146.975348) (xy 74.602537 -146.957341)
			(xy 74.552937 -146.93184) (xy 74.507579 -146.899389) (xy 74.46743 -146.86068) (xy 74.433344 -146.816537)
			(xy 74.406048 -146.767902) (xy 74.386125 -146.715811) (xy 74.373999 -146.661374) (xy 74.369928 -146.605752)
			(xy 53.321966 -146.605752) (xy 52.510182 -147.417536) (xy 75.262992 -147.417536) (xy 75.267063 -147.361914)
			(xy 75.279189 -147.307477) (xy 75.299112 -147.255386) (xy 75.326408 -147.206751) (xy 75.360494 -147.162608)
			(xy 75.400643 -147.123899) (xy 75.446001 -147.091448) (xy 75.495601 -147.065947) (xy 75.548385 -147.04794)
			(xy 75.603228 -147.03781) (xy 75.658962 -147.035773) (xy 75.714399 -147.041873) (xy 75.768356 -147.055979)
			(xy 75.819685 -147.077791) (xy 75.867291 -147.106845) (xy 75.910159 -147.14252) (xy 75.947376 -147.184057)
			(xy 75.978149 -147.23057) (xy 76.001821 -147.281067) (xy 76.017889 -147.334474) (xy 76.026009 -147.38965)
			(xy 76.026518 -147.417536) (xy 76.026027 -147.44446) (xy 103.134414 -147.44446) (xy 103.134842 -147.418796)
			(xy 103.14171 -147.367929) (xy 103.155345 -147.318446) (xy 103.175498 -147.27124) (xy 103.201806 -147.227166)
			(xy 103.233791 -147.187023) (xy 103.270876 -147.151537) (xy 103.291386 -147.136104) (xy 103.302172 -147.127651)
			(xy 103.319255 -147.106243) (xy 103.330025 -147.081061) (xy 103.333708 -147.053921) (xy 103.330036 -147.026779)
			(xy 103.319276 -147.001593) (xy 103.302202 -146.980177) (xy 103.291386 -146.971766) (xy 103.267495 -146.953705)
			(xy 103.225182 -146.911322) (xy 103.190012 -146.862847) (xy 103.162849 -146.809472) (xy 103.14436 -146.752508)
			(xy 103.135 -146.693355) (xy 103.134414 -146.66341) (xy 103.1349 -146.636159) (xy 103.142656 -146.582211)
			(xy 103.158011 -146.529916) (xy 103.180653 -146.480339) (xy 103.210119 -146.434489) (xy 103.24581 -146.393298)
			(xy 103.287001 -146.357607) (xy 103.332851 -146.328141) (xy 103.382428 -146.305499) (xy 103.434723 -146.290144)
			(xy 103.488671 -146.282388) (xy 103.543173 -146.282388) (xy 103.597121 -146.290144) (xy 103.649416 -146.305499)
			(xy 103.698993 -146.328141) (xy 103.744843 -146.357607) (xy 103.786034 -146.393298) (xy 103.821725 -146.434489)
			(xy 103.84103 -146.464528) (xy 115.805966 -146.464528) (xy 115.806432 -146.437158) (xy 115.814248 -146.382978)
			(xy 115.829736 -146.330474) (xy 115.852578 -146.280727) (xy 115.882304 -146.234761) (xy 115.899946 -146.21383)
			(xy 115.906042 -146.206718) (xy 115.912392 -146.1897) (xy 115.912392 -146.104356) (xy 115.906042 -146.087338)
			(xy 115.899946 -146.080226) (xy 115.882332 -146.059271) (xy 115.852605 -146.013308) (xy 115.829756 -145.963565)
			(xy 115.814257 -145.911066) (xy 115.806426 -145.856891) (xy 115.806422 -145.802152) (xy 115.814248 -145.747975)
			(xy 115.829742 -145.695474) (xy 115.852584 -145.645729) (xy 115.882307 -145.599762) (xy 115.899946 -145.57883)
			(xy 115.906042 -145.571718) (xy 115.912392 -145.5547) (xy 115.912392 -145.469356) (xy 115.906042 -145.452338)
			(xy 115.899946 -145.445226) (xy 115.882332 -145.424271) (xy 115.852605 -145.378308) (xy 115.829756 -145.328565)
			(xy 115.814257 -145.276066) (xy 115.806426 -145.221891) (xy 115.806422 -145.167152) (xy 115.814248 -145.112975)
			(xy 115.829742 -145.060474) (xy 115.852584 -145.010729) (xy 115.882307 -144.964762) (xy 115.899946 -144.94383)
			(xy 115.906042 -144.936718) (xy 115.912392 -144.9197) (xy 115.912392 -144.834356) (xy 115.906042 -144.817338)
			(xy 115.899946 -144.810226) (xy 115.882332 -144.789271) (xy 115.852605 -144.743308) (xy 115.829756 -144.693565)
			(xy 115.814257 -144.641066) (xy 115.806426 -144.586891) (xy 115.806422 -144.532152) (xy 115.814248 -144.477975)
			(xy 115.829742 -144.425474) (xy 115.852584 -144.375729) (xy 115.882307 -144.329762) (xy 115.899946 -144.30883)
			(xy 115.906042 -144.301718) (xy 115.912392 -144.2847) (xy 115.912392 -144.199356) (xy 115.906042 -144.182338)
			(xy 115.899946 -144.175226) (xy 115.882313 -144.154289) (xy 115.852598 -144.108318) (xy 115.829761 -144.058572)
			(xy 115.814268 -144.006072) (xy 115.80644 -143.951897) (xy 115.805966 -143.924528) (xy 115.806481 -143.897277)
			(xy 115.814234 -143.843329) (xy 115.829585 -143.791034) (xy 115.852222 -143.741456) (xy 115.881685 -143.695604)
			(xy 115.917373 -143.654411) (xy 115.95856 -143.618717) (xy 116.004408 -143.589248) (xy 116.053983 -143.566604)
			(xy 116.106276 -143.551245) (xy 116.160223 -143.543485) (xy 116.187474 -143.54302) (xy 116.214844 -143.543496)
			(xy 116.269023 -143.551311) (xy 116.321526 -143.566797) (xy 116.371273 -143.589637) (xy 116.41724 -143.61936)
			(xy 116.438172 -143.637) (xy 116.445284 -143.643096) (xy 116.462302 -143.649446) (xy 116.547646 -143.649446)
			(xy 116.564664 -143.643096) (xy 116.571776 -143.637) (xy 116.592706 -143.619359) (xy 116.63868 -143.589647)
			(xy 116.688428 -143.566812) (xy 116.740929 -143.551321) (xy 116.795105 -143.543494) (xy 116.822474 -143.54302)
			(xy 116.850048 -143.543497) (xy 116.904621 -143.551446) (xy 116.957481 -143.567168) (xy 117.007527 -143.590336)
			(xy 117.053717 -143.620467) (xy 117.095088 -143.656933) (xy 117.113304 -143.67764) (xy 117.120903 -143.685762)
			(xy 117.141057 -143.695113) (xy 117.152166 -143.695674) (xy 117.229382 -143.695674) (xy 117.240494 -143.69512)
			(xy 117.260653 -143.685773) (xy 117.268244 -143.67764) (xy 117.28649 -143.656961) (xy 117.32785 -143.620486)
			(xy 117.374033 -143.590349) (xy 117.424074 -143.567177) (xy 117.476931 -143.551455) (xy 117.531501 -143.543509)
			(xy 117.559074 -143.54302) (xy 117.586444 -143.543496) (xy 117.640623 -143.551311) (xy 117.693126 -143.566797)
			(xy 117.742873 -143.589637) (xy 117.78884 -143.61936) (xy 117.809772 -143.637) (xy 117.816884 -143.643096)
			(xy 117.833902 -143.649446) (xy 117.919246 -143.649446) (xy 117.936264 -143.643096) (xy 117.943376 -143.637)
			(xy 117.964309 -143.619359) (xy 118.010277 -143.589635) (xy 118.060023 -143.566789) (xy 118.112525 -143.551293)
			(xy 118.166703 -143.543464) (xy 118.221445 -143.543464) (xy 118.275623 -143.551293) (xy 118.328125 -143.566789)
			(xy 118.377871 -143.589635) (xy 118.423839 -143.619359) (xy 118.444772 -143.637) (xy 118.451884 -143.643096)
			(xy 118.468902 -143.649446) (xy 118.554246 -143.649446) (xy 118.571264 -143.643096) (xy 118.578376 -143.637)
			(xy 118.599309 -143.619359) (xy 118.645277 -143.589635) (xy 118.695023 -143.566789) (xy 118.747525 -143.551293)
			(xy 118.801703 -143.543464) (xy 118.856445 -143.543464) (xy 118.910623 -143.551293) (xy 118.963125 -143.566789)
			(xy 119.012871 -143.589635) (xy 119.058839 -143.619359) (xy 119.079772 -143.637) (xy 119.086884 -143.643096)
			(xy 119.103902 -143.649446) (xy 119.189246 -143.649446) (xy 119.206264 -143.643096) (xy 119.213376 -143.637)
			(xy 119.234306 -143.619359) (xy 119.28028 -143.589647) (xy 119.330028 -143.566812) (xy 119.382529 -143.551321)
			(xy 119.436705 -143.543494) (xy 119.464074 -143.54302) (xy 119.491648 -143.543497) (xy 119.546221 -143.551446)
			(xy 119.599081 -143.567168) (xy 119.649127 -143.590336) (xy 119.695317 -143.620467) (xy 119.736688 -143.656933)
			(xy 119.754904 -143.67764) (xy 119.762503 -143.685762) (xy 119.782657 -143.695113) (xy 119.793766 -143.695674)
			(xy 119.870982 -143.695674) (xy 119.882094 -143.69512) (xy 119.902253 -143.685773) (xy 119.909844 -143.67764)
			(xy 119.92809 -143.656961) (xy 119.96945 -143.620486) (xy 120.015633 -143.590349) (xy 120.065674 -143.567177)
			(xy 120.118531 -143.551455) (xy 120.173101 -143.543509) (xy 120.200674 -143.54302) (xy 120.228044 -143.543496)
			(xy 120.282223 -143.551311) (xy 120.334726 -143.566797) (xy 120.384473 -143.589637) (xy 120.43044 -143.61936)
			(xy 120.451372 -143.637) (xy 120.458484 -143.643096) (xy 120.475502 -143.649446) (xy 120.560846 -143.649446)
			(xy 120.577864 -143.643096) (xy 120.584976 -143.637) (xy 120.605906 -143.619359) (xy 120.65188 -143.589647)
			(xy 120.701628 -143.566812) (xy 120.754129 -143.551321) (xy 120.808305 -143.543494) (xy 120.835674 -143.54302)
			(xy 120.862927 -143.54348) (xy 120.91688 -143.551234) (xy 120.96918 -143.566588) (xy 121.018762 -143.589229)
			(xy 121.064616 -143.618697) (xy 121.10581 -143.654392) (xy 121.141504 -143.695585) (xy 121.170972 -143.74144)
			(xy 121.193613 -143.791022) (xy 121.208967 -143.843322) (xy 121.216721 -143.897275) (xy 121.217182 -143.924528)
			(xy 121.216737 -143.951899) (xy 121.208915 -144.006079) (xy 121.193421 -144.058583) (xy 121.170574 -144.108329)
			(xy 121.140845 -144.154295) (xy 121.123202 -144.175226) (xy 121.117106 -144.182338) (xy 121.110756 -144.199356)
			(xy 121.110756 -144.2847) (xy 121.117106 -144.301718) (xy 121.123202 -144.30883) (xy 121.140869 -144.329741)
			(xy 121.17059 -144.375713) (xy 121.193432 -144.425463) (xy 121.208925 -144.477968) (xy 121.216751 -144.532149)
			(xy 121.216747 -144.586893) (xy 121.208916 -144.641073) (xy 121.193417 -144.693576) (xy 121.17057 -144.743324)
			(xy 121.140843 -144.789293) (xy 121.123202 -144.810226) (xy 121.117106 -144.817338) (xy 121.110756 -144.834356)
			(xy 121.110756 -144.9197) (xy 121.117106 -144.936718) (xy 121.123202 -144.94383) (xy 121.140869 -144.964741)
			(xy 121.17059 -145.010713) (xy 121.193432 -145.060463) (xy 121.208925 -145.112968) (xy 121.216751 -145.167149)
			(xy 121.216747 -145.221893) (xy 121.208916 -145.276073) (xy 121.193417 -145.328576) (xy 121.17057 -145.378324)
			(xy 121.140843 -145.424293) (xy 121.123202 -145.445226) (xy 121.117106 -145.452338) (xy 121.110756 -145.469356)
			(xy 121.110756 -145.5547) (xy 121.117106 -145.571718) (xy 121.123202 -145.57883) (xy 121.140869 -145.599741)
			(xy 121.17059 -145.645713) (xy 121.193432 -145.695463) (xy 121.208925 -145.747968) (xy 121.216751 -145.802149)
			(xy 121.216747 -145.856893) (xy 121.208916 -145.911073) (xy 121.193417 -145.963576) (xy 121.17057 -146.013324)
			(xy 121.140843 -146.059293) (xy 121.123202 -146.080226) (xy 121.117106 -146.087338) (xy 121.110756 -146.104356)
			(xy 121.110756 -146.1897) (xy 121.117106 -146.206718) (xy 121.123202 -146.21383) (xy 121.140822 -146.234777)
			(xy 121.170537 -146.280746) (xy 121.193376 -146.33049) (xy 121.208872 -146.382987) (xy 121.216705 -146.43716)
			(xy 121.217182 -146.464528) (xy 121.216748 -146.491781) (xy 121.208987 -146.545732) (xy 121.193627 -146.598029)
			(xy 121.170981 -146.647608) (xy 121.141509 -146.69346) (xy 121.105812 -146.734651) (xy 121.064617 -146.770342)
			(xy 121.018761 -146.799807) (xy 120.969179 -146.822446) (xy 120.916879 -146.837799) (xy 120.862927 -146.845552)
			(xy 120.835674 -146.846036) (xy 120.808302 -146.845601) (xy 120.754121 -146.837778) (xy 120.701617 -146.822282)
			(xy 120.651871 -146.799433) (xy 120.605906 -146.769701) (xy 120.584976 -146.752056) (xy 120.577864 -146.74596)
			(xy 120.560846 -146.73961) (xy 120.475502 -146.73961) (xy 120.458484 -146.74596) (xy 120.451372 -146.752056)
			(xy 120.430418 -146.769668) (xy 120.384452 -146.799385) (xy 120.33471 -146.822227) (xy 120.282214 -146.837725)
			(xy 120.228042 -146.845559) (xy 120.200674 -146.846036) (xy 120.173354 -146.845559) (xy 120.119273 -146.83776)
			(xy 120.066857 -146.822326) (xy 120.01718 -146.799573) (xy 119.971256 -146.769965) (xy 119.930026 -146.734109)
			(xy 119.894333 -146.692738) (xy 119.864907 -146.646698) (xy 119.853202 -146.622008) (xy 119.847106 -146.608292)
			(xy 119.82196 -146.592036) (xy 119.759984 -146.592036) (xy 119.741188 -146.59991) (xy 119.734076 -146.607022)
			(xy 119.714472 -146.626004) (xy 119.670814 -146.658738) (xy 119.622937 -146.684918) (xy 119.571819 -146.704009)
			(xy 119.518502 -146.715621) (xy 119.464074 -146.719519) (xy 119.409646 -146.715621) (xy 119.356329 -146.704009)
			(xy 119.305211 -146.684918) (xy 119.257334 -146.658738) (xy 119.213676 -146.626004) (xy 119.194072 -146.607022)
			(xy 119.18696 -146.59991) (xy 119.168164 -146.592036) (xy 119.124984 -146.592036) (xy 119.106188 -146.59991)
			(xy 119.099076 -146.607022) (xy 119.079472 -146.626004) (xy 119.035814 -146.658738) (xy 118.987937 -146.684918)
			(xy 118.936819 -146.704009) (xy 118.883502 -146.715621) (xy 118.829074 -146.719519) (xy 118.774646 -146.715621)
			(xy 118.721329 -146.704009) (xy 118.670211 -146.684918) (xy 118.622334 -146.658738) (xy 118.578676 -146.626004)
			(xy 118.559072 -146.607022) (xy 118.55196 -146.59991) (xy 118.533164 -146.592036) (xy 118.489984 -146.592036)
			(xy 118.471188 -146.59991) (xy 118.464076 -146.607022) (xy 118.444472 -146.626004) (xy 118.400814 -146.658738)
			(xy 118.352937 -146.684918) (xy 118.301819 -146.704009) (xy 118.248502 -146.715621) (xy 118.194074 -146.719519)
			(xy 118.139646 -146.715621) (xy 118.086329 -146.704009) (xy 118.035211 -146.684918) (xy 117.987334 -146.658738)
			(xy 117.943676 -146.626004) (xy 117.924072 -146.607022) (xy 117.91696 -146.59991) (xy 117.898164 -146.592036)
			(xy 117.854984 -146.592036) (xy 117.836188 -146.59991) (xy 117.829076 -146.607022) (xy 117.809472 -146.626004)
			(xy 117.765814 -146.658738) (xy 117.717937 -146.684918) (xy 117.666819 -146.704009) (xy 117.613502 -146.715621)
			(xy 117.559074 -146.719519) (xy 117.504646 -146.715621) (xy 117.451329 -146.704009) (xy 117.400211 -146.684918)
			(xy 117.352334 -146.658738) (xy 117.308676 -146.626004) (xy 117.289072 -146.607022) (xy 117.28196 -146.59991)
			(xy 117.263164 -146.592036) (xy 117.201188 -146.592036) (xy 117.176042 -146.608292) (xy 117.169946 -146.622008)
			(xy 117.158242 -146.6467) (xy 117.128821 -146.692745) (xy 117.093131 -146.734122) (xy 117.051901 -146.769981)
			(xy 117.005977 -146.799591) (xy 116.956297 -146.822344) (xy 116.903879 -146.837776) (xy 116.849795 -146.845569)
			(xy 116.822474 -146.846036) (xy 116.795102 -146.845601) (xy 116.740921 -146.837778) (xy 116.688417 -146.822282)
			(xy 116.638671 -146.799433) (xy 116.592706 -146.769701) (xy 116.571776 -146.752056) (xy 116.564664 -146.74596)
			(xy 116.547646 -146.73961) (xy 116.462302 -146.73961) (xy 116.445284 -146.74596) (xy 116.438172 -146.752056)
			(xy 116.417218 -146.769668) (xy 116.371252 -146.799385) (xy 116.32151 -146.822227) (xy 116.269014 -146.837725)
			(xy 116.214842 -146.845559) (xy 116.187474 -146.846036) (xy 116.160223 -146.845546) (xy 116.106277 -146.837787)
			(xy 116.053984 -146.82243) (xy 116.004409 -146.799788) (xy 115.95856 -146.770322) (xy 115.917371 -146.734631)
			(xy 115.88168 -146.693442) (xy 115.852213 -146.647593) (xy 115.829571 -146.598018) (xy 115.814213 -146.545725)
			(xy 115.806454 -146.491779) (xy 115.805966 -146.464528) (xy 103.84103 -146.464528) (xy 103.851191 -146.480339)
			(xy 103.873833 -146.529916) (xy 103.889188 -146.582211) (xy 103.896944 -146.636159) (xy 103.89743 -146.66341)
			(xy 103.897037 -146.689075) (xy 103.89016 -146.739942) (xy 103.876518 -146.789426) (xy 103.856359 -146.836632)
			(xy 103.830046 -146.880705) (xy 103.798057 -146.920847) (xy 103.760969 -146.956334) (xy 103.740458 -146.971766)
			(xy 103.729652 -146.980167) (xy 103.712661 -147.001617) (xy 103.701957 -147.026801) (xy 103.698306 -147.053921)
			(xy 103.701968 -147.081039) (xy 103.712682 -147.106219) (xy 103.729682 -147.127662) (xy 103.740458 -147.136104)
			(xy 103.764322 -147.154199) (xy 103.806639 -147.196573) (xy 103.841814 -147.24504) (xy 103.868982 -147.298409)
			(xy 103.887476 -147.355368) (xy 103.896841 -147.414517) (xy 103.89743 -147.44446) (xy 103.896944 -147.471711)
			(xy 103.889188 -147.525659) (xy 103.873833 -147.577954) (xy 103.851191 -147.627531) (xy 103.821725 -147.673381)
			(xy 103.786034 -147.714572) (xy 103.744843 -147.750263) (xy 103.698993 -147.779729) (xy 103.649416 -147.802371)
			(xy 103.597121 -147.817726) (xy 103.543173 -147.825482) (xy 103.488671 -147.825482) (xy 103.434723 -147.817726)
			(xy 103.382428 -147.802371) (xy 103.332851 -147.779729) (xy 103.287001 -147.750263) (xy 103.24581 -147.714572)
			(xy 103.210119 -147.673381) (xy 103.180653 -147.627531) (xy 103.158011 -147.577954) (xy 103.142656 -147.525659)
			(xy 103.1349 -147.471711) (xy 103.134414 -147.44446) (xy 76.026027 -147.44446) (xy 76.026009 -147.445422)
			(xy 76.017889 -147.500598) (xy 76.001821 -147.554005) (xy 75.978149 -147.604502) (xy 75.947376 -147.651015)
			(xy 75.910159 -147.692552) (xy 75.867291 -147.728227) (xy 75.819685 -147.757281) (xy 75.768356 -147.779093)
			(xy 75.714399 -147.793199) (xy 75.658962 -147.799299) (xy 75.603228 -147.797262) (xy 75.548385 -147.787132)
			(xy 75.495601 -147.769125) (xy 75.446001 -147.743624) (xy 75.400643 -147.711173) (xy 75.360494 -147.672464)
			(xy 75.326408 -147.628321) (xy 75.299112 -147.579686) (xy 75.279189 -147.527595) (xy 75.267063 -147.473158)
			(xy 75.262992 -147.417536) (xy 52.510182 -147.417536) (xy 51.972718 -147.955) (xy 86.612982 -147.955)
			(xy 86.617053 -147.899378) (xy 86.629179 -147.844941) (xy 86.649102 -147.79285) (xy 86.676398 -147.744215)
			(xy 86.710484 -147.700072) (xy 86.750633 -147.661363) (xy 86.795991 -147.628912) (xy 86.845591 -147.603411)
			(xy 86.898375 -147.585404) (xy 86.953218 -147.575274) (xy 87.008952 -147.573237) (xy 87.064389 -147.579337)
			(xy 87.118346 -147.593443) (xy 87.169675 -147.615255) (xy 87.217281 -147.644309) (xy 87.260149 -147.679984)
			(xy 87.297366 -147.721521) (xy 87.328139 -147.768034) (xy 87.351811 -147.818531) (xy 87.367879 -147.871938)
			(xy 87.375999 -147.927114) (xy 87.376508 -147.955) (xy 87.375999 -147.982886) (xy 87.367879 -148.038062)
			(xy 87.351811 -148.091469) (xy 87.328139 -148.141966) (xy 87.297366 -148.188479) (xy 87.260149 -148.230016)
			(xy 87.217281 -148.265691) (xy 87.169675 -148.294745) (xy 87.118346 -148.316557) (xy 87.064389 -148.330663)
			(xy 87.008952 -148.336763) (xy 86.953218 -148.334726) (xy 86.898375 -148.324596) (xy 86.845591 -148.306589)
			(xy 86.795991 -148.281088) (xy 86.750633 -148.248637) (xy 86.710484 -148.209928) (xy 86.676398 -148.165785)
			(xy 86.649102 -148.11715) (xy 86.629179 -148.065059) (xy 86.617053 -148.010622) (xy 86.612982 -147.955)
			(xy 51.972718 -147.955) (xy 51.551078 -148.37664) (xy 76.359002 -148.37664) (xy 76.363073 -148.321018)
			(xy 76.375199 -148.266581) (xy 76.395122 -148.21449) (xy 76.422418 -148.165855) (xy 76.456504 -148.121712)
			(xy 76.496653 -148.083003) (xy 76.542011 -148.050552) (xy 76.591611 -148.025051) (xy 76.644395 -148.007044)
			(xy 76.699238 -147.996914) (xy 76.754972 -147.994877) (xy 76.810409 -148.000977) (xy 76.864366 -148.015083)
			(xy 76.915695 -148.036895) (xy 76.963301 -148.065949) (xy 77.006169 -148.101624) (xy 77.043386 -148.143161)
			(xy 77.074159 -148.189674) (xy 77.097831 -148.240171) (xy 77.113899 -148.293578) (xy 77.122019 -148.348754)
			(xy 77.122528 -148.37664) (xy 77.122019 -148.404526) (xy 77.113899 -148.459702) (xy 77.112448 -148.464524)
			(xy 97.942144 -148.464524) (xy 97.946215 -148.408902) (xy 97.958341 -148.354465) (xy 97.978264 -148.302374)
			(xy 98.00556 -148.253739) (xy 98.039646 -148.209596) (xy 98.079795 -148.170887) (xy 98.125153 -148.138436)
			(xy 98.174753 -148.112935) (xy 98.227537 -148.094928) (xy 98.28238 -148.084798) (xy 98.338114 -148.082761)
			(xy 98.393551 -148.088861) (xy 98.447508 -148.102967) (xy 98.498837 -148.124779) (xy 98.546443 -148.153833)
			(xy 98.589311 -148.189508) (xy 98.626528 -148.231045) (xy 98.657301 -148.277558) (xy 98.680973 -148.328055)
			(xy 98.697041 -148.381462) (xy 98.705161 -148.436638) (xy 98.70567 -148.464524) (xy 98.705161 -148.49241)
			(xy 98.697041 -148.547586) (xy 98.680973 -148.600993) (xy 98.657301 -148.65149) (xy 98.626528 -148.698003)
			(xy 98.589311 -148.73954) (xy 98.546443 -148.775215) (xy 98.498837 -148.804269) (xy 98.447508 -148.826081)
			(xy 98.393551 -148.840187) (xy 98.338114 -148.846287) (xy 98.28238 -148.84425) (xy 98.227537 -148.83412)
			(xy 98.174753 -148.816113) (xy 98.125153 -148.790612) (xy 98.079795 -148.758161) (xy 98.039646 -148.719452)
			(xy 98.00556 -148.675309) (xy 97.978264 -148.626674) (xy 97.958341 -148.574583) (xy 97.946215 -148.520146)
			(xy 97.942144 -148.464524) (xy 77.112448 -148.464524) (xy 77.097831 -148.513109) (xy 77.074159 -148.563606)
			(xy 77.043386 -148.610119) (xy 77.006169 -148.651656) (xy 76.963301 -148.687331) (xy 76.915695 -148.716385)
			(xy 76.864366 -148.738197) (xy 76.810409 -148.752303) (xy 76.754972 -148.758403) (xy 76.699238 -148.756366)
			(xy 76.644395 -148.746236) (xy 76.591611 -148.728229) (xy 76.542011 -148.702728) (xy 76.496653 -148.670277)
			(xy 76.456504 -148.631568) (xy 76.422418 -148.587425) (xy 76.395122 -148.53879) (xy 76.375199 -148.486699)
			(xy 76.363073 -148.432262) (xy 76.359002 -148.37664) (xy 51.551078 -148.37664) (xy 51.140761 -148.786957)
			(xy 54.228627 -148.786957) (xy 54.228627 -148.732443) (xy 54.236386 -148.678484) (xy 54.251745 -148.626179)
			(xy 54.274393 -148.576592) (xy 54.303867 -148.530733) (xy 54.339569 -148.489536) (xy 54.38077 -148.45384)
			(xy 54.426632 -148.424371) (xy 54.476222 -148.401729) (xy 54.528529 -148.386376) (xy 54.582489 -148.378624)
			(xy 54.609746 -148.378164) (xy 54.638663 -148.378697) (xy 54.695834 -148.38742) (xy 54.751034 -148.404673)
			(xy 54.802996 -148.430062) (xy 54.85053 -148.463004) (xy 54.892546 -148.502745) (xy 54.910736 -148.52523)
			(xy 54.918281 -148.534009) (xy 54.939053 -148.544182) (xy 54.950614 -148.544788) (xy 55.030878 -148.544788)
			(xy 55.042445 -148.544209) (xy 55.063216 -148.534021) (xy 55.070756 -148.52523) (xy 55.087509 -148.504447)
			(xy 55.125863 -148.467317) (xy 55.169017 -148.435895) (xy 55.216131 -148.410796) (xy 55.266283 -148.39251)
			(xy 55.318494 -148.381393) (xy 55.371746 -148.377663) (xy 55.424998 -148.381393) (xy 55.477209 -148.39251)
			(xy 55.527361 -148.410796) (xy 55.574475 -148.435895) (xy 55.617629 -148.467317) (xy 55.655983 -148.504447)
			(xy 55.672736 -148.52523) (xy 55.680281 -148.534009) (xy 55.701053 -148.544182) (xy 55.712614 -148.544788)
			(xy 55.792878 -148.544788) (xy 55.804445 -148.544209) (xy 55.825216 -148.534021) (xy 55.832756 -148.52523)
			(xy 55.849509 -148.504447) (xy 55.887863 -148.467317) (xy 55.931017 -148.435895) (xy 55.978131 -148.410796)
			(xy 56.028283 -148.39251) (xy 56.080494 -148.381393) (xy 56.133746 -148.377663) (xy 56.186998 -148.381393)
			(xy 56.239209 -148.39251) (xy 56.289361 -148.410796) (xy 56.336475 -148.435895) (xy 56.379629 -148.467317)
			(xy 56.417983 -148.504447) (xy 56.434736 -148.52523) (xy 56.442281 -148.534009) (xy 56.463053 -148.544182)
			(xy 56.474614 -148.544788) (xy 56.554878 -148.544788) (xy 56.566445 -148.544209) (xy 56.587216 -148.534021)
			(xy 56.594756 -148.52523) (xy 56.612979 -148.502774) (xy 56.654992 -148.463036) (xy 56.702519 -148.430092)
			(xy 56.754475 -148.404699) (xy 56.809667 -148.387437) (xy 56.866832 -148.378702) (xy 56.895746 -148.378164)
			(xy 56.922993 -148.378709) (xy 56.976932 -148.386471) (xy 57.029217 -148.401829) (xy 57.078785 -148.424471)
			(xy 57.124626 -148.453936) (xy 57.165808 -148.489625) (xy 57.201492 -148.530811) (xy 57.230951 -148.576656)
			(xy 57.253588 -148.626226) (xy 57.268939 -148.678513) (xy 57.276694 -148.732453) (xy 57.276694 -148.786947)
			(xy 57.268939 -148.840887) (xy 57.253588 -148.893174) (xy 57.230951 -148.942744) (xy 57.226668 -148.94941)
			(xy 88.81186 -148.94941) (xy 88.815931 -148.893788) (xy 88.828057 -148.839351) (xy 88.84798 -148.78726)
			(xy 88.875276 -148.738625) (xy 88.909362 -148.694482) (xy 88.949511 -148.655773) (xy 88.994869 -148.623322)
			(xy 89.044469 -148.597821) (xy 89.097253 -148.579814) (xy 89.152096 -148.569684) (xy 89.20783 -148.567647)
			(xy 89.263267 -148.573747) (xy 89.317224 -148.587853) (xy 89.368553 -148.609665) (xy 89.416159 -148.638719)
			(xy 89.459027 -148.674394) (xy 89.496244 -148.715931) (xy 89.527017 -148.762444) (xy 89.550689 -148.812941)
			(xy 89.56309 -148.85416) (xy 96.058988 -148.85416) (xy 96.063059 -148.798538) (xy 96.075185 -148.744101)
			(xy 96.095108 -148.69201) (xy 96.122404 -148.643375) (xy 96.15649 -148.599232) (xy 96.196639 -148.560523)
			(xy 96.241997 -148.528072) (xy 96.291597 -148.502571) (xy 96.344381 -148.484564) (xy 96.399224 -148.474434)
			(xy 96.454958 -148.472397) (xy 96.510395 -148.478497) (xy 96.564352 -148.492603) (xy 96.615681 -148.514415)
			(xy 96.663287 -148.543469) (xy 96.706155 -148.579144) (xy 96.743372 -148.620681) (xy 96.774145 -148.667194)
			(xy 96.797817 -148.717691) (xy 96.813885 -148.771098) (xy 96.822005 -148.826274) (xy 96.822514 -148.85416)
			(xy 96.822005 -148.882046) (xy 96.813885 -148.937222) (xy 96.797817 -148.990629) (xy 96.774145 -149.041126)
			(xy 96.743372 -149.087639) (xy 96.706155 -149.129176) (xy 96.663287 -149.164851) (xy 96.615681 -149.193905)
			(xy 96.564352 -149.215717) (xy 96.510395 -149.229823) (xy 96.454958 -149.235923) (xy 96.399224 -149.233886)
			(xy 96.344381 -149.223756) (xy 96.291597 -149.205749) (xy 96.241997 -149.180248) (xy 96.196639 -149.147797)
			(xy 96.15649 -149.109088) (xy 96.122404 -149.064945) (xy 96.095108 -149.01631) (xy 96.075185 -148.964219)
			(xy 96.063059 -148.909782) (xy 96.058988 -148.85416) (xy 89.56309 -148.85416) (xy 89.566757 -148.866348)
			(xy 89.574877 -148.921524) (xy 89.575386 -148.94941) (xy 89.574877 -148.977296) (xy 89.566757 -149.032472)
			(xy 89.550689 -149.085879) (xy 89.527017 -149.136376) (xy 89.496244 -149.182889) (xy 89.459027 -149.224426)
			(xy 89.416159 -149.260101) (xy 89.368553 -149.289155) (xy 89.317224 -149.310967) (xy 89.263267 -149.325073)
			(xy 89.20783 -149.331173) (xy 89.152096 -149.329136) (xy 89.097253 -149.319006) (xy 89.044469 -149.300999)
			(xy 88.994869 -149.275498) (xy 88.949511 -149.243047) (xy 88.909362 -149.204338) (xy 88.875276 -149.160195)
			(xy 88.84798 -149.11156) (xy 88.828057 -149.059469) (xy 88.815931 -149.005032) (xy 88.81186 -148.94941)
			(xy 57.226668 -148.94941) (xy 57.201492 -148.988589) (xy 57.165808 -149.029775) (xy 57.124626 -149.065464)
			(xy 57.078785 -149.094929) (xy 57.029217 -149.117571) (xy 56.976932 -149.132929) (xy 56.922993 -149.140691)
			(xy 56.895746 -149.14118) (xy 56.86683 -149.140636) (xy 56.80966 -149.131914) (xy 56.754461 -149.114661)
			(xy 56.702499 -149.089274) (xy 56.654964 -149.056335) (xy 56.612947 -149.016598) (xy 56.594756 -148.994114)
			(xy 56.587207 -148.985339) (xy 56.566439 -148.975162) (xy 56.554878 -148.974556) (xy 56.474614 -148.974556)
			(xy 56.463044 -148.975115) (xy 56.442272 -148.985316) (xy 56.434736 -148.994114) (xy 56.417983 -149.014897)
			(xy 56.379629 -149.052027) (xy 56.336475 -149.083449) (xy 56.289361 -149.108548) (xy 56.239209 -149.126834)
			(xy 56.186998 -149.137951) (xy 56.133746 -149.141681) (xy 56.080494 -149.137951) (xy 56.028283 -149.126834)
			(xy 55.978131 -149.108548) (xy 55.931017 -149.083449) (xy 55.887863 -149.052027) (xy 55.849509 -149.014897)
			(xy 55.832756 -148.994114) (xy 55.825207 -148.985339) (xy 55.804439 -148.975162) (xy 55.792878 -148.974556)
			(xy 55.712614 -148.974556) (xy 55.701044 -148.975115) (xy 55.680272 -148.985316) (xy 55.672736 -148.994114)
			(xy 55.655983 -149.014897) (xy 55.617629 -149.052027) (xy 55.574475 -149.083449) (xy 55.527361 -149.108548)
			(xy 55.477209 -149.126834) (xy 55.424998 -149.137951) (xy 55.371746 -149.141681) (xy 55.318494 -149.137951)
			(xy 55.266283 -149.126834) (xy 55.216131 -149.108548) (xy 55.169017 -149.083449) (xy 55.125863 -149.052027)
			(xy 55.087509 -149.014897) (xy 55.070756 -148.994114) (xy 55.063207 -148.985339) (xy 55.042439 -148.975162)
			(xy 55.030878 -148.974556) (xy 54.950614 -148.974556) (xy 54.939044 -148.975115) (xy 54.918272 -148.985316)
			(xy 54.910736 -148.994114) (xy 54.892528 -149.016583) (xy 54.850512 -149.056319) (xy 54.80298 -149.089259)
			(xy 54.751022 -149.11465) (xy 54.695828 -149.131909) (xy 54.638661 -149.140643) (xy 54.609746 -149.14118)
			(xy 54.582489 -149.140776) (xy 54.528529 -149.133024) (xy 54.476222 -149.117671) (xy 54.426632 -149.095029)
			(xy 54.38077 -149.06556) (xy 54.339569 -149.029864) (xy 54.303867 -148.988667) (xy 54.274393 -148.942808)
			(xy 54.251745 -148.893221) (xy 54.236386 -148.840916) (xy 54.228627 -148.786957) (xy 51.140761 -148.786957)
			(xy 50.51552 -149.412198) (xy 69.012814 -149.412198) (xy 69.016885 -149.356576) (xy 69.029011 -149.302139)
			(xy 69.048934 -149.250048) (xy 69.07623 -149.201413) (xy 69.110316 -149.15727) (xy 69.150465 -149.118561)
			(xy 69.195823 -149.08611) (xy 69.245423 -149.060609) (xy 69.298207 -149.042602) (xy 69.35305 -149.032472)
			(xy 69.408784 -149.030435) (xy 69.464221 -149.036535) (xy 69.518178 -149.050641) (xy 69.569507 -149.072453)
			(xy 69.617113 -149.101507) (xy 69.659981 -149.137182) (xy 69.697198 -149.178719) (xy 69.727971 -149.225232)
			(xy 69.751643 -149.275729) (xy 69.767711 -149.329136) (xy 69.768758 -149.336252) (xy 93.292674 -149.336252)
			(xy 93.296745 -149.28063) (xy 93.308871 -149.226193) (xy 93.328794 -149.174102) (xy 93.35609 -149.125467)
			(xy 93.390176 -149.081324) (xy 93.430325 -149.042615) (xy 93.475683 -149.010164) (xy 93.525283 -148.984663)
			(xy 93.578067 -148.966656) (xy 93.63291 -148.956526) (xy 93.688644 -148.954489) (xy 93.744081 -148.960589)
			(xy 93.798038 -148.974695) (xy 93.849367 -148.996507) (xy 93.896973 -149.025561) (xy 93.939841 -149.061236)
			(xy 93.977058 -149.102773) (xy 94.007831 -149.149286) (xy 94.031503 -149.199783) (xy 94.047571 -149.25319)
			(xy 94.055691 -149.308366) (xy 94.0562 -149.336252) (xy 94.055691 -149.364138) (xy 94.047571 -149.419314)
			(xy 94.031503 -149.472721) (xy 94.007831 -149.523218) (xy 93.977058 -149.569731) (xy 93.939841 -149.611268)
			(xy 93.896973 -149.646943) (xy 93.849367 -149.675997) (xy 93.798038 -149.697809) (xy 93.744081 -149.711915)
			(xy 93.688644 -149.718015) (xy 93.63291 -149.715978) (xy 93.578067 -149.705848) (xy 93.525283 -149.687841)
			(xy 93.475683 -149.66234) (xy 93.430325 -149.629889) (xy 93.390176 -149.59118) (xy 93.35609 -149.547037)
			(xy 93.328794 -149.498402) (xy 93.308871 -149.446311) (xy 93.296745 -149.391874) (xy 93.292674 -149.336252)
			(xy 69.768758 -149.336252) (xy 69.775831 -149.384312) (xy 69.77634 -149.412198) (xy 69.775831 -149.440084)
			(xy 69.767711 -149.49526) (xy 69.751643 -149.548667) (xy 69.727971 -149.599164) (xy 69.697198 -149.645677)
			(xy 69.659981 -149.687214) (xy 69.617113 -149.722889) (xy 69.569507 -149.751943) (xy 69.518178 -149.773755)
			(xy 69.464221 -149.787861) (xy 69.408784 -149.793961) (xy 69.35305 -149.791924) (xy 69.298207 -149.781794)
			(xy 69.245423 -149.763787) (xy 69.195823 -149.738286) (xy 69.150465 -149.705835) (xy 69.110316 -149.667126)
			(xy 69.07623 -149.622983) (xy 69.048934 -149.574348) (xy 69.029011 -149.522257) (xy 69.016885 -149.46782)
			(xy 69.012814 -149.412198) (xy 50.51552 -149.412198) (xy 50.158396 -149.769322) (xy 50.151554 -149.776722)
			(xy 50.143828 -149.79532) (xy 50.14341 -149.80539) (xy 50.14341 -149.96541) (xy 88.81186 -149.96541)
			(xy 88.815931 -149.909788) (xy 88.828057 -149.855351) (xy 88.84798 -149.80326) (xy 88.875276 -149.754625)
			(xy 88.909362 -149.710482) (xy 88.949511 -149.671773) (xy 88.994869 -149.639322) (xy 89.044469 -149.613821)
			(xy 89.097253 -149.595814) (xy 89.152096 -149.585684) (xy 89.20783 -149.583647) (xy 89.263267 -149.589747)
			(xy 89.317224 -149.603853) (xy 89.368553 -149.625665) (xy 89.416159 -149.654719) (xy 89.459027 -149.690394)
			(xy 89.496244 -149.731931) (xy 89.527017 -149.778444) (xy 89.550689 -149.828941) (xy 89.566757 -149.882348)
			(xy 89.568178 -149.892004) (xy 95.52305 -149.892004) (xy 95.523536 -149.864753) (xy 95.531292 -149.810805)
			(xy 95.546647 -149.75851) (xy 95.569289 -149.708933) (xy 95.598755 -149.663083) (xy 95.634446 -149.621892)
			(xy 95.675637 -149.586201) (xy 95.721487 -149.556735) (xy 95.771064 -149.534093) (xy 95.823359 -149.518738)
			(xy 95.877307 -149.510982) (xy 95.931809 -149.510982) (xy 95.985757 -149.518738) (xy 96.038052 -149.534093)
			(xy 96.077594 -149.552152) (xy 98.937316 -149.552152) (xy 98.941387 -149.49653) (xy 98.953513 -149.442093)
			(xy 98.973436 -149.390002) (xy 99.000732 -149.341367) (xy 99.034818 -149.297224) (xy 99.074967 -149.258515)
			(xy 99.120325 -149.226064) (xy 99.169925 -149.200563) (xy 99.222709 -149.182556) (xy 99.277552 -149.172426)
			(xy 99.333286 -149.170389) (xy 99.388723 -149.176489) (xy 99.44268 -149.190595) (xy 99.494009 -149.212407)
			(xy 99.541615 -149.241461) (xy 99.584483 -149.277136) (xy 99.6217 -149.318673) (xy 99.652473 -149.365186)
			(xy 99.676145 -149.415683) (xy 99.692213 -149.46909) (xy 99.700333 -149.524266) (xy 99.700842 -149.552152)
			(xy 99.700333 -149.580038) (xy 99.692213 -149.635214) (xy 99.676145 -149.688621) (xy 99.652473 -149.739118)
			(xy 99.6217 -149.785631) (xy 99.584483 -149.827168) (xy 99.541615 -149.862843) (xy 99.494009 -149.891897)
			(xy 99.44268 -149.913709) (xy 99.388723 -149.927815) (xy 99.333286 -149.933915) (xy 99.277552 -149.931878)
			(xy 99.222709 -149.921748) (xy 99.169925 -149.903741) (xy 99.120325 -149.87824) (xy 99.074967 -149.845789)
			(xy 99.034818 -149.80708) (xy 99.000732 -149.762937) (xy 98.973436 -149.714302) (xy 98.953513 -149.662211)
			(xy 98.941387 -149.607774) (xy 98.937316 -149.552152) (xy 96.077594 -149.552152) (xy 96.087629 -149.556735)
			(xy 96.133479 -149.586201) (xy 96.17467 -149.621892) (xy 96.210361 -149.663083) (xy 96.239827 -149.708933)
			(xy 96.262469 -149.75851) (xy 96.277824 -149.810805) (xy 96.28558 -149.864753) (xy 96.286066 -149.892004)
			(xy 96.285543 -149.920929) (xy 96.276862 -149.978124) (xy 96.25964 -150.033351) (xy 96.234273 -150.085342)
			(xy 96.218248 -150.109428) (xy 96.210868 -150.120879) (xy 96.201847 -150.146571) (xy 96.199948 -150.173736)
			(xy 96.205307 -150.200434) (xy 96.217541 -150.224761) (xy 96.235777 -150.244983) (xy 96.258715 -150.259658)
			(xy 96.271588 -150.264114) (xy 96.297187 -150.272507) (xy 96.345882 -150.295554) (xy 96.390851 -150.325221)
			(xy 96.4312 -150.360919) (xy 96.466126 -150.401936) (xy 96.494936 -150.447459) (xy 96.517056 -150.496582)
			(xy 96.532047 -150.548327) (xy 96.53961 -150.601667) (xy 96.540066 -150.628604) (xy 96.53958 -150.655855)
			(xy 96.531824 -150.709803) (xy 96.516469 -150.762098) (xy 96.493827 -150.811675) (xy 96.464361 -150.857525)
			(xy 96.42867 -150.898716) (xy 96.387479 -150.934407) (xy 96.341629 -150.963873) (xy 96.292052 -150.986515)
			(xy 96.239757 -151.00187) (xy 96.185809 -151.009626) (xy 96.131307 -151.009626) (xy 96.077359 -151.00187)
			(xy 96.025064 -150.986515) (xy 95.975487 -150.963873) (xy 95.929637 -150.934407) (xy 95.888446 -150.898716)
			(xy 95.852755 -150.857525) (xy 95.823289 -150.811675) (xy 95.800647 -150.762098) (xy 95.785292 -150.709803)
			(xy 95.777536 -150.655855) (xy 95.77705 -150.628604) (xy 95.777543 -150.599678) (xy 95.786235 -150.542482)
			(xy 95.803466 -150.487256) (xy 95.828841 -150.435266) (xy 95.844868 -150.41118) (xy 95.85223 -150.399719)
			(xy 95.861249 -150.37403) (xy 95.863149 -150.346869) (xy 95.857793 -150.320174) (xy 95.845563 -150.295849)
			(xy 95.827331 -150.275627) (xy 95.804398 -150.260952) (xy 95.791528 -150.256494) (xy 95.765935 -150.248084)
			(xy 95.71724 -150.22504) (xy 95.672271 -150.195375) (xy 95.631922 -150.15968) (xy 95.596994 -150.118664)
			(xy 95.568184 -150.073144) (xy 95.546063 -150.024023) (xy 95.531071 -149.972279) (xy 95.523506 -149.91894)
			(xy 95.52305 -149.892004) (xy 89.568178 -149.892004) (xy 89.574877 -149.937524) (xy 89.575386 -149.96541)
			(xy 89.574877 -149.993296) (xy 89.566757 -150.048472) (xy 89.550689 -150.101879) (xy 89.527017 -150.152376)
			(xy 89.496244 -150.198889) (xy 89.459027 -150.240426) (xy 89.416159 -150.276101) (xy 89.368553 -150.305155)
			(xy 89.317224 -150.326967) (xy 89.263267 -150.341073) (xy 89.20783 -150.347173) (xy 89.152096 -150.345136)
			(xy 89.097253 -150.335006) (xy 89.044469 -150.316999) (xy 88.994869 -150.291498) (xy 88.949511 -150.259047)
			(xy 88.909362 -150.220338) (xy 88.875276 -150.176195) (xy 88.84798 -150.12756) (xy 88.828057 -150.075469)
			(xy 88.815931 -150.021032) (xy 88.81186 -149.96541) (xy 50.14341 -149.96541) (xy 50.14341 -150.76932)
			(xy 92.368114 -150.76932) (xy 92.372185 -150.713698) (xy 92.384311 -150.659261) (xy 92.404234 -150.60717)
			(xy 92.43153 -150.558535) (xy 92.465616 -150.514392) (xy 92.505765 -150.475683) (xy 92.551123 -150.443232)
			(xy 92.600723 -150.417731) (xy 92.653507 -150.399724) (xy 92.70835 -150.389594) (xy 92.764084 -150.387557)
			(xy 92.819521 -150.393657) (xy 92.873478 -150.407763) (xy 92.924807 -150.429575) (xy 92.972413 -150.458629)
			(xy 93.015281 -150.494304) (xy 93.052498 -150.535841) (xy 93.083271 -150.582354) (xy 93.106943 -150.632851)
			(xy 93.123011 -150.686258) (xy 93.126189 -150.707852) (xy 94.48114 -150.707852) (xy 94.485211 -150.65223)
			(xy 94.497337 -150.597793) (xy 94.51726 -150.545702) (xy 94.544556 -150.497067) (xy 94.578642 -150.452924)
			(xy 94.618791 -150.414215) (xy 94.664149 -150.381764) (xy 94.713749 -150.356263) (xy 94.766533 -150.338256)
			(xy 94.821376 -150.328126) (xy 94.87711 -150.326089) (xy 94.932547 -150.332189) (xy 94.986504 -150.346295)
			(xy 95.037833 -150.368107) (xy 95.085439 -150.397161) (xy 95.128307 -150.432836) (xy 95.165524 -150.474373)
			(xy 95.196297 -150.520886) (xy 95.219969 -150.571383) (xy 95.236037 -150.62479) (xy 95.244157 -150.679966)
			(xy 95.244666 -150.707852) (xy 95.244157 -150.735738) (xy 95.236037 -150.790914) (xy 95.219969 -150.844321)
			(xy 95.196297 -150.894818) (xy 95.165524 -150.941331) (xy 95.128307 -150.982868) (xy 95.085439 -151.018543)
			(xy 95.037833 -151.047597) (xy 94.986504 -151.069409) (xy 94.932547 -151.083515) (xy 94.87711 -151.089615)
			(xy 94.821376 -151.087578) (xy 94.766533 -151.077448) (xy 94.713749 -151.059441) (xy 94.664149 -151.03394)
			(xy 94.618791 -151.001489) (xy 94.578642 -150.96278) (xy 94.544556 -150.918637) (xy 94.51726 -150.870002)
			(xy 94.497337 -150.817911) (xy 94.485211 -150.763474) (xy 94.48114 -150.707852) (xy 93.126189 -150.707852)
			(xy 93.131131 -150.741434) (xy 93.13164 -150.76932) (xy 93.131131 -150.797206) (xy 93.123011 -150.852382)
			(xy 93.106943 -150.905789) (xy 93.083271 -150.956286) (xy 93.052498 -151.002799) (xy 93.015281 -151.044336)
			(xy 92.972413 -151.080011) (xy 92.924807 -151.109065) (xy 92.873478 -151.130877) (xy 92.819521 -151.144983)
			(xy 92.764084 -151.151083) (xy 92.70835 -151.149046) (xy 92.653507 -151.138916) (xy 92.600723 -151.120909)
			(xy 92.551123 -151.095408) (xy 92.505765 -151.062957) (xy 92.465616 -151.024248) (xy 92.43153 -150.980105)
			(xy 92.404234 -150.93147) (xy 92.384311 -150.879379) (xy 92.372185 -150.824942) (xy 92.368114 -150.76932)
			(xy 50.14341 -150.76932) (xy 50.14341 -151.194051) (xy 52.515485 -151.194051) (xy 52.515485 -151.139549)
			(xy 52.523242 -151.0856) (xy 52.538598 -151.033305) (xy 52.56124 -150.983728) (xy 52.590707 -150.937878)
			(xy 52.626399 -150.896688) (xy 52.667591 -150.860997) (xy 52.713442 -150.831532) (xy 52.76302 -150.808892)
			(xy 52.815316 -150.793539) (xy 52.869265 -150.785784) (xy 52.896516 -150.785322) (xy 52.925431 -150.785893)
			(xy 52.9826 -150.79461) (xy 53.037798 -150.811857) (xy 53.08976 -150.837239) (xy 53.137296 -150.870173)
			(xy 53.179314 -150.909906) (xy 53.197506 -150.932388) (xy 53.205072 -150.941146) (xy 53.225827 -150.951332)
			(xy 53.237384 -150.951946) (xy 53.317648 -150.951946) (xy 53.329215 -150.951365) (xy 53.349987 -150.94118)
			(xy 53.357526 -150.932388) (xy 53.375699 -150.90989) (xy 53.417723 -150.870156) (xy 53.465262 -150.837219)
			(xy 53.517226 -150.811833) (xy 53.572427 -150.79458) (xy 53.629599 -150.785855) (xy 53.658516 -150.785322)
			(xy 53.685769 -150.785749) (xy 53.739719 -150.793508) (xy 53.792016 -150.808866) (xy 53.841595 -150.831509)
			(xy 53.887447 -150.860979) (xy 53.928638 -150.896673) (xy 53.964331 -150.937866) (xy 53.993798 -150.983719)
			(xy 54.01644 -151.033299) (xy 54.031795 -151.085597) (xy 54.039552 -151.139547) (xy 54.039552 -151.194053)
			(xy 54.031795 -151.248003) (xy 54.01644 -151.300301) (xy 53.993798 -151.349881) (xy 53.964331 -151.395734)
			(xy 53.928638 -151.436927) (xy 53.887447 -151.472621) (xy 53.841595 -151.502091) (xy 53.792016 -151.524734)
			(xy 53.739719 -151.540092) (xy 53.685769 -151.547851) (xy 53.658516 -151.548338) (xy 53.629598 -151.547832)
			(xy 53.572426 -151.539104) (xy 53.517225 -151.521845) (xy 53.465263 -151.496451) (xy 53.41773 -151.463504)
			(xy 53.375715 -151.423759) (xy 53.357526 -151.401272) (xy 53.349953 -151.392522) (xy 53.329203 -151.382333)
			(xy 53.317648 -151.381714) (xy 53.237384 -151.381714) (xy 53.225814 -151.38227) (xy 53.205043 -151.392474)
			(xy 53.197506 -151.401272) (xy 53.179305 -151.423747) (xy 53.137288 -151.463484) (xy 53.089755 -151.496425)
			(xy 53.037796 -151.521815) (xy 52.9826 -151.539073) (xy 52.925432 -151.547803) (xy 52.896516 -151.548338)
			(xy 52.869265 -151.547816) (xy 52.815316 -151.540061) (xy 52.76302 -151.524708) (xy 52.713442 -151.502068)
			(xy 52.667591 -151.472603) (xy 52.626399 -151.436912) (xy 52.590707 -151.395722) (xy 52.56124 -151.349872)
			(xy 52.538598 -151.300295) (xy 52.523242 -151.248) (xy 52.515485 -151.194051) (xy 50.14341 -151.194051)
			(xy 50.14341 -151.776684) (xy 92.368114 -151.776684) (xy 92.372185 -151.721062) (xy 92.384311 -151.666625)
			(xy 92.404234 -151.614534) (xy 92.43153 -151.565899) (xy 92.465616 -151.521756) (xy 92.505765 -151.483047)
			(xy 92.551123 -151.450596) (xy 92.600723 -151.425095) (xy 92.653507 -151.407088) (xy 92.70835 -151.396958)
			(xy 92.764084 -151.394921) (xy 92.819521 -151.401021) (xy 92.873478 -151.415127) (xy 92.924807 -151.436939)
			(xy 92.972413 -151.465993) (xy 93.015281 -151.501668) (xy 93.052498 -151.543205) (xy 93.083271 -151.589718)
			(xy 93.104476 -151.634952) (xy 99.305616 -151.634952) (xy 99.309687 -151.57933) (xy 99.321813 -151.524893)
			(xy 99.341736 -151.472802) (xy 99.369032 -151.424167) (xy 99.403118 -151.380024) (xy 99.443267 -151.341315)
			(xy 99.488625 -151.308864) (xy 99.538225 -151.283363) (xy 99.591009 -151.265356) (xy 99.645852 -151.255226)
			(xy 99.701586 -151.253189) (xy 99.757023 -151.259289) (xy 99.81098 -151.273395) (xy 99.862309 -151.295207)
			(xy 99.909915 -151.324261) (xy 99.952783 -151.359936) (xy 99.99 -151.401473) (xy 100.020773 -151.447986)
			(xy 100.044445 -151.498483) (xy 100.060513 -151.55189) (xy 100.068633 -151.607066) (xy 100.069142 -151.634952)
			(xy 100.068633 -151.662838) (xy 100.060513 -151.718014) (xy 100.044445 -151.771421) (xy 100.020773 -151.821918)
			(xy 99.99 -151.868431) (xy 99.952783 -151.909968) (xy 99.909915 -151.945643) (xy 99.862309 -151.974697)
			(xy 99.81098 -151.996509) (xy 99.757023 -152.010615) (xy 99.701586 -152.016715) (xy 99.645852 -152.014678)
			(xy 99.591009 -152.004548) (xy 99.538225 -151.986541) (xy 99.488625 -151.96104) (xy 99.443267 -151.928589)
			(xy 99.403118 -151.88988) (xy 99.369032 -151.845737) (xy 99.341736 -151.797102) (xy 99.321813 -151.745011)
			(xy 99.309687 -151.690574) (xy 99.305616 -151.634952) (xy 93.104476 -151.634952) (xy 93.106943 -151.640215)
			(xy 93.123011 -151.693622) (xy 93.131131 -151.748798) (xy 93.13164 -151.776684) (xy 93.131131 -151.80457)
			(xy 93.123011 -151.859746) (xy 93.106943 -151.913153) (xy 93.083271 -151.96365) (xy 93.052498 -152.010163)
			(xy 93.015281 -152.0517) (xy 92.972413 -152.087375) (xy 92.924807 -152.116429) (xy 92.873478 -152.138241)
			(xy 92.819521 -152.152347) (xy 92.764084 -152.158447) (xy 92.70835 -152.15641) (xy 92.653507 -152.14628)
			(xy 92.600723 -152.128273) (xy 92.551123 -152.102772) (xy 92.505765 -152.070321) (xy 92.465616 -152.031612)
			(xy 92.43153 -151.987469) (xy 92.404234 -151.938834) (xy 92.384311 -151.886743) (xy 92.372185 -151.832306)
			(xy 92.368114 -151.776684) (xy 50.14341 -151.776684) (xy 50.14341 -152.207468) (xy 50.142975 -152.217533)
			(xy 50.135244 -152.236121) (xy 50.128424 -152.243536) (xy 50.128424 -153.251451) (xy 52.515485 -153.251451)
			(xy 52.515485 -153.196949) (xy 52.523242 -153.143) (xy 52.538598 -153.090705) (xy 52.56124 -153.041128)
			(xy 52.590707 -152.995278) (xy 52.626399 -152.954088) (xy 52.667591 -152.918397) (xy 52.713442 -152.888932)
			(xy 52.76302 -152.866292) (xy 52.815316 -152.850939) (xy 52.869265 -152.843184) (xy 52.896516 -152.842722)
			(xy 52.925431 -152.843293) (xy 52.9826 -152.85201) (xy 53.037798 -152.869257) (xy 53.08976 -152.894639)
			(xy 53.137296 -152.927573) (xy 53.179314 -152.967306) (xy 53.197506 -152.989788) (xy 53.205072 -152.998546)
			(xy 53.225827 -153.008732) (xy 53.237384 -153.009346) (xy 53.317648 -153.009346) (xy 53.329215 -153.008765)
			(xy 53.349987 -152.99858) (xy 53.357526 -152.989788) (xy 53.375699 -152.96729) (xy 53.417723 -152.927556)
			(xy 53.465262 -152.894619) (xy 53.517226 -152.869233) (xy 53.572427 -152.85198) (xy 53.629599 -152.843255)
			(xy 53.658516 -152.842722) (xy 53.685769 -152.843149) (xy 53.739719 -152.850908) (xy 53.792016 -152.866266)
			(xy 53.841595 -152.888909) (xy 53.887447 -152.918379) (xy 53.928638 -152.954073) (xy 53.964331 -152.995266)
			(xy 53.993798 -153.041119) (xy 54.01644 -153.090699) (xy 54.031795 -153.142997) (xy 54.039552 -153.196947)
			(xy 54.039552 -153.251453) (xy 54.031795 -153.305403) (xy 54.01644 -153.357701) (xy 53.993798 -153.407281)
			(xy 53.964331 -153.453134) (xy 53.928638 -153.494327) (xy 53.887447 -153.530021) (xy 53.841595 -153.559491)
			(xy 53.792016 -153.582134) (xy 53.739719 -153.597492) (xy 53.685769 -153.605251) (xy 53.658516 -153.605738)
			(xy 53.629598 -153.605232) (xy 53.572426 -153.596504) (xy 53.517225 -153.579245) (xy 53.465263 -153.553851)
			(xy 53.41773 -153.520904) (xy 53.375715 -153.481159) (xy 53.357526 -153.458672) (xy 53.349953 -153.449922)
			(xy 53.329203 -153.439733) (xy 53.317648 -153.439114) (xy 53.237384 -153.439114) (xy 53.225814 -153.43967)
			(xy 53.205043 -153.449874) (xy 53.197506 -153.458672) (xy 53.179305 -153.481147) (xy 53.137288 -153.520884)
			(xy 53.089755 -153.553825) (xy 53.037796 -153.579215) (xy 52.9826 -153.596473) (xy 52.925432 -153.605203)
			(xy 52.896516 -153.605738) (xy 52.869265 -153.605216) (xy 52.815316 -153.597461) (xy 52.76302 -153.582108)
			(xy 52.713442 -153.559468) (xy 52.667591 -153.530003) (xy 52.626399 -153.494312) (xy 52.590707 -153.453122)
			(xy 52.56124 -153.407272) (xy 52.538598 -153.357695) (xy 52.523242 -153.3054) (xy 52.515485 -153.251451)
			(xy 50.128424 -153.251451) (xy 50.128424 -154.940254) (xy 52.452778 -154.940254) (xy 52.453308 -154.9115)
			(xy 52.461938 -154.854644) (xy 52.47901 -154.799729) (xy 52.504137 -154.748001) (xy 52.536749 -154.700635)
			(xy 52.576105 -154.658704) (xy 52.621313 -154.62316) (xy 52.646072 -154.60853) (xy 52.656994 -154.60218)
			(xy 52.670202 -154.58186) (xy 52.681124 -154.474672) (xy 52.672234 -154.452066) (xy 52.66309 -154.443684)
			(xy 52.643127 -154.425459) (xy 52.607955 -154.384415) (xy 52.578923 -154.338822) (xy 52.556612 -154.289589)
			(xy 52.541467 -154.237702) (xy 52.533791 -154.184198) (xy 52.533296 -154.157172) (xy 52.533752 -154.12992)
			(xy 52.541512 -154.075971) (xy 52.556871 -154.023675) (xy 52.579516 -153.974098) (xy 52.608985 -153.928247)
			(xy 52.64468 -153.887057) (xy 52.685873 -153.851366) (xy 52.731726 -153.8219) (xy 52.781305 -153.79926)
			(xy 52.833602 -153.783905) (xy 52.887552 -153.776149) (xy 52.914804 -153.775664) (xy 52.943722 -153.776155)
			(xy 53.000896 -153.784886) (xy 53.056096 -153.802148) (xy 53.108058 -153.827545) (xy 53.155591 -153.860494)
			(xy 53.197606 -153.900241) (xy 53.215794 -153.92273) (xy 53.223358 -153.93149) (xy 53.244115 -153.941673)
			(xy 53.255672 -153.942288) (xy 53.335936 -153.942288) (xy 53.3475 -153.941685) (xy 53.368271 -153.931514)
			(xy 53.375814 -153.92273) (xy 53.394005 -153.900246) (xy 53.436024 -153.86051) (xy 53.483558 -153.82757)
			(xy 53.53552 -153.802181) (xy 53.590718 -153.784925) (xy 53.647888 -153.776198) (xy 53.676804 -153.775664)
			(xy 53.704349 -153.776165) (xy 53.758868 -153.78407) (xy 53.811679 -153.799745) (xy 53.861683 -153.822863)
			(xy 53.907836 -153.852941) (xy 53.949177 -153.889352) (xy 53.96738 -153.91003) (xy 53.974746 -153.918666)
			(xy 53.994304 -153.92781) (xy 54.093872 -153.928572) (xy 54.113684 -153.919682) (xy 54.12105 -153.9113)
			(xy 54.139233 -153.89135) (xy 54.180275 -153.856289) (xy 54.225848 -153.827363) (xy 54.275044 -153.805147)
			(xy 54.326879 -153.790086) (xy 54.380319 -153.78248) (xy 54.407308 -153.782014) (xy 54.436223 -153.782593)
			(xy 54.493391 -153.791309) (xy 54.548589 -153.808555) (xy 54.600551 -153.833935) (xy 54.648087 -153.866868)
			(xy 54.690106 -153.906599) (xy 54.708298 -153.92908) (xy 54.715851 -153.93785) (xy 54.736617 -153.948026)
			(xy 54.748176 -153.948638) (xy 54.82844 -153.948638) (xy 54.840007 -153.948055) (xy 54.860779 -153.937871)
			(xy 54.868318 -153.92908) (xy 54.885071 -153.908297) (xy 54.923425 -153.871167) (xy 54.966579 -153.839745)
			(xy 55.013693 -153.814646) (xy 55.063845 -153.79636) (xy 55.116056 -153.785243) (xy 55.169308 -153.781513)
			(xy 55.22256 -153.785243) (xy 55.274771 -153.79636) (xy 55.324923 -153.814646) (xy 55.372037 -153.839745)
			(xy 55.415191 -153.871167) (xy 55.453545 -153.908297) (xy 55.470298 -153.92908) (xy 55.477851 -153.93785)
			(xy 55.498617 -153.948026) (xy 55.510176 -153.948638) (xy 55.59044 -153.948638) (xy 55.602007 -153.948055)
			(xy 55.622779 -153.937871) (xy 55.630318 -153.92908) (xy 55.647801 -153.90749) (xy 55.687963 -153.869107)
			(xy 55.710328 -153.852626) (xy 55.720742 -153.845006) (xy 55.731918 -153.822654) (xy 55.72887 -153.712418)
			(xy 55.716424 -153.690574) (xy 55.705248 -153.683716) (xy 55.682195 -153.668651) (xy 55.640264 -153.632952)
			(xy 55.6039 -153.591597) (xy 55.573857 -153.545444) (xy 55.550761 -153.495452) (xy 55.53509 -153.442659)
			(xy 55.527171 -153.388163) (xy 55.526686 -153.360628) (xy 55.527181 -153.333376) (xy 55.534934 -153.279427)
			(xy 55.550287 -153.22713) (xy 55.572925 -153.17755) (xy 55.60239 -153.131697) (xy 55.63808 -153.090504)
			(xy 55.67927 -153.05481) (xy 55.72512 -153.025342) (xy 55.774698 -153.002698) (xy 55.826993 -152.987342)
			(xy 55.880942 -152.979584) (xy 55.908194 -152.97912) (xy 55.937111 -152.979635) (xy 55.994283 -152.988364)
			(xy 56.049482 -153.005622) (xy 56.101444 -153.031014) (xy 56.148978 -153.063958) (xy 56.190994 -153.1037)
			(xy 56.209184 -153.126186) (xy 56.216759 -153.134934) (xy 56.237508 -153.145126) (xy 56.249062 -153.145744)
			(xy 56.329326 -153.145744) (xy 56.340891 -153.145151) (xy 56.361664 -153.134974) (xy 56.369204 -153.126186)
			(xy 56.387389 -153.103698) (xy 56.429411 -153.063963) (xy 56.476947 -153.031025) (xy 56.528909 -153.005638)
			(xy 56.584108 -152.988383) (xy 56.641278 -152.979655) (xy 56.670194 -152.97912) (xy 56.697448 -152.979561)
			(xy 56.751401 -152.987318) (xy 56.803701 -153.002675) (xy 56.853283 -153.025318) (xy 56.899138 -153.054788)
			(xy 56.940331 -153.090485) (xy 56.976025 -153.13168) (xy 57.005492 -153.177536) (xy 57.028133 -153.22712)
			(xy 57.043487 -153.27942) (xy 57.051241 -153.333374) (xy 57.051702 -153.360628) (xy 57.051259 -153.386603)
			(xy 57.044214 -153.438073) (xy 57.030243 -153.48811) (xy 57.009607 -153.535785) (xy 56.982687 -153.580217)
			(xy 56.949983 -153.62058) (xy 56.9121 -153.656129) (xy 56.891174 -153.671524) (xy 56.88076 -153.679144)
			(xy 56.869584 -153.701496) (xy 56.872632 -153.811732) (xy 56.885078 -153.833576) (xy 56.896254 -153.840434)
			(xy 56.919285 -153.855531) (xy 56.961216 -153.891225) (xy 56.963904 -153.894282) (xy 83.466178 -153.894282)
			(xy 83.466726 -153.865366) (xy 83.475445 -153.808195) (xy 83.492695 -153.752995) (xy 83.518081 -153.701033)
			(xy 83.551021 -153.653498) (xy 83.590759 -153.611482) (xy 83.613244 -153.593292) (xy 83.622012 -153.585737)
			(xy 83.63219 -153.564973) (xy 83.632802 -153.553414) (xy 83.632802 -153.47315) (xy 83.632202 -153.461586)
			(xy 83.622028 -153.440815) (xy 83.613244 -153.433272) (xy 83.590756 -153.415086) (xy 83.551019 -153.373066)
			(xy 83.51808 -153.325531) (xy 83.492691 -153.273568) (xy 83.475437 -153.218369) (xy 83.466711 -153.161199)
			(xy 83.466178 -153.132282) (xy 83.466661 -153.105031) (xy 83.47442 -153.051084) (xy 83.489776 -152.99879)
			(xy 83.512419 -152.949214) (xy 83.541885 -152.903364) (xy 83.577577 -152.862174) (xy 83.618767 -152.826483)
			(xy 83.664617 -152.797017) (xy 83.714194 -152.774375) (xy 83.766488 -152.759019) (xy 83.820435 -152.751261)
			(xy 83.847686 -152.750774) (xy 83.874961 -152.751244) (xy 83.928959 -152.758987) (xy 83.981303 -152.774346)
			(xy 84.030923 -152.797008) (xy 84.076808 -152.82651) (xy 84.11802 -152.86225) (xy 84.153718 -152.903497)
			(xy 84.183174 -152.949411) (xy 84.194904 -152.97404) (xy 84.201 -152.987248) (xy 84.224622 -153.00325)
			(xy 84.344256 -153.008076) (xy 84.369148 -152.994106) (xy 84.376006 -152.981406) (xy 84.388811 -152.959294)
			(xy 84.419408 -152.918369) (xy 84.455175 -152.881876) (xy 84.475066 -152.865836) (xy 84.483818 -152.858266)
			(xy 84.494004 -152.837513) (xy 84.494624 -152.825958) (xy 84.494624 -152.745694) (xy 84.494084 -152.734121)
			(xy 84.483871 -152.713349) (xy 84.475066 -152.705816) (xy 84.452583 -152.687625) (xy 84.412849 -152.645604)
			(xy 84.379911 -152.598069) (xy 84.354523 -152.546108) (xy 84.337266 -152.490911) (xy 84.328536 -152.433742)
			(xy 84.328 -152.404826) (xy 84.328486 -152.377575) (xy 84.336242 -152.323627) (xy 84.351597 -152.271332)
			(xy 84.374239 -152.221755) (xy 84.403705 -152.175905) (xy 84.439396 -152.134714) (xy 84.480587 -152.099023)
			(xy 84.526437 -152.069557) (xy 84.576014 -152.046915) (xy 84.628309 -152.03156) (xy 84.682257 -152.023804)
			(xy 84.736759 -152.023804) (xy 84.790707 -152.03156) (xy 84.843002 -152.046915) (xy 84.892579 -152.069557)
			(xy 84.938429 -152.099023) (xy 84.97962 -152.134714) (xy 85.015311 -152.175905) (xy 85.044777 -152.221755)
			(xy 85.067419 -152.271332) (xy 85.082774 -152.323627) (xy 85.09053 -152.377575) (xy 85.091016 -152.404826)
			(xy 85.090476 -152.433743) (xy 85.090276 -152.435052) (xy 93.412816 -152.435052) (xy 93.416887 -152.37943)
			(xy 93.429013 -152.324993) (xy 93.448936 -152.272902) (xy 93.476232 -152.224267) (xy 93.510318 -152.180124)
			(xy 93.550467 -152.141415) (xy 93.595825 -152.108964) (xy 93.645425 -152.083463) (xy 93.698209 -152.065456)
			(xy 93.753052 -152.055326) (xy 93.808786 -152.053289) (xy 93.864223 -152.059389) (xy 93.91818 -152.073495)
			(xy 93.969509 -152.095307) (xy 94.017115 -152.124361) (xy 94.059983 -152.160036) (xy 94.0972 -152.201573)
			(xy 94.127973 -152.248086) (xy 94.151645 -152.298583) (xy 94.167713 -152.35199) (xy 94.175833 -152.407166)
			(xy 94.176342 -152.435052) (xy 94.175833 -152.462938) (xy 94.167713 -152.518114) (xy 94.151645 -152.571521)
			(xy 94.127973 -152.622018) (xy 94.0972 -152.668531) (xy 94.059983 -152.710068) (xy 94.017115 -152.745743)
			(xy 93.969509 -152.774797) (xy 93.91818 -152.796609) (xy 93.864223 -152.810715) (xy 93.808786 -152.816815)
			(xy 93.753052 -152.814778) (xy 93.698209 -152.804648) (xy 93.645425 -152.786641) (xy 93.595825 -152.76114)
			(xy 93.550467 -152.728689) (xy 93.510318 -152.68998) (xy 93.476232 -152.645837) (xy 93.448936 -152.597202)
			(xy 93.429013 -152.545111) (xy 93.416887 -152.490674) (xy 93.412816 -152.435052) (xy 85.090276 -152.435052)
			(xy 85.081756 -152.490914) (xy 85.064505 -152.546114) (xy 85.039117 -152.598076) (xy 85.006176 -152.645611)
			(xy 84.966435 -152.687626) (xy 84.94395 -152.705816) (xy 84.935177 -152.713367) (xy 84.925001 -152.734134)
			(xy 84.924392 -152.745694) (xy 84.924392 -152.825958) (xy 84.924989 -152.837522) (xy 84.935165 -152.858293)
			(xy 84.94395 -152.865836) (xy 84.966461 -152.883994) (xy 85.006192 -152.926022) (xy 85.039127 -152.973564)
			(xy 85.06451 -153.025532) (xy 85.081761 -153.080735) (xy 85.090484 -153.137908) (xy 85.091016 -153.166826)
			(xy 85.090546 -153.194078) (xy 85.082787 -153.248025) (xy 85.067429 -153.30032) (xy 85.044785 -153.349897)
			(xy 85.015317 -153.395747) (xy 84.979624 -153.436936) (xy 84.938432 -153.472628) (xy 84.892581 -153.502094)
			(xy 84.843003 -153.524735) (xy 84.790708 -153.54009) (xy 84.73676 -153.547848) (xy 84.709508 -153.548334)
			(xy 84.682233 -153.547865) (xy 84.628235 -153.540121) (xy 84.575892 -153.524761) (xy 84.526271 -153.502099)
			(xy 84.480387 -153.472597) (xy 84.439175 -153.436857) (xy 84.403476 -153.39561) (xy 84.37402 -153.349696)
			(xy 84.36229 -153.325068) (xy 84.356194 -153.31186) (xy 84.332572 -153.295858) (xy 84.212938 -153.291032)
			(xy 84.188046 -153.305002) (xy 84.181188 -153.317702) (xy 84.168386 -153.339816) (xy 84.137788 -153.38074)
			(xy 84.102019 -153.417232) (xy 84.082128 -153.433272) (xy 84.073371 -153.440838) (xy 84.063188 -153.461594)
			(xy 84.06257 -153.47315) (xy 84.06257 -153.553414) (xy 84.063108 -153.564987) (xy 84.073323 -153.585759)
			(xy 84.082128 -153.593292) (xy 84.104613 -153.61148) (xy 84.144347 -153.653502) (xy 84.177285 -153.701037)
			(xy 84.202673 -153.752999) (xy 84.219929 -153.808197) (xy 84.228659 -153.865366) (xy 84.229194 -153.894282)
			(xy 84.228708 -153.921533) (xy 84.220952 -153.975481) (xy 84.205597 -154.027776) (xy 84.182955 -154.077353)
			(xy 84.153489 -154.123203) (xy 84.117798 -154.164394) (xy 84.076607 -154.200085) (xy 84.030757 -154.229551)
			(xy 83.98118 -154.252193) (xy 83.928885 -154.267548) (xy 83.874937 -154.275304) (xy 83.820435 -154.275304)
			(xy 83.766487 -154.267548) (xy 83.714192 -154.252193) (xy 83.664615 -154.229551) (xy 83.618765 -154.200085)
			(xy 83.577574 -154.164394) (xy 83.541883 -154.123203) (xy 83.512417 -154.077353) (xy 83.489775 -154.027776)
			(xy 83.47442 -153.975481) (xy 83.466664 -153.921533) (xy 83.466178 -153.894282) (xy 56.963904 -153.894282)
			(xy 56.997581 -153.932575) (xy 57.027626 -153.978722) (xy 57.050726 -154.028709) (xy 57.066402 -154.081496)
			(xy 57.074328 -154.135989) (xy 57.074816 -154.163522) (xy 57.074448 -154.189074) (xy 57.067633 -154.239722)
			(xy 57.054115 -154.289006) (xy 57.034136 -154.336044) (xy 57.008055 -154.379992) (xy 56.976337 -154.420063)
			(xy 56.95823 -154.438096) (xy 56.951182 -154.445548) (xy 56.943198 -154.464424) (xy 56.942736 -154.474672)
			(xy 56.942736 -154.547824) (xy 56.943192 -154.558073) (xy 56.951179 -154.576949) (xy 56.95823 -154.5844)
			(xy 56.964326 -154.590496) (xy 56.971438 -154.597862) (xy 56.990234 -154.605482) (xy 57.082436 -154.60599)
			(xy 57.100978 -154.598116) (xy 57.108344 -154.591004) (xy 57.129939 -154.570358) (xy 57.178341 -154.53534)
			(xy 57.231612 -154.508299) (xy 57.288448 -154.489897) (xy 57.347459 -154.480584) (xy 57.37733 -154.480006)
			(xy 57.406245 -154.480572) (xy 57.463414 -154.489291) (xy 57.518612 -154.506539) (xy 57.570574 -154.531922)
			(xy 57.618109 -154.564857) (xy 57.660128 -154.60459) (xy 57.67832 -154.627072) (xy 57.685865 -154.63585)
			(xy 57.706637 -154.646022) (xy 57.718198 -154.64663) (xy 57.798462 -154.64663) (xy 57.810031 -154.646062)
			(xy 57.830804 -154.635868) (xy 57.83834 -154.627072) (xy 57.856501 -154.604564) (xy 57.898528 -154.564831)
			(xy 57.946069 -154.531896) (xy 57.998036 -154.506512) (xy 58.053239 -154.489261) (xy 58.110412 -154.480538)
			(xy 58.13933 -154.480006) (xy 58.166581 -154.480466) (xy 58.220527 -154.488226) (xy 58.27282 -154.503584)
			(xy 58.322396 -154.526228) (xy 58.325172 -154.528012) (xy 67.588636 -154.528012) (xy 67.592707 -154.47239)
			(xy 67.604833 -154.417953) (xy 67.624756 -154.365862) (xy 67.652052 -154.317227) (xy 67.686138 -154.273084)
			(xy 67.726287 -154.234375) (xy 67.771645 -154.201924) (xy 67.821245 -154.176423) (xy 67.874029 -154.158416)
			(xy 67.928872 -154.148286) (xy 67.984606 -154.146249) (xy 68.040043 -154.152349) (xy 68.094 -154.166455)
			(xy 68.145329 -154.188267) (xy 68.192935 -154.217321) (xy 68.235803 -154.252996) (xy 68.27302 -154.294533)
			(xy 68.303793 -154.341046) (xy 68.327465 -154.391543) (xy 68.343533 -154.44495) (xy 68.351653 -154.500126)
			(xy 68.352162 -154.528012) (xy 68.351653 -154.555898) (xy 68.343533 -154.611074) (xy 68.327465 -154.664481)
			(xy 68.303793 -154.714978) (xy 68.27302 -154.761491) (xy 68.235803 -154.803028) (xy 68.192935 -154.838703)
			(xy 68.145329 -154.867757) (xy 68.094 -154.889569) (xy 68.040043 -154.903675) (xy 67.984606 -154.909775)
			(xy 67.928872 -154.907738) (xy 67.874029 -154.897608) (xy 67.821245 -154.879601) (xy 67.771645 -154.8541)
			(xy 67.726287 -154.821649) (xy 67.686138 -154.78294) (xy 67.652052 -154.738797) (xy 67.624756 -154.690162)
			(xy 67.604833 -154.638071) (xy 67.592707 -154.583634) (xy 67.588636 -154.528012) (xy 58.325172 -154.528012)
			(xy 58.368244 -154.555696) (xy 58.409432 -154.591389) (xy 58.445122 -154.63258) (xy 58.474586 -154.678431)
			(xy 58.497226 -154.728008) (xy 58.51258 -154.780302) (xy 58.520336 -154.834249) (xy 58.520336 -154.888751)
			(xy 58.51258 -154.942698) (xy 58.497226 -154.994992) (xy 58.474586 -155.044569) (xy 58.445122 -155.09042)
			(xy 58.409432 -155.131611) (xy 58.368244 -155.167304) (xy 58.322396 -155.196772) (xy 58.27282 -155.219416)
			(xy 58.220527 -155.234774) (xy 58.166581 -155.242534) (xy 58.13933 -155.243022) (xy 58.110412 -155.242512)
			(xy 58.053239 -155.233785) (xy 57.998039 -155.216528) (xy 57.946077 -155.191135) (xy 57.898543 -155.158188)
			(xy 57.856528 -155.118444) (xy 57.83834 -155.095956) (xy 57.830764 -155.087209) (xy 57.810016 -155.077019)
			(xy 57.798462 -155.076398) (xy 57.718198 -155.076398) (xy 57.70663 -155.076968) (xy 57.685859 -155.087163)
			(xy 57.67832 -155.095956) (xy 57.660107 -155.118421) (xy 57.618093 -155.158159) (xy 57.570563 -155.191102)
			(xy 57.518606 -155.216494) (xy 57.463412 -155.233753) (xy 57.406245 -155.242486) (xy 57.37733 -155.243022)
			(xy 57.347171 -155.242439) (xy 57.287605 -155.232939) (xy 57.230276 -155.214187) (xy 57.17661 -155.18665)
			(xy 57.127945 -155.151014) (xy 57.106312 -155.129992) (xy 57.0992 -155.122626) (xy 57.080404 -155.115006)
			(xy 56.988202 -155.114498) (xy 56.96966 -155.122372) (xy 56.962294 -155.129484) (xy 56.940697 -155.150127)
			(xy 56.892294 -155.185142) (xy 56.839023 -155.212182) (xy 56.782188 -155.230585) (xy 56.723178 -155.239901)
			(xy 56.693308 -155.240482) (xy 56.664391 -155.239965) (xy 56.607219 -155.231236) (xy 56.55202 -155.213979)
			(xy 56.500059 -155.188587) (xy 56.452525 -155.155643) (xy 56.410508 -155.115902) (xy 56.392318 -155.093416)
			(xy 56.384759 -155.084652) (xy 56.363997 -155.074473) (xy 56.35244 -155.073858) (xy 56.272176 -155.073858)
			(xy 56.260611 -155.074452) (xy 56.239838 -155.084628) (xy 56.232298 -155.093416) (xy 56.215545 -155.114199)
			(xy 56.177191 -155.151329) (xy 56.134037 -155.182751) (xy 56.086923 -155.20785) (xy 56.036771 -155.226136)
			(xy 55.98456 -155.237253) (xy 55.931308 -155.240983) (xy 55.878056 -155.237253) (xy 55.825845 -155.226136)
			(xy 55.775693 -155.20785) (xy 55.728579 -155.182751) (xy 55.685425 -155.151329) (xy 55.647071 -155.114199)
			(xy 55.630318 -155.093416) (xy 55.622759 -155.084652) (xy 55.601997 -155.074473) (xy 55.59044 -155.073858)
			(xy 55.510176 -155.073858) (xy 55.498611 -155.074452) (xy 55.477838 -155.084628) (xy 55.470298 -155.093416)
			(xy 55.453545 -155.114199) (xy 55.415191 -155.151329) (xy 55.372037 -155.182751) (xy 55.324923 -155.20785)
			(xy 55.274771 -155.226136) (xy 55.22256 -155.237253) (xy 55.169308 -155.240983) (xy 55.116056 -155.237253)
			(xy 55.063845 -155.226136) (xy 55.013693 -155.20785) (xy 54.966579 -155.182751) (xy 54.923425 -155.151329)
			(xy 54.885071 -155.114199) (xy 54.868318 -155.093416) (xy 54.860759 -155.084652) (xy 54.839997 -155.074473)
			(xy 54.82844 -155.073858) (xy 54.748176 -155.073858) (xy 54.736611 -155.074452) (xy 54.715838 -155.084628)
			(xy 54.708298 -155.093416) (xy 54.690112 -155.115904) (xy 54.648091 -155.155638) (xy 54.600555 -155.188576)
			(xy 54.548593 -155.213963) (xy 54.493394 -155.231219) (xy 54.436224 -155.239947) (xy 54.407308 -155.240482)
			(xy 54.378559 -155.239983) (xy 54.321716 -155.231331) (xy 54.266813 -155.214251) (xy 54.215093 -155.18913)
			(xy 54.167725 -155.156535) (xy 54.125782 -155.117206) (xy 54.107588 -155.09494) (xy 54.09946 -155.084526)
			(xy 54.075584 -155.074366) (xy 53.964078 -155.085542) (xy 53.942742 -155.100274) (xy 53.9369 -155.111958)
			(xy 53.924612 -155.135249) (xy 53.894686 -155.178579) (xy 53.859083 -155.217378) (xy 53.818478 -155.250907)
			(xy 53.773646 -155.27853) (xy 53.725438 -155.29972) (xy 53.674774 -155.314074) (xy 53.622615 -155.321319)
			(xy 53.596286 -155.321762) (xy 53.567371 -155.321196) (xy 53.510201 -155.312479) (xy 53.455003 -155.295231)
			(xy 53.40304 -155.269849) (xy 53.355505 -155.236913) (xy 53.313487 -155.197178) (xy 53.295296 -155.174696)
			(xy 53.287732 -155.165936) (xy 53.266975 -155.155752) (xy 53.255418 -155.155138) (xy 53.175154 -155.155138)
			(xy 53.163588 -155.155726) (xy 53.142816 -155.165907) (xy 53.135276 -155.174696) (xy 53.117098 -155.19719)
			(xy 53.075075 -155.236925) (xy 53.027538 -155.269863) (xy 52.975574 -155.295249) (xy 52.920374 -155.312503)
			(xy 52.863203 -155.321229) (xy 52.834286 -155.321762) (xy 52.807031 -155.321358) (xy 52.753075 -155.313598)
			(xy 52.700773 -155.298238) (xy 52.65119 -155.27559) (xy 52.605335 -155.246117) (xy 52.564141 -155.210417)
			(xy 52.528447 -155.169217) (xy 52.498981 -155.123357) (xy 52.476341 -155.07377) (xy 52.460989 -155.021466)
			(xy 52.453238 -154.967509) (xy 52.452778 -154.940254) (xy 50.128424 -154.940254) (xy 50.128424 -155.828495)
			(xy 83.791294 -155.828495) (xy 83.795025 -155.775242) (xy 83.806143 -155.72303) (xy 83.824431 -155.672877)
			(xy 83.849532 -155.625763) (xy 83.880955 -155.582608) (xy 83.918088 -155.544255) (xy 83.938872 -155.527502)
			(xy 83.947641 -155.519947) (xy 83.957817 -155.499183) (xy 83.95843 -155.487624) (xy 83.95843 -155.40736)
			(xy 83.957849 -155.395793) (xy 83.947664 -155.37502) (xy 83.938872 -155.367482) (xy 83.916374 -155.349308)
			(xy 83.876641 -155.307284) (xy 83.843705 -155.259745) (xy 83.818319 -155.207781) (xy 83.801066 -155.152581)
			(xy 83.79234 -155.095409) (xy 83.791806 -155.066492) (xy 83.792248 -155.039238) (xy 83.800006 -154.985286)
			(xy 83.815364 -154.932987) (xy 83.838009 -154.883406) (xy 83.867479 -154.837552) (xy 83.903175 -154.796359)
			(xy 83.94437 -154.760666) (xy 83.990225 -154.731198) (xy 84.039807 -154.708556) (xy 84.092107 -154.693202)
			(xy 84.14606 -154.685446) (xy 84.173314 -154.684984) (xy 84.202588 -154.685536) (xy 84.260445 -154.694503)
			(xy 84.316252 -154.712208) (xy 84.368696 -154.738236) (xy 84.416546 -154.771974) (xy 84.437982 -154.791918)
			(xy 84.445348 -154.798776) (xy 84.463382 -154.806142) (xy 84.553806 -154.806142) (xy 84.57184 -154.798776)
			(xy 84.579206 -154.791918) (xy 84.600664 -154.772) (xy 84.648515 -154.738272) (xy 84.700954 -154.712245)
			(xy 84.756753 -154.694529) (xy 84.814603 -154.685541) (xy 84.843874 -154.684984) (xy 84.872792 -154.685489)
			(xy 84.929965 -154.694216) (xy 84.985166 -154.711475) (xy 85.037128 -154.736869) (xy 85.084661 -154.769816)
			(xy 85.126676 -154.809562) (xy 85.144864 -154.83205) (xy 85.152437 -154.8408) (xy 85.173188 -154.850988)
			(xy 85.184742 -154.851608) (xy 85.265006 -154.851608) (xy 85.276574 -154.851038) (xy 85.297344 -154.840843)
			(xy 85.304884 -154.83205) (xy 85.319664 -154.813652) (xy 85.353034 -154.780281) (xy 85.371432 -154.765502)
			(xy 85.380194 -154.75794) (xy 85.390376 -154.737181) (xy 85.39099 -154.725624) (xy 85.39099 -154.64536)
			(xy 85.390389 -154.633796) (xy 85.380216 -154.613025) (xy 85.371432 -154.605482) (xy 85.348947 -154.587293)
			(xy 85.30921 -154.545274) (xy 85.27627 -154.497739) (xy 85.250882 -154.445777) (xy 85.233627 -154.390579)
			(xy 85.2249 -154.333408) (xy 85.224366 -154.304492) (xy 85.22487 -154.277242) (xy 85.232627 -154.223296)
			(xy 85.247982 -154.171003) (xy 85.270622 -154.121428) (xy 85.300087 -154.075579) (xy 85.335776 -154.034389)
			(xy 85.376964 -153.998698) (xy 85.422812 -153.969231) (xy 85.472386 -153.946588) (xy 85.524678 -153.931231)
			(xy 85.578624 -153.923472) (xy 85.605874 -153.922984) (xy 85.634792 -153.923489) (xy 85.691965 -153.932216)
			(xy 85.747166 -153.949475) (xy 85.799128 -153.974869) (xy 85.846661 -154.007816) (xy 85.888676 -154.047562)
			(xy 85.906864 -154.07005) (xy 85.914437 -154.0788) (xy 85.935188 -154.088988) (xy 85.946742 -154.089608)
			(xy 86.027006 -154.089608) (xy 86.038574 -154.089038) (xy 86.059344 -154.078843) (xy 86.066884 -154.07005)
			(xy 86.081664 -154.051652) (xy 86.115034 -154.018281) (xy 86.133432 -154.003502) (xy 86.142194 -153.99594)
			(xy 86.152376 -153.975181) (xy 86.15299 -153.963624) (xy 86.15299 -153.88336) (xy 86.152389 -153.871796)
			(xy 86.142216 -153.851025) (xy 86.133432 -153.843482) (xy 86.110947 -153.825293) (xy 86.07121 -153.783274)
			(xy 86.03827 -153.735739) (xy 86.012882 -153.683777) (xy 85.995627 -153.628579) (xy 85.9869 -153.571408)
			(xy 85.986366 -153.542492) (xy 85.98687 -153.515242) (xy 85.994627 -153.461296) (xy 86.009982 -153.409003)
			(xy 86.032622 -153.359428) (xy 86.062087 -153.313579) (xy 86.097776 -153.272389) (xy 86.138964 -153.236698)
			(xy 86.184812 -153.207231) (xy 86.234386 -153.184588) (xy 86.286678 -153.169231) (xy 86.340624 -153.161472)
			(xy 86.367874 -153.160984) (xy 86.396792 -153.161489) (xy 86.453965 -153.170216) (xy 86.509166 -153.187475)
			(xy 86.561128 -153.212869) (xy 86.608661 -153.245816) (xy 86.650676 -153.285562) (xy 86.668864 -153.30805)
			(xy 86.676437 -153.3168) (xy 86.697188 -153.326988) (xy 86.708742 -153.327608) (xy 86.789006 -153.327608)
			(xy 86.800574 -153.327038) (xy 86.821344 -153.316843) (xy 86.828884 -153.30805) (xy 86.845637 -153.287267)
			(xy 86.883991 -153.250137) (xy 86.927145 -153.218715) (xy 86.974259 -153.193616) (xy 87.024411 -153.17533)
			(xy 87.076622 -153.164213) (xy 87.129874 -153.160483) (xy 87.183126 -153.164213) (xy 87.235337 -153.17533)
			(xy 87.285489 -153.193616) (xy 87.332603 -153.218715) (xy 87.375757 -153.250137) (xy 87.414111 -153.287267)
			(xy 87.430864 -153.30805) (xy 87.438437 -153.3168) (xy 87.459188 -153.326988) (xy 87.470742 -153.327608)
			(xy 87.551006 -153.327608) (xy 87.562574 -153.327038) (xy 87.583344 -153.316843) (xy 87.590884 -153.30805)
			(xy 87.607637 -153.287267) (xy 87.645991 -153.250137) (xy 87.689145 -153.218715) (xy 87.736259 -153.193616)
			(xy 87.786411 -153.17533) (xy 87.838622 -153.164213) (xy 87.891874 -153.160483) (xy 87.945126 -153.164213)
			(xy 87.997337 -153.17533) (xy 88.047489 -153.193616) (xy 88.094603 -153.218715) (xy 88.137757 -153.250137)
			(xy 88.176111 -153.287267) (xy 88.192864 -153.30805) (xy 88.200437 -153.3168) (xy 88.221188 -153.326988)
			(xy 88.232742 -153.327608) (xy 88.313006 -153.327608) (xy 88.324574 -153.327038) (xy 88.345344 -153.316843)
			(xy 88.352884 -153.30805) (xy 88.369637 -153.287267) (xy 88.407991 -153.250137) (xy 88.451145 -153.218715)
			(xy 88.498259 -153.193616) (xy 88.548411 -153.17533) (xy 88.600622 -153.164213) (xy 88.653874 -153.160483)
			(xy 88.707126 -153.164213) (xy 88.759337 -153.17533) (xy 88.809489 -153.193616) (xy 88.856603 -153.218715)
			(xy 88.899757 -153.250137) (xy 88.938111 -153.287267) (xy 88.954864 -153.30805) (xy 88.962437 -153.3168)
			(xy 88.983188 -153.326988) (xy 88.994742 -153.327608) (xy 89.075006 -153.327608) (xy 89.086574 -153.327038)
			(xy 89.107344 -153.316843) (xy 89.114884 -153.30805) (xy 89.131637 -153.287267) (xy 89.169991 -153.250137)
			(xy 89.213145 -153.218715) (xy 89.260259 -153.193616) (xy 89.310411 -153.17533) (xy 89.362622 -153.164213)
			(xy 89.415874 -153.160483) (xy 89.469126 -153.164213) (xy 89.521337 -153.17533) (xy 89.571489 -153.193616)
			(xy 89.618603 -153.218715) (xy 89.661757 -153.250137) (xy 89.700111 -153.287267) (xy 89.716864 -153.30805)
			(xy 89.724437 -153.3168) (xy 89.745188 -153.326988) (xy 89.756742 -153.327608) (xy 89.837006 -153.327608)
			(xy 89.848574 -153.327038) (xy 89.869344 -153.316843) (xy 89.876884 -153.30805) (xy 89.893637 -153.287267)
			(xy 89.931991 -153.250137) (xy 89.975145 -153.218715) (xy 90.022259 -153.193616) (xy 90.072411 -153.17533)
			(xy 90.124622 -153.164213) (xy 90.177874 -153.160483) (xy 90.231126 -153.164213) (xy 90.283337 -153.17533)
			(xy 90.333489 -153.193616) (xy 90.380603 -153.218715) (xy 90.423757 -153.250137) (xy 90.462111 -153.287267)
			(xy 90.478864 -153.30805) (xy 90.486437 -153.3168) (xy 90.507188 -153.326988) (xy 90.518742 -153.327608)
			(xy 90.599006 -153.327608) (xy 90.610574 -153.327038) (xy 90.631344 -153.316843) (xy 90.638884 -153.30805)
			(xy 90.657071 -153.285564) (xy 90.699093 -153.245831) (xy 90.74663 -153.212894) (xy 90.798591 -153.187506)
			(xy 90.853789 -153.17025) (xy 90.910958 -153.16152) (xy 90.939874 -153.160984) (xy 90.967126 -153.161479)
			(xy 91.021075 -153.169233) (xy 91.073372 -153.184585) (xy 91.122951 -153.207224) (xy 91.168804 -153.236688)
			(xy 91.209997 -153.272379) (xy 91.245691 -153.313568) (xy 91.27516 -153.359419) (xy 91.297803 -153.408996)
			(xy 91.31316 -153.461292) (xy 91.320918 -153.51524) (xy 91.321382 -153.542492) (xy 91.320865 -153.571409)
			(xy 91.312136 -153.628581) (xy 91.294879 -153.68378) (xy 91.269487 -153.735741) (xy 91.236543 -153.783275)
			(xy 91.196802 -153.825292) (xy 91.174316 -153.843482) (xy 91.165552 -153.851041) (xy 91.155373 -153.871803)
			(xy 91.154758 -153.88336) (xy 91.154758 -153.963624) (xy 91.155352 -153.975189) (xy 91.165528 -153.995962)
			(xy 91.174316 -154.003502) (xy 91.192712 -154.018284) (xy 91.226085 -154.051652) (xy 91.240864 -154.07005)
			(xy 91.248437 -154.0788) (xy 91.269188 -154.088988) (xy 91.280742 -154.089608) (xy 91.361006 -154.089608)
			(xy 91.372574 -154.089038) (xy 91.393344 -154.078843) (xy 91.400884 -154.07005) (xy 91.419071 -154.047564)
			(xy 91.461093 -154.007831) (xy 91.50863 -153.974894) (xy 91.560591 -153.949506) (xy 91.615789 -153.93225)
			(xy 91.672958 -153.92352) (xy 91.701874 -153.922984) (xy 91.729126 -153.923479) (xy 91.783075 -153.931233)
			(xy 91.835372 -153.946585) (xy 91.884951 -153.969224) (xy 91.930804 -153.998688) (xy 91.971997 -154.034379)
			(xy 92.007691 -154.075568) (xy 92.03716 -154.121419) (xy 92.059803 -154.170996) (xy 92.07516 -154.223292)
			(xy 92.082918 -154.27724) (xy 92.083382 -154.304492) (xy 92.082865 -154.333409) (xy 92.074136 -154.390581)
			(xy 92.056879 -154.44578) (xy 92.031487 -154.497741) (xy 91.998543 -154.545275) (xy 91.958802 -154.587292)
			(xy 91.936316 -154.605482) (xy 91.927552 -154.613041) (xy 91.917373 -154.633803) (xy 91.916758 -154.64536)
			(xy 91.916758 -154.725624) (xy 91.917352 -154.737189) (xy 91.927528 -154.757962) (xy 91.936316 -154.765502)
			(xy 91.957092 -154.782264) (xy 91.994224 -154.820615) (xy 92.025648 -154.863768) (xy 92.050749 -154.910881)
			(xy 92.069037 -154.961032) (xy 92.080155 -155.013244) (xy 92.083885 -155.066495) (xy 92.080156 -155.119747)
			(xy 92.06904 -155.171958) (xy 92.050753 -155.22211) (xy 92.025653 -155.269223) (xy 91.994231 -155.312377)
			(xy 91.957099 -155.350729) (xy 91.936316 -155.367482) (xy 91.927552 -155.375041) (xy 91.917373 -155.395803)
			(xy 91.916758 -155.40736) (xy 91.916758 -155.487624) (xy 91.917352 -155.499189) (xy 91.927528 -155.519962)
			(xy 91.936316 -155.527502) (xy 91.957092 -155.544264) (xy 91.994224 -155.582615) (xy 92.025648 -155.625768)
			(xy 92.050749 -155.672881) (xy 92.069037 -155.723032) (xy 92.080155 -155.775244) (xy 92.083885 -155.828495)
			(xy 92.080156 -155.881747) (xy 92.06904 -155.933958) (xy 92.050753 -155.98411) (xy 92.025653 -156.031223)
			(xy 91.994231 -156.074377) (xy 91.957099 -156.112729) (xy 91.936316 -156.129482) (xy 91.927552 -156.137041)
			(xy 91.917373 -156.157803) (xy 91.916758 -156.16936) (xy 91.916758 -156.249624) (xy 91.917352 -156.261189)
			(xy 91.927528 -156.281962) (xy 91.936316 -156.289502) (xy 91.958804 -156.307688) (xy 91.998538 -156.349709)
			(xy 92.031476 -156.397245) (xy 92.056863 -156.449207) (xy 92.074119 -156.504406) (xy 92.082847 -156.561576)
			(xy 92.083382 -156.590492) (xy 92.082917 -156.618067) (xy 92.074965 -156.67264) (xy 92.059241 -156.7255)
			(xy 92.03607 -156.775546) (xy 92.005937 -156.821736) (xy 91.969469 -156.863106) (xy 91.948762 -156.881322)
			(xy 91.940632 -156.888914) (xy 91.931286 -156.909074) (xy 91.930728 -156.920184) (xy 91.930728 -156.9974)
			(xy 91.931271 -157.008513) (xy 91.940626 -157.028672) (xy 91.948762 -157.036262) (xy 91.96945 -157.054498)
			(xy 92.005924 -157.095861) (xy 92.03606 -157.142045) (xy 92.05923 -157.192088) (xy 92.074951 -157.244947)
			(xy 92.082895 -157.299519) (xy 92.083382 -157.327092) (xy 92.082937 -157.354346) (xy 92.075181 -157.408299)
			(xy 92.059824 -157.460599) (xy 92.037181 -157.51018) (xy 92.007711 -157.556035) (xy 91.972015 -157.597228)
			(xy 91.93082 -157.632922) (xy 91.884965 -157.662389) (xy 91.835382 -157.685031) (xy 91.783081 -157.700384)
			(xy 91.729128 -157.708138) (xy 91.701874 -157.7086) (xy 91.672959 -157.708029) (xy 91.61579 -157.699311)
			(xy 91.560593 -157.682063) (xy 91.508631 -157.656682) (xy 91.461095 -157.623747) (xy 91.419076 -157.584015)
			(xy 91.400884 -157.561534) (xy 91.393336 -157.552758) (xy 91.372566 -157.542585) (xy 91.361006 -157.541976)
			(xy 91.280742 -157.541976) (xy 91.269173 -157.542544) (xy 91.248401 -157.552738) (xy 91.240864 -157.561534)
			(xy 91.224111 -157.582317) (xy 91.185757 -157.619447) (xy 91.142603 -157.650869) (xy 91.095489 -157.675968)
			(xy 91.045337 -157.694254) (xy 90.993126 -157.705371) (xy 90.939874 -157.709101) (xy 90.886622 -157.705371)
			(xy 90.834411 -157.694254) (xy 90.784259 -157.675968) (xy 90.737145 -157.650869) (xy 90.693991 -157.619447)
			(xy 90.655637 -157.582317) (xy 90.638884 -157.561534) (xy 90.631336 -157.552758) (xy 90.610566 -157.542585)
			(xy 90.599006 -157.541976) (xy 90.518742 -157.541976) (xy 90.507173 -157.542544) (xy 90.486401 -157.552738)
			(xy 90.478864 -157.561534) (xy 90.460702 -157.584042) (xy 90.418675 -157.623774) (xy 90.371134 -157.656709)
			(xy 90.319167 -157.682093) (xy 90.263965 -157.699344) (xy 90.206792 -157.708068) (xy 90.177874 -157.7086)
			(xy 90.15153 -157.708154) (xy 90.099341 -157.700917) (xy 90.048644 -157.686571) (xy 90.000402 -157.665389)
			(xy 89.955532 -157.637772) (xy 89.914886 -157.604247) (xy 89.879239 -157.565449) (xy 89.849266 -157.522118)
			(xy 89.837006 -157.498796) (xy 89.830656 -157.485588) (xy 89.806272 -157.470856) (xy 86.739476 -157.470856)
			(xy 86.715092 -157.485588) (xy 86.708742 -157.498796) (xy 86.696496 -157.522125) (xy 86.666517 -157.565453)
			(xy 86.630865 -157.604247) (xy 86.590217 -157.63777) (xy 86.545346 -157.665386) (xy 86.497103 -157.686569)
			(xy 86.446407 -157.700918) (xy 86.394218 -157.708159) (xy 86.367874 -157.7086) (xy 86.338959 -157.708029)
			(xy 86.28179 -157.699311) (xy 86.226593 -157.682063) (xy 86.174631 -157.656682) (xy 86.127095 -157.623747)
			(xy 86.085076 -157.584015) (xy 86.066884 -157.561534) (xy 86.059336 -157.552758) (xy 86.038566 -157.542585)
			(xy 86.027006 -157.541976) (xy 85.946742 -157.541976) (xy 85.935173 -157.542544) (xy 85.914401 -157.552738)
			(xy 85.906864 -157.561534) (xy 85.890111 -157.582317) (xy 85.851757 -157.619447) (xy 85.808603 -157.650869)
			(xy 85.761489 -157.675968) (xy 85.711337 -157.694254) (xy 85.659126 -157.705371) (xy 85.605874 -157.709101)
			(xy 85.552622 -157.705371) (xy 85.500411 -157.694254) (xy 85.450259 -157.675968) (xy 85.403145 -157.650869)
			(xy 85.359991 -157.619447) (xy 85.321637 -157.582317) (xy 85.304884 -157.561534) (xy 85.297336 -157.552758)
			(xy 85.276566 -157.542585) (xy 85.265006 -157.541976) (xy 85.184742 -157.541976) (xy 85.173173 -157.542544)
			(xy 85.152401 -157.552738) (xy 85.144864 -157.561534) (xy 85.126702 -157.584042) (xy 85.084675 -157.623774)
			(xy 85.037134 -157.656709) (xy 84.985167 -157.682093) (xy 84.929965 -157.699344) (xy 84.872792 -157.708068)
			(xy 84.843874 -157.7086) (xy 84.8146 -157.70806) (xy 84.756742 -157.699091) (xy 84.700935 -157.681383)
			(xy 84.64849 -157.655352) (xy 84.600641 -157.621611) (xy 84.579206 -157.601666) (xy 84.57184 -157.594808)
			(xy 84.553806 -157.587442) (xy 84.463382 -157.587442) (xy 84.445348 -157.594808) (xy 84.437982 -157.601666)
			(xy 84.416527 -157.621587) (xy 84.368676 -157.655316) (xy 84.316235 -157.681342) (xy 84.260436 -157.699057)
			(xy 84.202586 -157.708044) (xy 84.173314 -157.7086) (xy 84.146061 -157.708132) (xy 84.09211 -157.700376)
			(xy 84.039812 -157.685022) (xy 83.990231 -157.66238) (xy 83.944378 -157.632913) (xy 83.903185 -157.59722)
			(xy 83.867491 -157.556027) (xy 83.838023 -157.510174) (xy 83.81538 -157.460594) (xy 83.800025 -157.408296)
			(xy 83.792269 -157.354345) (xy 83.791806 -157.327092) (xy 83.792333 -157.29952) (xy 83.800273 -157.244949)
			(xy 83.815985 -157.192091) (xy 83.839144 -157.142044) (xy 83.869266 -157.095853) (xy 83.905723 -157.054479)
			(xy 83.926426 -157.036262) (xy 83.934561 -157.028675) (xy 83.943905 -157.008512) (xy 83.94446 -156.9974)
			(xy 83.94446 -156.920184) (xy 83.94393 -156.909069) (xy 83.934566 -156.88891) (xy 83.926426 -156.881322)
			(xy 83.905727 -156.863097) (xy 83.869255 -156.821732) (xy 83.839121 -156.775545) (xy 83.815953 -156.7255)
			(xy 83.800234 -156.672639) (xy 83.792292 -156.618066) (xy 83.791806 -156.590492) (xy 83.792388 -156.561577)
			(xy 83.801103 -156.504409) (xy 83.818349 -156.449211) (xy 83.843728 -156.397249) (xy 83.876661 -156.349714)
			(xy 83.916391 -156.307694) (xy 83.938872 -156.289502) (xy 83.947641 -156.281947) (xy 83.957817 -156.261183)
			(xy 83.95843 -156.249624) (xy 83.95843 -156.16936) (xy 83.957849 -156.157793) (xy 83.947664 -156.13702)
			(xy 83.938872 -156.129482) (xy 83.91808 -156.112738) (xy 83.880949 -156.074385) (xy 83.849526 -156.031229)
			(xy 83.824427 -155.984115) (xy 83.80614 -155.933961) (xy 83.795023 -155.881748) (xy 83.791294 -155.828495)
			(xy 50.128424 -155.828495) (xy 50.128424 -158.113052) (xy 54.997068 -158.113052) (xy 54.997068 -158.058548)
			(xy 55.004824 -158.004599) (xy 55.02018 -157.952304) (xy 55.042821 -157.902725) (xy 55.072288 -157.856874)
			(xy 55.10798 -157.815683) (xy 55.149171 -157.77999) (xy 55.195022 -157.750523) (xy 55.2446 -157.727881)
			(xy 55.296896 -157.712525) (xy 55.350844 -157.704768) (xy 55.378096 -157.704282) (xy 55.407014 -157.704772)
			(xy 55.464188 -157.713503) (xy 55.519389 -157.730764) (xy 55.571351 -157.756161) (xy 55.618884 -157.789111)
			(xy 55.660898 -157.828859) (xy 55.679086 -157.851348) (xy 55.68665 -157.860107) (xy 55.707407 -157.87029)
			(xy 55.718964 -157.870906) (xy 55.799228 -157.870906) (xy 55.81079 -157.870292) (xy 55.831562 -157.860128)
			(xy 55.839106 -157.851348) (xy 55.855859 -157.830565) (xy 55.894213 -157.793435) (xy 55.937367 -157.762013)
			(xy 55.984481 -157.736914) (xy 56.034633 -157.718628) (xy 56.086844 -157.707511) (xy 56.140096 -157.703781)
			(xy 56.193348 -157.707511) (xy 56.245559 -157.718628) (xy 56.295711 -157.736914) (xy 56.342825 -157.762013)
			(xy 56.385979 -157.793435) (xy 56.424333 -157.830565) (xy 56.441086 -157.851348) (xy 56.44865 -157.860107)
			(xy 56.469407 -157.87029) (xy 56.480964 -157.870906) (xy 56.561228 -157.870906) (xy 56.57279 -157.870292)
			(xy 56.593562 -157.860128) (xy 56.601106 -157.851348) (xy 56.617859 -157.830565) (xy 56.656213 -157.793435)
			(xy 56.699367 -157.762013) (xy 56.746481 -157.736914) (xy 56.796633 -157.718628) (xy 56.848844 -157.707511)
			(xy 56.902096 -157.703781) (xy 56.955348 -157.707511) (xy 57.007559 -157.718628) (xy 57.057711 -157.736914)
			(xy 57.104825 -157.762013) (xy 57.147979 -157.793435) (xy 57.186333 -157.830565) (xy 57.203086 -157.851348)
			(xy 57.21065 -157.860107) (xy 57.231407 -157.87029) (xy 57.242964 -157.870906) (xy 57.323228 -157.870906)
			(xy 57.33479 -157.870292) (xy 57.355562 -157.860128) (xy 57.363106 -157.851348) (xy 57.38128 -157.828851)
			(xy 57.423305 -157.789119) (xy 57.470844 -157.756183) (xy 57.522808 -157.730797) (xy 57.578008 -157.713544)
			(xy 57.635179 -157.704816) (xy 57.664096 -157.704282) (xy 57.691348 -157.704765) (xy 57.745298 -157.712521)
			(xy 57.797595 -157.727877) (xy 57.847175 -157.750518) (xy 57.893027 -157.779985) (xy 57.934219 -157.815678)
			(xy 57.969912 -157.85687) (xy 57.99938 -157.902722) (xy 58.022022 -157.952301) (xy 58.037378 -158.004598)
			(xy 58.045135 -158.058548) (xy 58.045135 -158.113052) (xy 58.037378 -158.167002) (xy 58.022022 -158.219299)
			(xy 57.99938 -158.268878) (xy 57.969912 -158.31473) (xy 57.934219 -158.355922) (xy 57.893027 -158.391615)
			(xy 57.847175 -158.421082) (xy 57.797595 -158.443723) (xy 57.745298 -158.459079) (xy 57.691348 -158.466835)
			(xy 57.664096 -158.467298) (xy 57.635179 -158.466783) (xy 57.578008 -158.458053) (xy 57.522809 -158.440795)
			(xy 57.470847 -158.415403) (xy 57.423313 -158.382458) (xy 57.381296 -158.342717) (xy 57.363106 -158.320232)
			(xy 57.355549 -158.311466) (xy 57.334786 -158.301288) (xy 57.323228 -158.300674) (xy 57.242964 -158.300674)
			(xy 57.231397 -158.301255) (xy 57.210624 -158.31144) (xy 57.203086 -158.320232) (xy 57.186333 -158.341015)
			(xy 57.147979 -158.378145) (xy 57.104825 -158.409567) (xy 57.057711 -158.434666) (xy 57.007559 -158.452952)
			(xy 56.955348 -158.464069) (xy 56.902096 -158.467799) (xy 56.848844 -158.464069) (xy 56.796633 -158.452952)
			(xy 56.746481 -158.434666) (xy 56.699367 -158.409567) (xy 56.656213 -158.378145) (xy 56.617859 -158.341015)
			(xy 56.601106 -158.320232) (xy 56.593549 -158.311466) (xy 56.572786 -158.301288) (xy 56.561228 -158.300674)
			(xy 56.480964 -158.300674) (xy 56.469397 -158.301255) (xy 56.448624 -158.31144) (xy 56.441086 -158.320232)
			(xy 56.424333 -158.341015) (xy 56.385979 -158.378145) (xy 56.342825 -158.409567) (xy 56.295711 -158.434666)
			(xy 56.245559 -158.452952) (xy 56.193348 -158.464069) (xy 56.140096 -158.467799) (xy 56.086844 -158.464069)
			(xy 56.034633 -158.452952) (xy 55.984481 -158.434666) (xy 55.937367 -158.409567) (xy 55.894213 -158.378145)
			(xy 55.855859 -158.341015) (xy 55.839106 -158.320232) (xy 55.831549 -158.311466) (xy 55.810786 -158.301288)
			(xy 55.799228 -158.300674) (xy 55.718964 -158.300674) (xy 55.707397 -158.301255) (xy 55.686624 -158.31144)
			(xy 55.679086 -158.320232) (xy 55.660911 -158.342729) (xy 55.618887 -158.382462) (xy 55.571348 -158.415398)
			(xy 55.519384 -158.440784) (xy 55.464184 -158.458038) (xy 55.407013 -158.466764) (xy 55.378096 -158.467298)
			(xy 55.350844 -158.466832) (xy 55.296896 -158.459075) (xy 55.2446 -158.443719) (xy 55.195022 -158.421077)
			(xy 55.149171 -158.39161) (xy 55.10798 -158.355917) (xy 55.072288 -158.314726) (xy 55.042821 -158.268875)
			(xy 55.02018 -158.219296) (xy 55.004824 -158.167001) (xy 54.997068 -158.113052) (xy 50.128424 -158.113052)
			(xy 50.128424 -160.653052) (xy 54.997068 -160.653052) (xy 54.997068 -160.598548) (xy 55.004824 -160.544599)
			(xy 55.02018 -160.492304) (xy 55.042821 -160.442725) (xy 55.072288 -160.396874) (xy 55.10798 -160.355683)
			(xy 55.149171 -160.31999) (xy 55.195022 -160.290523) (xy 55.2446 -160.267881) (xy 55.296896 -160.252525)
			(xy 55.350844 -160.244768) (xy 55.378096 -160.244282) (xy 55.407014 -160.244772) (xy 55.464188 -160.253503)
			(xy 55.519389 -160.270764) (xy 55.571351 -160.296161) (xy 55.618884 -160.329111) (xy 55.660898 -160.368859)
			(xy 55.679086 -160.391348) (xy 55.68665 -160.400107) (xy 55.707407 -160.41029) (xy 55.718964 -160.410906)
			(xy 55.799228 -160.410906) (xy 55.81079 -160.410292) (xy 55.831562 -160.400128) (xy 55.839106 -160.391348)
			(xy 55.855859 -160.370565) (xy 55.894213 -160.333435) (xy 55.937367 -160.302013) (xy 55.984481 -160.276914)
			(xy 56.034633 -160.258628) (xy 56.086844 -160.247511) (xy 56.140096 -160.243781) (xy 56.193348 -160.247511)
			(xy 56.245559 -160.258628) (xy 56.295711 -160.276914) (xy 56.342825 -160.302013) (xy 56.385979 -160.333435)
			(xy 56.424333 -160.370565) (xy 56.441086 -160.391348) (xy 56.44865 -160.400107) (xy 56.469407 -160.41029)
			(xy 56.480964 -160.410906) (xy 56.561228 -160.410906) (xy 56.57279 -160.410292) (xy 56.593562 -160.400128)
			(xy 56.601106 -160.391348) (xy 56.617859 -160.370565) (xy 56.656213 -160.333435) (xy 56.699367 -160.302013)
			(xy 56.746481 -160.276914) (xy 56.796633 -160.258628) (xy 56.848844 -160.247511) (xy 56.902096 -160.243781)
			(xy 56.955348 -160.247511) (xy 57.007559 -160.258628) (xy 57.057711 -160.276914) (xy 57.104825 -160.302013)
			(xy 57.147979 -160.333435) (xy 57.186333 -160.370565) (xy 57.203086 -160.391348) (xy 57.21065 -160.400107)
			(xy 57.231407 -160.41029) (xy 57.242964 -160.410906) (xy 57.323228 -160.410906) (xy 57.33479 -160.410292)
			(xy 57.355562 -160.400128) (xy 57.363106 -160.391348) (xy 57.38128 -160.368851) (xy 57.423305 -160.329119)
			(xy 57.470844 -160.296183) (xy 57.522808 -160.270797) (xy 57.578008 -160.253544) (xy 57.635179 -160.244816)
			(xy 57.664096 -160.244282) (xy 57.691348 -160.244765) (xy 57.745298 -160.252521) (xy 57.797595 -160.267877)
			(xy 57.847175 -160.290518) (xy 57.893027 -160.319985) (xy 57.934219 -160.355678) (xy 57.969912 -160.39687)
			(xy 57.99938 -160.442722) (xy 58.022022 -160.492301) (xy 58.037378 -160.544598) (xy 58.045135 -160.598548)
			(xy 58.045135 -160.653052) (xy 58.037378 -160.707002) (xy 58.022022 -160.759299) (xy 57.99938 -160.808878)
			(xy 57.969912 -160.85473) (xy 57.934219 -160.895922) (xy 57.893027 -160.931615) (xy 57.847175 -160.961082)
			(xy 57.797595 -160.983723) (xy 57.745298 -160.999079) (xy 57.691348 -161.006835) (xy 57.664096 -161.007298)
			(xy 57.635179 -161.006783) (xy 57.578008 -160.998053) (xy 57.522809 -160.980795) (xy 57.470847 -160.955403)
			(xy 57.423313 -160.922458) (xy 57.381296 -160.882717) (xy 57.363106 -160.860232) (xy 57.355549 -160.851466)
			(xy 57.334786 -160.841288) (xy 57.323228 -160.840674) (xy 57.242964 -160.840674) (xy 57.231397 -160.841255)
			(xy 57.210624 -160.85144) (xy 57.203086 -160.860232) (xy 57.186333 -160.881015) (xy 57.147979 -160.918145)
			(xy 57.104825 -160.949567) (xy 57.057711 -160.974666) (xy 57.007559 -160.992952) (xy 56.955348 -161.004069)
			(xy 56.902096 -161.007799) (xy 56.848844 -161.004069) (xy 56.796633 -160.992952) (xy 56.746481 -160.974666)
			(xy 56.699367 -160.949567) (xy 56.656213 -160.918145) (xy 56.617859 -160.881015) (xy 56.601106 -160.860232)
			(xy 56.593549 -160.851466) (xy 56.572786 -160.841288) (xy 56.561228 -160.840674) (xy 56.480964 -160.840674)
			(xy 56.469397 -160.841255) (xy 56.448624 -160.85144) (xy 56.441086 -160.860232) (xy 56.424333 -160.881015)
			(xy 56.385979 -160.918145) (xy 56.342825 -160.949567) (xy 56.295711 -160.974666) (xy 56.245559 -160.992952)
			(xy 56.193348 -161.004069) (xy 56.140096 -161.007799) (xy 56.086844 -161.004069) (xy 56.034633 -160.992952)
			(xy 55.984481 -160.974666) (xy 55.937367 -160.949567) (xy 55.894213 -160.918145) (xy 55.855859 -160.881015)
			(xy 55.839106 -160.860232) (xy 55.831549 -160.851466) (xy 55.810786 -160.841288) (xy 55.799228 -160.840674)
			(xy 55.718964 -160.840674) (xy 55.707397 -160.841255) (xy 55.686624 -160.85144) (xy 55.679086 -160.860232)
			(xy 55.660911 -160.882729) (xy 55.618887 -160.922462) (xy 55.571348 -160.955398) (xy 55.519384 -160.980784)
			(xy 55.464184 -160.998038) (xy 55.407013 -161.006764) (xy 55.378096 -161.007298) (xy 55.350844 -161.006832)
			(xy 55.296896 -160.999075) (xy 55.2446 -160.983719) (xy 55.195022 -160.961077) (xy 55.149171 -160.93161)
			(xy 55.10798 -160.895917) (xy 55.072288 -160.854726) (xy 55.042821 -160.808875) (xy 55.02018 -160.759296)
			(xy 55.004824 -160.707001) (xy 54.997068 -160.653052) (xy 50.128424 -160.653052) (xy 50.128424 -168.412668)
			(xy 59.348624 -168.412668) (xy 59.348624 -160.095692) (xy 59.34909 -160.085724) (xy 59.356673 -160.067288)
			(xy 59.363356 -160.059878) (xy 61.009784 -158.41345) (xy 61.017175 -158.406711) (xy 61.03561 -158.399001)
			(xy 61.045598 -158.398464) (xy 102.682548 -158.398464) (xy 102.692554 -158.398914) (xy 102.711017 -158.40664)
			(xy 102.718362 -158.41345) (xy 103.2764 -158.971488) (xy 103.283092 -158.978889) (xy 103.290659 -158.997334)
			(xy 103.291132 -159.007302) (xy 103.291132 -160.83788) (xy 105.696512 -160.83788) (xy 105.696512 -150.278846)
			(xy 105.696972 -150.268842) (xy 105.704693 -150.250379) (xy 105.711498 -150.243032) (xy 107.558332 -148.396198)
			(xy 107.565712 -148.389445) (xy 107.584155 -148.381741) (xy 107.594146 -148.381212) (xy 129.678176 -148.381212)
			(xy 129.688182 -148.381661) (xy 129.706644 -148.389389) (xy 129.71399 -148.396198) (xy 131.412742 -150.09495)
			(xy 131.419465 -150.102353) (xy 131.427185 -150.120779) (xy 131.427728 -150.130764) (xy 131.427728 -150.533608)
			(xy 136.287 -150.533608) (xy 136.291071 -150.477986) (xy 136.303197 -150.423549) (xy 136.32312 -150.371458)
			(xy 136.350416 -150.322823) (xy 136.384502 -150.27868) (xy 136.424651 -150.239971) (xy 136.470009 -150.20752)
			(xy 136.519609 -150.182019) (xy 136.572393 -150.164012) (xy 136.627236 -150.153882) (xy 136.68297 -150.151845)
			(xy 136.738407 -150.157945) (xy 136.792364 -150.172051) (xy 136.843693 -150.193863) (xy 136.891299 -150.222917)
			(xy 136.934167 -150.258592) (xy 136.971384 -150.300129) (xy 137.002157 -150.346642) (xy 137.025829 -150.397139)
			(xy 137.041897 -150.450546) (xy 137.050017 -150.505722) (xy 137.050526 -150.533608) (xy 137.050017 -150.561494)
			(xy 137.041897 -150.61667) (xy 137.033492 -150.644606) (xy 137.304016 -150.644606) (xy 137.308087 -150.588984)
			(xy 137.320213 -150.534547) (xy 137.340136 -150.482456) (xy 137.367432 -150.433821) (xy 137.401518 -150.389678)
			(xy 137.441667 -150.350969) (xy 137.487025 -150.318518) (xy 137.536625 -150.293017) (xy 137.589409 -150.27501)
			(xy 137.644252 -150.26488) (xy 137.699986 -150.262843) (xy 137.755423 -150.268943) (xy 137.80938 -150.283049)
			(xy 137.860709 -150.304861) (xy 137.908315 -150.333915) (xy 137.951183 -150.36959) (xy 137.9884 -150.411127)
			(xy 138.019173 -150.45764) (xy 138.042845 -150.508137) (xy 138.058913 -150.561544) (xy 138.067033 -150.61672)
			(xy 138.067542 -150.644606) (xy 138.067033 -150.672492) (xy 138.058913 -150.727668) (xy 138.042845 -150.781075)
			(xy 138.019173 -150.831572) (xy 137.9884 -150.878085) (xy 137.951183 -150.919622) (xy 137.908315 -150.955297)
			(xy 137.860709 -150.984351) (xy 137.80938 -151.006163) (xy 137.755423 -151.020269) (xy 137.699986 -151.026369)
			(xy 137.644252 -151.024332) (xy 137.589409 -151.014202) (xy 137.536625 -150.996195) (xy 137.487025 -150.970694)
			(xy 137.441667 -150.938243) (xy 137.401518 -150.899534) (xy 137.367432 -150.855391) (xy 137.340136 -150.806756)
			(xy 137.320213 -150.754665) (xy 137.308087 -150.700228) (xy 137.304016 -150.644606) (xy 137.033492 -150.644606)
			(xy 137.025829 -150.670077) (xy 137.002157 -150.720574) (xy 136.971384 -150.767087) (xy 136.934167 -150.808624)
			(xy 136.891299 -150.844299) (xy 136.843693 -150.873353) (xy 136.792364 -150.895165) (xy 136.738407 -150.909271)
			(xy 136.68297 -150.915371) (xy 136.627236 -150.913334) (xy 136.572393 -150.903204) (xy 136.519609 -150.885197)
			(xy 136.470009 -150.859696) (xy 136.424651 -150.827245) (xy 136.384502 -150.788536) (xy 136.350416 -150.744393)
			(xy 136.32312 -150.695758) (xy 136.303197 -150.643667) (xy 136.291071 -150.58923) (xy 136.287 -150.533608)
			(xy 131.427728 -150.533608) (xy 131.427728 -152.191212) (xy 132.117846 -152.191212) (xy 132.118332 -152.163961)
			(xy 132.126088 -152.110013) (xy 132.141443 -152.057718) (xy 132.164085 -152.008141) (xy 132.193551 -151.962291)
			(xy 132.229242 -151.9211) (xy 132.270433 -151.885409) (xy 132.316283 -151.855943) (xy 132.36586 -151.833301)
			(xy 132.418155 -151.817946) (xy 132.472103 -151.81019) (xy 132.526605 -151.81019) (xy 132.580553 -151.817946)
			(xy 132.632848 -151.833301) (xy 132.682425 -151.855943) (xy 132.728275 -151.885409) (xy 132.769466 -151.9211)
			(xy 132.805157 -151.962291) (xy 132.834623 -152.008141) (xy 132.857265 -152.057718) (xy 132.863423 -152.07869)
			(xy 134.023354 -152.07869) (xy 134.02384 -152.051439) (xy 134.031596 -151.997491) (xy 134.046951 -151.945196)
			(xy 134.069593 -151.895619) (xy 134.099059 -151.849769) (xy 134.13475 -151.808578) (xy 134.175941 -151.772887)
			(xy 134.221791 -151.743421) (xy 134.271368 -151.720779) (xy 134.323663 -151.705424) (xy 134.377611 -151.697668)
			(xy 134.432113 -151.697668) (xy 134.486061 -151.705424) (xy 134.538356 -151.720779) (xy 134.587933 -151.743421)
			(xy 134.633783 -151.772887) (xy 134.674974 -151.808578) (xy 134.710665 -151.849769) (xy 134.740131 -151.895619)
			(xy 134.762773 -151.945196) (xy 134.778128 -151.997491) (xy 134.785884 -152.051439) (xy 134.78637 -152.07869)
			(xy 134.785938 -152.104179) (xy 134.779161 -152.154704) (xy 134.765712 -152.203876) (xy 134.745833 -152.250818)
			(xy 134.719877 -152.294693) (xy 134.688307 -152.334719) (xy 134.670292 -152.352756) (xy 134.662418 -152.360376)
			(xy 134.654544 -152.380188) (xy 134.657338 -152.476454) (xy 134.666482 -152.495758) (xy 134.67461 -152.50287)
			(xy 134.695019 -152.52108) (xy 134.730949 -152.562319) (xy 134.760621 -152.608266) (xy 134.783427 -152.65798)
			(xy 134.7989 -152.710441) (xy 134.804508 -152.74925) (xy 135.34593 -152.74925) (xy 135.350001 -152.693628)
			(xy 135.362127 -152.639191) (xy 135.38205 -152.5871) (xy 135.409346 -152.538465) (xy 135.443432 -152.494322)
			(xy 135.483581 -152.455613) (xy 135.528939 -152.423162) (xy 135.578539 -152.397661) (xy 135.631323 -152.379654)
			(xy 135.686166 -152.369524) (xy 135.7419 -152.367487) (xy 135.797337 -152.373587) (xy 135.851294 -152.387693)
			(xy 135.902623 -152.409505) (xy 135.950229 -152.438559) (xy 135.993097 -152.474234) (xy 136.030314 -152.515771)
			(xy 136.061087 -152.562284) (xy 136.084759 -152.612781) (xy 136.100827 -152.666188) (xy 136.108947 -152.721364)
			(xy 136.109456 -152.74925) (xy 136.108947 -152.777136) (xy 136.100827 -152.832312) (xy 136.084759 -152.885719)
			(xy 136.061087 -152.936216) (xy 136.030314 -152.982729) (xy 135.993097 -153.024266) (xy 135.950229 -153.059941)
			(xy 135.902623 -153.088995) (xy 135.851294 -153.110807) (xy 135.797337 -153.124913) (xy 135.7419 -153.131013)
			(xy 135.686166 -153.128976) (xy 135.631323 -153.118846) (xy 135.578539 -153.100839) (xy 135.528939 -153.075338)
			(xy 135.483581 -153.042887) (xy 135.443432 -153.004178) (xy 135.409346 -152.960035) (xy 135.38205 -152.9114)
			(xy 135.362127 -152.859309) (xy 135.350001 -152.804872) (xy 135.34593 -152.74925) (xy 134.804508 -152.74925)
			(xy 134.806722 -152.764574) (xy 134.807198 -152.791922) (xy 134.806712 -152.819173) (xy 134.798956 -152.873121)
			(xy 134.783601 -152.925416) (xy 134.760959 -152.974993) (xy 134.731493 -153.020843) (xy 134.695802 -153.062034)
			(xy 134.654611 -153.097725) (xy 134.608761 -153.127191) (xy 134.559184 -153.149833) (xy 134.506889 -153.165188)
			(xy 134.452941 -153.172944) (xy 134.398439 -153.172944) (xy 134.344491 -153.165188) (xy 134.292196 -153.149833)
			(xy 134.242619 -153.127191) (xy 134.196769 -153.097725) (xy 134.155578 -153.062034) (xy 134.119887 -153.020843)
			(xy 134.090421 -152.974993) (xy 134.067779 -152.925416) (xy 134.052424 -152.873121) (xy 134.044668 -152.819173)
			(xy 134.044182 -152.791922) (xy 134.044637 -152.766434) (xy 134.051411 -152.71591) (xy 134.064856 -152.666739)
			(xy 134.084731 -152.619797) (xy 134.110683 -152.575922) (xy 134.142248 -152.535894) (xy 134.16026 -152.517856)
			(xy 134.168134 -152.510236) (xy 134.176008 -152.490424) (xy 134.173214 -152.394158) (xy 134.16407 -152.374854)
			(xy 134.155942 -152.367742) (xy 134.135549 -152.349514) (xy 134.099616 -152.30828) (xy 134.06994 -152.262337)
			(xy 134.047131 -152.212627) (xy 134.031655 -152.160168) (xy 134.023831 -152.106037) (xy 134.023354 -152.07869)
			(xy 132.863423 -152.07869) (xy 132.87262 -152.110013) (xy 132.880376 -152.163961) (xy 132.880862 -152.191212)
			(xy 132.880196 -152.222775) (xy 132.869812 -152.28504) (xy 132.849329 -152.344749) (xy 132.834888 -152.372822)
			(xy 132.830062 -152.381712) (xy 132.82803 -152.40127) (xy 132.853684 -152.489408) (xy 132.86613 -152.504902)
			(xy 132.87502 -152.509982) (xy 132.882386 -152.514046) (xy 132.892038 -152.519888) (xy 132.914136 -152.52192)
			(xy 133.008624 -152.488392) (xy 133.024626 -152.472898) (xy 133.02869 -152.462484) (xy 133.039369 -152.4357)
			(xy 133.067659 -152.385458) (xy 133.103192 -152.340049) (xy 133.145156 -152.300507) (xy 133.192596 -152.267734)
			(xy 133.244429 -152.242477) (xy 133.299474 -152.225313) (xy 133.356476 -152.216632) (xy 133.385306 -152.216104)
			(xy 133.412558 -152.216566) (xy 133.466507 -152.224324) (xy 133.518802 -152.23968) (xy 133.56838 -152.262322)
			(xy 133.614231 -152.291789) (xy 133.655422 -152.327482) (xy 133.691114 -152.368673) (xy 133.720581 -152.414525)
			(xy 133.743222 -152.464103) (xy 133.758578 -152.516399) (xy 133.766334 -152.570348) (xy 133.766334 -152.624852)
			(xy 133.758578 -152.678801) (xy 133.743222 -152.731097) (xy 133.720581 -152.780675) (xy 133.691114 -152.826527)
			(xy 133.655422 -152.867718) (xy 133.614231 -152.903411) (xy 133.56838 -152.932878) (xy 133.518802 -152.95552)
			(xy 133.466507 -152.970876) (xy 133.412558 -152.978634) (xy 133.385306 -152.97912) (xy 133.360071 -152.978718)
			(xy 133.310037 -152.972101) (xy 133.261317 -152.958929) (xy 133.214765 -152.939434) (xy 133.192774 -152.92705)
			(xy 133.183122 -152.921208) (xy 133.161024 -152.919176) (xy 133.066536 -152.952704) (xy 133.050534 -152.968198)
			(xy 133.04647 -152.978612) (xy 133.035739 -153.005373) (xy 133.007455 -153.055613) (xy 132.97193 -153.101022)
			(xy 132.929973 -153.140565) (xy 132.882541 -153.17334) (xy 132.830715 -153.198601) (xy 132.775677 -153.215771)
			(xy 132.718681 -153.224459) (xy 132.689854 -153.224992) (xy 132.662601 -153.224565) (xy 132.60865 -153.216802)
			(xy 132.556353 -153.20144) (xy 132.506775 -153.178792) (xy 132.460924 -153.14932) (xy 132.419734 -153.113622)
			(xy 132.384043 -153.072426) (xy 132.354578 -153.026571) (xy 132.331938 -152.976988) (xy 132.316585 -152.924689)
			(xy 132.308831 -152.870737) (xy 132.308346 -152.843484) (xy 132.309009 -152.811921) (xy 132.319394 -152.749656)
			(xy 132.339879 -152.689947) (xy 132.35432 -152.661874) (xy 132.359146 -152.652984) (xy 132.361178 -152.633426)
			(xy 132.335524 -152.545288) (xy 132.323078 -152.529794) (xy 132.314188 -152.524714) (xy 132.289062 -152.510206)
			(xy 132.24318 -152.474696) (xy 132.203207 -152.432645) (xy 132.170065 -152.385024) (xy 132.144518 -152.332933)
			(xy 132.127157 -152.277572) (xy 132.118382 -152.220221) (xy 132.117846 -152.191212) (xy 131.427728 -152.191212)
			(xy 131.427728 -153.200608) (xy 131.428112 -153.210652) (xy 131.435691 -153.229248) (xy 131.44246 -153.236676)
			(xy 131.850384 -153.6446) (xy 134.76681 -153.6446) (xy 134.770881 -153.588978) (xy 134.783007 -153.534541)
			(xy 134.80293 -153.48245) (xy 134.830226 -153.433815) (xy 134.864312 -153.389672) (xy 134.904461 -153.350963)
			(xy 134.949819 -153.318512) (xy 134.999419 -153.293011) (xy 135.052203 -153.275004) (xy 135.107046 -153.264874)
			(xy 135.16278 -153.262837) (xy 135.218217 -153.268937) (xy 135.272174 -153.283043) (xy 135.323503 -153.304855)
			(xy 135.371109 -153.333909) (xy 135.413977 -153.369584) (xy 135.451194 -153.411121) (xy 135.481967 -153.457634)
			(xy 135.505639 -153.508131) (xy 135.521707 -153.561538) (xy 135.529827 -153.616714) (xy 135.530336 -153.6446)
			(xy 135.529827 -153.672486) (xy 135.521707 -153.727662) (xy 135.505639 -153.781069) (xy 135.481967 -153.831566)
			(xy 135.451194 -153.878079) (xy 135.413977 -153.919616) (xy 135.371109 -153.955291) (xy 135.323503 -153.984345)
			(xy 135.272174 -154.006157) (xy 135.218217 -154.020263) (xy 135.16278 -154.026363) (xy 135.107046 -154.024326)
			(xy 135.052203 -154.014196) (xy 134.999419 -153.996189) (xy 134.949819 -153.970688) (xy 134.904461 -153.938237)
			(xy 134.864312 -153.899528) (xy 134.830226 -153.855385) (xy 134.80293 -153.80675) (xy 134.783007 -153.754659)
			(xy 134.770881 -153.700222) (xy 134.76681 -153.6446) (xy 131.850384 -153.6446) (xy 132.282438 -154.076654)
			(xy 132.289163 -154.084057) (xy 132.296882 -154.102483) (xy 132.297424 -154.112468) (xy 132.297424 -154.345132)
			(xy 136.69086 -154.345132) (xy 136.694931 -154.28951) (xy 136.707057 -154.235073) (xy 136.72698 -154.182982)
			(xy 136.754276 -154.134347) (xy 136.788362 -154.090204) (xy 136.828511 -154.051495) (xy 136.873869 -154.019044)
			(xy 136.923469 -153.993543) (xy 136.976253 -153.975536) (xy 137.031096 -153.965406) (xy 137.08683 -153.963369)
			(xy 137.142267 -153.969469) (xy 137.196224 -153.983575) (xy 137.247553 -154.005387) (xy 137.295159 -154.034441)
			(xy 137.338027 -154.070116) (xy 137.375244 -154.111653) (xy 137.406017 -154.158166) (xy 137.429689 -154.208663)
			(xy 137.445757 -154.26207) (xy 137.453877 -154.317246) (xy 137.454386 -154.345132) (xy 137.453877 -154.373018)
			(xy 137.445757 -154.428194) (xy 137.429689 -154.481601) (xy 137.406017 -154.532098) (xy 137.375244 -154.578611)
			(xy 137.338027 -154.620148) (xy 137.295159 -154.655823) (xy 137.247553 -154.684877) (xy 137.196224 -154.706689)
			(xy 137.142267 -154.720795) (xy 137.08683 -154.726895) (xy 137.031096 -154.724858) (xy 136.976253 -154.714728)
			(xy 136.923469 -154.696721) (xy 136.873869 -154.67122) (xy 136.828511 -154.638769) (xy 136.788362 -154.60006)
			(xy 136.754276 -154.555917) (xy 136.72698 -154.507282) (xy 136.707057 -154.455191) (xy 136.694931 -154.400754)
			(xy 136.69086 -154.345132) (xy 132.297424 -154.345132) (xy 132.297424 -155.52166) (xy 135.725662 -155.52166)
			(xy 135.726138 -155.493749) (xy 135.734277 -155.438522) (xy 135.750377 -155.385072) (xy 135.774094 -155.334537)
			(xy 135.80492 -155.287998) (xy 135.823198 -155.266898) (xy 135.829548 -155.259786) (xy 135.836152 -155.242514)
			(xy 135.836152 -155.155392) (xy 135.829548 -155.13812) (xy 135.823198 -155.131008) (xy 135.804902 -155.109923)
			(xy 135.774077 -155.063381) (xy 135.750365 -155.012842) (xy 135.734273 -154.959388) (xy 135.726144 -154.904158)
			(xy 135.725662 -154.876246) (xy 135.726148 -154.848995) (xy 135.733904 -154.795047) (xy 135.749259 -154.742752)
			(xy 135.771901 -154.693175) (xy 135.801367 -154.647325) (xy 135.837058 -154.606134) (xy 135.878249 -154.570443)
			(xy 135.924099 -154.540977) (xy 135.973676 -154.518335) (xy 136.025971 -154.50298) (xy 136.079919 -154.495224)
			(xy 136.134421 -154.495224) (xy 136.188369 -154.50298) (xy 136.240664 -154.518335) (xy 136.290241 -154.540977)
			(xy 136.336091 -154.570443) (xy 136.377282 -154.606134) (xy 136.412973 -154.647325) (xy 136.442439 -154.693175)
			(xy 136.465081 -154.742752) (xy 136.480436 -154.795047) (xy 136.488192 -154.848995) (xy 136.488678 -154.876246)
			(xy 136.488196 -154.904157) (xy 136.480056 -154.959383) (xy 136.463957 -155.012833) (xy 136.440243 -155.063367)
			(xy 136.409418 -155.109907) (xy 136.391142 -155.131008) (xy 136.384792 -155.13812) (xy 136.378188 -155.155392)
			(xy 136.378188 -155.242514) (xy 136.384792 -155.259786) (xy 136.391142 -155.266898) (xy 136.4094 -155.288014)
			(xy 136.440229 -155.334549) (xy 136.463947 -155.385079) (xy 136.480049 -155.438527) (xy 136.488189 -155.49375)
			(xy 136.488678 -155.52166) (xy 136.488192 -155.548911) (xy 136.480436 -155.602859) (xy 136.465081 -155.655154)
			(xy 136.442439 -155.704731) (xy 136.412973 -155.750581) (xy 136.377282 -155.791772) (xy 136.336091 -155.827463)
			(xy 136.290241 -155.856929) (xy 136.240664 -155.879571) (xy 136.188369 -155.894926) (xy 136.134421 -155.902682)
			(xy 136.079919 -155.902682) (xy 136.025971 -155.894926) (xy 135.973676 -155.879571) (xy 135.924099 -155.856929)
			(xy 135.878249 -155.827463) (xy 135.837058 -155.791772) (xy 135.801367 -155.750581) (xy 135.771901 -155.704731)
			(xy 135.749259 -155.655154) (xy 135.733904 -155.602859) (xy 135.726148 -155.548911) (xy 135.725662 -155.52166)
			(xy 132.297424 -155.52166) (xy 132.297424 -156.306012) (xy 132.296959 -156.316016) (xy 132.289244 -156.33448)
			(xy 132.282438 -156.341826) (xy 132.13334 -156.490924) (xy 132.125921 -156.497594) (xy 132.10749 -156.505176)
			(xy 132.097526 -156.505656) (xy 130.442208 -156.505656) (xy 130.432137 -156.506071) (xy 130.413539 -156.513797)
			(xy 130.40614 -156.520642) (xy 130.385058 -156.541724) (xy 130.377633 -156.548386) (xy 130.359207 -156.555973)
			(xy 130.349244 -156.556456) (xy 126.251208 -156.556456) (xy 126.241137 -156.556871) (xy 126.222539 -156.564597)
			(xy 126.21514 -156.571442) (xy 123.19381 -159.592772) (xy 123.186952 -159.592772) (xy 122.97918 -159.800544)
			(xy 122.972482 -159.808022) (xy 122.964894 -159.826584) (xy 122.964448 -159.836612) (xy 122.964448 -160.852612)
			(xy 123.659646 -160.852612) (xy 123.660132 -160.825361) (xy 123.667888 -160.771413) (xy 123.683243 -160.719118)
			(xy 123.705885 -160.669541) (xy 123.735351 -160.623691) (xy 123.771042 -160.5825) (xy 123.812233 -160.546809)
			(xy 123.858083 -160.517343) (xy 123.90766 -160.494701) (xy 123.959955 -160.479346) (xy 124.013903 -160.47159)
			(xy 124.068405 -160.47159) (xy 124.122353 -160.479346) (xy 124.174648 -160.494701) (xy 124.224225 -160.517343)
			(xy 124.270075 -160.546809) (xy 124.311266 -160.5825) (xy 124.346957 -160.623691) (xy 124.376423 -160.669541)
			(xy 124.399065 -160.719118) (xy 124.403731 -160.73501) (xy 125.549914 -160.73501) (xy 125.5504 -160.707759)
			(xy 125.558156 -160.653811) (xy 125.573511 -160.601516) (xy 125.596153 -160.551939) (xy 125.625619 -160.506089)
			(xy 125.66131 -160.464898) (xy 125.702501 -160.429207) (xy 125.748351 -160.399741) (xy 125.797928 -160.377099)
			(xy 125.850223 -160.361744) (xy 125.904171 -160.353988) (xy 125.958673 -160.353988) (xy 126.012621 -160.361744)
			(xy 126.064916 -160.377099) (xy 126.114493 -160.399741) (xy 126.160343 -160.429207) (xy 126.201534 -160.464898)
			(xy 126.237225 -160.506089) (xy 126.266691 -160.551939) (xy 126.289333 -160.601516) (xy 126.304688 -160.653811)
			(xy 126.312444 -160.707759) (xy 126.31293 -160.73501) (xy 126.312484 -160.761804) (xy 126.304979 -160.814864)
			(xy 126.290129 -160.866354) (xy 126.268229 -160.915263) (xy 126.239707 -160.960631) (xy 126.22276 -160.98139)
			(xy 126.216664 -160.988502) (xy 126.210568 -161.00552) (xy 126.212092 -161.091372) (xy 126.21895 -161.108136)
			(xy 126.2253 -161.115248) (xy 126.243886 -161.136439) (xy 126.275271 -161.183257) (xy 126.299425 -161.234183)
			(xy 126.315825 -161.288108) (xy 126.324111 -161.34386) (xy 126.324614 -161.372042) (xy 126.324128 -161.399293)
			(xy 126.322495 -161.41065) (xy 126.88773 -161.41065) (xy 126.891801 -161.355028) (xy 126.903927 -161.300591)
			(xy 126.92385 -161.2485) (xy 126.951146 -161.199865) (xy 126.985232 -161.155722) (xy 127.025381 -161.117013)
			(xy 127.070739 -161.084562) (xy 127.120339 -161.059061) (xy 127.173123 -161.041054) (xy 127.227966 -161.030924)
			(xy 127.2837 -161.028887) (xy 127.339137 -161.034987) (xy 127.393094 -161.049093) (xy 127.444423 -161.070905)
			(xy 127.492029 -161.099959) (xy 127.534897 -161.135634) (xy 127.572114 -161.177171) (xy 127.602887 -161.223684)
			(xy 127.626559 -161.274181) (xy 127.642627 -161.327588) (xy 127.650747 -161.382764) (xy 127.651256 -161.41065)
			(xy 127.650747 -161.438536) (xy 127.642627 -161.493712) (xy 127.626559 -161.547119) (xy 127.602887 -161.597616)
			(xy 127.572114 -161.644129) (xy 127.534897 -161.685666) (xy 127.492029 -161.721341) (xy 127.444423 -161.750395)
			(xy 127.393094 -161.772207) (xy 127.339137 -161.786313) (xy 127.2837 -161.792413) (xy 127.227966 -161.790376)
			(xy 127.173123 -161.780246) (xy 127.120339 -161.762239) (xy 127.070739 -161.736738) (xy 127.025381 -161.704287)
			(xy 126.985232 -161.665578) (xy 126.951146 -161.621435) (xy 126.92385 -161.5728) (xy 126.903927 -161.520709)
			(xy 126.891801 -161.466272) (xy 126.88773 -161.41065) (xy 126.322495 -161.41065) (xy 126.316372 -161.453241)
			(xy 126.301017 -161.505536) (xy 126.278375 -161.555113) (xy 126.248909 -161.600963) (xy 126.213218 -161.642154)
			(xy 126.172027 -161.677845) (xy 126.126177 -161.707311) (xy 126.0766 -161.729953) (xy 126.024305 -161.745308)
			(xy 125.970357 -161.753064) (xy 125.915855 -161.753064) (xy 125.861907 -161.745308) (xy 125.809612 -161.729953)
			(xy 125.760035 -161.707311) (xy 125.714185 -161.677845) (xy 125.672994 -161.642154) (xy 125.637303 -161.600963)
			(xy 125.607837 -161.555113) (xy 125.585195 -161.505536) (xy 125.56984 -161.453241) (xy 125.562084 -161.399293)
			(xy 125.561598 -161.372042) (xy 125.562067 -161.345249) (xy 125.569567 -161.292189) (xy 125.58441 -161.240699)
			(xy 125.606306 -161.19179) (xy 125.634823 -161.146422) (xy 125.651768 -161.125662) (xy 125.657864 -161.11855)
			(xy 125.66396 -161.101532) (xy 125.662436 -161.01568) (xy 125.655578 -160.998916) (xy 125.649228 -160.991804)
			(xy 125.630608 -160.970642) (xy 125.59923 -160.923815) (xy 125.575084 -160.872882) (xy 125.558692 -160.81895)
			(xy 125.550413 -160.763194) (xy 125.549914 -160.73501) (xy 124.403731 -160.73501) (xy 124.41442 -160.771413)
			(xy 124.422176 -160.825361) (xy 124.422662 -160.852612) (xy 124.421996 -160.884175) (xy 124.411612 -160.94644)
			(xy 124.391129 -161.006149) (xy 124.376688 -161.034222) (xy 124.371862 -161.043112) (xy 124.36983 -161.06267)
			(xy 124.395484 -161.150808) (xy 124.40793 -161.166302) (xy 124.41682 -161.171382) (xy 124.424186 -161.175446)
			(xy 124.433838 -161.181288) (xy 124.455936 -161.18332) (xy 124.550424 -161.149792) (xy 124.566426 -161.134298)
			(xy 124.57049 -161.123884) (xy 124.581169 -161.0971) (xy 124.609459 -161.046858) (xy 124.644992 -161.001449)
			(xy 124.686956 -160.961907) (xy 124.734396 -160.929134) (xy 124.786229 -160.903877) (xy 124.841274 -160.886713)
			(xy 124.898276 -160.878032) (xy 124.927106 -160.877504) (xy 124.954358 -160.877966) (xy 125.008307 -160.885724)
			(xy 125.060602 -160.90108) (xy 125.11018 -160.923722) (xy 125.156031 -160.953189) (xy 125.197222 -160.988882)
			(xy 125.232914 -161.030073) (xy 125.262381 -161.075925) (xy 125.285022 -161.125503) (xy 125.300378 -161.177799)
			(xy 125.308134 -161.231748) (xy 125.308134 -161.286252) (xy 125.300378 -161.340201) (xy 125.285022 -161.392497)
			(xy 125.262381 -161.442075) (xy 125.232914 -161.487927) (xy 125.197222 -161.529118) (xy 125.156031 -161.564811)
			(xy 125.11018 -161.594278) (xy 125.060602 -161.61692) (xy 125.008307 -161.632276) (xy 124.954358 -161.640034)
			(xy 124.927106 -161.64052) (xy 124.901871 -161.640118) (xy 124.851837 -161.633501) (xy 124.803117 -161.620329)
			(xy 124.756565 -161.600834) (xy 124.734574 -161.58845) (xy 124.724922 -161.582608) (xy 124.702824 -161.580576)
			(xy 124.608336 -161.614104) (xy 124.592334 -161.629598) (xy 124.58827 -161.640012) (xy 124.577539 -161.666773)
			(xy 124.549255 -161.717013) (xy 124.51373 -161.762422) (xy 124.471773 -161.801965) (xy 124.424341 -161.83474)
			(xy 124.372515 -161.860001) (xy 124.317477 -161.877171) (xy 124.260481 -161.885859) (xy 124.231654 -161.886392)
			(xy 124.204401 -161.885965) (xy 124.15045 -161.878202) (xy 124.098153 -161.86284) (xy 124.048575 -161.840192)
			(xy 124.002724 -161.81072) (xy 123.961534 -161.775022) (xy 123.925843 -161.733826) (xy 123.896378 -161.687971)
			(xy 123.873738 -161.638388) (xy 123.858385 -161.586089) (xy 123.850631 -161.532137) (xy 123.850146 -161.504884)
			(xy 123.850809 -161.473321) (xy 123.861194 -161.411056) (xy 123.881679 -161.351347) (xy 123.89612 -161.323274)
			(xy 123.900946 -161.314384) (xy 123.902978 -161.294826) (xy 123.877324 -161.206688) (xy 123.864878 -161.191194)
			(xy 123.855988 -161.186114) (xy 123.830862 -161.171606) (xy 123.78498 -161.136096) (xy 123.745007 -161.094045)
			(xy 123.711865 -161.046424) (xy 123.686318 -160.994333) (xy 123.668957 -160.938972) (xy 123.660182 -160.881621)
			(xy 123.659646 -160.852612) (xy 122.964448 -160.852612) (xy 122.964448 -161.862008) (xy 122.964826 -161.872053)
			(xy 122.972408 -161.890649) (xy 122.97918 -161.898076) (xy 123.387104 -162.306) (xy 126.30861 -162.306)
			(xy 126.312681 -162.250378) (xy 126.324807 -162.195941) (xy 126.34473 -162.14385) (xy 126.372026 -162.095215)
			(xy 126.406112 -162.051072) (xy 126.446261 -162.012363) (xy 126.491619 -161.979912) (xy 126.541219 -161.954411)
			(xy 126.594003 -161.936404) (xy 126.648846 -161.926274) (xy 126.70458 -161.924237) (xy 126.760017 -161.930337)
			(xy 126.813974 -161.944443) (xy 126.865303 -161.966255) (xy 126.912909 -161.995309) (xy 126.955777 -162.030984)
			(xy 126.992994 -162.072521) (xy 127.023767 -162.119034) (xy 127.047439 -162.169531) (xy 127.063507 -162.222938)
			(xy 127.071627 -162.278114) (xy 127.072136 -162.306) (xy 127.071627 -162.333886) (xy 127.063507 -162.389062)
			(xy 127.047439 -162.442469) (xy 127.023767 -162.492966) (xy 126.992994 -162.539479) (xy 126.955777 -162.581016)
			(xy 126.912909 -162.616691) (xy 126.865303 -162.645745) (xy 126.813974 -162.667557) (xy 126.760017 -162.681663)
			(xy 126.70458 -162.687763) (xy 126.648846 -162.685726) (xy 126.594003 -162.675596) (xy 126.541219 -162.657589)
			(xy 126.491619 -162.632088) (xy 126.446261 -162.599637) (xy 126.406112 -162.560928) (xy 126.372026 -162.516785)
			(xy 126.34473 -162.46815) (xy 126.324807 -162.416059) (xy 126.312681 -162.361622) (xy 126.30861 -162.306)
			(xy 123.387104 -162.306) (xy 123.824238 -162.743134) (xy 123.830997 -162.750509) (xy 123.838696 -162.768956)
			(xy 123.839224 -162.778948) (xy 123.839224 -164.18306) (xy 127.267462 -164.18306) (xy 127.267938 -164.155149)
			(xy 127.276077 -164.099922) (xy 127.292177 -164.046472) (xy 127.315894 -163.995937) (xy 127.34672 -163.949398)
			(xy 127.364998 -163.928298) (xy 127.371348 -163.921186) (xy 127.377952 -163.903914) (xy 127.377952 -163.816792)
			(xy 127.371348 -163.79952) (xy 127.364998 -163.792408) (xy 127.346702 -163.771323) (xy 127.315877 -163.724781)
			(xy 127.292165 -163.674242) (xy 127.276073 -163.620788) (xy 127.267944 -163.565558) (xy 127.267462 -163.537646)
			(xy 127.267948 -163.510395) (xy 127.275704 -163.456447) (xy 127.291059 -163.404152) (xy 127.313701 -163.354575)
			(xy 127.343167 -163.308725) (xy 127.378858 -163.267534) (xy 127.420049 -163.231843) (xy 127.465899 -163.202377)
			(xy 127.515476 -163.179735) (xy 127.567771 -163.16438) (xy 127.621719 -163.156624) (xy 127.676221 -163.156624)
			(xy 127.730169 -163.16438) (xy 127.782464 -163.179735) (xy 127.832041 -163.202377) (xy 127.877891 -163.231843)
			(xy 127.919082 -163.267534) (xy 127.954773 -163.308725) (xy 127.984239 -163.354575) (xy 128.006881 -163.404152)
			(xy 128.022236 -163.456447) (xy 128.029992 -163.510395) (xy 128.030478 -163.537646) (xy 128.029996 -163.565557)
			(xy 128.021856 -163.620783) (xy 128.005757 -163.674233) (xy 127.982043 -163.724767) (xy 127.951218 -163.771307)
			(xy 127.932942 -163.792408) (xy 127.926592 -163.79952) (xy 127.919988 -163.816792) (xy 127.919988 -163.903914)
			(xy 127.926592 -163.921186) (xy 127.932942 -163.928298) (xy 127.9512 -163.949414) (xy 127.982029 -163.995949)
			(xy 128.005747 -164.046479) (xy 128.021849 -164.099927) (xy 128.029989 -164.15515) (xy 128.030478 -164.18306)
			(xy 128.029992 -164.210311) (xy 128.022236 -164.264259) (xy 128.006881 -164.316554) (xy 127.984239 -164.366131)
			(xy 127.954773 -164.411981) (xy 127.919082 -164.453172) (xy 127.877891 -164.488863) (xy 127.832041 -164.518329)
			(xy 127.782464 -164.540971) (xy 127.730169 -164.556326) (xy 127.676221 -164.564082) (xy 127.621719 -164.564082)
			(xy 127.567771 -164.556326) (xy 127.515476 -164.540971) (xy 127.465899 -164.518329) (xy 127.420049 -164.488863)
			(xy 127.378858 -164.453172) (xy 127.343167 -164.411981) (xy 127.313701 -164.366131) (xy 127.291059 -164.316554)
			(xy 127.275704 -164.264259) (xy 127.267948 -164.210311) (xy 127.267462 -164.18306) (xy 123.839224 -164.18306)
			(xy 123.839224 -164.972492) (xy 123.838801 -164.982501) (xy 123.831056 -165.000964) (xy 123.824238 -165.008306)
			(xy 123.68022 -165.152324) (xy 123.672808 -165.159002) (xy 123.654372 -165.166579) (xy 123.644406 -165.167056)
			(xy 121.984008 -165.167056) (xy 121.973937 -165.167471) (xy 121.955339 -165.175197) (xy 121.94794 -165.182042)
			(xy 121.926858 -165.203124) (xy 121.919433 -165.209786) (xy 121.901007 -165.217373) (xy 121.891044 -165.217856)
			(xy 119.084852 -165.217856) (xy 119.074784 -165.218294) (xy 119.056185 -165.226004) (xy 119.048784 -165.232842)
			(xy 118.602506 -165.67912) (xy 118.595098 -165.685804) (xy 118.576659 -165.693378) (xy 118.566692 -165.693852)
			(xy 114.777012 -165.693852) (xy 114.766942 -165.69427) (xy 114.748343 -165.701995) (xy 114.740944 -165.708838)
			(xy 114.6683 -165.781482) (xy 114.661574 -165.788938) (xy 114.654005 -165.807517) (xy 114.653568 -165.81755)
			(xy 114.653568 -167.583612) (xy 115.379246 -167.583612) (xy 115.379732 -167.556361) (xy 115.387488 -167.502413)
			(xy 115.402843 -167.450118) (xy 115.425485 -167.400541) (xy 115.454951 -167.354691) (xy 115.490642 -167.3135)
			(xy 115.531833 -167.277809) (xy 115.577683 -167.248343) (xy 115.62726 -167.225701) (xy 115.679555 -167.210346)
			(xy 115.733503 -167.20259) (xy 115.788005 -167.20259) (xy 115.841953 -167.210346) (xy 115.894248 -167.225701)
			(xy 115.943825 -167.248343) (xy 115.989675 -167.277809) (xy 116.030866 -167.3135) (xy 116.066557 -167.354691)
			(xy 116.096023 -167.400541) (xy 116.118665 -167.450118) (xy 116.13402 -167.502413) (xy 116.141776 -167.556361)
			(xy 116.142262 -167.583612) (xy 116.141596 -167.615175) (xy 116.131212 -167.67744) (xy 116.110729 -167.737149)
			(xy 116.096288 -167.765222) (xy 116.091462 -167.774112) (xy 116.08943 -167.79367) (xy 116.115084 -167.881808)
			(xy 116.12753 -167.897302) (xy 116.13642 -167.902382) (xy 116.143786 -167.906446) (xy 116.153438 -167.912288)
			(xy 116.175536 -167.91432) (xy 116.270024 -167.880792) (xy 116.286026 -167.865298) (xy 116.29009 -167.854884)
			(xy 116.300769 -167.8281) (xy 116.329059 -167.777858) (xy 116.364592 -167.732449) (xy 116.406556 -167.692907)
			(xy 116.453996 -167.660134) (xy 116.505829 -167.634877) (xy 116.560874 -167.617713) (xy 116.617876 -167.609032)
			(xy 116.646706 -167.608504) (xy 116.673958 -167.608966) (xy 116.727907 -167.616724) (xy 116.780202 -167.63208)
			(xy 116.82978 -167.654722) (xy 116.875631 -167.684189) (xy 116.916822 -167.719882) (xy 116.952514 -167.761073)
			(xy 116.981981 -167.806925) (xy 117.004622 -167.856503) (xy 117.019978 -167.908799) (xy 117.027734 -167.962748)
			(xy 117.027734 -168.017252) (xy 117.019978 -168.071201) (xy 117.010628 -168.103042) (xy 117.269514 -168.103042)
			(xy 117.270022 -168.075568) (xy 117.277908 -168.021189) (xy 117.293523 -167.968507) (xy 117.316543 -167.918614)
			(xy 117.34649 -167.872544) (xy 117.364256 -167.851582) (xy 117.370352 -167.84447) (xy 117.376702 -167.827452)
			(xy 117.376702 -167.7416) (xy 117.370352 -167.724582) (xy 117.364256 -167.71747) (xy 117.34649 -167.69651)
			(xy 117.316567 -167.650427) (xy 117.293555 -167.600532) (xy 117.27793 -167.547855) (xy 117.270013 -167.493482)
			(xy 117.269514 -167.46601) (xy 117.27 -167.438759) (xy 117.277756 -167.384811) (xy 117.293111 -167.332516)
			(xy 117.315753 -167.282939) (xy 117.345219 -167.237089) (xy 117.38091 -167.195898) (xy 117.422101 -167.160207)
			(xy 117.467951 -167.130741) (xy 117.517528 -167.108099) (xy 117.569823 -167.092744) (xy 117.623771 -167.084988)
			(xy 117.678273 -167.084988) (xy 117.732221 -167.092744) (xy 117.784516 -167.108099) (xy 117.834093 -167.130741)
			(xy 117.879943 -167.160207) (xy 117.921134 -167.195898) (xy 117.956825 -167.237089) (xy 117.986291 -167.282939)
			(xy 118.008933 -167.332516) (xy 118.024288 -167.384811) (xy 118.032044 -167.438759) (xy 118.03253 -167.46601)
			(xy 118.032042 -167.493484) (xy 118.02415 -167.547864) (xy 118.008529 -167.600546) (xy 117.985505 -167.650439)
			(xy 117.955555 -167.696508) (xy 117.937788 -167.71747) (xy 117.931692 -167.724582) (xy 117.925342 -167.7416)
			(xy 117.925342 -167.827452) (xy 117.931692 -167.84447) (xy 117.937788 -167.851582) (xy 117.955523 -167.872568)
			(xy 117.985452 -167.918643) (xy 118.008471 -167.968531) (xy 118.024104 -168.021203) (xy 118.032027 -168.075571)
			(xy 118.03253 -168.103042) (xy 118.032044 -168.130293) (xy 118.030411 -168.14165) (xy 118.60733 -168.14165)
			(xy 118.611401 -168.086028) (xy 118.623527 -168.031591) (xy 118.64345 -167.9795) (xy 118.670746 -167.930865)
			(xy 118.704832 -167.886722) (xy 118.744981 -167.848013) (xy 118.790339 -167.815562) (xy 118.839939 -167.790061)
			(xy 118.892723 -167.772054) (xy 118.947566 -167.761924) (xy 119.0033 -167.759887) (xy 119.058737 -167.765987)
			(xy 119.112694 -167.780093) (xy 119.164023 -167.801905) (xy 119.211629 -167.830959) (xy 119.254497 -167.866634)
			(xy 119.291714 -167.908171) (xy 119.322487 -167.954684) (xy 119.346159 -168.005181) (xy 119.349237 -168.015412)
			(xy 139.30757 -168.015412) (xy 139.30807 -167.986494) (xy 139.316799 -167.929321) (xy 139.334059 -167.874121)
			(xy 139.359454 -167.822158) (xy 139.392402 -167.774625) (xy 139.432148 -167.73261) (xy 139.454636 -167.714422)
			(xy 139.46339 -167.706852) (xy 139.473576 -167.686099) (xy 139.474194 -167.674544) (xy 139.474194 -167.59428)
			(xy 139.47358 -167.582718) (xy 139.463416 -167.561946) (xy 139.454636 -167.554402) (xy 139.432161 -167.536201)
			(xy 139.392424 -167.494184) (xy 139.359483 -167.446652) (xy 139.334092 -167.394692) (xy 139.316835 -167.339496)
			(xy 139.308105 -167.282328) (xy 139.30757 -167.253412) (xy 139.308056 -167.226161) (xy 139.315812 -167.172213)
			(xy 139.331167 -167.119918) (xy 139.353809 -167.070341) (xy 139.383275 -167.024491) (xy 139.418966 -166.9833)
			(xy 139.460157 -166.947609) (xy 139.506007 -166.918143) (xy 139.555584 -166.895501) (xy 139.607879 -166.880146)
			(xy 139.661827 -166.87239) (xy 139.716329 -166.87239) (xy 139.770277 -166.880146) (xy 139.822572 -166.895501)
			(xy 139.872149 -166.918143) (xy 139.917999 -166.947609) (xy 139.95919 -166.9833) (xy 139.994881 -167.024491)
			(xy 140.024347 -167.070341) (xy 140.046989 -167.119918) (xy 140.062344 -167.172213) (xy 140.0701 -167.226161)
			(xy 140.070586 -167.253412) (xy 140.07001 -167.282327) (xy 140.061294 -167.339496) (xy 140.044048 -167.394694)
			(xy 140.018667 -167.446656) (xy 139.985733 -167.494191) (xy 139.946001 -167.53621) (xy 139.92352 -167.554402)
			(xy 139.914748 -167.561954) (xy 139.904574 -167.582721) (xy 139.903962 -167.59428) (xy 139.903962 -167.674544)
			(xy 139.904543 -167.686111) (xy 139.914728 -167.706884) (xy 139.92352 -167.714422) (xy 139.946018 -167.732596)
			(xy 139.985752 -167.77462) (xy 140.018688 -167.822158) (xy 140.044074 -167.874123) (xy 140.061327 -167.929323)
			(xy 140.070053 -167.986495) (xy 140.070586 -168.015412) (xy 140.0701 -168.042663) (xy 140.062344 -168.096611)
			(xy 140.046989 -168.148906) (xy 140.024347 -168.198483) (xy 139.994881 -168.244333) (xy 139.95919 -168.285524)
			(xy 139.917999 -168.321215) (xy 139.872149 -168.350681) (xy 139.822572 -168.373323) (xy 139.770277 -168.388678)
			(xy 139.716329 -168.396434) (xy 139.661827 -168.396434) (xy 139.607879 -168.388678) (xy 139.555584 -168.373323)
			(xy 139.506007 -168.350681) (xy 139.460157 -168.321215) (xy 139.418966 -168.285524) (xy 139.383275 -168.244333)
			(xy 139.353809 -168.198483) (xy 139.331167 -168.148906) (xy 139.315812 -168.096611) (xy 139.308056 -168.042663)
			(xy 139.30757 -168.015412) (xy 119.349237 -168.015412) (xy 119.362227 -168.058588) (xy 119.370347 -168.113764)
			(xy 119.370856 -168.14165) (xy 119.370347 -168.169536) (xy 119.362227 -168.224712) (xy 119.346159 -168.278119)
			(xy 119.322487 -168.328616) (xy 119.291714 -168.375129) (xy 119.254497 -168.416666) (xy 119.211629 -168.452341)
			(xy 119.164023 -168.481395) (xy 119.112694 -168.503207) (xy 119.058737 -168.517313) (xy 119.0033 -168.523413)
			(xy 118.947566 -168.521376) (xy 118.892723 -168.511246) (xy 118.839939 -168.493239) (xy 118.790339 -168.467738)
			(xy 118.744981 -168.435287) (xy 118.704832 -168.396578) (xy 118.670746 -168.352435) (xy 118.64345 -168.3038)
			(xy 118.623527 -168.251709) (xy 118.611401 -168.197272) (xy 118.60733 -168.14165) (xy 118.030411 -168.14165)
			(xy 118.024288 -168.184241) (xy 118.008933 -168.236536) (xy 117.986291 -168.286113) (xy 117.956825 -168.331963)
			(xy 117.921134 -168.373154) (xy 117.879943 -168.408845) (xy 117.834093 -168.438311) (xy 117.784516 -168.460953)
			(xy 117.732221 -168.476308) (xy 117.678273 -168.484064) (xy 117.623771 -168.484064) (xy 117.569823 -168.476308)
			(xy 117.517528 -168.460953) (xy 117.467951 -168.438311) (xy 117.422101 -168.408845) (xy 117.38091 -168.373154)
			(xy 117.345219 -168.331963) (xy 117.315753 -168.286113) (xy 117.293111 -168.236536) (xy 117.277756 -168.184241)
			(xy 117.27 -168.130293) (xy 117.269514 -168.103042) (xy 117.010628 -168.103042) (xy 117.004622 -168.123497)
			(xy 116.981981 -168.173075) (xy 116.952514 -168.218927) (xy 116.916822 -168.260118) (xy 116.875631 -168.295811)
			(xy 116.82978 -168.325278) (xy 116.780202 -168.34792) (xy 116.727907 -168.363276) (xy 116.673958 -168.371034)
			(xy 116.646706 -168.37152) (xy 116.621471 -168.371118) (xy 116.571437 -168.364501) (xy 116.522717 -168.351329)
			(xy 116.476165 -168.331834) (xy 116.454174 -168.31945) (xy 116.444522 -168.313608) (xy 116.422424 -168.311576)
			(xy 116.327936 -168.345104) (xy 116.311934 -168.360598) (xy 116.30787 -168.371012) (xy 116.297139 -168.397773)
			(xy 116.268855 -168.448013) (xy 116.23333 -168.493422) (xy 116.191373 -168.532965) (xy 116.143941 -168.56574)
			(xy 116.092115 -168.591001) (xy 116.037077 -168.608171) (xy 115.980081 -168.616859) (xy 115.951254 -168.617392)
			(xy 115.924001 -168.616965) (xy 115.87005 -168.609202) (xy 115.817753 -168.59384) (xy 115.768175 -168.571192)
			(xy 115.722324 -168.54172) (xy 115.681134 -168.506022) (xy 115.645443 -168.464826) (xy 115.615978 -168.418971)
			(xy 115.593338 -168.369388) (xy 115.577985 -168.317089) (xy 115.570231 -168.263137) (xy 115.569746 -168.235884)
			(xy 115.570409 -168.204321) (xy 115.580794 -168.142056) (xy 115.601279 -168.082347) (xy 115.61572 -168.054274)
			(xy 115.620546 -168.045384) (xy 115.622578 -168.025826) (xy 115.596924 -167.937688) (xy 115.584478 -167.922194)
			(xy 115.575588 -167.917114) (xy 115.550462 -167.902606) (xy 115.50458 -167.867096) (xy 115.464607 -167.825045)
			(xy 115.431465 -167.777424) (xy 115.405918 -167.725333) (xy 115.388557 -167.669972) (xy 115.379782 -167.612621)
			(xy 115.379246 -167.583612) (xy 114.653568 -167.583612) (xy 114.653568 -168.610788) (xy 114.653899 -168.620838)
			(xy 114.661513 -168.639434) (xy 114.6683 -168.646856) (xy 115.058444 -169.037) (xy 118.02821 -169.037)
			(xy 118.032281 -168.981378) (xy 118.044407 -168.926941) (xy 118.06433 -168.87485) (xy 118.091626 -168.826215)
			(xy 118.125712 -168.782072) (xy 118.165861 -168.743363) (xy 118.211219 -168.710912) (xy 118.260819 -168.685411)
			(xy 118.313603 -168.667404) (xy 118.368446 -168.657274) (xy 118.42418 -168.655237) (xy 118.479617 -168.661337)
			(xy 118.533574 -168.675443) (xy 118.584903 -168.697255) (xy 118.632509 -168.726309) (xy 118.675377 -168.761984)
			(xy 118.712594 -168.803521) (xy 118.743367 -168.850034) (xy 118.767039 -168.900531) (xy 118.783107 -168.953938)
			(xy 118.791227 -169.009114) (xy 118.791736 -169.037) (xy 118.791227 -169.064886) (xy 118.783107 -169.120062)
			(xy 118.767039 -169.173469) (xy 118.743367 -169.223966) (xy 118.712594 -169.270479) (xy 118.675377 -169.312016)
			(xy 118.632509 -169.347691) (xy 118.584903 -169.376745) (xy 118.533574 -169.398557) (xy 118.479617 -169.412663)
			(xy 118.42418 -169.418763) (xy 118.368446 -169.416726) (xy 118.313603 -169.406596) (xy 118.260819 -169.388589)
			(xy 118.211219 -169.363088) (xy 118.165861 -169.330637) (xy 118.125712 -169.291928) (xy 118.091626 -169.247785)
			(xy 118.06433 -169.19915) (xy 118.044407 -169.147059) (xy 118.032281 -169.092622) (xy 118.02821 -169.037)
			(xy 115.058444 -169.037) (xy 115.530376 -169.508932) (xy 115.53704 -169.516354) (xy 115.544624 -169.534783)
			(xy 115.545108 -169.544746) (xy 115.545108 -170.91406) (xy 118.987062 -170.91406) (xy 118.987538 -170.886149)
			(xy 118.995677 -170.830922) (xy 119.011777 -170.777472) (xy 119.035494 -170.726937) (xy 119.06632 -170.680398)
			(xy 119.084598 -170.659298) (xy 119.090948 -170.652186) (xy 119.097552 -170.634914) (xy 119.097552 -170.547792)
			(xy 119.090948 -170.53052) (xy 119.084598 -170.523408) (xy 119.066302 -170.502323) (xy 119.035477 -170.455781)
			(xy 119.011765 -170.405242) (xy 118.995673 -170.351788) (xy 118.987544 -170.296558) (xy 118.987062 -170.268646)
			(xy 118.987548 -170.241395) (xy 118.995304 -170.187447) (xy 119.010659 -170.135152) (xy 119.033301 -170.085575)
			(xy 119.062767 -170.039725) (xy 119.098458 -169.998534) (xy 119.139649 -169.962843) (xy 119.185499 -169.933377)
			(xy 119.235076 -169.910735) (xy 119.287371 -169.89538) (xy 119.341319 -169.887624) (xy 119.395821 -169.887624)
			(xy 119.449769 -169.89538) (xy 119.502064 -169.910735) (xy 119.551641 -169.933377) (xy 119.597491 -169.962843)
			(xy 119.638682 -169.998534) (xy 119.674373 -170.039725) (xy 119.703839 -170.085575) (xy 119.726481 -170.135152)
			(xy 119.741836 -170.187447) (xy 119.749592 -170.241395) (xy 119.750078 -170.268646) (xy 119.749596 -170.296557)
			(xy 119.741456 -170.351783) (xy 119.725357 -170.405233) (xy 119.701643 -170.455767) (xy 119.670818 -170.502307)
			(xy 119.652542 -170.523408) (xy 119.646192 -170.53052) (xy 119.639588 -170.547792) (xy 119.639588 -170.634914)
			(xy 119.646192 -170.652186) (xy 119.652542 -170.659298) (xy 119.6708 -170.680414) (xy 119.701629 -170.726949)
			(xy 119.725347 -170.777479) (xy 119.741449 -170.830927) (xy 119.749589 -170.88615) (xy 119.750078 -170.91406)
			(xy 119.749592 -170.941311) (xy 119.741836 -170.995259) (xy 119.726481 -171.047554) (xy 119.703839 -171.097131)
			(xy 119.674373 -171.142981) (xy 119.638682 -171.184172) (xy 119.597491 -171.219863) (xy 119.551641 -171.249329)
			(xy 119.502064 -171.271971) (xy 119.449769 -171.287326) (xy 119.395821 -171.295082) (xy 119.341319 -171.295082)
			(xy 119.287371 -171.287326) (xy 119.235076 -171.271971) (xy 119.185499 -171.249329) (xy 119.139649 -171.219863)
			(xy 119.098458 -171.184172) (xy 119.062767 -171.142981) (xy 119.033301 -171.097131) (xy 119.010659 -171.047554)
			(xy 118.995304 -170.995259) (xy 118.987548 -170.941311) (xy 118.987062 -170.91406) (xy 115.545108 -170.91406)
			(xy 115.545108 -171.691554) (xy 115.544632 -171.701521) (xy 115.537058 -171.719958) (xy 115.530376 -171.727368)
			(xy 115.37442 -171.883324) (xy 115.367008 -171.890002) (xy 115.348572 -171.897579) (xy 115.338606 -171.898056)
			(xy 113.703608 -171.898056) (xy 113.693537 -171.898471) (xy 113.674939 -171.906197) (xy 113.66754 -171.913042)
			(xy 113.663222 -171.91736) (xy 113.655813 -171.924042) (xy 113.637375 -171.931616) (xy 113.627408 -171.932092)
			(xy 110.441232 -171.932092) (xy 110.43125 -171.931696) (xy 110.412788 -171.924104) (xy 110.405418 -171.91736)
			(xy 109.857032 -171.368974) (xy 109.850371 -171.361549) (xy 109.842785 -171.343123) (xy 109.8423 -171.33316)
			(xy 109.8423 -165.025578) (xy 109.841913 -165.015504) (xy 109.834168 -164.996905) (xy 109.827314 -164.98951)
			(xy 105.711498 -160.873694) (xy 105.704756 -160.866305) (xy 105.697046 -160.847869) (xy 105.696512 -160.83788)
			(xy 103.291132 -160.83788) (xy 103.291132 -167.725344) (xy 103.291526 -167.735417) (xy 103.299268 -167.754015)
			(xy 103.306118 -167.761412) (xy 106.426762 -170.882056) (xy 106.433477 -170.889467) (xy 106.441204 -170.907886)
			(xy 106.441748 -170.91787) (xy 106.441748 -173.832012) (xy 107.149646 -173.832012) (xy 107.150132 -173.804761)
			(xy 107.157888 -173.750813) (xy 107.173243 -173.698518) (xy 107.195885 -173.648941) (xy 107.225351 -173.603091)
			(xy 107.261042 -173.5619) (xy 107.302233 -173.526209) (xy 107.348083 -173.496743) (xy 107.39766 -173.474101)
			(xy 107.449955 -173.458746) (xy 107.503903 -173.45099) (xy 107.558405 -173.45099) (xy 107.612353 -173.458746)
			(xy 107.664648 -173.474101) (xy 107.714225 -173.496743) (xy 107.760075 -173.526209) (xy 107.801266 -173.5619)
			(xy 107.836957 -173.603091) (xy 107.866423 -173.648941) (xy 107.889065 -173.698518) (xy 107.90442 -173.750813)
			(xy 107.912176 -173.804761) (xy 107.912662 -173.832012) (xy 107.911996 -173.863575) (xy 107.901612 -173.92584)
			(xy 107.881129 -173.985549) (xy 107.866688 -174.013622) (xy 107.861862 -174.022512) (xy 107.85983 -174.04207)
			(xy 107.885484 -174.130208) (xy 107.89793 -174.145702) (xy 107.90682 -174.150782) (xy 107.914186 -174.154846)
			(xy 107.923838 -174.160688) (xy 107.945936 -174.16272) (xy 108.040424 -174.129192) (xy 108.056426 -174.113698)
			(xy 108.06049 -174.103284) (xy 108.071169 -174.0765) (xy 108.099459 -174.026258) (xy 108.134992 -173.980849)
			(xy 108.176956 -173.941307) (xy 108.224396 -173.908534) (xy 108.276229 -173.883277) (xy 108.331274 -173.866113)
			(xy 108.388276 -173.857432) (xy 108.417106 -173.856904) (xy 108.444358 -173.857366) (xy 108.498307 -173.865124)
			(xy 108.550602 -173.88048) (xy 108.60018 -173.903122) (xy 108.646031 -173.932589) (xy 108.687222 -173.968282)
			(xy 108.722914 -174.009473) (xy 108.752381 -174.055325) (xy 108.775022 -174.104903) (xy 108.790378 -174.157199)
			(xy 108.798134 -174.211148) (xy 108.798134 -174.265652) (xy 108.790378 -174.319601) (xy 108.781028 -174.351442)
			(xy 109.039914 -174.351442) (xy 109.040422 -174.323968) (xy 109.048308 -174.269589) (xy 109.063923 -174.216907)
			(xy 109.086943 -174.167014) (xy 109.11689 -174.120944) (xy 109.134656 -174.099982) (xy 109.140752 -174.09287)
			(xy 109.147102 -174.075852) (xy 109.147102 -173.99) (xy 109.140752 -173.972982) (xy 109.134656 -173.96587)
			(xy 109.11689 -173.94491) (xy 109.086967 -173.898827) (xy 109.063955 -173.848932) (xy 109.04833 -173.796255)
			(xy 109.040413 -173.741882) (xy 109.039914 -173.71441) (xy 109.0404 -173.687159) (xy 109.048156 -173.633211)
			(xy 109.063511 -173.580916) (xy 109.086153 -173.531339) (xy 109.115619 -173.485489) (xy 109.15131 -173.444298)
			(xy 109.192501 -173.408607) (xy 109.238351 -173.379141) (xy 109.287928 -173.356499) (xy 109.340223 -173.341144)
			(xy 109.394171 -173.333388) (xy 109.448673 -173.333388) (xy 109.502621 -173.341144) (xy 109.554916 -173.356499)
			(xy 109.604493 -173.379141) (xy 109.650343 -173.408607) (xy 109.691534 -173.444298) (xy 109.727225 -173.485489)
			(xy 109.756691 -173.531339) (xy 109.779333 -173.580916) (xy 109.784596 -173.59884) (xy 130.214624 -173.59884)
			(xy 130.215108 -173.57147) (xy 130.22292 -173.517292) (xy 130.238405 -173.464789) (xy 130.261243 -173.415041)
			(xy 130.290964 -173.369074) (xy 130.308604 -173.348142) (xy 130.3147 -173.34103) (xy 130.32105 -173.324012)
			(xy 130.32105 -173.238668) (xy 130.3147 -173.22165) (xy 130.308604 -173.214538) (xy 130.291003 -173.193573)
			(xy 130.261279 -173.14761) (xy 130.238432 -173.097869) (xy 130.222934 -173.045372) (xy 130.215102 -172.991199)
			(xy 130.215098 -172.936462) (xy 130.222921 -172.882287) (xy 130.238411 -172.829787) (xy 130.26125 -172.780043)
			(xy 130.290967 -172.734075) (xy 130.308604 -172.713142) (xy 130.3147 -172.70603) (xy 130.32105 -172.689012)
			(xy 130.32105 -172.603668) (xy 130.3147 -172.58665) (xy 130.308604 -172.579538) (xy 130.291003 -172.558573)
			(xy 130.261279 -172.51261) (xy 130.238432 -172.462869) (xy 130.222934 -172.410372) (xy 130.215102 -172.356199)
			(xy 130.215098 -172.301462) (xy 130.222921 -172.247287) (xy 130.238411 -172.194787) (xy 130.26125 -172.145043)
			(xy 130.290967 -172.099075) (xy 130.308604 -172.078142) (xy 130.3147 -172.07103) (xy 130.32105 -172.054012)
			(xy 130.32105 -171.968668) (xy 130.3147 -171.95165) (xy 130.308604 -171.944538) (xy 130.29097 -171.923602)
			(xy 130.261257 -171.87763) (xy 130.23842 -171.827884) (xy 130.222928 -171.775384) (xy 130.215099 -171.721209)
			(xy 130.214624 -171.69384) (xy 130.215109 -171.665965) (xy 130.22322 -171.610807) (xy 130.239275 -171.557418)
			(xy 130.262932 -171.506936) (xy 130.293686 -171.460435) (xy 130.311906 -171.439332) (xy 130.318002 -171.432474)
			(xy 130.32486 -171.415202) (xy 130.32486 -171.328588) (xy 130.318256 -171.311316) (xy 130.31216 -171.304204)
			(xy 130.294099 -171.283136) (xy 130.263576 -171.236796) (xy 130.240103 -171.186515) (xy 130.224177 -171.13336)
			(xy 130.216135 -171.078457) (xy 130.21564 -171.050712) (xy 130.216103 -171.023342) (xy 130.22392 -170.969162)
			(xy 130.23941 -170.916658) (xy 130.262252 -170.866912) (xy 130.291978 -170.820945) (xy 130.30962 -170.800014)
			(xy 130.315716 -170.792902) (xy 130.322066 -170.775884) (xy 130.322066 -170.69054) (xy 130.315716 -170.673522)
			(xy 130.30962 -170.66641) (xy 130.291991 -170.645468) (xy 130.262267 -170.599501) (xy 130.239421 -170.549757)
			(xy 130.223924 -170.497256) (xy 130.216095 -170.443079) (xy 130.216093 -170.388339) (xy 130.22392 -170.334162)
			(xy 130.239415 -170.28166) (xy 130.262258 -170.231915) (xy 130.29198 -170.185947) (xy 130.30962 -170.165014)
			(xy 130.315716 -170.157902) (xy 130.322066 -170.140884) (xy 130.322066 -170.05554) (xy 130.315716 -170.038522)
			(xy 130.30962 -170.03141) (xy 130.291991 -170.010468) (xy 130.262267 -169.964501) (xy 130.239421 -169.914757)
			(xy 130.223924 -169.862256) (xy 130.216095 -169.808079) (xy 130.216093 -169.753339) (xy 130.22392 -169.699162)
			(xy 130.239415 -169.64666) (xy 130.262258 -169.596915) (xy 130.29198 -169.550947) (xy 130.30962 -169.530014)
			(xy 130.315716 -169.522902) (xy 130.322066 -169.505884) (xy 130.322066 -169.42054) (xy 130.315716 -169.403522)
			(xy 130.30962 -169.39641) (xy 130.291975 -169.375482) (xy 130.262264 -169.329509) (xy 130.239428 -169.27976)
			(xy 130.223939 -169.227258) (xy 130.216113 -169.173082) (xy 130.21564 -169.145712) (xy 130.216121 -169.118413)
			(xy 130.223892 -169.064371) (xy 130.23929 -169.01199) (xy 130.262002 -168.96234) (xy 130.291562 -168.916437)
			(xy 130.309112 -168.895522) (xy 130.315462 -168.88841) (xy 130.321558 -168.871392) (xy 130.321558 -168.785794)
			(xy 130.315208 -168.76903) (xy 130.309112 -168.761918) (xy 130.291409 -168.740948) (xy 130.261528 -168.694919)
			(xy 130.238559 -168.645079) (xy 130.222977 -168.592461) (xy 130.215103 -168.538151) (xy 130.214624 -168.510712)
			(xy 130.215067 -168.483458) (xy 130.222823 -168.429505) (xy 130.238179 -168.377204) (xy 130.260822 -168.327622)
			(xy 130.290292 -168.281768) (xy 130.325988 -168.240574) (xy 130.367184 -168.20488) (xy 130.41304 -168.175413)
			(xy 130.462623 -168.152772) (xy 130.514924 -168.137418) (xy 130.568878 -168.129665) (xy 130.596132 -168.129204)
			(xy 130.623503 -168.12965) (xy 130.677683 -168.137473) (xy 130.730186 -168.152966) (xy 130.779933 -168.175813)
			(xy 130.825899 -168.205541) (xy 130.84683 -168.223184) (xy 130.853942 -168.22928) (xy 130.87096 -168.23563)
			(xy 130.956304 -168.23563) (xy 130.973322 -168.22928) (xy 130.980434 -168.223184) (xy 131.001378 -168.20556)
			(xy 131.047348 -168.175846) (xy 131.097092 -168.153008) (xy 131.14959 -168.137513) (xy 131.203764 -168.129681)
			(xy 131.231132 -168.129204) (xy 131.258385 -168.129648) (xy 131.312334 -168.137409) (xy 131.364631 -168.152769)
			(xy 131.414209 -168.175415) (xy 131.46006 -168.204886) (xy 131.50125 -168.240581) (xy 131.536941 -168.281776)
			(xy 131.566406 -168.32763) (xy 131.589046 -168.377211) (xy 131.6044 -168.429509) (xy 131.612155 -168.483459)
			(xy 131.61264 -168.510712) (xy 131.612153 -168.538011) (xy 131.604381 -168.592051) (xy 131.588983 -168.644432)
			(xy 131.566273 -168.694081) (xy 131.536716 -168.739986) (xy 131.519168 -168.760902) (xy 131.512818 -168.768014)
			(xy 131.506722 -168.785032) (xy 131.506722 -168.87063) (xy 131.513072 -168.887394) (xy 131.519168 -168.894506)
			(xy 131.53688 -168.915469) (xy 131.56676 -168.9615) (xy 131.589727 -169.011341) (xy 131.605308 -169.063962)
			(xy 131.613178 -169.118273) (xy 131.613656 -169.145712) (xy 131.613208 -169.173083) (xy 131.605387 -169.227263)
			(xy 131.589895 -169.279767) (xy 131.567049 -169.329514) (xy 131.53732 -169.375479) (xy 131.519676 -169.39641)
			(xy 131.51358 -169.403522) (xy 131.50723 -169.42054) (xy 131.50723 -169.505884) (xy 131.51358 -169.522902)
			(xy 131.519676 -169.530014) (xy 131.537328 -169.550937) (xy 131.567052 -169.596907) (xy 131.589897 -169.646655)
			(xy 131.605392 -169.699158) (xy 131.61322 -169.753338) (xy 131.613218 -169.80808) (xy 131.605388 -169.86226)
			(xy 131.589891 -169.914762) (xy 131.567044 -169.964509) (xy 131.537317 -170.010477) (xy 131.519676 -170.03141)
			(xy 131.51358 -170.038522) (xy 131.50723 -170.05554) (xy 131.50723 -170.140884) (xy 131.51358 -170.157902)
			(xy 131.519676 -170.165014) (xy 131.537328 -170.185937) (xy 131.567052 -170.231907) (xy 131.589897 -170.281655)
			(xy 131.605392 -170.334158) (xy 131.61322 -170.388338) (xy 131.613218 -170.44308) (xy 131.605388 -170.49726)
			(xy 131.589891 -170.549762) (xy 131.567044 -170.599509) (xy 131.537317 -170.645477) (xy 131.519676 -170.66641)
			(xy 131.51358 -170.673522) (xy 131.50723 -170.69054) (xy 131.50723 -170.775884) (xy 131.51358 -170.792902)
			(xy 131.519676 -170.800014) (xy 131.537285 -170.820971) (xy 131.567002 -170.866936) (xy 131.589844 -170.916678)
			(xy 131.605342 -170.969173) (xy 131.613178 -171.023344) (xy 131.613656 -171.050712) (xy 131.613122 -171.078585)
			(xy 131.60502 -171.13374) (xy 131.588975 -171.187128) (xy 131.56533 -171.237611) (xy 131.534587 -171.284114)
			(xy 131.516374 -171.30522) (xy 131.510278 -171.312078) (xy 131.50342 -171.32935) (xy 131.50342 -171.415964)
			(xy 131.510024 -171.433236) (xy 131.51612 -171.440348) (xy 131.534202 -171.461398) (xy 131.564723 -171.507743)
			(xy 131.588192 -171.558028) (xy 131.604113 -171.611187) (xy 131.612148 -171.666094) (xy 131.61264 -171.69384)
			(xy 131.612153 -171.72121) (xy 131.604343 -171.775388) (xy 131.588859 -171.827892) (xy 131.566022 -171.877639)
			(xy 131.5363 -171.923606) (xy 131.51866 -171.944538) (xy 131.512564 -171.95165) (xy 131.506214 -171.968668)
			(xy 131.506214 -172.054012) (xy 131.512564 -172.07103) (xy 131.51866 -172.078142) (xy 131.53634 -172.099043)
			(xy 131.566065 -172.145016) (xy 131.588908 -172.194767) (xy 131.604402 -172.247274) (xy 131.612227 -172.301457)
			(xy 131.612225 -172.32884) (xy 133.592824 -172.32884) (xy 133.593308 -172.30147) (xy 133.60112 -172.247292)
			(xy 133.616605 -172.194789) (xy 133.639443 -172.145041) (xy 133.669164 -172.099074) (xy 133.686804 -172.078142)
			(xy 133.6929 -172.07103) (xy 133.69925 -172.054012) (xy 133.69925 -171.968668) (xy 133.6929 -171.95165)
			(xy 133.686804 -171.944538) (xy 133.66917 -171.923602) (xy 133.639457 -171.87763) (xy 133.61662 -171.827884)
			(xy 133.601128 -171.775384) (xy 133.593299 -171.721209) (xy 133.592824 -171.69384) (xy 133.593309 -171.665965)
			(xy 133.60142 -171.610807) (xy 133.617475 -171.557418) (xy 133.641132 -171.506936) (xy 133.671886 -171.460435)
			(xy 133.690106 -171.439332) (xy 133.696202 -171.432474) (xy 133.70306 -171.415202) (xy 133.70306 -171.328588)
			(xy 133.696456 -171.311316) (xy 133.69036 -171.304204) (xy 133.672299 -171.283136) (xy 133.641776 -171.236796)
			(xy 133.618303 -171.186515) (xy 133.602377 -171.13336) (xy 133.594335 -171.078457) (xy 133.59384 -171.050712)
			(xy 133.594303 -171.023342) (xy 133.60212 -170.969162) (xy 133.61761 -170.916658) (xy 133.640452 -170.866912)
			(xy 133.670178 -170.820945) (xy 133.68782 -170.800014) (xy 133.693916 -170.792902) (xy 133.700266 -170.775884)
			(xy 133.700266 -170.69054) (xy 133.693916 -170.673522) (xy 133.68782 -170.66641) (xy 133.670191 -170.645468)
			(xy 133.640467 -170.599501) (xy 133.617621 -170.549757) (xy 133.602124 -170.497256) (xy 133.594295 -170.443079)
			(xy 133.594293 -170.388339) (xy 133.60212 -170.334162) (xy 133.617615 -170.28166) (xy 133.640458 -170.231915)
			(xy 133.67018 -170.185947) (xy 133.68782 -170.165014) (xy 133.693916 -170.157902) (xy 133.700266 -170.140884)
			(xy 133.700266 -170.05554) (xy 133.693916 -170.038522) (xy 133.68782 -170.03141) (xy 133.670191 -170.010468)
			(xy 133.640467 -169.964501) (xy 133.617621 -169.914757) (xy 133.602124 -169.862256) (xy 133.594295 -169.808079)
			(xy 133.594293 -169.753339) (xy 133.60212 -169.699162) (xy 133.617615 -169.64666) (xy 133.640458 -169.596915)
			(xy 133.67018 -169.550947) (xy 133.68782 -169.530014) (xy 133.693916 -169.522902) (xy 133.700266 -169.505884)
			(xy 133.700266 -169.42054) (xy 133.693916 -169.403522) (xy 133.68782 -169.39641) (xy 133.670175 -169.375482)
			(xy 133.640464 -169.329509) (xy 133.617628 -169.27976) (xy 133.602139 -169.227258) (xy 133.594313 -169.173082)
			(xy 133.59384 -169.145712) (xy 133.594321 -169.118413) (xy 133.602092 -169.064371) (xy 133.61749 -169.01199)
			(xy 133.640202 -168.96234) (xy 133.669762 -168.916437) (xy 133.687312 -168.895522) (xy 133.693662 -168.88841)
			(xy 133.699758 -168.871392) (xy 133.699758 -168.785794) (xy 133.693408 -168.76903) (xy 133.687312 -168.761918)
			(xy 133.669609 -168.740948) (xy 133.639728 -168.694919) (xy 133.616759 -168.645079) (xy 133.601177 -168.592461)
			(xy 133.593303 -168.538151) (xy 133.592824 -168.510712) (xy 133.593267 -168.483458) (xy 133.601023 -168.429505)
			(xy 133.616379 -168.377204) (xy 133.639022 -168.327622) (xy 133.668492 -168.281768) (xy 133.704188 -168.240574)
			(xy 133.745384 -168.20488) (xy 133.79124 -168.175413) (xy 133.840823 -168.152772) (xy 133.893124 -168.137418)
			(xy 133.947078 -168.129665) (xy 133.974332 -168.129204) (xy 134.001703 -168.12965) (xy 134.055883 -168.137473)
			(xy 134.108386 -168.152966) (xy 134.158133 -168.175813) (xy 134.204099 -168.205541) (xy 134.22503 -168.223184)
			(xy 134.232142 -168.22928) (xy 134.24916 -168.23563) (xy 134.334504 -168.23563) (xy 134.351522 -168.22928)
			(xy 134.358634 -168.223184) (xy 134.379578 -168.20556) (xy 134.425548 -168.175846) (xy 134.475292 -168.153008)
			(xy 134.52779 -168.137513) (xy 134.581964 -168.129681) (xy 134.609332 -168.129204) (xy 134.637242 -168.129699)
			(xy 134.692467 -168.137836) (xy 134.745917 -168.153933) (xy 134.796452 -168.177644) (xy 134.842993 -168.208465)
			(xy 134.864094 -168.22674) (xy 134.871206 -168.23309) (xy 134.88797 -168.239694) (xy 134.973822 -168.24071)
			(xy 134.990586 -168.234614) (xy 134.997952 -168.228518) (xy 135.018731 -168.211373) (xy 135.064232 -168.182532)
			(xy 135.11334 -168.160384) (xy 135.165077 -168.145372) (xy 135.218412 -168.137793) (xy 135.245348 -168.137332)
			(xy 135.272718 -168.137821) (xy 135.326896 -168.145632) (xy 135.379399 -168.161115) (xy 135.429146 -168.183952)
			(xy 135.475114 -168.213673) (xy 135.496046 -168.231312) (xy 135.503158 -168.237408) (xy 135.520176 -168.243758)
			(xy 135.60552 -168.243758) (xy 135.622538 -168.237408) (xy 135.62965 -168.231312) (xy 135.650592 -168.213685)
			(xy 135.696562 -168.183971) (xy 135.746307 -168.161132) (xy 135.798805 -168.145639) (xy 135.852979 -168.137807)
			(xy 135.880348 -168.137332) (xy 135.907602 -168.137733) (xy 135.961555 -168.145497) (xy 136.013854 -168.160861)
			(xy 136.063434 -168.18351) (xy 136.109286 -168.212985) (xy 136.150477 -168.248686) (xy 136.186168 -168.289885)
			(xy 136.215632 -168.335743) (xy 136.23827 -168.385329) (xy 136.253621 -168.437631) (xy 136.261373 -168.491586)
			(xy 136.261856 -168.51884) (xy 136.261365 -168.546209) (xy 136.253555 -168.600388) (xy 136.238072 -168.652891)
			(xy 136.215236 -168.702639) (xy 136.185515 -168.748606) (xy 136.167876 -168.769538) (xy 136.16178 -168.77665)
			(xy 136.15543 -168.793668) (xy 136.15543 -168.879012) (xy 136.16178 -168.89603) (xy 136.167876 -168.903142)
			(xy 136.185556 -168.924043) (xy 136.215279 -168.970016) (xy 136.238122 -169.019768) (xy 136.253615 -169.072275)
			(xy 136.261439 -169.126458) (xy 136.261435 -169.181203) (xy 136.253602 -169.235384) (xy 136.2381 -169.287889)
			(xy 136.21525 -169.337636) (xy 136.185519 -169.383605) (xy 136.167876 -169.404538) (xy 136.16178 -169.41165)
			(xy 136.15543 -169.428668) (xy 136.15543 -169.514012) (xy 136.16178 -169.53103) (xy 136.167876 -169.538142)
			(xy 136.185556 -169.559043) (xy 136.215279 -169.605016) (xy 136.238122 -169.654768) (xy 136.253615 -169.707275)
			(xy 136.261439 -169.761458) (xy 136.261435 -169.816203) (xy 136.253602 -169.870384) (xy 136.2381 -169.922889)
			(xy 136.21525 -169.972636) (xy 136.185519 -170.018605) (xy 136.167876 -170.039538) (xy 136.16178 -170.04665)
			(xy 136.15543 -170.063668) (xy 136.15543 -170.149012) (xy 136.16178 -170.16603) (xy 136.167876 -170.173142)
			(xy 136.185556 -170.194043) (xy 136.215279 -170.240016) (xy 136.238122 -170.289768) (xy 136.253615 -170.342275)
			(xy 136.261439 -170.396458) (xy 136.261435 -170.451203) (xy 136.253602 -170.505384) (xy 136.2381 -170.557889)
			(xy 136.21525 -170.607636) (xy 136.185519 -170.653605) (xy 136.167876 -170.674538) (xy 136.16178 -170.68165)
			(xy 136.15543 -170.698668) (xy 136.15543 -170.784012) (xy 136.16178 -170.80103) (xy 136.167876 -170.808142)
			(xy 136.185556 -170.829043) (xy 136.215279 -170.875016) (xy 136.238122 -170.924768) (xy 136.253615 -170.977275)
			(xy 136.261439 -171.031458) (xy 136.261435 -171.086203) (xy 136.253602 -171.140384) (xy 136.2381 -171.192889)
			(xy 136.21525 -171.242636) (xy 136.185519 -171.288605) (xy 136.167876 -171.309538) (xy 136.16178 -171.31665)
			(xy 136.15543 -171.333668) (xy 136.15543 -171.419012) (xy 136.16178 -171.43603) (xy 136.167876 -171.443142)
			(xy 136.185498 -171.464088) (xy 136.215213 -171.510057) (xy 136.238053 -171.559801) (xy 136.253548 -171.612298)
			(xy 136.26138 -171.666472) (xy 136.261856 -171.69384) (xy 136.26136 -171.72109) (xy 136.253599 -171.775035)
			(xy 136.238241 -171.827326) (xy 136.215599 -171.876901) (xy 136.186133 -171.922749) (xy 136.150443 -171.963937)
			(xy 136.109255 -171.999628) (xy 136.063408 -172.029095) (xy 136.013834 -172.051738) (xy 135.961543 -172.067097)
			(xy 135.907598 -172.074859) (xy 135.880348 -172.075348) (xy 135.852978 -172.074866) (xy 135.798799 -172.067054)
			(xy 135.746296 -172.05157) (xy 135.696549 -172.028731) (xy 135.650582 -171.999009) (xy 135.62965 -171.981368)
			(xy 135.622538 -171.975272) (xy 135.60552 -171.968922) (xy 135.520176 -171.968922) (xy 135.503158 -171.975272)
			(xy 135.496046 -171.981368) (xy 135.475103 -171.998994) (xy 135.429134 -172.028709) (xy 135.379389 -172.051548)
			(xy 135.326891 -172.067042) (xy 135.272717 -172.074873) (xy 135.245348 -172.075348) (xy 135.215799 -172.074812)
			(xy 135.157408 -172.065693) (xy 135.101122 -172.047679) (xy 135.048286 -172.021203) (xy 135.000164 -171.986897)
			(xy 134.978648 -171.966636) (xy 134.971299 -171.96012) (xy 134.953149 -171.952666) (xy 134.943342 -171.952158)
			(xy 134.890002 -171.952158) (xy 134.882636 -171.960032) (xy 134.876086 -171.967354) (xy 134.868652 -171.985524)
			(xy 134.868158 -171.995338) (xy 134.868158 -172.027342) (xy 134.868643 -172.037156) (xy 134.87609 -172.05532)
			(xy 134.882636 -172.062648) (xy 134.90283 -172.084129) (xy 134.936972 -172.132193) (xy 134.963315 -172.184937)
			(xy 134.981232 -172.241106) (xy 134.990294 -172.299362) (xy 134.99084 -172.32884) (xy 134.990359 -172.356091)
			(xy 134.982598 -172.410037) (xy 134.96724 -172.46233) (xy 134.944596 -172.511905) (xy 134.915129 -172.557754)
			(xy 134.879437 -172.598943) (xy 134.838247 -172.634634) (xy 134.792398 -172.6641) (xy 134.742822 -172.686743)
			(xy 134.690529 -172.7021) (xy 134.636583 -172.70986) (xy 134.609332 -172.710348) (xy 134.581962 -172.709876)
			(xy 134.527783 -172.702061) (xy 134.475279 -172.686574) (xy 134.425532 -172.663734) (xy 134.379565 -172.634009)
			(xy 134.358634 -172.616368) (xy 134.351522 -172.610272) (xy 134.334504 -172.603922) (xy 134.24916 -172.603922)
			(xy 134.232142 -172.610272) (xy 134.22503 -172.616368) (xy 134.204093 -172.634002) (xy 134.158122 -172.663715)
			(xy 134.108376 -172.686553) (xy 134.055876 -172.702045) (xy 134.001701 -172.709874) (xy 133.974332 -172.710348)
			(xy 133.947083 -172.709792) (xy 133.89314 -172.702041) (xy 133.840849 -172.686692) (xy 133.791275 -172.664057)
			(xy 133.745426 -172.634598) (xy 133.704237 -172.598914) (xy 133.668545 -172.557731) (xy 133.639077 -172.511888)
			(xy 133.616433 -172.462318) (xy 133.601074 -172.41003) (xy 133.593313 -172.356089) (xy 133.592824 -172.32884)
			(xy 131.612225 -172.32884) (xy 131.612223 -172.356203) (xy 131.604389 -172.410385) (xy 131.588887 -172.462889)
			(xy 131.566036 -172.512637) (xy 131.536304 -172.558605) (xy 131.51866 -172.579538) (xy 131.512564 -172.58665)
			(xy 131.506214 -172.603668) (xy 131.506214 -172.689012) (xy 131.512564 -172.70603) (xy 131.51866 -172.713142)
			(xy 131.53634 -172.734043) (xy 131.566065 -172.780016) (xy 131.588908 -172.829767) (xy 131.604402 -172.882274)
			(xy 131.612227 -172.936457) (xy 131.612223 -172.991203) (xy 131.604389 -173.045385) (xy 131.588887 -173.097889)
			(xy 131.566036 -173.147637) (xy 131.536304 -173.193605) (xy 131.51866 -173.214538) (xy 131.512564 -173.22165)
			(xy 131.506214 -173.238668) (xy 131.506214 -173.324012) (xy 131.512564 -173.34103) (xy 131.51866 -173.348142)
			(xy 131.536279 -173.36909) (xy 131.565995 -173.415058) (xy 131.588836 -173.464801) (xy 131.604331 -173.517299)
			(xy 131.612164 -173.571472) (xy 131.61264 -173.59884) (xy 131.612159 -173.626091) (xy 131.604398 -173.680037)
			(xy 131.58904 -173.73233) (xy 131.566396 -173.781905) (xy 131.536929 -173.827754) (xy 131.501237 -173.868943)
			(xy 131.460047 -173.904634) (xy 131.414198 -173.9341) (xy 131.364622 -173.956743) (xy 131.312329 -173.9721)
			(xy 131.258383 -173.97986) (xy 131.231132 -173.980348) (xy 131.203762 -173.979876) (xy 131.149583 -173.972061)
			(xy 131.097079 -173.956574) (xy 131.047332 -173.933734) (xy 131.001365 -173.904009) (xy 130.980434 -173.886368)
			(xy 130.973322 -173.880272) (xy 130.956304 -173.873922) (xy 130.87096 -173.873922) (xy 130.853942 -173.880272)
			(xy 130.84683 -173.886368) (xy 130.825893 -173.904002) (xy 130.779922 -173.933715) (xy 130.730176 -173.956553)
			(xy 130.677676 -173.972045) (xy 130.623501 -173.979874) (xy 130.596132 -173.980348) (xy 130.568883 -173.979792)
			(xy 130.51494 -173.972041) (xy 130.462649 -173.956692) (xy 130.413075 -173.934057) (xy 130.367226 -173.904598)
			(xy 130.326037 -173.868914) (xy 130.290345 -173.827731) (xy 130.260877 -173.781888) (xy 130.238233 -173.732318)
			(xy 130.222874 -173.68003) (xy 130.215113 -173.626089) (xy 130.214624 -173.59884) (xy 109.784596 -173.59884)
			(xy 109.794688 -173.633211) (xy 109.802444 -173.687159) (xy 109.80293 -173.71441) (xy 109.802442 -173.741884)
			(xy 109.79455 -173.796264) (xy 109.778929 -173.848946) (xy 109.755905 -173.898839) (xy 109.725955 -173.944908)
			(xy 109.708188 -173.96587) (xy 109.702092 -173.972982) (xy 109.695742 -173.99) (xy 109.695742 -174.075852)
			(xy 109.702092 -174.09287) (xy 109.708188 -174.099982) (xy 109.725923 -174.120968) (xy 109.755852 -174.167043)
			(xy 109.778871 -174.216931) (xy 109.794504 -174.269603) (xy 109.802427 -174.323971) (xy 109.80293 -174.351442)
			(xy 109.802444 -174.378693) (xy 109.800811 -174.39005) (xy 110.37773 -174.39005) (xy 110.381801 -174.334428)
			(xy 110.393927 -174.279991) (xy 110.41385 -174.2279) (xy 110.441146 -174.179265) (xy 110.475232 -174.135122)
			(xy 110.515381 -174.096413) (xy 110.560739 -174.063962) (xy 110.610339 -174.038461) (xy 110.663123 -174.020454)
			(xy 110.717966 -174.010324) (xy 110.7737 -174.008287) (xy 110.829137 -174.014387) (xy 110.883094 -174.028493)
			(xy 110.934423 -174.050305) (xy 110.982029 -174.079359) (xy 111.024897 -174.115034) (xy 111.062114 -174.156571)
			(xy 111.092887 -174.203084) (xy 111.116559 -174.253581) (xy 111.132627 -174.306988) (xy 111.140747 -174.362164)
			(xy 111.141256 -174.39005) (xy 111.140747 -174.417936) (xy 111.132627 -174.473112) (xy 111.116559 -174.526519)
			(xy 111.092887 -174.577016) (xy 111.062114 -174.623529) (xy 111.024897 -174.665066) (xy 110.982029 -174.700741)
			(xy 110.934423 -174.729795) (xy 110.883094 -174.751607) (xy 110.829137 -174.765713) (xy 110.7737 -174.771813)
			(xy 110.717966 -174.769776) (xy 110.663123 -174.759646) (xy 110.610339 -174.741639) (xy 110.560739 -174.716138)
			(xy 110.515381 -174.683687) (xy 110.475232 -174.644978) (xy 110.441146 -174.600835) (xy 110.41385 -174.5522)
			(xy 110.393927 -174.500109) (xy 110.381801 -174.445672) (xy 110.37773 -174.39005) (xy 109.800811 -174.39005)
			(xy 109.794688 -174.432641) (xy 109.779333 -174.484936) (xy 109.756691 -174.534513) (xy 109.727225 -174.580363)
			(xy 109.691534 -174.621554) (xy 109.650343 -174.657245) (xy 109.604493 -174.686711) (xy 109.554916 -174.709353)
			(xy 109.502621 -174.724708) (xy 109.448673 -174.732464) (xy 109.394171 -174.732464) (xy 109.340223 -174.724708)
			(xy 109.287928 -174.709353) (xy 109.238351 -174.686711) (xy 109.192501 -174.657245) (xy 109.15131 -174.621554)
			(xy 109.115619 -174.580363) (xy 109.086153 -174.534513) (xy 109.063511 -174.484936) (xy 109.048156 -174.432641)
			(xy 109.0404 -174.378693) (xy 109.039914 -174.351442) (xy 108.781028 -174.351442) (xy 108.775022 -174.371897)
			(xy 108.752381 -174.421475) (xy 108.722914 -174.467327) (xy 108.687222 -174.508518) (xy 108.646031 -174.544211)
			(xy 108.60018 -174.573678) (xy 108.550602 -174.59632) (xy 108.498307 -174.611676) (xy 108.444358 -174.619434)
			(xy 108.417106 -174.61992) (xy 108.391871 -174.619518) (xy 108.341837 -174.612901) (xy 108.293117 -174.599729)
			(xy 108.246565 -174.580234) (xy 108.224574 -174.56785) (xy 108.214922 -174.562008) (xy 108.192824 -174.559976)
			(xy 108.098336 -174.593504) (xy 108.082334 -174.608998) (xy 108.07827 -174.619412) (xy 108.067539 -174.646173)
			(xy 108.039255 -174.696413) (xy 108.00373 -174.741822) (xy 107.961773 -174.781365) (xy 107.914341 -174.81414)
			(xy 107.862515 -174.839401) (xy 107.807477 -174.856571) (xy 107.750481 -174.865259) (xy 107.721654 -174.865792)
			(xy 107.694401 -174.865365) (xy 107.64045 -174.857602) (xy 107.588153 -174.84224) (xy 107.538575 -174.819592)
			(xy 107.492724 -174.79012) (xy 107.451534 -174.754422) (xy 107.415843 -174.713226) (xy 107.386378 -174.667371)
			(xy 107.363738 -174.617788) (xy 107.348385 -174.565489) (xy 107.340631 -174.511537) (xy 107.340146 -174.484284)
			(xy 107.340809 -174.452721) (xy 107.351194 -174.390456) (xy 107.371679 -174.330747) (xy 107.38612 -174.302674)
			(xy 107.390946 -174.293784) (xy 107.392978 -174.274226) (xy 107.367324 -174.186088) (xy 107.354878 -174.170594)
			(xy 107.345988 -174.165514) (xy 107.320862 -174.151006) (xy 107.27498 -174.115496) (xy 107.235007 -174.073445)
			(xy 107.201865 -174.025824) (xy 107.176318 -173.973733) (xy 107.158957 -173.918372) (xy 107.150182 -173.861021)
			(xy 107.149646 -173.832012) (xy 106.441748 -173.832012) (xy 106.441748 -174.846488) (xy 106.442085 -174.856537)
			(xy 106.449696 -174.875133) (xy 106.45648 -174.882556) (xy 106.859324 -175.2854) (xy 109.79861 -175.2854)
			(xy 109.802681 -175.229778) (xy 109.814807 -175.175341) (xy 109.83473 -175.12325) (xy 109.862026 -175.074615)
			(xy 109.896112 -175.030472) (xy 109.936261 -174.991763) (xy 109.981619 -174.959312) (xy 110.031219 -174.933811)
			(xy 110.084003 -174.915804) (xy 110.138846 -174.905674) (xy 110.19458 -174.903637) (xy 110.250017 -174.909737)
			(xy 110.303974 -174.923843) (xy 110.355303 -174.945655) (xy 110.402909 -174.974709) (xy 110.445777 -175.010384)
			(xy 110.482994 -175.051921) (xy 110.513767 -175.098434) (xy 110.537439 -175.148931) (xy 110.553507 -175.202338)
			(xy 110.561627 -175.257514) (xy 110.562136 -175.2854) (xy 110.561627 -175.313286) (xy 110.553507 -175.368462)
			(xy 110.537439 -175.421869) (xy 110.513767 -175.472366) (xy 110.482994 -175.518879) (xy 110.445777 -175.560416)
			(xy 110.402909 -175.596091) (xy 110.355303 -175.625145) (xy 110.303974 -175.646957) (xy 110.250017 -175.661063)
			(xy 110.19458 -175.667163) (xy 110.138846 -175.665126) (xy 110.084003 -175.654996) (xy 110.031219 -175.636989)
			(xy 109.981619 -175.611488) (xy 109.936261 -175.579037) (xy 109.896112 -175.540328) (xy 109.862026 -175.496185)
			(xy 109.83473 -175.44755) (xy 109.814807 -175.395459) (xy 109.802681 -175.341022) (xy 109.79861 -175.2854)
			(xy 106.859324 -175.2854) (xy 107.314238 -175.740314) (xy 107.320989 -175.747696) (xy 107.328692 -175.766138)
			(xy 107.329224 -175.776128) (xy 107.329224 -177.16246) (xy 110.757462 -177.16246) (xy 110.757938 -177.134549)
			(xy 110.766077 -177.079322) (xy 110.782177 -177.025872) (xy 110.805894 -176.975337) (xy 110.83672 -176.928798)
			(xy 110.854998 -176.907698) (xy 110.861348 -176.900586) (xy 110.867952 -176.883314) (xy 110.867952 -176.796192)
			(xy 110.861348 -176.77892) (xy 110.854998 -176.771808) (xy 110.836702 -176.750723) (xy 110.805877 -176.704181)
			(xy 110.782165 -176.653642) (xy 110.766073 -176.600188) (xy 110.757944 -176.544958) (xy 110.757462 -176.517046)
			(xy 110.757948 -176.489795) (xy 110.765704 -176.435847) (xy 110.781059 -176.383552) (xy 110.803701 -176.333975)
			(xy 110.833167 -176.288125) (xy 110.868858 -176.246934) (xy 110.910049 -176.211243) (xy 110.955899 -176.181777)
			(xy 111.005476 -176.159135) (xy 111.057771 -176.14378) (xy 111.111719 -176.136024) (xy 111.166221 -176.136024)
			(xy 111.220169 -176.14378) (xy 111.272464 -176.159135) (xy 111.322041 -176.181777) (xy 111.367891 -176.211243)
			(xy 111.409082 -176.246934) (xy 111.444773 -176.288125) (xy 111.474239 -176.333975) (xy 111.496881 -176.383552)
			(xy 111.512236 -176.435847) (xy 111.519992 -176.489795) (xy 111.520478 -176.517046) (xy 111.519996 -176.544957)
			(xy 111.511856 -176.600183) (xy 111.495757 -176.653633) (xy 111.472043 -176.704167) (xy 111.441218 -176.750707)
			(xy 111.422942 -176.771808) (xy 111.416592 -176.77892) (xy 111.409988 -176.796192) (xy 111.409988 -176.883314)
			(xy 111.416592 -176.900586) (xy 111.422942 -176.907698) (xy 111.4412 -176.928814) (xy 111.472029 -176.975349)
			(xy 111.495747 -177.025879) (xy 111.511849 -177.079327) (xy 111.519989 -177.13455) (xy 111.520478 -177.16246)
			(xy 111.519992 -177.189711) (xy 111.512236 -177.243659) (xy 111.496881 -177.295954) (xy 111.474239 -177.345531)
			(xy 111.444773 -177.391381) (xy 111.409082 -177.432572) (xy 111.367891 -177.468263) (xy 111.322041 -177.497729)
			(xy 111.272464 -177.520371) (xy 111.220169 -177.535726) (xy 111.166221 -177.543482) (xy 111.111719 -177.543482)
			(xy 111.057771 -177.535726) (xy 111.005476 -177.520371) (xy 110.955899 -177.497729) (xy 110.910049 -177.468263)
			(xy 110.868858 -177.432572) (xy 110.833167 -177.391381) (xy 110.803701 -177.345531) (xy 110.781059 -177.295954)
			(xy 110.765704 -177.243659) (xy 110.757948 -177.189711) (xy 110.757462 -177.16246) (xy 107.329224 -177.16246)
			(xy 107.329224 -177.841402) (xy 107.328809 -177.865389) (xy 107.321299 -177.912773) (xy 107.306466 -177.958397)
			(xy 107.284673 -178.001137) (xy 107.25646 -178.039938) (xy 107.222521 -178.073846) (xy 107.183692 -178.102023)
			(xy 107.140932 -178.123775) (xy 107.095294 -178.138566) (xy 107.047904 -178.146031) (xy 107.023916 -178.146456)
			(xy 105.459022 -178.146456) (xy 105.452128 -178.146668) (xy 105.438856 -178.150411) (xy 105.43286 -178.153822)
			(xy 105.408968 -178.167449) (xy 105.357494 -178.186816) (xy 105.303386 -178.196666) (xy 105.275888 -178.197256)
			(xy 103.616506 -178.197256) (xy 103.592508 -178.196855) (xy 103.545098 -178.189375) (xy 103.499448 -178.174552)
			(xy 103.456688 -178.152753) (xy 103.417876 -178.124517) (xy 103.400606 -178.107848) (xy 103.398828 -178.10607)
			(xy 103.382227 -178.088745) (xy 103.354036 -178.049922) (xy 103.332257 -178.007172) (xy 103.317424 -177.961544)
			(xy 103.309902 -177.914159) (xy 103.30942 -177.89017) (xy 103.30942 -177.474372) (xy 103.309031 -177.464298)
			(xy 103.301287 -177.445699) (xy 103.294434 -177.438304) (xy 103.254048 -177.397918) (xy 102.804468 -176.948592)
			(xy 102.520496 -176.66462) (xy 102.513011 -176.657932) (xy 102.494454 -176.65034) (xy 102.484428 -176.649888)
			(xy 101.84892 -176.649888) (xy 101.83887 -176.650218) (xy 101.820273 -176.657832) (xy 101.812852 -176.66462)
			(xy 101.478842 -176.99863) (xy 101.47144 -177.005355) (xy 101.453013 -177.013074) (xy 101.443028 -177.013616)
			(xy 98.291904 -177.013616) (xy 98.281861 -177.014009) (xy 98.263265 -177.021582) (xy 98.255836 -177.028348)
			(xy 98.06178 -177.222404) (xy 98.0551 -177.229896) (xy 98.047501 -177.248447) (xy 98.047048 -177.258472)
			(xy 98.047048 -178.353212) (xy 98.767646 -178.353212) (xy 98.768132 -178.325961) (xy 98.775888 -178.272013)
			(xy 98.791243 -178.219718) (xy 98.813885 -178.170141) (xy 98.843351 -178.124291) (xy 98.879042 -178.0831)
			(xy 98.920233 -178.047409) (xy 98.966083 -178.017943) (xy 99.01566 -177.995301) (xy 99.067955 -177.979946)
			(xy 99.121903 -177.97219) (xy 99.176405 -177.97219) (xy 99.230353 -177.979946) (xy 99.282648 -177.995301)
			(xy 99.332225 -178.017943) (xy 99.378075 -178.047409) (xy 99.419266 -178.0831) (xy 99.454957 -178.124291)
			(xy 99.484423 -178.170141) (xy 99.507065 -178.219718) (xy 99.52242 -178.272013) (xy 99.530176 -178.325961)
			(xy 99.530662 -178.353212) (xy 99.529996 -178.384775) (xy 99.519612 -178.44704) (xy 99.499129 -178.506749)
			(xy 99.484688 -178.534822) (xy 99.479862 -178.543712) (xy 99.47783 -178.56327) (xy 99.503484 -178.651408)
			(xy 99.51593 -178.666902) (xy 99.52482 -178.671982) (xy 99.532186 -178.676046) (xy 99.541838 -178.681888)
			(xy 99.563936 -178.68392) (xy 99.658424 -178.650392) (xy 99.674426 -178.634898) (xy 99.67849 -178.624484)
			(xy 99.689169 -178.5977) (xy 99.717459 -178.547458) (xy 99.752992 -178.502049) (xy 99.794956 -178.462507)
			(xy 99.842396 -178.429734) (xy 99.894229 -178.404477) (xy 99.949274 -178.387313) (xy 100.006276 -178.378632)
			(xy 100.035106 -178.378104) (xy 100.062358 -178.378566) (xy 100.116307 -178.386324) (xy 100.168602 -178.40168)
			(xy 100.21818 -178.424322) (xy 100.264031 -178.453789) (xy 100.305222 -178.489482) (xy 100.340914 -178.530673)
			(xy 100.370381 -178.576525) (xy 100.393022 -178.626103) (xy 100.408378 -178.678399) (xy 100.416134 -178.732348)
			(xy 100.416134 -178.786852) (xy 100.408378 -178.840801) (xy 100.399028 -178.872642) (xy 100.657914 -178.872642)
			(xy 100.658422 -178.845168) (xy 100.666308 -178.790789) (xy 100.681923 -178.738107) (xy 100.704943 -178.688214)
			(xy 100.73489 -178.642144) (xy 100.752656 -178.621182) (xy 100.758752 -178.61407) (xy 100.765102 -178.597052)
			(xy 100.765102 -178.5112) (xy 100.758752 -178.494182) (xy 100.752656 -178.48707) (xy 100.73489 -178.46611)
			(xy 100.704967 -178.420027) (xy 100.681955 -178.370132) (xy 100.66633 -178.317455) (xy 100.658413 -178.263082)
			(xy 100.657914 -178.23561) (xy 100.6584 -178.208359) (xy 100.666156 -178.154411) (xy 100.681511 -178.102116)
			(xy 100.704153 -178.052539) (xy 100.733619 -178.006689) (xy 100.76931 -177.965498) (xy 100.810501 -177.929807)
			(xy 100.856351 -177.900341) (xy 100.905928 -177.877699) (xy 100.958223 -177.862344) (xy 101.012171 -177.854588)
			(xy 101.066673 -177.854588) (xy 101.120621 -177.862344) (xy 101.172916 -177.877699) (xy 101.222493 -177.900341)
			(xy 101.268343 -177.929807) (xy 101.309534 -177.965498) (xy 101.345225 -178.006689) (xy 101.374691 -178.052539)
			(xy 101.397333 -178.102116) (xy 101.412688 -178.154411) (xy 101.420444 -178.208359) (xy 101.42093 -178.23561)
			(xy 101.420442 -178.263084) (xy 101.41255 -178.317464) (xy 101.396929 -178.370146) (xy 101.373905 -178.420039)
			(xy 101.343955 -178.466108) (xy 101.326188 -178.48707) (xy 101.320092 -178.494182) (xy 101.313742 -178.5112)
			(xy 101.313742 -178.597052) (xy 101.320092 -178.61407) (xy 101.326188 -178.621182) (xy 101.343923 -178.642168)
			(xy 101.373852 -178.688243) (xy 101.396871 -178.738131) (xy 101.412504 -178.790803) (xy 101.420427 -178.845171)
			(xy 101.42093 -178.872642) (xy 101.420444 -178.899893) (xy 101.418811 -178.91125) (xy 101.99573 -178.91125)
			(xy 101.999801 -178.855628) (xy 102.011927 -178.801191) (xy 102.03185 -178.7491) (xy 102.059146 -178.700465)
			(xy 102.093232 -178.656322) (xy 102.133381 -178.617613) (xy 102.178739 -178.585162) (xy 102.228339 -178.559661)
			(xy 102.281123 -178.541654) (xy 102.335966 -178.531524) (xy 102.3917 -178.529487) (xy 102.447137 -178.535587)
			(xy 102.501094 -178.549693) (xy 102.552423 -178.571505) (xy 102.600029 -178.600559) (xy 102.642897 -178.636234)
			(xy 102.680114 -178.677771) (xy 102.710887 -178.724284) (xy 102.734559 -178.774781) (xy 102.750627 -178.828188)
			(xy 102.758747 -178.883364) (xy 102.759256 -178.91125) (xy 102.758747 -178.939136) (xy 102.750627 -178.994312)
			(xy 102.734559 -179.047719) (xy 102.710887 -179.098216) (xy 102.680114 -179.144729) (xy 102.642897 -179.186266)
			(xy 102.600029 -179.221941) (xy 102.552423 -179.250995) (xy 102.501094 -179.272807) (xy 102.447137 -179.286913)
			(xy 102.3917 -179.293013) (xy 102.335966 -179.290976) (xy 102.281123 -179.280846) (xy 102.228339 -179.262839)
			(xy 102.178739 -179.237338) (xy 102.133381 -179.204887) (xy 102.093232 -179.166178) (xy 102.059146 -179.122035)
			(xy 102.03185 -179.0734) (xy 102.011927 -179.021309) (xy 101.999801 -178.966872) (xy 101.99573 -178.91125)
			(xy 101.418811 -178.91125) (xy 101.412688 -178.953841) (xy 101.397333 -179.006136) (xy 101.374691 -179.055713)
			(xy 101.345225 -179.101563) (xy 101.309534 -179.142754) (xy 101.268343 -179.178445) (xy 101.222493 -179.207911)
			(xy 101.172916 -179.230553) (xy 101.120621 -179.245908) (xy 101.066673 -179.253664) (xy 101.012171 -179.253664)
			(xy 100.958223 -179.245908) (xy 100.905928 -179.230553) (xy 100.856351 -179.207911) (xy 100.810501 -179.178445)
			(xy 100.76931 -179.142754) (xy 100.733619 -179.101563) (xy 100.704153 -179.055713) (xy 100.681511 -179.006136)
			(xy 100.666156 -178.953841) (xy 100.6584 -178.899893) (xy 100.657914 -178.872642) (xy 100.399028 -178.872642)
			(xy 100.393022 -178.893097) (xy 100.370381 -178.942675) (xy 100.340914 -178.988527) (xy 100.305222 -179.029718)
			(xy 100.264031 -179.065411) (xy 100.21818 -179.094878) (xy 100.168602 -179.11752) (xy 100.116307 -179.132876)
			(xy 100.062358 -179.140634) (xy 100.035106 -179.14112) (xy 100.009871 -179.140718) (xy 99.959837 -179.134101)
			(xy 99.911117 -179.120929) (xy 99.864565 -179.101434) (xy 99.842574 -179.08905) (xy 99.832922 -179.083208)
			(xy 99.810824 -179.081176) (xy 99.716336 -179.114704) (xy 99.700334 -179.130198) (xy 99.69627 -179.140612)
			(xy 99.685539 -179.167373) (xy 99.657255 -179.217613) (xy 99.62173 -179.263022) (xy 99.579773 -179.302565)
			(xy 99.532341 -179.33534) (xy 99.480515 -179.360601) (xy 99.425477 -179.377771) (xy 99.368481 -179.386459)
			(xy 99.339654 -179.386992) (xy 99.312401 -179.386565) (xy 99.25845 -179.378802) (xy 99.206153 -179.36344)
			(xy 99.156575 -179.340792) (xy 99.110724 -179.31132) (xy 99.069534 -179.275622) (xy 99.033843 -179.234426)
			(xy 99.004378 -179.188571) (xy 98.981738 -179.138988) (xy 98.966385 -179.086689) (xy 98.958631 -179.032737)
			(xy 98.958146 -179.005484) (xy 98.958809 -178.973921) (xy 98.969194 -178.911656) (xy 98.989679 -178.851947)
			(xy 99.00412 -178.823874) (xy 99.008946 -178.814984) (xy 99.010978 -178.795426) (xy 98.985324 -178.707288)
			(xy 98.972878 -178.691794) (xy 98.963988 -178.686714) (xy 98.938862 -178.672206) (xy 98.89298 -178.636696)
			(xy 98.853007 -178.594645) (xy 98.819865 -178.547024) (xy 98.794318 -178.494933) (xy 98.776957 -178.439572)
			(xy 98.768182 -178.382221) (xy 98.767646 -178.353212) (xy 98.047048 -178.353212) (xy 98.047048 -179.405788)
			(xy 98.047385 -179.415837) (xy 98.054996 -179.434433) (xy 98.06178 -179.441856) (xy 98.426524 -179.8066)
			(xy 101.41661 -179.8066) (xy 101.420681 -179.750978) (xy 101.432807 -179.696541) (xy 101.45273 -179.64445)
			(xy 101.480026 -179.595815) (xy 101.514112 -179.551672) (xy 101.554261 -179.512963) (xy 101.599619 -179.480512)
			(xy 101.649219 -179.455011) (xy 101.702003 -179.437004) (xy 101.756846 -179.426874) (xy 101.81258 -179.424837)
			(xy 101.868017 -179.430937) (xy 101.921974 -179.445043) (xy 101.973303 -179.466855) (xy 102.020909 -179.495909)
			(xy 102.063777 -179.531584) (xy 102.100994 -179.573121) (xy 102.131767 -179.619634) (xy 102.155439 -179.670131)
			(xy 102.171507 -179.723538) (xy 102.179627 -179.778714) (xy 102.180136 -179.8066) (xy 102.179627 -179.834486)
			(xy 102.171507 -179.889662) (xy 102.155439 -179.943069) (xy 102.131767 -179.993566) (xy 102.100994 -180.040079)
			(xy 102.063777 -180.081616) (xy 102.020909 -180.117291) (xy 101.973303 -180.146345) (xy 101.921974 -180.168157)
			(xy 101.868017 -180.182263) (xy 101.81258 -180.188363) (xy 101.756846 -180.186326) (xy 101.702003 -180.176196)
			(xy 101.649219 -180.158189) (xy 101.599619 -180.132688) (xy 101.554261 -180.100237) (xy 101.514112 -180.061528)
			(xy 101.480026 -180.017385) (xy 101.45273 -179.96875) (xy 101.432807 -179.916659) (xy 101.420681 -179.862222)
			(xy 101.41661 -179.8066) (xy 98.426524 -179.8066) (xy 98.931476 -180.311552) (xy 98.938149 -180.318968)
			(xy 98.945728 -180.337401) (xy 98.946208 -180.347366) (xy 98.946208 -181.68366) (xy 102.375462 -181.68366)
			(xy 102.375938 -181.655749) (xy 102.384077 -181.600522) (xy 102.400177 -181.547072) (xy 102.423894 -181.496537)
			(xy 102.45472 -181.449998) (xy 102.472998 -181.428898) (xy 102.479348 -181.421786) (xy 102.485952 -181.404514)
			(xy 102.485952 -181.317392) (xy 102.479348 -181.30012) (xy 102.472998 -181.293008) (xy 102.454702 -181.271923)
			(xy 102.423877 -181.225381) (xy 102.400165 -181.174842) (xy 102.384073 -181.121388) (xy 102.375944 -181.066158)
			(xy 102.375462 -181.038246) (xy 102.375948 -181.010995) (xy 102.383704 -180.957047) (xy 102.399059 -180.904752)
			(xy 102.421701 -180.855175) (xy 102.451167 -180.809325) (xy 102.486858 -180.768134) (xy 102.528049 -180.732443)
			(xy 102.573899 -180.702977) (xy 102.623476 -180.680335) (xy 102.675771 -180.66498) (xy 102.729719 -180.657224)
			(xy 102.784221 -180.657224) (xy 102.838169 -180.66498) (xy 102.890464 -180.680335) (xy 102.940041 -180.702977)
			(xy 102.985891 -180.732443) (xy 103.027082 -180.768134) (xy 103.062773 -180.809325) (xy 103.092239 -180.855175)
			(xy 103.114881 -180.904752) (xy 103.130236 -180.957047) (xy 103.137992 -181.010995) (xy 103.138478 -181.038246)
			(xy 103.137996 -181.066157) (xy 103.129856 -181.121383) (xy 103.113757 -181.174833) (xy 103.090043 -181.225367)
			(xy 103.059218 -181.271907) (xy 103.040942 -181.293008) (xy 103.034592 -181.30012) (xy 103.027988 -181.317392)
			(xy 103.027988 -181.404514) (xy 103.034592 -181.421786) (xy 103.040942 -181.428898) (xy 103.0592 -181.450014)
			(xy 103.090029 -181.496549) (xy 103.113747 -181.547079) (xy 103.129849 -181.600527) (xy 103.137989 -181.65575)
			(xy 103.138478 -181.68366) (xy 103.137992 -181.710911) (xy 103.130236 -181.764859) (xy 103.114881 -181.817154)
			(xy 103.092239 -181.866731) (xy 103.062773 -181.912581) (xy 103.027082 -181.953772) (xy 102.985891 -181.989463)
			(xy 102.940041 -182.018929) (xy 102.890464 -182.041571) (xy 102.838169 -182.056926) (xy 102.784221 -182.064682)
			(xy 102.729719 -182.064682) (xy 102.675771 -182.056926) (xy 102.623476 -182.041571) (xy 102.573899 -182.018929)
			(xy 102.528049 -181.989463) (xy 102.486858 -181.953772) (xy 102.451167 -181.912581) (xy 102.421701 -181.866731)
			(xy 102.399059 -181.817154) (xy 102.383704 -181.764859) (xy 102.375948 -181.710911) (xy 102.375462 -181.68366)
			(xy 98.946208 -181.68366) (xy 98.946208 -182.28564) (xy 121.299224 -182.28564) (xy 121.299708 -182.25827)
			(xy 121.30752 -182.204092) (xy 121.323005 -182.151589) (xy 121.345843 -182.101841) (xy 121.375564 -182.055874)
			(xy 121.393204 -182.034942) (xy 121.3993 -182.02783) (xy 121.40565 -182.010812) (xy 121.40565 -181.925468)
			(xy 121.3993 -181.90845) (xy 121.393204 -181.901338) (xy 121.375603 -181.880373) (xy 121.345879 -181.83441)
			(xy 121.323032 -181.784669) (xy 121.307534 -181.732172) (xy 121.299702 -181.677999) (xy 121.299698 -181.623262)
			(xy 121.307521 -181.569087) (xy 121.323011 -181.516587) (xy 121.34585 -181.466843) (xy 121.375567 -181.420875)
			(xy 121.393204 -181.399942) (xy 121.3993 -181.39283) (xy 121.40565 -181.375812) (xy 121.40565 -181.290468)
			(xy 121.3993 -181.27345) (xy 121.393204 -181.266338) (xy 121.375603 -181.245373) (xy 121.345879 -181.19941)
			(xy 121.323032 -181.149669) (xy 121.307534 -181.097172) (xy 121.299702 -181.042999) (xy 121.299698 -180.988262)
			(xy 121.307521 -180.934087) (xy 121.323011 -180.881587) (xy 121.34585 -180.831843) (xy 121.375567 -180.785875)
			(xy 121.393204 -180.764942) (xy 121.3993 -180.75783) (xy 121.40565 -180.740812) (xy 121.40565 -180.655468)
			(xy 121.3993 -180.63845) (xy 121.393204 -180.631338) (xy 121.375603 -180.610373) (xy 121.345879 -180.56441)
			(xy 121.323032 -180.514669) (xy 121.307534 -180.462172) (xy 121.299702 -180.407999) (xy 121.299698 -180.353262)
			(xy 121.307521 -180.299087) (xy 121.323011 -180.246587) (xy 121.34585 -180.196843) (xy 121.375567 -180.150875)
			(xy 121.393204 -180.129942) (xy 121.3993 -180.12283) (xy 121.40565 -180.105812) (xy 121.40565 -180.020468)
			(xy 121.3993 -180.00345) (xy 121.393204 -179.996338) (xy 121.375603 -179.975373) (xy 121.345879 -179.92941)
			(xy 121.323032 -179.879669) (xy 121.307534 -179.827172) (xy 121.299702 -179.772999) (xy 121.299698 -179.718262)
			(xy 121.307521 -179.664087) (xy 121.323011 -179.611587) (xy 121.34585 -179.561843) (xy 121.375567 -179.515875)
			(xy 121.393204 -179.494942) (xy 121.3993 -179.48783) (xy 121.40565 -179.470812) (xy 121.40565 -179.385468)
			(xy 121.3993 -179.36845) (xy 121.393204 -179.361338) (xy 121.375603 -179.340373) (xy 121.345879 -179.29441)
			(xy 121.323032 -179.244669) (xy 121.307534 -179.192172) (xy 121.299702 -179.137999) (xy 121.299698 -179.083262)
			(xy 121.307521 -179.029087) (xy 121.323011 -178.976587) (xy 121.34585 -178.926843) (xy 121.375567 -178.880875)
			(xy 121.393204 -178.859942) (xy 121.3993 -178.85283) (xy 121.40565 -178.835812) (xy 121.40565 -178.750468)
			(xy 121.3993 -178.73345) (xy 121.393204 -178.726338) (xy 121.375603 -178.705373) (xy 121.345879 -178.65941)
			(xy 121.323032 -178.609669) (xy 121.307534 -178.557172) (xy 121.299702 -178.502999) (xy 121.299698 -178.448262)
			(xy 121.307521 -178.394087) (xy 121.323011 -178.341587) (xy 121.34585 -178.291843) (xy 121.375567 -178.245875)
			(xy 121.393204 -178.224942) (xy 121.3993 -178.21783) (xy 121.40565 -178.200812) (xy 121.40565 -178.115468)
			(xy 121.3993 -178.09845) (xy 121.393204 -178.091338) (xy 121.37557 -178.070402) (xy 121.345857 -178.02443)
			(xy 121.32302 -177.974684) (xy 121.307528 -177.922184) (xy 121.299699 -177.868009) (xy 121.299224 -177.84064)
			(xy 121.29977 -177.811474) (xy 121.308667 -177.753823) (xy 121.326243 -177.698201) (xy 121.352088 -177.645906)
			(xy 121.385599 -177.59816) (xy 121.405396 -177.576734) (xy 121.412254 -177.569368) (xy 121.419366 -177.551588)
			(xy 121.419366 -177.461164) (xy 121.412254 -177.443384) (xy 121.405396 -177.436018) (xy 121.385611 -177.414586)
			(xy 121.352127 -177.366827) (xy 121.326295 -177.314532) (xy 121.308716 -177.258917) (xy 121.299799 -177.201275)
			(xy 121.299224 -177.172112) (xy 121.299667 -177.144858) (xy 121.307423 -177.090905) (xy 121.322779 -177.038604)
			(xy 121.345422 -176.989022) (xy 121.374892 -176.943168) (xy 121.410588 -176.901974) (xy 121.451784 -176.86628)
			(xy 121.49764 -176.836813) (xy 121.547223 -176.814172) (xy 121.599524 -176.798818) (xy 121.653478 -176.791065)
			(xy 121.680732 -176.790604) (xy 121.708103 -176.79105) (xy 121.762283 -176.798873) (xy 121.814786 -176.814366)
			(xy 121.864533 -176.837213) (xy 121.910499 -176.866941) (xy 121.93143 -176.884584) (xy 121.938542 -176.89068)
			(xy 121.95556 -176.89703) (xy 122.040904 -176.89703) (xy 122.057922 -176.89068) (xy 122.065034 -176.884584)
			(xy 122.085967 -176.866943) (xy 122.131935 -176.837219) (xy 122.181681 -176.814373) (xy 122.234183 -176.798877)
			(xy 122.288361 -176.791048) (xy 122.343103 -176.791048) (xy 122.397281 -176.798877) (xy 122.449783 -176.814373)
			(xy 122.499529 -176.837219) (xy 122.545497 -176.866943) (xy 122.56643 -176.884584) (xy 122.573542 -176.89068)
			(xy 122.59056 -176.89703) (xy 122.675904 -176.89703) (xy 122.692922 -176.89068) (xy 122.700034 -176.884584)
			(xy 122.720978 -176.86696) (xy 122.766948 -176.837246) (xy 122.816692 -176.814408) (xy 122.86919 -176.798913)
			(xy 122.923364 -176.791081) (xy 122.950732 -176.790604) (xy 122.977985 -176.791048) (xy 123.031934 -176.798809)
			(xy 123.084231 -176.814169) (xy 123.133809 -176.836815) (xy 123.17966 -176.866286) (xy 123.22085 -176.901981)
			(xy 123.256541 -176.943176) (xy 123.286006 -176.98903) (xy 123.308646 -177.038611) (xy 123.324 -177.090909)
			(xy 123.331755 -177.144859) (xy 123.33224 -177.172112) (xy 125.312424 -177.172112) (xy 125.312867 -177.144858)
			(xy 125.320623 -177.090905) (xy 125.335979 -177.038604) (xy 125.358622 -176.989022) (xy 125.388092 -176.943168)
			(xy 125.423788 -176.901974) (xy 125.464984 -176.86628) (xy 125.51084 -176.836813) (xy 125.560423 -176.814172)
			(xy 125.612724 -176.798818) (xy 125.666678 -176.791065) (xy 125.693932 -176.790604) (xy 125.721303 -176.79105)
			(xy 125.775483 -176.798873) (xy 125.827986 -176.814366) (xy 125.877733 -176.837213) (xy 125.923699 -176.866941)
			(xy 125.94463 -176.884584) (xy 125.951742 -176.89068) (xy 125.96876 -176.89703) (xy 126.054104 -176.89703)
			(xy 126.071122 -176.89068) (xy 126.078234 -176.884584) (xy 126.099167 -176.866943) (xy 126.145135 -176.837219)
			(xy 126.194881 -176.814373) (xy 126.247383 -176.798877) (xy 126.301561 -176.791048) (xy 126.356303 -176.791048)
			(xy 126.410481 -176.798877) (xy 126.462983 -176.814373) (xy 126.512729 -176.837219) (xy 126.558697 -176.866943)
			(xy 126.57963 -176.884584) (xy 126.586742 -176.89068) (xy 126.60376 -176.89703) (xy 126.689104 -176.89703)
			(xy 126.706122 -176.89068) (xy 126.713234 -176.884584) (xy 126.734178 -176.86696) (xy 126.780148 -176.837246)
			(xy 126.829892 -176.814408) (xy 126.88239 -176.798913) (xy 126.936564 -176.791081) (xy 126.963932 -176.790604)
			(xy 126.991185 -176.791048) (xy 127.045134 -176.798809) (xy 127.097431 -176.814169) (xy 127.147009 -176.836815)
			(xy 127.19286 -176.866286) (xy 127.23405 -176.901981) (xy 127.269741 -176.943176) (xy 127.299206 -176.98903)
			(xy 127.321846 -177.038611) (xy 127.3372 -177.090909) (xy 127.344955 -177.144859) (xy 127.34544 -177.172112)
			(xy 127.344905 -177.201231) (xy 127.336058 -177.258792) (xy 127.31857 -177.314341) (xy 127.292849 -177.366591)
			(xy 127.25949 -177.414327) (xy 127.239776 -177.435764) (xy 127.232918 -177.442876) (xy 127.225806 -177.46091)
			(xy 127.225806 -177.55108) (xy 127.233172 -177.569114) (xy 127.24003 -177.576226) (xy 127.259872 -177.59769)
			(xy 127.293469 -177.64552) (xy 127.319378 -177.697914) (xy 127.336993 -177.753647) (xy 127.345901 -177.811415)
			(xy 127.346456 -177.84064) (xy 127.345965 -177.868009) (xy 127.338155 -177.922188) (xy 127.322672 -177.974691)
			(xy 127.299836 -178.024439) (xy 127.270115 -178.070406) (xy 127.252476 -178.091338) (xy 127.24638 -178.09845)
			(xy 127.24003 -178.115468) (xy 127.24003 -178.200812) (xy 127.24638 -178.21783) (xy 127.252476 -178.224942)
			(xy 127.270156 -178.245843) (xy 127.299879 -178.291816) (xy 127.322722 -178.341568) (xy 127.338215 -178.394075)
			(xy 127.346039 -178.448258) (xy 127.346035 -178.503003) (xy 127.338202 -178.557184) (xy 127.3227 -178.609689)
			(xy 127.29985 -178.659436) (xy 127.270119 -178.705405) (xy 127.252476 -178.726338) (xy 127.24638 -178.73345)
			(xy 127.24003 -178.750468) (xy 127.24003 -178.835812) (xy 127.24638 -178.85283) (xy 127.252476 -178.859942)
			(xy 127.270098 -178.880888) (xy 127.299813 -178.926857) (xy 127.322653 -178.976601) (xy 127.338148 -179.029098)
			(xy 127.34598 -179.083272) (xy 127.346456 -179.11064) (xy 127.34596 -179.13789) (xy 127.338199 -179.191835)
			(xy 127.322841 -179.244126) (xy 127.300199 -179.293701) (xy 127.270733 -179.339549) (xy 127.235043 -179.380737)
			(xy 127.193855 -179.416428) (xy 127.148008 -179.445895) (xy 127.098434 -179.468538) (xy 127.046143 -179.483897)
			(xy 126.992198 -179.491659) (xy 126.964948 -179.492148) (xy 126.935506 -179.4916) (xy 126.877322 -179.482559)
			(xy 126.821217 -179.464683) (xy 126.768527 -179.438398) (xy 126.720501 -179.404329) (xy 126.69901 -179.384198)
			(xy 126.692406 -179.377594) (xy 126.675642 -179.370482) (xy 126.590298 -179.36591) (xy 126.573026 -179.371498)
			(xy 126.56566 -179.377086) (xy 126.545426 -179.392476) (xy 126.501634 -179.418299) (xy 126.454801 -179.438076)
			(xy 126.405755 -179.451457) (xy 126.355367 -179.458203) (xy 126.329948 -179.45862) (xy 126.302578 -179.458145)
			(xy 126.248398 -179.450333) (xy 126.195895 -179.434847) (xy 126.146147 -179.412006) (xy 126.100181 -179.382282)
			(xy 126.07925 -179.36464) (xy 126.072138 -179.358544) (xy 126.05512 -179.352194) (xy 125.969776 -179.352194)
			(xy 125.952758 -179.358544) (xy 125.945646 -179.36464) (xy 125.924713 -179.382278) (xy 125.87874 -179.411988)
			(xy 125.828992 -179.434824) (xy 125.776492 -179.450316) (xy 125.722317 -179.458145) (xy 125.694948 -179.45862)
			(xy 125.667697 -179.4581) (xy 125.613749 -179.45035) (xy 125.561453 -179.435001) (xy 125.511873 -179.412365)
			(xy 125.466021 -179.382903) (xy 125.424828 -179.347215) (xy 125.389133 -179.306028) (xy 125.359664 -179.260179)
			(xy 125.33702 -179.210604) (xy 125.321663 -179.15831) (xy 125.313904 -179.104363) (xy 125.31344 -179.077112)
			(xy 125.313903 -179.049742) (xy 125.32172 -178.995562) (xy 125.33721 -178.943058) (xy 125.360052 -178.893312)
			(xy 125.389778 -178.847345) (xy 125.40742 -178.826414) (xy 125.413516 -178.819302) (xy 125.419866 -178.802284)
			(xy 125.419866 -178.71694) (xy 125.413516 -178.699922) (xy 125.40742 -178.69281) (xy 125.389791 -178.671868)
			(xy 125.360067 -178.625901) (xy 125.337221 -178.576157) (xy 125.321724 -178.523656) (xy 125.313895 -178.469479)
			(xy 125.313893 -178.414739) (xy 125.32172 -178.360562) (xy 125.337215 -178.30806) (xy 125.360058 -178.258315)
			(xy 125.38978 -178.212347) (xy 125.40742 -178.191414) (xy 125.413516 -178.184302) (xy 125.419866 -178.167284)
			(xy 125.419866 -178.08194) (xy 125.413516 -178.064922) (xy 125.40742 -178.05781) (xy 125.389775 -178.036882)
			(xy 125.360064 -177.990909) (xy 125.337228 -177.94116) (xy 125.321739 -177.888658) (xy 125.313913 -177.834482)
			(xy 125.31344 -177.807112) (xy 125.313921 -177.779813) (xy 125.321692 -177.725771) (xy 125.33709 -177.67339)
			(xy 125.359802 -177.62374) (xy 125.389362 -177.577837) (xy 125.406912 -177.556922) (xy 125.413262 -177.54981)
			(xy 125.419358 -177.532792) (xy 125.419358 -177.447194) (xy 125.413008 -177.43043) (xy 125.406912 -177.423318)
			(xy 125.389209 -177.402348) (xy 125.359328 -177.356319) (xy 125.336359 -177.306479) (xy 125.320777 -177.253861)
			(xy 125.312903 -177.199551) (xy 125.312424 -177.172112) (xy 123.33224 -177.172112) (xy 123.331753 -177.199411)
			(xy 123.323981 -177.253451) (xy 123.308583 -177.305832) (xy 123.285873 -177.355481) (xy 123.256316 -177.401386)
			(xy 123.238768 -177.422302) (xy 123.232418 -177.429414) (xy 123.226322 -177.446432) (xy 123.226322 -177.53203)
			(xy 123.232672 -177.548794) (xy 123.238768 -177.555906) (xy 123.25648 -177.576869) (xy 123.28636 -177.6229)
			(xy 123.309327 -177.672741) (xy 123.324908 -177.725362) (xy 123.332778 -177.779673) (xy 123.333256 -177.807112)
			(xy 123.332808 -177.834483) (xy 123.324987 -177.888663) (xy 123.309495 -177.941167) (xy 123.286649 -177.990914)
			(xy 123.25692 -178.036879) (xy 123.239276 -178.05781) (xy 123.23318 -178.064922) (xy 123.22683 -178.08194)
			(xy 123.22683 -178.167284) (xy 123.23318 -178.184302) (xy 123.239276 -178.191414) (xy 123.256928 -178.212337)
			(xy 123.286652 -178.258307) (xy 123.309497 -178.308055) (xy 123.324992 -178.360558) (xy 123.33282 -178.414738)
			(xy 123.332818 -178.46948) (xy 123.324988 -178.52366) (xy 123.309491 -178.576162) (xy 123.286644 -178.625909)
			(xy 123.256917 -178.671877) (xy 123.239276 -178.69281) (xy 123.23318 -178.699922) (xy 123.22683 -178.71694)
			(xy 123.22683 -178.802284) (xy 123.23318 -178.819302) (xy 123.239276 -178.826414) (xy 123.256928 -178.847337)
			(xy 123.286652 -178.893307) (xy 123.309497 -178.943055) (xy 123.324992 -178.995558) (xy 123.33282 -179.049738)
			(xy 123.332818 -179.10448) (xy 123.324988 -179.15866) (xy 123.309491 -179.211162) (xy 123.286644 -179.260909)
			(xy 123.256917 -179.306877) (xy 123.239276 -179.32781) (xy 123.23318 -179.334922) (xy 123.22683 -179.35194)
			(xy 123.22683 -179.437284) (xy 123.23318 -179.454302) (xy 123.239276 -179.461414) (xy 123.256885 -179.482371)
			(xy 123.286602 -179.528336) (xy 123.309444 -179.578078) (xy 123.324942 -179.630573) (xy 123.332778 -179.684744)
			(xy 123.333256 -179.712112) (xy 123.33272 -179.741337) (xy 123.323795 -179.799103) (xy 123.306173 -179.854833)
			(xy 123.280264 -179.907228) (xy 123.246673 -179.955062) (xy 123.22683 -179.976526) (xy 123.219972 -179.983638)
			(xy 123.212606 -180.001672) (xy 123.212606 -180.091842) (xy 123.219718 -180.109876) (xy 123.226576 -180.116988)
			(xy 123.246304 -180.138413) (xy 123.279658 -180.186153) (xy 123.305373 -180.238406) (xy 123.322854 -180.293958)
			(xy 123.331694 -180.351521) (xy 123.33224 -180.38064) (xy 123.331753 -180.40801) (xy 123.323943 -180.462188)
			(xy 123.308459 -180.514692) (xy 123.285622 -180.564439) (xy 123.2559 -180.610406) (xy 123.23826 -180.631338)
			(xy 123.232164 -180.63845) (xy 123.225814 -180.655468) (xy 123.225814 -180.740812) (xy 123.232164 -180.75783)
			(xy 123.23826 -180.764942) (xy 123.25594 -180.785843) (xy 123.285665 -180.831816) (xy 123.308508 -180.881567)
			(xy 123.324002 -180.934074) (xy 123.331827 -180.988257) (xy 123.331823 -181.043003) (xy 123.323989 -181.097185)
			(xy 123.308487 -181.149689) (xy 123.285636 -181.199437) (xy 123.255904 -181.245405) (xy 123.23826 -181.266338)
			(xy 123.232164 -181.27345) (xy 123.225814 -181.290468) (xy 123.225814 -181.375812) (xy 123.232164 -181.39283)
			(xy 123.23826 -181.399942) (xy 123.255879 -181.42089) (xy 123.285595 -181.466858) (xy 123.308436 -181.516601)
			(xy 123.323931 -181.569099) (xy 123.331764 -181.623272) (xy 123.33224 -181.65064) (xy 123.331759 -181.677891)
			(xy 123.323998 -181.731837) (xy 123.30864 -181.78413) (xy 123.285996 -181.833705) (xy 123.256529 -181.879554)
			(xy 123.220837 -181.920743) (xy 123.179647 -181.956434) (xy 123.133798 -181.9859) (xy 123.084222 -182.008543)
			(xy 123.031929 -182.0239) (xy 122.977983 -182.03166) (xy 122.950732 -182.032148) (xy 122.923362 -182.031676)
			(xy 122.869183 -182.023861) (xy 122.816679 -182.008374) (xy 122.766932 -181.985534) (xy 122.720965 -181.955809)
			(xy 122.700034 -181.938168) (xy 122.692922 -181.932072) (xy 122.675904 -181.925722) (xy 122.59056 -181.925722)
			(xy 122.573542 -181.932072) (xy 122.56643 -181.938168) (xy 122.545493 -181.955802) (xy 122.499522 -181.985515)
			(xy 122.449776 -182.008353) (xy 122.397276 -182.023845) (xy 122.343101 -182.031674) (xy 122.315732 -182.032148)
			(xy 122.286254 -182.031603) (xy 122.228001 -182.022537) (xy 122.171836 -182.004617) (xy 122.119096 -181.978268)
			(xy 122.071039 -181.944119) (xy 122.04954 -181.923944) (xy 122.042193 -181.917426) (xy 122.024042 -181.909973)
			(xy 122.014234 -181.909466) (xy 121.960894 -181.909466) (xy 121.954036 -181.916832) (xy 121.947486 -181.924154)
			(xy 121.940052 -181.942324) (xy 121.939558 -181.952138) (xy 121.939558 -181.984142) (xy 121.940043 -181.993956)
			(xy 121.94749 -182.01212) (xy 121.954036 -182.019448) (xy 121.97423 -182.040929) (xy 122.008372 -182.088993)
			(xy 122.034715 -182.141737) (xy 122.052632 -182.197906) (xy 122.061694 -182.256162) (xy 122.06224 -182.28564)
			(xy 122.061754 -182.312891) (xy 122.053998 -182.366839) (xy 122.038643 -182.419134) (xy 122.016001 -182.468711)
			(xy 121.986535 -182.514561) (xy 121.950844 -182.555752) (xy 121.909653 -182.591443) (xy 121.863803 -182.620909)
			(xy 121.814226 -182.643551) (xy 121.761931 -182.658906) (xy 121.707983 -182.666662) (xy 121.653481 -182.666662)
			(xy 121.599533 -182.658906) (xy 121.547238 -182.643551) (xy 121.497661 -182.620909) (xy 121.451811 -182.591443)
			(xy 121.41062 -182.555752) (xy 121.374929 -182.514561) (xy 121.345463 -182.468711) (xy 121.322821 -182.419134)
			(xy 121.307466 -182.366839) (xy 121.29971 -182.312891) (xy 121.299224 -182.28564) (xy 98.946208 -182.28564)
			(xy 98.946208 -182.362602) (xy 98.94581 -182.386578) (xy 98.938308 -182.433938) (xy 98.923488 -182.479542)
			(xy 98.901717 -182.522265) (xy 98.873529 -182.561057) (xy 98.83962 -182.594961) (xy 98.800824 -182.623142)
			(xy 98.758097 -182.644907) (xy 98.712491 -182.659719) (xy 98.66513 -182.667214) (xy 98.641154 -182.667656)
			(xy 97.067116 -182.667656) (xy 97.05467 -182.670958) (xy 97.048828 -182.674514) (xy 97.025705 -182.687006)
			(xy 96.976248 -182.704775) (xy 96.924481 -182.713819) (xy 96.898206 -182.714392) (xy 95.693992 -182.714392)
			(xy 95.68399 -182.713907) (xy 95.665528 -182.706204) (xy 95.658178 -182.699406) (xy 95.317818 -182.359046)
			(xy 95.311101 -182.351637) (xy 95.303376 -182.333216) (xy 95.302832 -182.323232) (xy 95.302832 -181.248558)
			(xy 95.302476 -181.238511) (xy 95.294879 -181.219914) (xy 95.2881 -181.21249) (xy 94.731332 -180.655722)
			(xy 94.724649 -180.648314) (xy 94.717076 -180.629875) (xy 94.7166 -180.619908) (xy 94.7166 -177.146204)
			(xy 94.716199 -177.136131) (xy 94.708464 -177.117532) (xy 94.701614 -177.110136) (xy 94.60484 -177.013362)
			(xy 94.597425 -177.006542) (xy 94.578837 -176.998812) (xy 94.568772 -176.998376) (xy 89.938352 -176.998376)
			(xy 89.928283 -176.998809) (xy 89.909684 -177.006522) (xy 89.902284 -177.013362) (xy 89.67978 -177.235866)
			(xy 89.673073 -177.243336) (xy 89.66549 -177.261904) (xy 89.665048 -177.271934) (xy 89.665048 -178.33594)
			(xy 90.375486 -178.33594) (xy 90.375972 -178.308689) (xy 90.383728 -178.254741) (xy 90.399083 -178.202446)
			(xy 90.421725 -178.152869) (xy 90.451191 -178.107019) (xy 90.486882 -178.065828) (xy 90.528073 -178.030137)
			(xy 90.573923 -178.000671) (xy 90.6235 -177.978029) (xy 90.675795 -177.962674) (xy 90.729743 -177.954918)
			(xy 90.784245 -177.954918) (xy 90.838193 -177.962674) (xy 90.890488 -177.978029) (xy 90.940065 -178.000671)
			(xy 90.985915 -178.030137) (xy 91.027106 -178.065828) (xy 91.062797 -178.107019) (xy 91.092263 -178.152869)
			(xy 91.114905 -178.202446) (xy 91.13026 -178.254741) (xy 91.138016 -178.308689) (xy 91.138502 -178.33594)
			(xy 91.137843 -178.367503) (xy 91.127455 -178.429768) (xy 91.106969 -178.489477) (xy 91.092528 -178.51755)
			(xy 91.087702 -178.52644) (xy 91.08567 -178.545998) (xy 91.111324 -178.634136) (xy 91.12377 -178.64963)
			(xy 91.13266 -178.65471) (xy 91.140026 -178.658774) (xy 91.149678 -178.664616) (xy 91.171776 -178.666648)
			(xy 91.266264 -178.63312) (xy 91.282266 -178.617626) (xy 91.28633 -178.607212) (xy 91.297074 -178.580456)
			(xy 91.325355 -178.530215) (xy 91.360878 -178.484806) (xy 91.402832 -178.445262) (xy 91.450263 -178.412485)
			(xy 91.502087 -178.387224) (xy 91.557124 -178.370053) (xy 91.614119 -178.361365) (xy 91.642946 -178.360832)
			(xy 91.670198 -178.361241) (xy 91.724146 -178.369004) (xy 91.776441 -178.384364) (xy 91.826018 -178.407011)
			(xy 91.871867 -178.436481) (xy 91.913056 -178.472176) (xy 91.948746 -178.51337) (xy 91.978212 -178.559223)
			(xy 92.000852 -178.608802) (xy 92.016206 -178.661099) (xy 92.023962 -178.715048) (xy 92.023962 -178.769552)
			(xy 92.016206 -178.823501) (xy 92.00685 -178.85537) (xy 92.265754 -178.85537) (xy 92.266209 -178.827894)
			(xy 92.274107 -178.773513) (xy 92.289733 -178.720829) (xy 92.312765 -178.670937) (xy 92.342725 -178.62487)
			(xy 92.360496 -178.60391) (xy 92.366592 -178.596798) (xy 92.372942 -178.57978) (xy 92.372942 -178.493928)
			(xy 92.366592 -178.47691) (xy 92.360496 -178.469798) (xy 92.34275 -178.448822) (xy 92.312822 -178.402744)
			(xy 92.289806 -178.352853) (xy 92.274176 -178.300179) (xy 92.266255 -178.245809) (xy 92.265754 -178.218338)
			(xy 92.26624 -178.191087) (xy 92.273996 -178.137139) (xy 92.289351 -178.084844) (xy 92.311993 -178.035267)
			(xy 92.341459 -177.989417) (xy 92.37715 -177.948226) (xy 92.418341 -177.912535) (xy 92.464191 -177.883069)
			(xy 92.513768 -177.860427) (xy 92.566063 -177.845072) (xy 92.620011 -177.837316) (xy 92.674513 -177.837316)
			(xy 92.728461 -177.845072) (xy 92.780756 -177.860427) (xy 92.830333 -177.883069) (xy 92.876183 -177.912535)
			(xy 92.917374 -177.948226) (xy 92.953065 -177.989417) (xy 92.982531 -178.035267) (xy 93.005173 -178.084844)
			(xy 93.020528 -178.137139) (xy 93.028284 -178.191087) (xy 93.02877 -178.218338) (xy 93.028313 -178.245814)
			(xy 93.020415 -178.300195) (xy 93.004789 -178.352878) (xy 92.981757 -178.40277) (xy 92.951799 -178.448837)
			(xy 92.934028 -178.469798) (xy 92.927932 -178.47691) (xy 92.921582 -178.493928) (xy 92.921582 -178.57978)
			(xy 92.927932 -178.596798) (xy 92.934028 -178.60391) (xy 92.951782 -178.62488) (xy 92.981707 -178.67096)
			(xy 93.004722 -178.720852) (xy 93.02035 -178.773527) (xy 93.028269 -178.827898) (xy 93.02877 -178.85537)
			(xy 93.028284 -178.882621) (xy 93.026651 -178.893978) (xy 93.60357 -178.893978) (xy 93.607641 -178.838356)
			(xy 93.619767 -178.783919) (xy 93.63969 -178.731828) (xy 93.666986 -178.683193) (xy 93.701072 -178.63905)
			(xy 93.741221 -178.600341) (xy 93.786579 -178.56789) (xy 93.836179 -178.542389) (xy 93.888963 -178.524382)
			(xy 93.943806 -178.514252) (xy 93.99954 -178.512215) (xy 94.054977 -178.518315) (xy 94.108934 -178.532421)
			(xy 94.160263 -178.554233) (xy 94.207869 -178.583287) (xy 94.250737 -178.618962) (xy 94.287954 -178.660499)
			(xy 94.318727 -178.707012) (xy 94.342399 -178.757509) (xy 94.358467 -178.810916) (xy 94.366587 -178.866092)
			(xy 94.367096 -178.893978) (xy 94.366587 -178.921864) (xy 94.358467 -178.97704) (xy 94.342399 -179.030447)
			(xy 94.318727 -179.080944) (xy 94.287954 -179.127457) (xy 94.250737 -179.168994) (xy 94.207869 -179.204669)
			(xy 94.160263 -179.233723) (xy 94.108934 -179.255535) (xy 94.054977 -179.269641) (xy 93.99954 -179.275741)
			(xy 93.943806 -179.273704) (xy 93.888963 -179.263574) (xy 93.836179 -179.245567) (xy 93.786579 -179.220066)
			(xy 93.741221 -179.187615) (xy 93.701072 -179.148906) (xy 93.666986 -179.104763) (xy 93.63969 -179.056128)
			(xy 93.619767 -179.004037) (xy 93.607641 -178.9496) (xy 93.60357 -178.893978) (xy 93.026651 -178.893978)
			(xy 93.020528 -178.936569) (xy 93.005173 -178.988864) (xy 92.982531 -179.038441) (xy 92.953065 -179.084291)
			(xy 92.917374 -179.125482) (xy 92.876183 -179.161173) (xy 92.830333 -179.190639) (xy 92.780756 -179.213281)
			(xy 92.728461 -179.228636) (xy 92.674513 -179.236392) (xy 92.620011 -179.236392) (xy 92.566063 -179.228636)
			(xy 92.513768 -179.213281) (xy 92.464191 -179.190639) (xy 92.418341 -179.161173) (xy 92.37715 -179.125482)
			(xy 92.341459 -179.084291) (xy 92.311993 -179.038441) (xy 92.289351 -178.988864) (xy 92.273996 -178.936569)
			(xy 92.26624 -178.882621) (xy 92.265754 -178.85537) (xy 92.00685 -178.85537) (xy 92.000852 -178.875798)
			(xy 91.978212 -178.925377) (xy 91.948746 -178.97123) (xy 91.913056 -179.012424) (xy 91.871867 -179.048119)
			(xy 91.826018 -179.077589) (xy 91.776441 -179.100236) (xy 91.724146 -179.115596) (xy 91.670198 -179.123359)
			(xy 91.642946 -179.123848) (xy 91.61771 -179.123468) (xy 91.567676 -179.116844) (xy 91.518956 -179.103666)
			(xy 91.472404 -179.084165) (xy 91.450414 -179.071778) (xy 91.440762 -179.065936) (xy 91.418664 -179.063904)
			(xy 91.324176 -179.097432) (xy 91.308174 -179.112926) (xy 91.30411 -179.12334) (xy 91.293443 -179.150129)
			(xy 91.26515 -179.20037) (xy 91.229616 -179.245779) (xy 91.187649 -179.28532) (xy 91.140208 -179.318092)
			(xy 91.088373 -179.343348) (xy 91.033327 -179.360511) (xy 90.976324 -179.369192) (xy 90.947494 -179.36972)
			(xy 90.920243 -179.369228) (xy 90.866296 -179.361471) (xy 90.814002 -179.346116) (xy 90.764426 -179.323475)
			(xy 90.718576 -179.294009) (xy 90.677386 -179.258318) (xy 90.641695 -179.217129) (xy 90.612228 -179.171279)
			(xy 90.589587 -179.121703) (xy 90.57423 -179.06941) (xy 90.566473 -179.015463) (xy 90.565986 -178.988212)
			(xy 90.566628 -178.956648) (xy 90.577023 -178.894383) (xy 90.597515 -178.834674) (xy 90.61196 -178.806602)
			(xy 90.616786 -178.797712) (xy 90.618818 -178.778154) (xy 90.593164 -178.690016) (xy 90.580718 -178.674522)
			(xy 90.571828 -178.669442) (xy 90.546724 -178.654899) (xy 90.50084 -178.619396) (xy 90.460864 -178.577351)
			(xy 90.427719 -178.529737) (xy 90.402168 -178.477651) (xy 90.384803 -178.422295) (xy 90.376024 -178.364948)
			(xy 90.375486 -178.33594) (xy 89.665048 -178.33594) (xy 89.665048 -179.385468) (xy 89.665395 -179.395516)
			(xy 89.672999 -179.414112) (xy 89.67978 -179.421536) (xy 90.047572 -179.789328) (xy 93.02445 -179.789328)
			(xy 93.028521 -179.733706) (xy 93.040647 -179.679269) (xy 93.06057 -179.627178) (xy 93.087866 -179.578543)
			(xy 93.121952 -179.5344) (xy 93.162101 -179.495691) (xy 93.207459 -179.46324) (xy 93.257059 -179.437739)
			(xy 93.309843 -179.419732) (xy 93.364686 -179.409602) (xy 93.42042 -179.407565) (xy 93.475857 -179.413665)
			(xy 93.529814 -179.427771) (xy 93.581143 -179.449583) (xy 93.628749 -179.478637) (xy 93.671617 -179.514312)
			(xy 93.708834 -179.555849) (xy 93.739607 -179.602362) (xy 93.763279 -179.652859) (xy 93.779347 -179.706266)
			(xy 93.787467 -179.761442) (xy 93.787976 -179.789328) (xy 93.787467 -179.817214) (xy 93.779347 -179.87239)
			(xy 93.763279 -179.925797) (xy 93.739607 -179.976294) (xy 93.708834 -180.022807) (xy 93.671617 -180.064344)
			(xy 93.628749 -180.100019) (xy 93.581143 -180.129073) (xy 93.529814 -180.150885) (xy 93.475857 -180.164991)
			(xy 93.42042 -180.171091) (xy 93.364686 -180.169054) (xy 93.309843 -180.158924) (xy 93.257059 -180.140917)
			(xy 93.207459 -180.115416) (xy 93.162101 -180.082965) (xy 93.121952 -180.044256) (xy 93.087866 -180.000113)
			(xy 93.06057 -179.951478) (xy 93.040647 -179.899387) (xy 93.028521 -179.84495) (xy 93.02445 -179.789328)
			(xy 90.047572 -179.789328) (xy 90.536776 -180.278532) (xy 90.54344 -180.285954) (xy 90.551024 -180.304383)
			(xy 90.551508 -180.314346) (xy 90.551508 -181.666388) (xy 93.983302 -181.666388) (xy 93.98381 -181.638478)
			(xy 93.991944 -181.583254) (xy 94.008037 -181.529804) (xy 94.031746 -181.479269) (xy 94.062564 -181.432728)
			(xy 94.080838 -181.411626) (xy 94.087188 -181.404514) (xy 94.093792 -181.387242) (xy 94.093792 -181.30012)
			(xy 94.087188 -181.282848) (xy 94.080838 -181.275736) (xy 94.062546 -181.254648) (xy 94.031722 -181.208106)
			(xy 94.008011 -181.157568) (xy 93.991918 -181.104114) (xy 93.983786 -181.048886) (xy 93.983302 -181.020974)
			(xy 93.983788 -180.993723) (xy 93.991544 -180.939775) (xy 94.006899 -180.88748) (xy 94.029541 -180.837903)
			(xy 94.059007 -180.792053) (xy 94.094698 -180.750862) (xy 94.135889 -180.715171) (xy 94.181739 -180.685705)
			(xy 94.231316 -180.663063) (xy 94.283611 -180.647708) (xy 94.337559 -180.639952) (xy 94.392061 -180.639952)
			(xy 94.446009 -180.647708) (xy 94.498304 -180.663063) (xy 94.547881 -180.685705) (xy 94.593731 -180.715171)
			(xy 94.634922 -180.750862) (xy 94.670613 -180.792053) (xy 94.700079 -180.837903) (xy 94.722721 -180.88748)
			(xy 94.738076 -180.939775) (xy 94.745832 -180.993723) (xy 94.746318 -181.020974) (xy 94.745868 -181.048886)
			(xy 94.737722 -181.104114) (xy 94.721617 -181.157565) (xy 94.697895 -181.208099) (xy 94.667063 -181.254637)
			(xy 94.648782 -181.275736) (xy 94.642432 -181.282848) (xy 94.635828 -181.30012) (xy 94.635828 -181.387242)
			(xy 94.642432 -181.404514) (xy 94.648782 -181.411626) (xy 94.667044 -181.432739) (xy 94.697874 -181.479274)
			(xy 94.721593 -181.529805) (xy 94.737693 -181.583253) (xy 94.745831 -181.638478) (xy 94.746318 -181.666388)
			(xy 94.745832 -181.693639) (xy 94.738076 -181.747587) (xy 94.722721 -181.799882) (xy 94.700079 -181.849459)
			(xy 94.670613 -181.895309) (xy 94.634922 -181.9365) (xy 94.593731 -181.972191) (xy 94.547881 -182.001657)
			(xy 94.498304 -182.024299) (xy 94.446009 -182.039654) (xy 94.392061 -182.04741) (xy 94.337559 -182.04741)
			(xy 94.283611 -182.039654) (xy 94.231316 -182.024299) (xy 94.181739 -182.001657) (xy 94.135889 -181.972191)
			(xy 94.094698 -181.9365) (xy 94.059007 -181.895309) (xy 94.029541 -181.849459) (xy 94.006899 -181.799882)
			(xy 93.991544 -181.747587) (xy 93.983788 -181.693639) (xy 93.983302 -181.666388) (xy 90.551508 -181.666388)
			(xy 90.551508 -182.34533) (xy 90.551136 -182.369306) (xy 90.54363 -182.416668) (xy 90.528807 -182.462272)
			(xy 90.507032 -182.504996) (xy 90.478841 -182.543787) (xy 90.444929 -182.57769) (xy 90.406131 -182.605871)
			(xy 90.363402 -182.627636) (xy 90.317794 -182.642447) (xy 90.27043 -182.649942) (xy 90.246454 -182.650384)
			(xy 88.66886 -182.650384) (xy 88.65743 -182.653178) (xy 88.652096 -182.655972) (xy 88.630646 -182.666349)
			(xy 88.585313 -182.681026) (xy 88.538252 -182.688496) (xy 88.514428 -182.688992) (xy 87.385652 -182.688992)
			(xy 87.375648 -182.688528) (xy 87.357186 -182.68081) (xy 87.349838 -182.674006) (xy 86.948518 -182.272686)
			(xy 86.941775 -182.265298) (xy 86.934065 -182.246861) (xy 86.933532 -182.236872) (xy 86.933532 -181.256178)
			(xy 86.933166 -181.246132) (xy 86.925576 -181.227535) (xy 86.9188 -181.22011) (xy 86.285832 -180.587142)
			(xy 86.279157 -180.579727) (xy 86.271579 -180.561293) (xy 86.2711 -180.551328) (xy 86.2711 -177.200052)
			(xy 86.270674 -177.189982) (xy 86.262957 -177.171383) (xy 86.256114 -177.163984) (xy 86.159086 -177.066956)
			(xy 86.151601 -177.060268) (xy 86.133045 -177.052674) (xy 86.123018 -177.052224) (xy 82.399886 -177.052224)
			(xy 82.375881 -177.051777) (xy 82.328467 -177.044228) (xy 82.28282 -177.029349) (xy 82.240064 -177.007508)
			(xy 82.201255 -176.979242) (xy 82.183986 -176.962562) (xy 82.183986 -176.962308) (xy 81.87436 -176.652682)
			(xy 81.86697 -176.64583) (xy 81.848363 -176.638118) (xy 81.838292 -176.637696) (xy 81.09839 -176.637696)
			(xy 81.088317 -176.638091) (xy 81.069718 -176.64583) (xy 81.062322 -176.652682) (xy 81.02346 -176.691544)
			(xy 81.016759 -176.69902) (xy 81.009173 -176.717583) (xy 81.008728 -176.727612) (xy 81.008728 -178.404012)
			(xy 81.978246 -178.404012) (xy 81.978732 -178.376761) (xy 81.986488 -178.322813) (xy 82.001843 -178.270518)
			(xy 82.024485 -178.220941) (xy 82.053951 -178.175091) (xy 82.089642 -178.1339) (xy 82.130833 -178.098209)
			(xy 82.176683 -178.068743) (xy 82.22626 -178.046101) (xy 82.278555 -178.030746) (xy 82.332503 -178.02299)
			(xy 82.387005 -178.02299) (xy 82.440953 -178.030746) (xy 82.493248 -178.046101) (xy 82.542825 -178.068743)
			(xy 82.588675 -178.098209) (xy 82.629866 -178.1339) (xy 82.665557 -178.175091) (xy 82.695023 -178.220941)
			(xy 82.717665 -178.270518) (xy 82.73302 -178.322813) (xy 82.740776 -178.376761) (xy 82.741262 -178.404012)
			(xy 82.740596 -178.435575) (xy 82.730212 -178.49784) (xy 82.709729 -178.557549) (xy 82.695288 -178.585622)
			(xy 82.690462 -178.594512) (xy 82.68843 -178.61407) (xy 82.714084 -178.702208) (xy 82.72653 -178.717702)
			(xy 82.73542 -178.722782) (xy 82.742786 -178.726846) (xy 82.752438 -178.732688) (xy 82.774536 -178.73472)
			(xy 82.869024 -178.701192) (xy 82.885026 -178.685698) (xy 82.88909 -178.675284) (xy 82.899769 -178.6485)
			(xy 82.928059 -178.598258) (xy 82.963592 -178.552849) (xy 83.005556 -178.513307) (xy 83.052996 -178.480534)
			(xy 83.104829 -178.455277) (xy 83.159874 -178.438113) (xy 83.216876 -178.429432) (xy 83.245706 -178.428904)
			(xy 83.272958 -178.429366) (xy 83.326907 -178.437124) (xy 83.379202 -178.45248) (xy 83.42878 -178.475122)
			(xy 83.474631 -178.504589) (xy 83.515822 -178.540282) (xy 83.551514 -178.581473) (xy 83.580981 -178.627325)
			(xy 83.603622 -178.676903) (xy 83.618978 -178.729199) (xy 83.626734 -178.783148) (xy 83.626734 -178.837652)
			(xy 83.618978 -178.891601) (xy 83.609628 -178.923442) (xy 83.868514 -178.923442) (xy 83.869022 -178.895968)
			(xy 83.876908 -178.841589) (xy 83.892523 -178.788907) (xy 83.915543 -178.739014) (xy 83.94549 -178.692944)
			(xy 83.963256 -178.671982) (xy 83.969352 -178.66487) (xy 83.975702 -178.647852) (xy 83.975702 -178.562)
			(xy 83.969352 -178.544982) (xy 83.963256 -178.53787) (xy 83.94549 -178.51691) (xy 83.915567 -178.470827)
			(xy 83.892555 -178.420932) (xy 83.87693 -178.368255) (xy 83.869013 -178.313882) (xy 83.868514 -178.28641)
			(xy 83.869 -178.259159) (xy 83.876756 -178.205211) (xy 83.892111 -178.152916) (xy 83.914753 -178.103339)
			(xy 83.944219 -178.057489) (xy 83.97991 -178.016298) (xy 84.021101 -177.980607) (xy 84.066951 -177.951141)
			(xy 84.116528 -177.928499) (xy 84.168823 -177.913144) (xy 84.222771 -177.905388) (xy 84.277273 -177.905388)
			(xy 84.331221 -177.913144) (xy 84.383516 -177.928499) (xy 84.433093 -177.951141) (xy 84.478943 -177.980607)
			(xy 84.520134 -178.016298) (xy 84.555825 -178.057489) (xy 84.585291 -178.103339) (xy 84.607933 -178.152916)
			(xy 84.623288 -178.205211) (xy 84.631044 -178.259159) (xy 84.63153 -178.28641) (xy 84.631042 -178.313884)
			(xy 84.62315 -178.368264) (xy 84.607529 -178.420946) (xy 84.584505 -178.470839) (xy 84.554555 -178.516908)
			(xy 84.536788 -178.53787) (xy 84.530692 -178.544982) (xy 84.524342 -178.562) (xy 84.524342 -178.647852)
			(xy 84.530692 -178.66487) (xy 84.536788 -178.671982) (xy 84.554523 -178.692968) (xy 84.584452 -178.739043)
			(xy 84.607471 -178.788931) (xy 84.623104 -178.841603) (xy 84.631027 -178.895971) (xy 84.63153 -178.923442)
			(xy 84.631044 -178.950693) (xy 84.629411 -178.96205) (xy 85.20633 -178.96205) (xy 85.210401 -178.906428)
			(xy 85.222527 -178.851991) (xy 85.24245 -178.7999) (xy 85.269746 -178.751265) (xy 85.303832 -178.707122)
			(xy 85.343981 -178.668413) (xy 85.389339 -178.635962) (xy 85.438939 -178.610461) (xy 85.491723 -178.592454)
			(xy 85.546566 -178.582324) (xy 85.6023 -178.580287) (xy 85.657737 -178.586387) (xy 85.711694 -178.600493)
			(xy 85.763023 -178.622305) (xy 85.810629 -178.651359) (xy 85.853497 -178.687034) (xy 85.890714 -178.728571)
			(xy 85.921487 -178.775084) (xy 85.945159 -178.825581) (xy 85.961227 -178.878988) (xy 85.969347 -178.934164)
			(xy 85.969856 -178.96205) (xy 85.969347 -178.989936) (xy 85.961227 -179.045112) (xy 85.945159 -179.098519)
			(xy 85.921487 -179.149016) (xy 85.890714 -179.195529) (xy 85.853497 -179.237066) (xy 85.810629 -179.272741)
			(xy 85.763023 -179.301795) (xy 85.711694 -179.323607) (xy 85.657737 -179.337713) (xy 85.6023 -179.343813)
			(xy 85.546566 -179.341776) (xy 85.491723 -179.331646) (xy 85.438939 -179.313639) (xy 85.389339 -179.288138)
			(xy 85.343981 -179.255687) (xy 85.303832 -179.216978) (xy 85.269746 -179.172835) (xy 85.24245 -179.1242)
			(xy 85.222527 -179.072109) (xy 85.210401 -179.017672) (xy 85.20633 -178.96205) (xy 84.629411 -178.96205)
			(xy 84.623288 -179.004641) (xy 84.607933 -179.056936) (xy 84.585291 -179.106513) (xy 84.555825 -179.152363)
			(xy 84.520134 -179.193554) (xy 84.478943 -179.229245) (xy 84.433093 -179.258711) (xy 84.383516 -179.281353)
			(xy 84.331221 -179.296708) (xy 84.277273 -179.304464) (xy 84.222771 -179.304464) (xy 84.168823 -179.296708)
			(xy 84.116528 -179.281353) (xy 84.066951 -179.258711) (xy 84.021101 -179.229245) (xy 83.97991 -179.193554)
			(xy 83.944219 -179.152363) (xy 83.914753 -179.106513) (xy 83.892111 -179.056936) (xy 83.876756 -179.004641)
			(xy 83.869 -178.950693) (xy 83.868514 -178.923442) (xy 83.609628 -178.923442) (xy 83.603622 -178.943897)
			(xy 83.580981 -178.993475) (xy 83.551514 -179.039327) (xy 83.515822 -179.080518) (xy 83.474631 -179.116211)
			(xy 83.42878 -179.145678) (xy 83.379202 -179.16832) (xy 83.326907 -179.183676) (xy 83.272958 -179.191434)
			(xy 83.245706 -179.19192) (xy 83.220471 -179.191518) (xy 83.170437 -179.184901) (xy 83.121717 -179.171729)
			(xy 83.075165 -179.152234) (xy 83.053174 -179.13985) (xy 83.043522 -179.134008) (xy 83.021424 -179.131976)
			(xy 82.926936 -179.165504) (xy 82.910934 -179.180998) (xy 82.90687 -179.191412) (xy 82.896139 -179.218173)
			(xy 82.867855 -179.268413) (xy 82.83233 -179.313822) (xy 82.790373 -179.353365) (xy 82.742941 -179.38614)
			(xy 82.691115 -179.411401) (xy 82.636077 -179.428571) (xy 82.579081 -179.437259) (xy 82.550254 -179.437792)
			(xy 82.523001 -179.437365) (xy 82.46905 -179.429602) (xy 82.416753 -179.41424) (xy 82.367175 -179.391592)
			(xy 82.321324 -179.36212) (xy 82.280134 -179.326422) (xy 82.244443 -179.285226) (xy 82.214978 -179.239371)
			(xy 82.192338 -179.189788) (xy 82.176985 -179.137489) (xy 82.169231 -179.083537) (xy 82.168746 -179.056284)
			(xy 82.169409 -179.024721) (xy 82.179794 -178.962456) (xy 82.200279 -178.902747) (xy 82.21472 -178.874674)
			(xy 82.219546 -178.865784) (xy 82.221578 -178.846226) (xy 82.195924 -178.758088) (xy 82.183478 -178.742594)
			(xy 82.174588 -178.737514) (xy 82.149462 -178.723006) (xy 82.10358 -178.687496) (xy 82.063607 -178.645445)
			(xy 82.030465 -178.597824) (xy 82.004918 -178.545733) (xy 81.987557 -178.490372) (xy 81.978782 -178.433021)
			(xy 81.978246 -178.404012) (xy 81.008728 -178.404012) (xy 81.008728 -179.156868) (xy 81.00908 -179.166915)
			(xy 81.016681 -179.185511) (xy 81.02346 -179.192936) (xy 81.687924 -179.8574) (xy 84.62721 -179.8574)
			(xy 84.631281 -179.801778) (xy 84.643407 -179.747341) (xy 84.66333 -179.69525) (xy 84.690626 -179.646615)
			(xy 84.724712 -179.602472) (xy 84.764861 -179.563763) (xy 84.810219 -179.531312) (xy 84.859819 -179.505811)
			(xy 84.912603 -179.487804) (xy 84.967446 -179.477674) (xy 85.02318 -179.475637) (xy 85.078617 -179.481737)
			(xy 85.132574 -179.495843) (xy 85.183903 -179.517655) (xy 85.231509 -179.546709) (xy 85.274377 -179.582384)
			(xy 85.311594 -179.623921) (xy 85.342367 -179.670434) (xy 85.366039 -179.720931) (xy 85.382107 -179.774338)
			(xy 85.390227 -179.829514) (xy 85.390736 -179.8574) (xy 85.390227 -179.885286) (xy 85.382107 -179.940462)
			(xy 85.366039 -179.993869) (xy 85.342367 -180.044366) (xy 85.311594 -180.090879) (xy 85.274377 -180.132416)
			(xy 85.231509 -180.168091) (xy 85.183903 -180.197145) (xy 85.132574 -180.218957) (xy 85.078617 -180.233063)
			(xy 85.02318 -180.239163) (xy 84.967446 -180.237126) (xy 84.912603 -180.226996) (xy 84.859819 -180.208989)
			(xy 84.810219 -180.183488) (xy 84.764861 -180.151037) (xy 84.724712 -180.112328) (xy 84.690626 -180.068185)
			(xy 84.66333 -180.01955) (xy 84.643407 -179.967459) (xy 84.631281 -179.913022) (xy 84.62721 -179.8574)
			(xy 81.687924 -179.8574) (xy 82.142838 -180.312314) (xy 82.149589 -180.319696) (xy 82.157292 -180.338138)
			(xy 82.157824 -180.348128) (xy 82.157824 -181.73446) (xy 85.586062 -181.73446) (xy 85.586538 -181.706549)
			(xy 85.594677 -181.651322) (xy 85.610777 -181.597872) (xy 85.634494 -181.547337) (xy 85.66532 -181.500798)
			(xy 85.683598 -181.479698) (xy 85.689948 -181.472586) (xy 85.696552 -181.455314) (xy 85.696552 -181.368192)
			(xy 85.689948 -181.35092) (xy 85.683598 -181.343808) (xy 85.665302 -181.322723) (xy 85.634477 -181.276181)
			(xy 85.610765 -181.225642) (xy 85.594673 -181.172188) (xy 85.586544 -181.116958) (xy 85.586062 -181.089046)
			(xy 85.586548 -181.061795) (xy 85.594304 -181.007847) (xy 85.609659 -180.955552) (xy 85.632301 -180.905975)
			(xy 85.661767 -180.860125) (xy 85.697458 -180.818934) (xy 85.738649 -180.783243) (xy 85.784499 -180.753777)
			(xy 85.834076 -180.731135) (xy 85.886371 -180.71578) (xy 85.940319 -180.708024) (xy 85.994821 -180.708024)
			(xy 86.048769 -180.71578) (xy 86.101064 -180.731135) (xy 86.150641 -180.753777) (xy 86.196491 -180.783243)
			(xy 86.237682 -180.818934) (xy 86.273373 -180.860125) (xy 86.302839 -180.905975) (xy 86.325481 -180.955552)
			(xy 86.340836 -181.007847) (xy 86.348592 -181.061795) (xy 86.349078 -181.089046) (xy 86.348596 -181.116957)
			(xy 86.340456 -181.172183) (xy 86.324357 -181.225633) (xy 86.300643 -181.276167) (xy 86.269818 -181.322707)
			(xy 86.251542 -181.343808) (xy 86.245192 -181.35092) (xy 86.238588 -181.368192) (xy 86.238588 -181.455314)
			(xy 86.245192 -181.472586) (xy 86.251542 -181.479698) (xy 86.2698 -181.500814) (xy 86.300629 -181.547349)
			(xy 86.324347 -181.597879) (xy 86.340449 -181.651327) (xy 86.348589 -181.70655) (xy 86.349078 -181.73446)
			(xy 86.348592 -181.761711) (xy 86.340836 -181.815659) (xy 86.325481 -181.867954) (xy 86.302839 -181.917531)
			(xy 86.273373 -181.963381) (xy 86.237682 -182.004572) (xy 86.196491 -182.040263) (xy 86.150641 -182.069729)
			(xy 86.101064 -182.092371) (xy 86.048769 -182.107726) (xy 85.994821 -182.115482) (xy 85.940319 -182.115482)
			(xy 85.886371 -182.107726) (xy 85.834076 -182.092371) (xy 85.784499 -182.069729) (xy 85.738649 -182.040263)
			(xy 85.697458 -182.004572) (xy 85.661767 -181.963381) (xy 85.632301 -181.917531) (xy 85.609659 -181.867954)
			(xy 85.594304 -181.815659) (xy 85.586548 -181.761711) (xy 85.586062 -181.73446) (xy 82.157824 -181.73446)
			(xy 82.157824 -182.413402) (xy 82.157409 -182.437389) (xy 82.149899 -182.484773) (xy 82.135066 -182.530397)
			(xy 82.113273 -182.573137) (xy 82.08506 -182.611938) (xy 82.051121 -182.645846) (xy 82.012292 -182.674023)
			(xy 81.969532 -182.695775) (xy 81.923894 -182.710566) (xy 81.876504 -182.718031) (xy 81.852516 -182.718456)
			(xy 80.287622 -182.718456) (xy 80.280728 -182.718668) (xy 80.267456 -182.722411) (xy 80.26146 -182.725822)
			(xy 80.237568 -182.739449) (xy 80.186094 -182.758816) (xy 80.131986 -182.768666) (xy 80.104488 -182.769256)
			(xy 78.349094 -182.769256) (xy 78.344216 -182.769165) (xy 78.334628 -182.76737) (xy 78.330044 -182.7657)
			(xy 78.234286 -182.726838) (xy 78.229455 -182.724758) (xy 78.220749 -182.718858) (xy 78.217014 -182.715154)
			(xy 78.181708 -182.678578) (xy 78.180946 -182.67807) (xy 78.107032 -182.604156) (xy 78.090425 -182.586837)
			(xy 78.062235 -182.548013) (xy 78.040457 -182.505261) (xy 78.025625 -182.459632) (xy 78.018105 -182.412245)
			(xy 78.017624 -182.388256) (xy 78.017624 -177.314352) (xy 78.018121 -177.304387) (xy 78.025682 -177.285952)
			(xy 78.032356 -177.278538) (xy 78.46822 -176.842674) (xy 78.47491 -176.83519) (xy 78.482503 -176.816633)
			(xy 78.482952 -176.806606) (xy 78.482952 -175.567594) (xy 78.482573 -175.557549) (xy 78.474991 -175.538953)
			(xy 78.46822 -175.531526) (xy 78.032356 -175.095662) (xy 78.025693 -175.088238) (xy 78.018107 -175.069811)
			(xy 78.017624 -175.059848) (xy 78.017624 -172.439584) (xy 78.017227 -172.429511) (xy 78.009488 -172.410913)
			(xy 78.002638 -172.403516) (xy 77.517752 -171.91863) (xy 77.510324 -171.911825) (xy 77.491746 -171.904084)
			(xy 77.481684 -171.903644) (xy 74.4093 -171.903644) (xy 74.385304 -171.903187) (xy 74.337896 -171.895721)
			(xy 74.292247 -171.880912) (xy 74.249486 -171.859125) (xy 74.210672 -171.8309) (xy 74.1934 -171.814236)
			(xy 74.1934 -171.813982) (xy 73.371456 -170.992038) (xy 73.364061 -170.985192) (xy 73.345458 -170.977474)
			(xy 73.335388 -170.977052) (xy 73.015094 -170.977052) (xy 73.005023 -170.97746) (xy 72.986424 -170.985191)
			(xy 72.979026 -170.992038) (xy 72.97674 -170.994324) (xy 72.970045 -171.001804) (xy 72.962456 -171.020364)
			(xy 72.962008 -171.030392) (xy 72.962008 -173.285912) (xy 73.654666 -173.285912) (xy 73.655152 -173.258661)
			(xy 73.662908 -173.204713) (xy 73.678263 -173.152418) (xy 73.700905 -173.102841) (xy 73.730371 -173.056991)
			(xy 73.766062 -173.0158) (xy 73.807253 -172.980109) (xy 73.853103 -172.950643) (xy 73.90268 -172.928001)
			(xy 73.954975 -172.912646) (xy 74.008923 -172.90489) (xy 74.063425 -172.90489) (xy 74.117373 -172.912646)
			(xy 74.169668 -172.928001) (xy 74.219245 -172.950643) (xy 74.265095 -172.980109) (xy 74.306286 -173.0158)
			(xy 74.341977 -173.056991) (xy 74.371443 -173.102841) (xy 74.394085 -173.152418) (xy 74.40944 -173.204713)
			(xy 74.417196 -173.258661) (xy 74.417682 -173.285912) (xy 74.417014 -173.317474) (xy 74.40663 -173.379739)
			(xy 74.386148 -173.439449) (xy 74.371708 -173.467522) (xy 74.366882 -173.476412) (xy 74.36485 -173.49597)
			(xy 74.390504 -173.584108) (xy 74.40295 -173.599602) (xy 74.41184 -173.604682) (xy 74.419206 -173.608746)
			(xy 74.428858 -173.614588) (xy 74.450956 -173.61662) (xy 74.545444 -173.583092) (xy 74.561446 -173.567598)
			(xy 74.56551 -173.557184) (xy 74.576173 -173.530393) (xy 74.604465 -173.480151) (xy 74.639999 -173.43474)
			(xy 74.681966 -173.395199) (xy 74.729408 -173.362426) (xy 74.781244 -173.337171) (xy 74.836291 -173.320009)
			(xy 74.893296 -173.311331) (xy 74.922126 -173.310804) (xy 74.949377 -173.311268) (xy 75.003324 -173.319027)
			(xy 75.055617 -173.334385) (xy 75.105192 -173.357029) (xy 75.151041 -173.386496) (xy 75.192229 -173.422189)
			(xy 75.227919 -173.46338) (xy 75.257384 -173.509231) (xy 75.280024 -173.558808) (xy 75.295378 -173.611102)
			(xy 75.303134 -173.665049) (xy 75.303134 -173.719551) (xy 75.295378 -173.773498) (xy 75.286028 -173.805342)
			(xy 75.544934 -173.805342) (xy 75.545437 -173.777868) (xy 75.553323 -173.723489) (xy 75.568939 -173.670806)
			(xy 75.59196 -173.620913) (xy 75.621909 -173.574844) (xy 75.639676 -173.553882) (xy 75.645772 -173.54677)
			(xy 75.652122 -173.529752) (xy 75.652122 -173.4439) (xy 75.645772 -173.426882) (xy 75.639676 -173.41977)
			(xy 75.621913 -173.398807) (xy 75.591989 -173.352725) (xy 75.568976 -173.302831) (xy 75.55335 -173.250154)
			(xy 75.545433 -173.195782) (xy 75.544934 -173.16831) (xy 75.54542 -173.141059) (xy 75.553176 -173.087111)
			(xy 75.568531 -173.034816) (xy 75.591173 -172.985239) (xy 75.620639 -172.939389) (xy 75.65633 -172.898198)
			(xy 75.697521 -172.862507) (xy 75.743371 -172.833041) (xy 75.792948 -172.810399) (xy 75.845243 -172.795044)
			(xy 75.899191 -172.787288) (xy 75.953693 -172.787288) (xy 76.007641 -172.795044) (xy 76.059936 -172.810399)
			(xy 76.109513 -172.833041) (xy 76.155363 -172.862507) (xy 76.196554 -172.898198) (xy 76.232245 -172.939389)
			(xy 76.261711 -172.985239) (xy 76.284353 -173.034816) (xy 76.299708 -173.087111) (xy 76.307464 -173.141059)
			(xy 76.30795 -173.16831) (xy 76.307482 -173.195785) (xy 76.299587 -173.250166) (xy 76.283964 -173.302849)
			(xy 76.260935 -173.352742) (xy 76.230978 -173.398809) (xy 76.213208 -173.41977) (xy 76.207112 -173.426882)
			(xy 76.200762 -173.4439) (xy 76.200762 -173.529752) (xy 76.207112 -173.54677) (xy 76.213208 -173.553882)
			(xy 76.230946 -173.574865) (xy 76.260874 -173.620941) (xy 76.283892 -173.67083) (xy 76.299524 -173.723502)
			(xy 76.307447 -173.777871) (xy 76.30795 -173.805342) (xy 76.307464 -173.832593) (xy 76.305831 -173.84395)
			(xy 76.88275 -173.84395) (xy 76.886821 -173.788328) (xy 76.898947 -173.733891) (xy 76.91887 -173.6818)
			(xy 76.946166 -173.633165) (xy 76.980252 -173.589022) (xy 77.020401 -173.550313) (xy 77.065759 -173.517862)
			(xy 77.115359 -173.492361) (xy 77.168143 -173.474354) (xy 77.222986 -173.464224) (xy 77.27872 -173.462187)
			(xy 77.334157 -173.468287) (xy 77.388114 -173.482393) (xy 77.439443 -173.504205) (xy 77.487049 -173.533259)
			(xy 77.529917 -173.568934) (xy 77.567134 -173.610471) (xy 77.597907 -173.656984) (xy 77.621579 -173.707481)
			(xy 77.637647 -173.760888) (xy 77.645767 -173.816064) (xy 77.646276 -173.84395) (xy 77.645767 -173.871836)
			(xy 77.637647 -173.927012) (xy 77.621579 -173.980419) (xy 77.597907 -174.030916) (xy 77.567134 -174.077429)
			(xy 77.529917 -174.118966) (xy 77.487049 -174.154641) (xy 77.439443 -174.183695) (xy 77.388114 -174.205507)
			(xy 77.334157 -174.219613) (xy 77.27872 -174.225713) (xy 77.222986 -174.223676) (xy 77.168143 -174.213546)
			(xy 77.115359 -174.195539) (xy 77.065759 -174.170038) (xy 77.020401 -174.137587) (xy 76.980252 -174.098878)
			(xy 76.946166 -174.054735) (xy 76.91887 -174.0061) (xy 76.898947 -173.954009) (xy 76.886821 -173.899572)
			(xy 76.88275 -173.84395) (xy 76.305831 -173.84395) (xy 76.299708 -173.886541) (xy 76.284353 -173.938836)
			(xy 76.261711 -173.988413) (xy 76.232245 -174.034263) (xy 76.196554 -174.075454) (xy 76.155363 -174.111145)
			(xy 76.109513 -174.140611) (xy 76.059936 -174.163253) (xy 76.007641 -174.178608) (xy 75.953693 -174.186364)
			(xy 75.899191 -174.186364) (xy 75.845243 -174.178608) (xy 75.792948 -174.163253) (xy 75.743371 -174.140611)
			(xy 75.697521 -174.111145) (xy 75.65633 -174.075454) (xy 75.620639 -174.034263) (xy 75.591173 -173.988413)
			(xy 75.568531 -173.938836) (xy 75.553176 -173.886541) (xy 75.54542 -173.832593) (xy 75.544934 -173.805342)
			(xy 75.286028 -173.805342) (xy 75.280024 -173.825792) (xy 75.257384 -173.875369) (xy 75.227919 -173.92122)
			(xy 75.192229 -173.962411) (xy 75.151041 -173.998104) (xy 75.105192 -174.027571) (xy 75.055617 -174.050215)
			(xy 75.003324 -174.065573) (xy 74.949377 -174.073332) (xy 74.922126 -174.07382) (xy 74.89689 -174.073453)
			(xy 74.846855 -174.066825) (xy 74.798134 -174.053644) (xy 74.751584 -174.034139) (xy 74.729594 -174.02175)
			(xy 74.719942 -174.015908) (xy 74.697844 -174.013876) (xy 74.603356 -174.047404) (xy 74.587354 -174.062898)
			(xy 74.58329 -174.073312) (xy 74.572625 -174.100102) (xy 74.544334 -174.150345) (xy 74.5088 -174.195755)
			(xy 74.466833 -174.235297) (xy 74.419391 -174.268069) (xy 74.367556 -174.293325) (xy 74.312508 -174.310487)
			(xy 74.255504 -174.319165) (xy 74.226674 -174.319692) (xy 74.199421 -174.319246) (xy 74.145471 -174.311486)
			(xy 74.093175 -174.296127) (xy 74.043597 -174.273481) (xy 73.997745 -174.244011) (xy 73.956555 -174.208315)
			(xy 73.920864 -174.167121) (xy 73.891399 -174.121267) (xy 73.868759 -174.071686) (xy 73.853405 -174.019388)
			(xy 73.845651 -173.965437) (xy 73.845166 -173.938184) (xy 73.845839 -173.906622) (xy 73.856221 -173.844357)
			(xy 73.876701 -173.784648) (xy 73.89114 -173.756574) (xy 73.895966 -173.747684) (xy 73.897998 -173.728126)
			(xy 73.872344 -173.639988) (xy 73.859898 -173.624494) (xy 73.851008 -173.619414) (xy 73.825887 -173.604898)
			(xy 73.780004 -173.56939) (xy 73.74003 -173.527341) (xy 73.706886 -173.479721) (xy 73.681339 -173.427631)
			(xy 73.663977 -173.372272) (xy 73.655202 -173.314921) (xy 73.654666 -173.285912) (xy 72.962008 -173.285912)
			(xy 72.962008 -174.358808) (xy 72.962397 -174.368851) (xy 72.969972 -174.387447) (xy 72.97674 -174.394876)
			(xy 73.321164 -174.7393) (xy 76.30363 -174.7393) (xy 76.307701 -174.683678) (xy 76.319827 -174.629241)
			(xy 76.33975 -174.57715) (xy 76.367046 -174.528515) (xy 76.401132 -174.484372) (xy 76.441281 -174.445663)
			(xy 76.486639 -174.413212) (xy 76.536239 -174.387711) (xy 76.589023 -174.369704) (xy 76.643866 -174.359574)
			(xy 76.6996 -174.357537) (xy 76.755037 -174.363637) (xy 76.808994 -174.377743) (xy 76.860323 -174.399555)
			(xy 76.907929 -174.428609) (xy 76.950797 -174.464284) (xy 76.988014 -174.505821) (xy 77.018787 -174.552334)
			(xy 77.042459 -174.602831) (xy 77.058527 -174.656238) (xy 77.066647 -174.711414) (xy 77.067156 -174.7393)
			(xy 77.066647 -174.767186) (xy 77.058527 -174.822362) (xy 77.042459 -174.875769) (xy 77.018787 -174.926266)
			(xy 76.988014 -174.972779) (xy 76.950797 -175.014316) (xy 76.907929 -175.049991) (xy 76.860323 -175.079045)
			(xy 76.808994 -175.100857) (xy 76.755037 -175.114963) (xy 76.6996 -175.121063) (xy 76.643866 -175.119026)
			(xy 76.589023 -175.108896) (xy 76.536239 -175.090889) (xy 76.486639 -175.065388) (xy 76.441281 -175.032937)
			(xy 76.401132 -174.994228) (xy 76.367046 -174.950085) (xy 76.33975 -174.90145) (xy 76.319827 -174.849359)
			(xy 76.307701 -174.794922) (xy 76.30363 -174.7393) (xy 73.321164 -174.7393) (xy 73.819258 -175.237394)
			(xy 73.825989 -175.244792) (xy 73.833706 -175.263221) (xy 73.834244 -175.273208) (xy 73.834244 -176.61636)
			(xy 77.262482 -176.61636) (xy 77.262953 -176.588448) (xy 77.271093 -176.533222) (xy 77.287194 -176.479771)
			(xy 77.310911 -176.429236) (xy 77.341739 -176.382697) (xy 77.360018 -176.361598) (xy 77.366368 -176.354486)
			(xy 77.372972 -176.337214) (xy 77.372972 -176.250092) (xy 77.366368 -176.23282) (xy 77.360018 -176.225708)
			(xy 77.341725 -176.204621) (xy 77.310899 -176.158079) (xy 77.287187 -176.107542) (xy 77.271094 -176.054087)
			(xy 77.262964 -175.998858) (xy 77.262482 -175.970946) (xy 77.262968 -175.943695) (xy 77.270724 -175.889747)
			(xy 77.286079 -175.837452) (xy 77.308721 -175.787875) (xy 77.338187 -175.742025) (xy 77.373878 -175.700834)
			(xy 77.415069 -175.665143) (xy 77.460919 -175.635677) (xy 77.510496 -175.613035) (xy 77.562791 -175.59768)
			(xy 77.616739 -175.589924) (xy 77.671241 -175.589924) (xy 77.725189 -175.59768) (xy 77.777484 -175.613035)
			(xy 77.827061 -175.635677) (xy 77.872911 -175.665143) (xy 77.914102 -175.700834) (xy 77.949793 -175.742025)
			(xy 77.979259 -175.787875) (xy 78.001901 -175.837452) (xy 78.017256 -175.889747) (xy 78.025012 -175.943695)
			(xy 78.025498 -175.970946) (xy 78.025011 -175.998857) (xy 78.016871 -176.054082) (xy 78.000773 -176.107532)
			(xy 77.97706 -176.158066) (xy 77.946238 -176.204607) (xy 77.927962 -176.225708) (xy 77.921612 -176.23282)
			(xy 77.915008 -176.250092) (xy 77.915008 -176.337214) (xy 77.921612 -176.354486) (xy 77.927962 -176.361598)
			(xy 77.946223 -176.382711) (xy 77.977051 -176.429247) (xy 78.000768 -176.479778) (xy 78.016869 -176.533226)
			(xy 78.025009 -176.58845) (xy 78.025498 -176.61636) (xy 78.025012 -176.643611) (xy 78.017256 -176.697559)
			(xy 78.001901 -176.749854) (xy 77.979259 -176.799431) (xy 77.949793 -176.845281) (xy 77.914102 -176.886472)
			(xy 77.872911 -176.922163) (xy 77.827061 -176.951629) (xy 77.777484 -176.974271) (xy 77.725189 -176.989626)
			(xy 77.671241 -176.997382) (xy 77.616739 -176.997382) (xy 77.562791 -176.989626) (xy 77.510496 -176.974271)
			(xy 77.460919 -176.951629) (xy 77.415069 -176.922163) (xy 77.373878 -176.886472) (xy 77.338187 -176.845281)
			(xy 77.308721 -176.799431) (xy 77.286079 -176.749854) (xy 77.270724 -176.697559) (xy 77.262968 -176.643611)
			(xy 77.262482 -176.61636) (xy 73.834244 -176.61636) (xy 73.834244 -177.295302) (xy 73.833809 -177.319288)
			(xy 73.8263 -177.36667) (xy 73.811467 -177.412292) (xy 73.789677 -177.455031) (xy 73.761466 -177.493832)
			(xy 73.727529 -177.527739) (xy 73.688703 -177.555916) (xy 73.645946 -177.577669) (xy 73.600311 -177.592462)
			(xy 73.552923 -177.59993) (xy 73.528936 -177.600356) (xy 71.937626 -177.600356) (xy 71.927466 -177.605182)
			(xy 71.907116 -177.614363) (xy 71.864399 -177.627339) (xy 71.820247 -177.63395) (xy 71.797926 -177.634392)
			(xy 70.013576 -177.634392) (xy 70.008686 -177.634247) (xy 69.999093 -177.632334) (xy 69.994526 -177.630582)
			(xy 69.898768 -177.59172) (xy 69.893944 -177.589625) (xy 69.885234 -177.583735) (xy 69.881496 -177.580036)
			(xy 69.84619 -177.54346) (xy 69.845428 -177.542952) (xy 69.725032 -177.422556) (xy 69.708425 -177.405237)
			(xy 69.680235 -177.366413) (xy 69.658457 -177.323661) (xy 69.643625 -177.278032) (xy 69.636105 -177.230645)
			(xy 69.635624 -177.206656) (xy 69.635624 -168.856914) (xy 69.636102 -168.846947) (xy 69.643677 -168.828512)
			(xy 69.650356 -168.8211) (xy 70.09638 -168.375076) (xy 70.103077 -168.367598) (xy 70.110664 -168.349036)
			(xy 70.111112 -168.339008) (xy 70.111112 -166.852092) (xy 70.110744 -166.842046) (xy 70.103156 -166.823449)
			(xy 70.09638 -166.816024) (xy 69.650356 -166.37) (xy 69.64371 -166.362563) (xy 69.636114 -166.344146)
			(xy 69.635624 -166.334186) (xy 69.635624 -163.732464) (xy 69.635172 -163.722458) (xy 69.627448 -163.703995)
			(xy 69.620638 -163.69665) (xy 69.302122 -163.37788) (xy 69.294656 -163.371167) (xy 69.276085 -163.363587)
			(xy 69.266054 -163.363148) (xy 65.92951 -163.363148) (xy 65.905504 -163.362708) (xy 65.858089 -163.35516)
			(xy 65.812441 -163.340281) (xy 65.769685 -163.318438) (xy 65.730878 -163.290168) (xy 65.71361 -163.273486)
			(xy 65.4304 -162.990276) (xy 65.422961 -162.983633) (xy 65.404546 -162.976035) (xy 65.394586 -162.975544)
			(xy 64.552576 -162.975544) (xy 64.542531 -162.975915) (xy 64.523934 -162.983502) (xy 64.516508 -162.990276)
			(xy 64.51092 -162.995864) (xy 64.504205 -163.003328) (xy 64.496629 -163.021901) (xy 64.496188 -163.031932)
			(xy 64.496188 -164.588698) (xy 65.341246 -164.588698) (xy 65.341732 -164.561447) (xy 65.349488 -164.507499)
			(xy 65.364843 -164.455204) (xy 65.387485 -164.405627) (xy 65.416951 -164.359777) (xy 65.452642 -164.318586)
			(xy 65.493833 -164.282895) (xy 65.539683 -164.253429) (xy 65.58926 -164.230787) (xy 65.641555 -164.215432)
			(xy 65.695503 -164.207676) (xy 65.750005 -164.207676) (xy 65.803953 -164.215432) (xy 65.856248 -164.230787)
			(xy 65.905825 -164.253429) (xy 65.951675 -164.282895) (xy 65.992866 -164.318586) (xy 66.028557 -164.359777)
			(xy 66.058023 -164.405627) (xy 66.080665 -164.455204) (xy 66.09602 -164.507499) (xy 66.103776 -164.561447)
			(xy 66.104262 -164.588698) (xy 66.10363 -164.620262) (xy 66.093232 -164.682528) (xy 66.072735 -164.742237)
			(xy 66.058288 -164.770308) (xy 66.053462 -164.779198) (xy 66.05143 -164.798756) (xy 66.077084 -164.886894)
			(xy 66.08953 -164.902388) (xy 66.09842 -164.907468) (xy 66.105786 -164.911532) (xy 66.115438 -164.917374)
			(xy 66.137536 -164.919406) (xy 66.232024 -164.885878) (xy 66.248026 -164.870384) (xy 66.25209 -164.85997)
			(xy 66.262762 -164.833183) (xy 66.291054 -164.782942) (xy 66.326587 -164.737533) (xy 66.368553 -164.697991)
			(xy 66.415994 -164.665219) (xy 66.467828 -164.639963) (xy 66.522874 -164.622799) (xy 66.579876 -164.614118)
			(xy 66.608706 -164.61359) (xy 66.635957 -164.61408) (xy 66.689904 -164.621837) (xy 66.742197 -164.637193)
			(xy 66.791774 -164.659834) (xy 66.837623 -164.689301) (xy 66.878812 -164.724992) (xy 66.914503 -164.766182)
			(xy 66.943969 -164.812032) (xy 66.966609 -164.861608) (xy 66.981964 -164.913902) (xy 66.98972 -164.967849)
			(xy 66.98972 -165.022351) (xy 66.981964 -165.076298) (xy 66.972618 -165.108128) (xy 67.231514 -165.108128)
			(xy 67.232013 -165.080654) (xy 67.239902 -165.026275) (xy 67.255519 -164.973592) (xy 67.27854 -164.923699)
			(xy 67.30849 -164.87763) (xy 67.326256 -164.856668) (xy 67.332352 -164.849556) (xy 67.338702 -164.832538)
			(xy 67.338702 -164.746686) (xy 67.332352 -164.729668) (xy 67.326256 -164.722556) (xy 67.308484 -164.701601)
			(xy 67.278561 -164.655517) (xy 67.255551 -164.60562) (xy 67.239927 -164.552942) (xy 67.232012 -164.498569)
			(xy 67.231514 -164.471096) (xy 67.232 -164.443845) (xy 67.239756 -164.389897) (xy 67.255111 -164.337602)
			(xy 67.277753 -164.288025) (xy 67.307219 -164.242175) (xy 67.34291 -164.200984) (xy 67.384101 -164.165293)
			(xy 67.429951 -164.135827) (xy 67.479528 -164.113185) (xy 67.531823 -164.09783) (xy 67.585771 -164.090074)
			(xy 67.640273 -164.090074) (xy 67.694221 -164.09783) (xy 67.746516 -164.113185) (xy 67.796093 -164.135827)
			(xy 67.841943 -164.165293) (xy 67.883134 -164.200984) (xy 67.918825 -164.242175) (xy 67.948291 -164.288025)
			(xy 67.970933 -164.337602) (xy 67.986288 -164.389897) (xy 67.994044 -164.443845) (xy 67.99453 -164.471096)
			(xy 67.994034 -164.49857) (xy 67.986143 -164.552949) (xy 67.970525 -164.605631) (xy 67.947503 -164.655524)
			(xy 67.917554 -164.701593) (xy 67.899788 -164.722556) (xy 67.893692 -164.729668) (xy 67.887342 -164.746686)
			(xy 67.887342 -164.832538) (xy 67.893692 -164.849556) (xy 67.899788 -164.856668) (xy 67.917516 -164.877659)
			(xy 67.947447 -164.923733) (xy 67.970467 -164.97362) (xy 67.986101 -165.02629) (xy 67.994026 -165.080658)
			(xy 67.99453 -165.108128) (xy 67.994044 -165.135379) (xy 67.992411 -165.146736) (xy 68.56933 -165.146736)
			(xy 68.573401 -165.091114) (xy 68.585527 -165.036677) (xy 68.60545 -164.984586) (xy 68.632746 -164.935951)
			(xy 68.666832 -164.891808) (xy 68.706981 -164.853099) (xy 68.752339 -164.820648) (xy 68.801939 -164.795147)
			(xy 68.854723 -164.77714) (xy 68.909566 -164.76701) (xy 68.9653 -164.764973) (xy 69.020737 -164.771073)
			(xy 69.074694 -164.785179) (xy 69.126023 -164.806991) (xy 69.173629 -164.836045) (xy 69.216497 -164.87172)
			(xy 69.253714 -164.913257) (xy 69.284487 -164.95977) (xy 69.308159 -165.010267) (xy 69.324227 -165.063674)
			(xy 69.332347 -165.11885) (xy 69.332856 -165.146736) (xy 69.332347 -165.174622) (xy 69.324227 -165.229798)
			(xy 69.308159 -165.283205) (xy 69.284487 -165.333702) (xy 69.253714 -165.380215) (xy 69.216497 -165.421752)
			(xy 69.173629 -165.457427) (xy 69.126023 -165.486481) (xy 69.074694 -165.508293) (xy 69.020737 -165.522399)
			(xy 68.9653 -165.528499) (xy 68.909566 -165.526462) (xy 68.854723 -165.516332) (xy 68.801939 -165.498325)
			(xy 68.752339 -165.472824) (xy 68.706981 -165.440373) (xy 68.666832 -165.401664) (xy 68.632746 -165.357521)
			(xy 68.60545 -165.308886) (xy 68.585527 -165.256795) (xy 68.573401 -165.202358) (xy 68.56933 -165.146736)
			(xy 67.992411 -165.146736) (xy 67.986288 -165.189327) (xy 67.970933 -165.241622) (xy 67.948291 -165.291199)
			(xy 67.918825 -165.337049) (xy 67.883134 -165.37824) (xy 67.841943 -165.413931) (xy 67.796093 -165.443397)
			(xy 67.746516 -165.466039) (xy 67.694221 -165.481394) (xy 67.640273 -165.48915) (xy 67.585771 -165.48915)
			(xy 67.531823 -165.481394) (xy 67.479528 -165.466039) (xy 67.429951 -165.443397) (xy 67.384101 -165.413931)
			(xy 67.34291 -165.37824) (xy 67.307219 -165.337049) (xy 67.277753 -165.291199) (xy 67.255111 -165.241622)
			(xy 67.239756 -165.189327) (xy 67.232 -165.135379) (xy 67.231514 -165.108128) (xy 66.972618 -165.108128)
			(xy 66.966609 -165.128592) (xy 66.943969 -165.178168) (xy 66.914503 -165.224018) (xy 66.878812 -165.265208)
			(xy 66.837623 -165.300899) (xy 66.791774 -165.330366) (xy 66.742197 -165.353007) (xy 66.689904 -165.368363)
			(xy 66.635957 -165.37612) (xy 66.608706 -165.376606) (xy 66.583471 -165.376206) (xy 66.533437 -165.369588)
			(xy 66.484717 -165.356416) (xy 66.438165 -165.33692) (xy 66.416174 -165.324536) (xy 66.406522 -165.318694)
			(xy 66.384424 -165.316662) (xy 66.289936 -165.35019) (xy 66.273934 -165.365684) (xy 66.26987 -165.376098)
			(xy 66.259131 -165.402856) (xy 66.230849 -165.453096) (xy 66.195325 -165.498506) (xy 66.15337 -165.538049)
			(xy 66.105939 -165.570825) (xy 66.054114 -165.596086) (xy 65.999076 -165.613257) (xy 65.942081 -165.621945)
			(xy 65.913254 -165.622478) (xy 65.886 -165.622065) (xy 65.832048 -165.614301) (xy 65.77975 -165.598939)
			(xy 65.730171 -165.57629) (xy 65.684319 -165.546816) (xy 65.643129 -165.511117) (xy 65.607438 -165.46992)
			(xy 65.577973 -165.424062) (xy 65.555335 -165.374478) (xy 65.539982 -165.322177) (xy 65.53223 -165.268224)
			(xy 65.531746 -165.24097) (xy 65.532404 -165.209407) (xy 65.542791 -165.147142) (xy 65.563278 -165.087432)
			(xy 65.57772 -165.05936) (xy 65.582546 -165.05047) (xy 65.584578 -165.030912) (xy 65.558924 -164.942774)
			(xy 65.546478 -164.92728) (xy 65.537588 -164.9222) (xy 65.5125 -164.907631) (xy 65.466618 -164.87213)
			(xy 65.426643 -164.830089) (xy 65.393497 -164.782479) (xy 65.367944 -164.730398) (xy 65.350574 -164.675047)
			(xy 65.341788 -164.617704) (xy 65.341246 -164.588698) (xy 64.496188 -164.588698) (xy 64.496188 -165.499288)
			(xy 64.496514 -165.509338) (xy 64.504131 -165.527935) (xy 64.51092 -165.535356) (xy 65.01765 -166.042086)
			(xy 67.99021 -166.042086) (xy 67.994281 -165.986464) (xy 68.006407 -165.932027) (xy 68.02633 -165.879936)
			(xy 68.053626 -165.831301) (xy 68.087712 -165.787158) (xy 68.127861 -165.748449) (xy 68.173219 -165.715998)
			(xy 68.222819 -165.690497) (xy 68.275603 -165.67249) (xy 68.330446 -165.66236) (xy 68.38618 -165.660323)
			(xy 68.441617 -165.666423) (xy 68.495574 -165.680529) (xy 68.546903 -165.702341) (xy 68.594509 -165.731395)
			(xy 68.637377 -165.76707) (xy 68.674594 -165.808607) (xy 68.705367 -165.85512) (xy 68.729039 -165.905617)
			(xy 68.745107 -165.959024) (xy 68.753227 -166.0142) (xy 68.753736 -166.042086) (xy 68.753227 -166.069972)
			(xy 68.745107 -166.125148) (xy 68.729039 -166.178555) (xy 68.705367 -166.229052) (xy 68.674594 -166.275565)
			(xy 68.637377 -166.317102) (xy 68.594509 -166.352777) (xy 68.546903 -166.381831) (xy 68.495574 -166.403643)
			(xy 68.441617 -166.417749) (xy 68.38618 -166.423849) (xy 68.330446 -166.421812) (xy 68.275603 -166.411682)
			(xy 68.222819 -166.393675) (xy 68.173219 -166.368174) (xy 68.127861 -166.335723) (xy 68.087712 -166.297014)
			(xy 68.053626 -166.252871) (xy 68.02633 -166.204236) (xy 68.006407 -166.152145) (xy 67.994281 -166.097708)
			(xy 67.99021 -166.042086) (xy 65.01765 -166.042086) (xy 65.505838 -166.530274) (xy 65.512571 -166.53767)
			(xy 65.520285 -166.556101) (xy 65.520824 -166.566088) (xy 65.520824 -167.919146) (xy 68.949062 -167.919146)
			(xy 68.949529 -167.891234) (xy 68.957671 -167.836008) (xy 68.973773 -167.782557) (xy 68.997491 -167.732023)
			(xy 69.028319 -167.685484) (xy 69.046598 -167.664384) (xy 69.052948 -167.657272) (xy 69.059552 -167.64)
			(xy 69.059552 -167.552878) (xy 69.052948 -167.535606) (xy 69.046598 -167.528494) (xy 69.028343 -167.507376)
			(xy 68.997512 -167.460842) (xy 68.973792 -167.410313) (xy 68.957691 -167.356865) (xy 68.94955 -167.301642)
			(xy 68.949062 -167.273732) (xy 68.949548 -167.246481) (xy 68.957304 -167.192533) (xy 68.972659 -167.140238)
			(xy 68.995301 -167.090661) (xy 69.024767 -167.044811) (xy 69.060458 -167.00362) (xy 69.101649 -166.967929)
			(xy 69.147499 -166.938463) (xy 69.197076 -166.915821) (xy 69.249371 -166.900466) (xy 69.303319 -166.89271)
			(xy 69.357821 -166.89271) (xy 69.411769 -166.900466) (xy 69.464064 -166.915821) (xy 69.513641 -166.938463)
			(xy 69.559491 -166.967929) (xy 69.600682 -167.00362) (xy 69.636373 -167.044811) (xy 69.665839 -167.090661)
			(xy 69.688481 -167.140238) (xy 69.703836 -167.192533) (xy 69.711592 -167.246481) (xy 69.712078 -167.273732)
			(xy 69.711587 -167.301643) (xy 69.70345 -167.356868) (xy 69.687353 -167.410318) (xy 69.66364 -167.460853)
			(xy 69.632818 -167.507393) (xy 69.614542 -167.528494) (xy 69.608192 -167.535606) (xy 69.601588 -167.552878)
			(xy 69.601588 -167.64) (xy 69.608192 -167.657272) (xy 69.614542 -167.664384) (xy 69.63284 -167.685466)
			(xy 69.663664 -167.73201) (xy 69.687374 -167.782549) (xy 69.703466 -167.836004) (xy 69.711595 -167.891234)
			(xy 69.712078 -167.919146) (xy 69.711592 -167.946397) (xy 69.703836 -168.000345) (xy 69.688481 -168.05264)
			(xy 69.665839 -168.102217) (xy 69.636373 -168.148067) (xy 69.600682 -168.189258) (xy 69.559491 -168.224949)
			(xy 69.513641 -168.254415) (xy 69.464064 -168.277057) (xy 69.411769 -168.292412) (xy 69.357821 -168.300168)
			(xy 69.303319 -168.300168) (xy 69.249371 -168.292412) (xy 69.197076 -168.277057) (xy 69.147499 -168.254415)
			(xy 69.101649 -168.224949) (xy 69.060458 -168.189258) (xy 69.024767 -168.148067) (xy 68.995301 -168.102217)
			(xy 68.972659 -168.05264) (xy 68.957304 -168.000345) (xy 68.949548 -167.946397) (xy 68.949062 -167.919146)
			(xy 65.520824 -167.919146) (xy 65.520824 -168.596818) (xy 65.52038 -168.620823) (xy 65.51283 -168.668237)
			(xy 65.49795 -168.713885) (xy 65.476108 -168.75664) (xy 65.447842 -168.795449) (xy 65.431162 -168.812718)
			(xy 65.430146 -168.813734) (xy 65.412881 -168.830415) (xy 65.374063 -168.858662) (xy 65.331305 -168.880489)
			(xy 65.285659 -168.895359) (xy 65.238249 -168.902906) (xy 65.214246 -168.903396) (xy 63.639192 -168.903396)
			(xy 63.626746 -168.906444) (xy 63.621158 -168.909492) (xy 63.598501 -168.921435) (xy 63.550178 -168.938397)
			(xy 63.499698 -168.947032) (xy 63.474092 -168.947592) (xy 59.883294 -168.947592) (xy 59.859289 -168.947149)
			(xy 59.811874 -168.9396) (xy 59.766226 -168.924721) (xy 59.723471 -168.902878) (xy 59.684663 -168.874611)
			(xy 59.667394 -168.85793) (xy 59.438032 -168.628568) (xy 59.421431 -168.611243) (xy 59.39324 -168.572421)
			(xy 59.371461 -168.52967) (xy 59.356628 -168.484042) (xy 59.349106 -168.436657) (xy 59.348624 -168.412668)
			(xy 50.128424 -168.412668) (xy 50.128424 -171.906946) (xy 50.128889 -171.91682) (xy 50.136343 -171.93511)
			(xy 50.142902 -171.942506) (xy 50.143156 -171.94276) (xy 55.929784 -177.729388) (xy 55.930292 -177.729896)
			(xy 55.937677 -177.736468) (xy 55.955976 -177.743898) (xy 55.965852 -177.744374) (xy 66.01333 -177.744374)
			(xy 66.023398 -177.744802) (xy 66.041997 -177.752521) (xy 66.049398 -177.75936) (xy 76.671678 -188.38164)
			(xy 113.076736 -188.38164) (xy 113.077217 -188.35427) (xy 113.08503 -188.300091) (xy 113.100515 -188.247588)
			(xy 113.123354 -188.197841) (xy 113.153076 -188.151874) (xy 113.170716 -188.130942) (xy 113.176812 -188.12383)
			(xy 113.183162 -188.106812) (xy 113.183162 -188.021468) (xy 113.176812 -188.00445) (xy 113.170716 -187.997338)
			(xy 113.153115 -187.976373) (xy 113.123389 -187.930411) (xy 113.100542 -187.88067) (xy 113.085043 -187.828173)
			(xy 113.077211 -187.773999) (xy 113.077207 -187.719262) (xy 113.085031 -187.665086) (xy 113.100521 -187.612587)
			(xy 113.12336 -187.562842) (xy 113.153079 -187.516875) (xy 113.170716 -187.495942) (xy 113.176812 -187.48883)
			(xy 113.183162 -187.471812) (xy 113.183162 -187.386468) (xy 113.176812 -187.36945) (xy 113.170716 -187.362338)
			(xy 113.153115 -187.341373) (xy 113.123389 -187.295411) (xy 113.100542 -187.24567) (xy 113.085043 -187.193173)
			(xy 113.077211 -187.138999) (xy 113.077207 -187.084262) (xy 113.085031 -187.030086) (xy 113.100521 -186.977587)
			(xy 113.12336 -186.927842) (xy 113.153079 -186.881875) (xy 113.170716 -186.860942) (xy 113.176812 -186.85383)
			(xy 113.183162 -186.836812) (xy 113.183162 -186.751468) (xy 113.176812 -186.73445) (xy 113.170716 -186.727338)
			(xy 113.153115 -186.706373) (xy 113.123389 -186.660411) (xy 113.100542 -186.61067) (xy 113.085043 -186.558173)
			(xy 113.077211 -186.503999) (xy 113.077207 -186.449262) (xy 113.085031 -186.395086) (xy 113.100521 -186.342587)
			(xy 113.12336 -186.292842) (xy 113.153079 -186.246875) (xy 113.170716 -186.225942) (xy 113.176812 -186.21883)
			(xy 113.183162 -186.201812) (xy 113.183162 -186.116468) (xy 113.176812 -186.09945) (xy 113.170716 -186.092338)
			(xy 113.153115 -186.071373) (xy 113.123389 -186.025411) (xy 113.100542 -185.97567) (xy 113.085043 -185.923173)
			(xy 113.077211 -185.868999) (xy 113.077207 -185.814262) (xy 113.085031 -185.760086) (xy 113.100521 -185.707587)
			(xy 113.12336 -185.657842) (xy 113.153079 -185.611875) (xy 113.170716 -185.590942) (xy 113.176812 -185.58383)
			(xy 113.183162 -185.566812) (xy 113.183162 -185.481468) (xy 113.176812 -185.46445) (xy 113.170716 -185.457338)
			(xy 113.153115 -185.436373) (xy 113.123389 -185.390411) (xy 113.100542 -185.34067) (xy 113.085043 -185.288173)
			(xy 113.077211 -185.233999) (xy 113.077207 -185.179262) (xy 113.085031 -185.125086) (xy 113.100521 -185.072587)
			(xy 113.12336 -185.022842) (xy 113.153079 -184.976875) (xy 113.170716 -184.955942) (xy 113.176812 -184.94883)
			(xy 113.183162 -184.931812) (xy 113.183162 -184.846468) (xy 113.176812 -184.82945) (xy 113.170716 -184.822338)
			(xy 113.153084 -184.8014) (xy 113.12337 -184.755429) (xy 113.100533 -184.705683) (xy 113.08504 -184.653184)
			(xy 113.077211 -184.599009) (xy 113.076736 -184.57164) (xy 113.077279 -184.542473) (xy 113.086176 -184.484823)
			(xy 113.103752 -184.429201) (xy 113.129598 -184.376906) (xy 113.163111 -184.32916) (xy 113.182908 -184.307734)
			(xy 113.189766 -184.300368) (xy 113.196878 -184.282588) (xy 113.196878 -184.192164) (xy 113.189766 -184.174384)
			(xy 113.182908 -184.167018) (xy 113.163125 -184.145584) (xy 113.12964 -184.097826) (xy 113.103808 -184.045531)
			(xy 113.086229 -183.989916) (xy 113.077311 -183.932275) (xy 113.076736 -183.903112) (xy 113.077167 -183.875857)
			(xy 113.084923 -183.821903) (xy 113.10028 -183.769602) (xy 113.122924 -183.720019) (xy 113.152395 -183.674164)
			(xy 113.188092 -183.63297) (xy 113.229289 -183.597276) (xy 113.275147 -183.567809) (xy 113.324732 -183.545169)
			(xy 113.377034 -183.529816) (xy 113.430989 -183.522064) (xy 113.458244 -183.521604) (xy 113.485613 -183.522102)
			(xy 113.539791 -183.529912) (xy 113.592294 -183.545393) (xy 113.642041 -183.568228) (xy 113.688009 -183.597946)
			(xy 113.708942 -183.615584) (xy 113.716054 -183.62168) (xy 113.733072 -183.62803) (xy 113.818416 -183.62803)
			(xy 113.835434 -183.62168) (xy 113.842546 -183.615584) (xy 113.863479 -183.597943) (xy 113.909447 -183.568219)
			(xy 113.959193 -183.545373) (xy 114.011695 -183.529877) (xy 114.065873 -183.522048) (xy 114.120615 -183.522048)
			(xy 114.174793 -183.529877) (xy 114.227295 -183.545373) (xy 114.277041 -183.568219) (xy 114.323009 -183.597943)
			(xy 114.343942 -183.615584) (xy 114.351054 -183.62168) (xy 114.368072 -183.62803) (xy 114.453416 -183.62803)
			(xy 114.470434 -183.62168) (xy 114.477546 -183.615584) (xy 114.498486 -183.597954) (xy 114.544457 -183.568242)
			(xy 114.594202 -183.545404) (xy 114.646701 -183.529911) (xy 114.700875 -183.52208) (xy 114.728244 -183.521604)
			(xy 114.755497 -183.522037) (xy 114.809447 -183.5298) (xy 114.861744 -183.545161) (xy 114.911322 -183.567808)
			(xy 114.957173 -183.59728) (xy 114.998363 -183.632977) (xy 115.034053 -183.674172) (xy 115.063519 -183.720027)
			(xy 115.086159 -183.769609) (xy 115.101512 -183.821908) (xy 115.109267 -183.875859) (xy 115.109752 -183.903112)
			(xy 117.089936 -183.903112) (xy 117.090367 -183.875857) (xy 117.098123 -183.821903) (xy 117.11348 -183.769602)
			(xy 117.136124 -183.720019) (xy 117.165595 -183.674164) (xy 117.201292 -183.63297) (xy 117.242489 -183.597276)
			(xy 117.288347 -183.567809) (xy 117.337932 -183.545169) (xy 117.390234 -183.529816) (xy 117.444189 -183.522064)
			(xy 117.471444 -183.521604) (xy 117.498813 -183.522102) (xy 117.552991 -183.529912) (xy 117.605494 -183.545393)
			(xy 117.655241 -183.568228) (xy 117.701209 -183.597946) (xy 117.722142 -183.615584) (xy 117.729254 -183.62168)
			(xy 117.746272 -183.62803) (xy 117.831616 -183.62803) (xy 117.848634 -183.62168) (xy 117.855746 -183.615584)
			(xy 117.876679 -183.597943) (xy 117.922647 -183.568219) (xy 117.972393 -183.545373) (xy 118.024895 -183.529877)
			(xy 118.079073 -183.522048) (xy 118.133815 -183.522048) (xy 118.187993 -183.529877) (xy 118.240495 -183.545373)
			(xy 118.290241 -183.568219) (xy 118.336209 -183.597943) (xy 118.357142 -183.615584) (xy 118.364254 -183.62168)
			(xy 118.381272 -183.62803) (xy 118.466616 -183.62803) (xy 118.483634 -183.62168) (xy 118.490746 -183.615584)
			(xy 118.511686 -183.597954) (xy 118.557657 -183.568242) (xy 118.607402 -183.545404) (xy 118.659901 -183.529911)
			(xy 118.714075 -183.52208) (xy 118.741444 -183.521604) (xy 118.768697 -183.522037) (xy 118.822647 -183.5298)
			(xy 118.874944 -183.545161) (xy 118.924522 -183.567808) (xy 118.970373 -183.59728) (xy 119.011563 -183.632977)
			(xy 119.047253 -183.674172) (xy 119.076719 -183.720027) (xy 119.099359 -183.769609) (xy 119.114712 -183.821908)
			(xy 119.122467 -183.875859) (xy 119.122952 -183.903112) (xy 119.122414 -183.93223) (xy 119.113567 -183.989791)
			(xy 119.09608 -184.045341) (xy 119.070359 -184.09759) (xy 119.037002 -184.145327) (xy 119.017288 -184.166764)
			(xy 119.01043 -184.173876) (xy 119.003318 -184.19191) (xy 119.003318 -184.28208) (xy 119.010684 -184.300114)
			(xy 119.017542 -184.307226) (xy 119.037386 -184.328688) (xy 119.070982 -184.376519) (xy 119.096891 -184.428914)
			(xy 119.114505 -184.484647) (xy 119.123413 -184.542415) (xy 119.123968 -184.57164) (xy 119.123559 -184.598894)
			(xy 119.115796 -184.652847) (xy 119.100434 -184.705145) (xy 119.077785 -184.754725) (xy 119.048311 -184.800577)
			(xy 119.012612 -184.841768) (xy 118.971413 -184.877459) (xy 118.925555 -184.906924) (xy 118.87597 -184.929562)
			(xy 118.823668 -184.944913) (xy 118.769714 -184.952665) (xy 118.74246 -184.953148) (xy 118.716175 -184.952671)
			(xy 118.664099 -184.945476) (xy 118.613504 -184.931202) (xy 118.565348 -184.910117) (xy 118.520541 -184.882622)
			(xy 118.479933 -184.849236) (xy 118.46179 -184.830212) (xy 118.454779 -184.823327) (xy 118.43702 -184.814961)
			(xy 118.427246 -184.813956) (xy 118.373906 -184.811162) (xy 118.366286 -184.818274) (xy 118.366286 -184.871614)
			(xy 118.366778 -184.881428) (xy 118.374219 -184.899592) (xy 118.380764 -184.90692) (xy 118.400949 -184.928409)
			(xy 118.435092 -184.976472) (xy 118.461436 -185.029214) (xy 118.479354 -185.08538) (xy 118.48842 -185.143634)
			(xy 118.488968 -185.173112) (xy 118.488556 -185.200367) (xy 118.480797 -185.254322) (xy 118.465437 -185.306623)
			(xy 118.44279 -185.356206) (xy 118.413317 -185.402061) (xy 118.377618 -185.443255) (xy 118.336419 -185.478948)
			(xy 118.29056 -185.508415) (xy 118.240974 -185.531055) (xy 118.188671 -185.546408) (xy 118.134715 -185.55416)
			(xy 118.10746 -185.55462) (xy 118.077984 -185.554037) (xy 118.019733 -185.544978) (xy 117.963569 -185.527065)
			(xy 117.910829 -185.500725) (xy 117.862769 -185.466586) (xy 117.841268 -185.446416) (xy 117.833937 -185.439877)
			(xy 117.815774 -185.432434) (xy 117.805962 -185.431938) (xy 117.752622 -185.431938) (xy 117.745764 -185.439304)
			(xy 117.73923 -185.446639) (xy 117.731786 -185.464799) (xy 117.731286 -185.47461) (xy 117.731286 -185.506614)
			(xy 117.731778 -185.516428) (xy 117.739219 -185.534592) (xy 117.745764 -185.54192) (xy 117.765949 -185.563409)
			(xy 117.800092 -185.611472) (xy 117.826436 -185.664214) (xy 117.844354 -185.72038) (xy 117.85342 -185.778634)
			(xy 117.853968 -185.808112) (xy 117.853482 -185.835363) (xy 117.845726 -185.889311) (xy 117.830371 -185.941606)
			(xy 117.807729 -185.991183) (xy 117.778263 -186.037033) (xy 117.742572 -186.078224) (xy 117.701381 -186.113915)
			(xy 117.655531 -186.143381) (xy 117.605954 -186.166023) (xy 117.553659 -186.181378) (xy 117.499711 -186.189134)
			(xy 117.445209 -186.189134) (xy 117.391261 -186.181378) (xy 117.338966 -186.166023) (xy 117.289389 -186.143381)
			(xy 117.243539 -186.113915) (xy 117.202348 -186.078224) (xy 117.166657 -186.037033) (xy 117.137191 -185.991183)
			(xy 117.114549 -185.941606) (xy 117.099194 -185.889311) (xy 117.091438 -185.835363) (xy 117.090952 -185.808112)
			(xy 117.091412 -185.780741) (xy 117.09923 -185.726562) (xy 117.114719 -185.674058) (xy 117.137563 -185.624311)
			(xy 117.167289 -185.578345) (xy 117.184932 -185.557414) (xy 117.191028 -185.550302) (xy 117.197378 -185.533284)
			(xy 117.197378 -185.44794) (xy 117.191028 -185.430922) (xy 117.184932 -185.42381) (xy 117.167303 -185.402868)
			(xy 117.137577 -185.356902) (xy 117.114731 -185.307157) (xy 117.099233 -185.254656) (xy 117.091404 -185.200479)
			(xy 117.091402 -185.145739) (xy 117.09923 -185.091561) (xy 117.114724 -185.03906) (xy 117.137568 -184.989314)
			(xy 117.167292 -184.943347) (xy 117.184932 -184.922414) (xy 117.191028 -184.915302) (xy 117.197378 -184.898284)
			(xy 117.197378 -184.81294) (xy 117.191028 -184.795922) (xy 117.184932 -184.78881) (xy 117.167289 -184.767881)
			(xy 117.137577 -184.721908) (xy 117.114741 -184.67216) (xy 117.099251 -184.619658) (xy 117.091425 -184.565481)
			(xy 117.090952 -184.538112) (xy 117.091455 -184.510814) (xy 117.099223 -184.456774) (xy 117.114618 -184.404394)
			(xy 117.137324 -184.354744) (xy 117.166878 -184.308839) (xy 117.184424 -184.287922) (xy 117.190774 -184.28081)
			(xy 117.19687 -184.263792) (xy 117.19687 -184.178194) (xy 117.19052 -184.16143) (xy 117.184424 -184.154318)
			(xy 117.166722 -184.133347) (xy 117.136841 -184.087318) (xy 117.113872 -184.037479) (xy 117.098289 -183.98486)
			(xy 117.090415 -183.930551) (xy 117.089936 -183.903112) (xy 115.109752 -183.903112) (xy 115.109287 -183.930412)
			(xy 115.101512 -183.984454) (xy 115.08611 -184.036836) (xy 115.063395 -184.086485) (xy 115.033831 -184.132387)
			(xy 115.01628 -184.153302) (xy 115.00993 -184.160414) (xy 115.003834 -184.177432) (xy 115.003834 -184.26303)
			(xy 115.010184 -184.279794) (xy 115.01628 -184.286906) (xy 115.033993 -184.307868) (xy 115.063873 -184.353899)
			(xy 115.08684 -184.403741) (xy 115.10242 -184.456361) (xy 115.110291 -184.510673) (xy 115.110768 -184.538112)
			(xy 115.110317 -184.565483) (xy 115.102497 -184.619663) (xy 115.087004 -184.672166) (xy 115.064159 -184.721913)
			(xy 115.034431 -184.767879) (xy 115.016788 -184.78881) (xy 115.010692 -184.795922) (xy 115.004342 -184.81294)
			(xy 115.004342 -184.898284) (xy 115.010692 -184.915302) (xy 115.016788 -184.922414) (xy 115.03444 -184.943338)
			(xy 115.064163 -184.989307) (xy 115.087007 -185.039055) (xy 115.102501 -185.091558) (xy 115.110329 -185.145738)
			(xy 115.110327 -185.20048) (xy 115.102498 -185.254659) (xy 115.087 -185.307162) (xy 115.064154 -185.356909)
			(xy 115.034429 -185.402877) (xy 115.016788 -185.42381) (xy 115.010692 -185.430922) (xy 115.004342 -185.44794)
			(xy 115.004342 -185.533284) (xy 115.010692 -185.550302) (xy 115.016788 -185.557414) (xy 115.03444 -185.578338)
			(xy 115.064163 -185.624307) (xy 115.087007 -185.674055) (xy 115.102501 -185.726558) (xy 115.110329 -185.780738)
			(xy 115.110327 -185.83548) (xy 115.102498 -185.889659) (xy 115.087 -185.942162) (xy 115.064154 -185.991909)
			(xy 115.034429 -186.037877) (xy 115.016788 -186.05881) (xy 115.010692 -186.065922) (xy 115.004342 -186.08294)
			(xy 115.004342 -186.168284) (xy 115.010692 -186.185302) (xy 115.016788 -186.192414) (xy 115.034398 -186.213369)
			(xy 115.064115 -186.259335) (xy 115.086957 -186.309077) (xy 115.102454 -186.361573) (xy 115.11029 -186.415744)
			(xy 115.110768 -186.443112) (xy 115.110228 -186.472337) (xy 115.101304 -186.530102) (xy 115.083683 -186.585833)
			(xy 115.057774 -186.638227) (xy 115.024184 -186.686062) (xy 115.004342 -186.707526) (xy 114.997484 -186.714638)
			(xy 114.990118 -186.732672) (xy 114.990118 -186.822842) (xy 114.99723 -186.840876) (xy 115.004088 -186.847988)
			(xy 115.023818 -186.869411) (xy 115.057171 -186.917152) (xy 115.082886 -186.969405) (xy 115.100366 -187.024958)
			(xy 115.109206 -187.082521) (xy 115.109752 -187.11164) (xy 115.109262 -187.13901) (xy 115.101452 -187.193188)
			(xy 115.085969 -187.245691) (xy 115.063132 -187.295439) (xy 115.033412 -187.341406) (xy 115.015772 -187.362338)
			(xy 115.009676 -187.36945) (xy 115.003326 -187.386468) (xy 115.003326 -187.471812) (xy 115.009676 -187.48883)
			(xy 115.015772 -187.495942) (xy 115.033452 -187.516843) (xy 115.063175 -187.562816) (xy 115.086018 -187.612568)
			(xy 115.101511 -187.665075) (xy 115.109336 -187.719258) (xy 115.109332 -187.774003) (xy 115.101499 -187.828184)
			(xy 115.085997 -187.880689) (xy 115.063146 -187.930437) (xy 115.033416 -187.976405) (xy 115.015772 -187.997338)
			(xy 115.009676 -188.00445) (xy 115.003326 -188.021468) (xy 115.003326 -188.106812) (xy 115.009676 -188.12383)
			(xy 115.015772 -188.130942) (xy 115.033393 -188.151889) (xy 115.063109 -188.197857) (xy 115.085948 -188.247601)
			(xy 115.101444 -188.300098) (xy 115.109276 -188.354272) (xy 115.109752 -188.38164) (xy 115.10926 -188.40889)
			(xy 115.101499 -188.462835) (xy 115.086141 -188.515127) (xy 115.063498 -188.564702) (xy 115.034032 -188.61055)
			(xy 114.998341 -188.651738) (xy 114.957153 -188.687429) (xy 114.911305 -188.716896) (xy 114.861731 -188.739539)
			(xy 114.809439 -188.754898) (xy 114.755494 -188.762659) (xy 114.728244 -188.763148) (xy 114.700874 -188.762669)
			(xy 114.646695 -188.754856) (xy 114.594192 -188.739371) (xy 114.544444 -188.716532) (xy 114.498478 -188.686809)
			(xy 114.477546 -188.669168) (xy 114.470434 -188.663072) (xy 114.453416 -188.656722) (xy 114.368072 -188.656722)
			(xy 114.351054 -188.663072) (xy 114.343942 -188.669168) (xy 114.323009 -188.686809) (xy 114.277041 -188.716533)
			(xy 114.227295 -188.739379) (xy 114.174793 -188.754875) (xy 114.120615 -188.762704) (xy 114.065873 -188.762704)
			(xy 114.011695 -188.754875) (xy 113.959193 -188.739379) (xy 113.909447 -188.716533) (xy 113.863479 -188.686809)
			(xy 113.842546 -188.669168) (xy 113.835434 -188.663072) (xy 113.818416 -188.656722) (xy 113.733072 -188.656722)
			(xy 113.716054 -188.663072) (xy 113.708942 -188.669168) (xy 113.688001 -188.686796) (xy 113.642031 -188.716511)
			(xy 113.592286 -188.739349) (xy 113.539787 -188.754843) (xy 113.485613 -188.762673) (xy 113.458244 -188.763148)
			(xy 113.430994 -188.762604) (xy 113.377048 -188.754854) (xy 113.324754 -188.739506) (xy 113.275177 -188.716871)
			(xy 113.229325 -188.687411) (xy 113.188133 -188.651726) (xy 113.152439 -188.610542) (xy 113.122969 -188.564697)
			(xy 113.100324 -188.515125) (xy 113.084964 -188.462834) (xy 113.077202 -188.40889) (xy 113.076736 -188.38164)
			(xy 76.671678 -188.38164) (xy 78.97368 -190.683642) (xy 78.974188 -190.68415) (xy 78.981571 -190.690727)
			(xy 78.99987 -190.698165) (xy 79.009748 -190.698628)
		)
		(stroke
			(width 0)
			(type solid)
		)
		(fill yes)
		(layer "In15.Cu")
		(net "GND")
	)
	(gr_poly
		(pts
			(xy 78.311248 -266.164822) (xy 78.322533 -266.164209) (xy 78.342949 -266.154583) (xy 78.350618 -266.14628)
			(xy 78.407768 -266.077192) (xy 78.413356 -266.055348) (xy 78.411324 -266.043918) (xy 78.408728 -266.029644)
			(xy 78.405929 -266.000766) (xy 78.405736 -265.98626) (xy 78.406258 -265.961005) (xy 78.414571 -265.911183)
			(xy 78.430972 -265.863409) (xy 78.455013 -265.818986) (xy 78.486037 -265.779126) (xy 78.523199 -265.744916)
			(xy 78.565485 -265.71729) (xy 78.611741 -265.697) (xy 78.660706 -265.6846) (xy 78.711044 -265.680429)
			(xy 78.761382 -265.6846) (xy 78.810347 -265.697) (xy 78.856603 -265.71729) (xy 78.898889 -265.744916)
			(xy 78.936051 -265.779126) (xy 78.967075 -265.818986) (xy 78.991116 -265.863409) (xy 79.007517 -265.911183)
			(xy 79.01583 -265.961005) (xy 79.016352 -265.98626) (xy 79.016155 -266.000766) (xy 79.013353 -266.029643)
			(xy 79.010764 -266.043918) (xy 79.008732 -266.055348) (xy 79.01432 -266.077192) (xy 79.07147 -266.14628)
			(xy 79.079095 -266.154638) (xy 79.099539 -266.164253) (xy 79.11084 -266.164822) (xy 81.131156 -266.164822)
			(xy 81.14244 -266.164208) (xy 81.162854 -266.154579) (xy 81.170526 -266.14628) (xy 81.227676 -266.077192)
			(xy 81.233264 -266.055348) (xy 81.231232 -266.043918) (xy 81.228636 -266.029644) (xy 81.225837 -266.000766)
			(xy 81.225644 -265.98626) (xy 81.226166 -265.961005) (xy 81.234479 -265.911183) (xy 81.25088 -265.863409)
			(xy 81.274921 -265.818986) (xy 81.305945 -265.779126) (xy 81.343107 -265.744916) (xy 81.385393 -265.71729)
			(xy 81.431649 -265.697) (xy 81.480614 -265.6846) (xy 81.530952 -265.680429) (xy 81.58129 -265.6846)
			(xy 81.630255 -265.697) (xy 81.676511 -265.71729) (xy 81.718797 -265.744916) (xy 81.755959 -265.779126)
			(xy 81.786983 -265.818986) (xy 81.811024 -265.863409) (xy 81.827425 -265.911183) (xy 81.835738 -265.961005)
			(xy 81.83626 -265.98626) (xy 81.836063 -266.000766) (xy 81.833261 -266.029643) (xy 81.830672 -266.043918)
			(xy 81.82864 -266.055348) (xy 81.834228 -266.077192) (xy 81.891378 -266.14628) (xy 81.899003 -266.154637)
			(xy 81.919448 -266.164248) (xy 81.930748 -266.164822) (xy 82.06105 -266.164822) (xy 82.063336 -266.164822)
			(xy 82.07226 -266.164069) (xy 82.088776 -266.157169) (xy 82.095594 -266.15136) (xy 82.100166 -266.14628)
			(xy 82.157316 -266.077446) (xy 82.162904 -266.055602) (xy 82.160872 -266.044426) (xy 82.158078 -266.027408)
			(xy 82.158078 -266.027154) (xy 82.156797 -266.016978) (xy 82.155398 -265.996515) (xy 82.155284 -265.98626)
			(xy 82.155771 -265.96145) (xy 82.163533 -265.912442) (xy 82.178866 -265.865252) (xy 82.201393 -265.821041)
			(xy 82.230558 -265.780898) (xy 82.265644 -265.745812) (xy 82.305787 -265.716647) (xy 82.349998 -265.69412)
			(xy 82.397188 -265.678787) (xy 82.446196 -265.671025) (xy 82.495816 -265.671025) (xy 82.544824 -265.678787)
			(xy 82.592014 -265.69412) (xy 82.636225 -265.716647) (xy 82.676368 -265.745812) (xy 82.711454 -265.780898)
			(xy 82.740619 -265.821041) (xy 82.763146 -265.865252) (xy 82.778479 -265.912442) (xy 82.786241 -265.96145)
			(xy 82.786728 -265.98626) (xy 82.786615 -265.996515) (xy 82.78522 -266.016979) (xy 82.783934 -266.027154)
			(xy 82.783934 -266.027408) (xy 82.78114 -266.044426) (xy 82.779108 -266.055602) (xy 82.784696 -266.077446)
			(xy 82.841846 -266.14628) (xy 82.846418 -266.15136) (xy 82.853225 -266.157184) (xy 82.869748 -266.164078)
			(xy 82.878676 -266.164822) (xy 83.011264 -266.164822) (xy 83.022547 -266.164206) (xy 83.042959 -266.154575)
			(xy 83.050634 -266.14628) (xy 83.107784 -266.077192) (xy 83.113372 -266.055348) (xy 83.11134 -266.043918)
			(xy 83.108744 -266.029644) (xy 83.105945 -266.000766) (xy 83.105752 -265.98626) (xy 83.106274 -265.961005)
			(xy 83.114587 -265.911183) (xy 83.130988 -265.863409) (xy 83.155029 -265.818986) (xy 83.186053 -265.779126)
			(xy 83.223215 -265.744916) (xy 83.265501 -265.71729) (xy 83.311757 -265.697) (xy 83.360722 -265.6846)
			(xy 83.41106 -265.680429) (xy 83.461398 -265.6846) (xy 83.510363 -265.697) (xy 83.556619 -265.71729)
			(xy 83.598905 -265.744916) (xy 83.636067 -265.779126) (xy 83.667091 -265.818986) (xy 83.691132 -265.863409)
			(xy 83.707533 -265.911183) (xy 83.715846 -265.961005) (xy 83.716368 -265.98626) (xy 83.716171 -266.000766)
			(xy 83.713369 -266.029643) (xy 83.71078 -266.043918) (xy 83.708748 -266.055348) (xy 83.714336 -266.077192)
			(xy 83.771486 -266.14628) (xy 83.779111 -266.154636) (xy 83.799557 -266.164244) (xy 83.810856 -266.164822)
			(xy 83.951318 -266.164822) (xy 83.962606 -266.164215) (xy 83.983032 -266.154596) (xy 83.990688 -266.14628)
			(xy 84.047838 -266.077192) (xy 84.053426 -266.055348) (xy 84.051394 -266.043918) (xy 84.048799 -266.029644)
			(xy 84.046 -266.000766) (xy 84.045806 -265.98626) (xy 84.046328 -265.961005) (xy 84.054641 -265.911183)
			(xy 84.071042 -265.863409) (xy 84.095083 -265.818986) (xy 84.126107 -265.779126) (xy 84.163269 -265.744916)
			(xy 84.205555 -265.71729) (xy 84.251811 -265.697) (xy 84.300776 -265.6846) (xy 84.351114 -265.680429)
			(xy 84.401452 -265.6846) (xy 84.450417 -265.697) (xy 84.496673 -265.71729) (xy 84.538959 -265.744916)
			(xy 84.576121 -265.779126) (xy 84.607145 -265.818986) (xy 84.631186 -265.863409) (xy 84.647587 -265.911183)
			(xy 84.6559 -265.961005) (xy 84.656422 -265.98626) (xy 84.656225 -266.000766) (xy 84.653422 -266.029643)
			(xy 84.650834 -266.043918) (xy 84.648802 -266.055348) (xy 84.65439 -266.077192) (xy 84.71154 -266.14628)
			(xy 84.719163 -266.154643) (xy 84.739607 -266.16427) (xy 84.75091 -266.164822) (xy 84.891118 -266.164822)
			(xy 84.902406 -266.164215) (xy 84.922832 -266.154596) (xy 84.930488 -266.14628) (xy 84.987638 -266.077192)
			(xy 84.993226 -266.055348) (xy 84.991194 -266.043918) (xy 84.988599 -266.029644) (xy 84.9858 -266.000766)
			(xy 84.985606 -265.98626) (xy 84.986128 -265.961005) (xy 84.994441 -265.911183) (xy 85.010842 -265.863409)
			(xy 85.034883 -265.818986) (xy 85.065907 -265.779126) (xy 85.103069 -265.744916) (xy 85.145355 -265.71729)
			(xy 85.191611 -265.697) (xy 85.240576 -265.6846) (xy 85.290914 -265.680429) (xy 85.341252 -265.6846)
			(xy 85.390217 -265.697) (xy 85.436473 -265.71729) (xy 85.478759 -265.744916) (xy 85.515921 -265.779126)
			(xy 85.546945 -265.818986) (xy 85.570986 -265.863409) (xy 85.587387 -265.911183) (xy 85.5957 -265.961005)
			(xy 85.596222 -265.98626) (xy 85.596025 -266.000766) (xy 85.593222 -266.029643) (xy 85.590634 -266.043918)
			(xy 85.588602 -266.055348) (xy 85.59419 -266.077192) (xy 85.65134 -266.14628) (xy 85.658963 -266.154643)
			(xy 85.679407 -266.16427) (xy 85.69071 -266.164822) (xy 85.821012 -266.164822) (xy 85.823298 -266.164822)
			(xy 85.832225 -266.164075) (xy 85.84875 -266.157184) (xy 85.855556 -266.15136) (xy 85.860128 -266.14628)
			(xy 85.917278 -266.077446) (xy 85.922866 -266.055602) (xy 85.920834 -266.044426) (xy 85.918328 -266.030015)
			(xy 85.915652 -266.000886) (xy 85.9155 -265.98626) (xy 85.915986 -265.96147) (xy 85.923742 -265.912502)
			(xy 85.939063 -265.865349) (xy 85.961572 -265.821174) (xy 85.990714 -265.781063) (xy 86.025771 -265.746006)
			(xy 86.065882 -265.716864) (xy 86.110057 -265.694355) (xy 86.15721 -265.679034) (xy 86.206178 -265.671278)
			(xy 86.255758 -265.671278) (xy 86.304726 -265.679034) (xy 86.351879 -265.694355) (xy 86.396054 -265.716864)
			(xy 86.436165 -265.746006) (xy 86.471222 -265.781063) (xy 86.500364 -265.821174) (xy 86.522873 -265.865349)
			(xy 86.538194 -265.912502) (xy 86.54595 -265.96147) (xy 86.546436 -265.98626) (xy 86.546297 -266.000887)
			(xy 86.543628 -266.030018) (xy 86.541102 -266.044426) (xy 86.53907 -266.055602) (xy 86.544658 -266.077446)
			(xy 86.601808 -266.14628) (xy 86.60638 -266.15136) (xy 86.613185 -266.15719) (xy 86.629708 -266.164096)
			(xy 86.638638 -266.164822) (xy 87.71128 -266.164822) (xy 87.722571 -266.164223) (xy 87.743009 -266.154613)
			(xy 87.75065 -266.14628) (xy 87.8078 -266.077192) (xy 87.813388 -266.055348) (xy 87.811356 -266.043918)
			(xy 87.808761 -266.029644) (xy 87.805962 -266.000766) (xy 87.805768 -265.98626) (xy 87.80629 -265.961005)
			(xy 87.814603 -265.911183) (xy 87.831004 -265.863409) (xy 87.855045 -265.818986) (xy 87.886069 -265.779126)
			(xy 87.923231 -265.744916) (xy 87.965517 -265.71729) (xy 88.011773 -265.697) (xy 88.060738 -265.6846)
			(xy 88.111076 -265.680429) (xy 88.161414 -265.6846) (xy 88.210379 -265.697) (xy 88.256635 -265.71729)
			(xy 88.298921 -265.744916) (xy 88.336083 -265.779126) (xy 88.367107 -265.818986) (xy 88.391148 -265.863409)
			(xy 88.407549 -265.911183) (xy 88.415862 -265.961005) (xy 88.416384 -265.98626) (xy 88.416187 -266.000766)
			(xy 88.413385 -266.029643) (xy 88.410796 -266.043918) (xy 88.408764 -266.055348) (xy 88.414352 -266.077192)
			(xy 88.471502 -266.14628) (xy 88.479122 -266.154649) (xy 88.499567 -266.164291) (xy 88.510872 -266.164822)
			(xy 88.641174 -266.164822) (xy 88.64346 -266.164822) (xy 88.652383 -266.164065) (xy 88.668893 -266.157159)
			(xy 88.675718 -266.15136) (xy 88.68029 -266.14628) (xy 88.73744 -266.077446) (xy 88.743028 -266.055602)
			(xy 88.740996 -266.044426) (xy 88.738202 -266.027408) (xy 88.738202 -266.027154) (xy 88.736921 -266.016978)
			(xy 88.735522 -265.996515) (xy 88.735408 -265.98626) (xy 88.735895 -265.96145) (xy 88.743657 -265.912442)
			(xy 88.75899 -265.865252) (xy 88.781517 -265.821041) (xy 88.810682 -265.780898) (xy 88.845768 -265.745812)
			(xy 88.885911 -265.716647) (xy 88.930122 -265.69412) (xy 88.977312 -265.678787) (xy 89.02632 -265.671025)
			(xy 89.07594 -265.671025) (xy 89.124948 -265.678787) (xy 89.172138 -265.69412) (xy 89.216349 -265.716647)
			(xy 89.256492 -265.745812) (xy 89.291578 -265.780898) (xy 89.320743 -265.821041) (xy 89.34327 -265.865252)
			(xy 89.358603 -265.912442) (xy 89.366365 -265.96145) (xy 89.366852 -265.98626) (xy 89.366739 -265.996515)
			(xy 89.365344 -266.016979) (xy 89.364058 -266.027154) (xy 89.364058 -266.027408) (xy 89.361264 -266.044426)
			(xy 89.359232 -266.055602) (xy 89.36482 -266.077446) (xy 89.42197 -266.14628) (xy 89.426542 -266.15136)
			(xy 89.43335 -266.157181) (xy 89.449874 -266.164067) (xy 89.4588 -266.164822) (xy 89.591134 -266.164822)
			(xy 89.60242 -266.164212) (xy 89.622841 -266.154589) (xy 89.630504 -266.14628) (xy 89.687654 -266.077192)
			(xy 89.693242 -266.055348) (xy 89.69121 -266.043918) (xy 89.688614 -266.029644) (xy 89.685815 -266.000766)
			(xy 89.685622 -265.98626) (xy 89.686144 -265.961005) (xy 89.694457 -265.911183) (xy 89.710858 -265.863409)
			(xy 89.734899 -265.818986) (xy 89.765923 -265.779126) (xy 89.803085 -265.744916) (xy 89.845371 -265.71729)
			(xy 89.891627 -265.697) (xy 89.940592 -265.6846) (xy 89.99093 -265.680429) (xy 90.041268 -265.6846)
			(xy 90.090233 -265.697) (xy 90.136489 -265.71729) (xy 90.178775 -265.744916) (xy 90.215937 -265.779126)
			(xy 90.246961 -265.818986) (xy 90.271002 -265.863409) (xy 90.287403 -265.911183) (xy 90.295716 -265.961005)
			(xy 90.296238 -265.98626) (xy 90.296041 -266.000766) (xy 90.293238 -266.029643) (xy 90.29065 -266.043918)
			(xy 90.288618 -266.055348) (xy 90.294206 -266.077192) (xy 90.351356 -266.14628) (xy 90.35898 -266.15464)
			(xy 90.379425 -266.16426) (xy 90.390726 -266.164822) (xy 90.531188 -266.164822) (xy 90.542479 -266.164221)
			(xy 90.562914 -266.15461) (xy 90.570558 -266.14628) (xy 90.627708 -266.077192) (xy 90.633296 -266.055348)
			(xy 90.631264 -266.043918) (xy 90.628669 -266.029644) (xy 90.62587 -266.000766) (xy 90.625676 -265.98626)
			(xy 90.626198 -265.961005) (xy 90.634511 -265.911183) (xy 90.650912 -265.863409) (xy 90.674953 -265.818986)
			(xy 90.705977 -265.779126) (xy 90.743139 -265.744916) (xy 90.785425 -265.71729) (xy 90.831681 -265.697)
			(xy 90.880646 -265.6846) (xy 90.930984 -265.680429) (xy 90.981322 -265.6846) (xy 91.030287 -265.697)
			(xy 91.076543 -265.71729) (xy 91.118829 -265.744916) (xy 91.155991 -265.779126) (xy 91.187015 -265.818986)
			(xy 91.211056 -265.863409) (xy 91.227457 -265.911183) (xy 91.23577 -265.961005) (xy 91.236292 -265.98626)
			(xy 91.236095 -266.000766) (xy 91.233293 -266.029643) (xy 91.230704 -266.043918) (xy 91.228672 -266.055348)
			(xy 91.23426 -266.077192) (xy 91.29141 -266.14628) (xy 91.299031 -266.154648) (xy 91.319475 -266.164287)
			(xy 91.33078 -266.164822) (xy 91.471242 -266.164822) (xy 91.482527 -266.164211) (xy 91.502946 -266.154585)
			(xy 91.510612 -266.14628) (xy 91.567762 -266.077192) (xy 91.57335 -266.055348) (xy 91.571318 -266.043918)
			(xy 91.568722 -266.029644) (xy 91.565923 -266.000766) (xy 91.56573 -265.98626) (xy 91.566252 -265.961005)
			(xy 91.574565 -265.911183) (xy 91.590966 -265.863409) (xy 91.615007 -265.818986) (xy 91.646031 -265.779126)
			(xy 91.683193 -265.744916) (xy 91.725479 -265.71729) (xy 91.771735 -265.697) (xy 91.8207 -265.6846)
			(xy 91.871038 -265.680429) (xy 91.921376 -265.6846) (xy 91.970341 -265.697) (xy 92.016597 -265.71729)
			(xy 92.058883 -265.744916) (xy 92.096045 -265.779126) (xy 92.127069 -265.818986) (xy 92.15111 -265.863409)
			(xy 92.167511 -265.911183) (xy 92.175824 -265.961005) (xy 92.176346 -265.98626) (xy 92.176149 -266.000766)
			(xy 92.173346 -266.029643) (xy 92.170758 -266.043918) (xy 92.168726 -266.055348) (xy 92.174314 -266.077192)
			(xy 92.231464 -266.14628) (xy 92.239088 -266.154639) (xy 92.259533 -266.164256) (xy 92.270834 -266.164822)
			(xy 92.401136 -266.164822) (xy 92.403422 -266.164822) (xy 92.412347 -266.164071) (xy 92.428866 -266.157174)
			(xy 92.43568 -266.15136) (xy 92.440252 -266.14628) (xy 92.497402 -266.077446) (xy 92.50299 -266.055602)
			(xy 92.500958 -266.044426) (xy 92.498452 -266.030015) (xy 92.495777 -266.000886) (xy 92.495624 -265.98626)
			(xy 92.49611 -265.96147) (xy 92.503866 -265.912502) (xy 92.519187 -265.865349) (xy 92.541696 -265.821174)
			(xy 92.570838 -265.781063) (xy 92.605895 -265.746006) (xy 92.646006 -265.716864) (xy 92.690181 -265.694355)
			(xy 92.737334 -265.679034) (xy 92.786302 -265.671278) (xy 92.835882 -265.671278) (xy 92.88485 -265.679034)
			(xy 92.932003 -265.694355) (xy 92.976178 -265.716864) (xy 93.016289 -265.746006) (xy 93.051346 -265.781063)
			(xy 93.080488 -265.821174) (xy 93.102997 -265.865349) (xy 93.118318 -265.912502) (xy 93.126074 -265.96147)
			(xy 93.12656 -265.98626) (xy 93.126421 -266.000887) (xy 93.123752 -266.030018) (xy 93.121226 -266.044426)
			(xy 93.119194 -266.055602) (xy 93.124782 -266.077446) (xy 93.181932 -266.14628) (xy 93.186504 -266.15136)
			(xy 93.19331 -266.157186) (xy 93.209833 -266.164085) (xy 93.218762 -266.164822) (xy 94.29115 -266.164822)
			(xy 94.302434 -266.164209) (xy 94.32285 -266.154582) (xy 94.33052 -266.14628) (xy 94.38767 -266.077192)
			(xy 94.393258 -266.055348) (xy 94.391226 -266.043918) (xy 94.38863 -266.029644) (xy 94.385831 -266.000766)
			(xy 94.385638 -265.98626) (xy 94.38616 -265.961005) (xy 94.394473 -265.911183) (xy 94.410874 -265.863409)
			(xy 94.434915 -265.818986) (xy 94.465939 -265.779126) (xy 94.503101 -265.744916) (xy 94.545387 -265.71729)
			(xy 94.591643 -265.697) (xy 94.640608 -265.6846) (xy 94.690946 -265.680429) (xy 94.741284 -265.6846)
			(xy 94.790249 -265.697) (xy 94.836505 -265.71729) (xy 94.878791 -265.744916) (xy 94.915953 -265.779126)
			(xy 94.946977 -265.818986) (xy 94.971018 -265.863409) (xy 94.987419 -265.911183) (xy 94.995732 -265.961005)
			(xy 94.996254 -265.98626) (xy 94.996057 -266.000766) (xy 94.993255 -266.029643) (xy 94.990666 -266.043918)
			(xy 94.988634 -266.055348) (xy 94.994222 -266.077192) (xy 95.051372 -266.14628) (xy 95.058997 -266.154638)
			(xy 95.079442 -266.164251) (xy 95.090742 -266.164822) (xy 95.221044 -266.164822) (xy 95.22333 -266.164822)
			(xy 95.232255 -266.16407) (xy 95.248772 -266.157171) (xy 95.255588 -266.15136) (xy 95.26016 -266.14628)
			(xy 95.31731 -266.077446) (xy 95.322898 -266.055602) (xy 95.320866 -266.044426) (xy 95.31836 -266.030015)
			(xy 95.315685 -266.000886) (xy 95.315532 -265.98626) (xy 95.316018 -265.96147) (xy 95.323774 -265.912502)
			(xy 95.339095 -265.865349) (xy 95.361604 -265.821174) (xy 95.390746 -265.781063) (xy 95.425803 -265.746006)
			(xy 95.465914 -265.716864) (xy 95.510089 -265.694355) (xy 95.557242 -265.679034) (xy 95.60621 -265.671278)
			(xy 95.65579 -265.671278) (xy 95.704758 -265.679034) (xy 95.751911 -265.694355) (xy 95.796086 -265.716864)
			(xy 95.836197 -265.746006) (xy 95.871254 -265.781063) (xy 95.900396 -265.821174) (xy 95.922905 -265.865349)
			(xy 95.938226 -265.912502) (xy 95.945982 -265.96147) (xy 95.946468 -265.98626) (xy 95.946329 -266.000887)
			(xy 95.94366 -266.030018) (xy 95.941134 -266.044426) (xy 95.939102 -266.055602) (xy 95.94469 -266.077446)
			(xy 96.00184 -266.14628) (xy 96.006412 -266.15136) (xy 96.013219 -266.157185) (xy 96.029742 -266.16408)
			(xy 96.03867 -266.164822) (xy 96.171258 -266.164822) (xy 96.182542 -266.164207) (xy 96.202955 -266.154578)
			(xy 96.210628 -266.14628) (xy 96.267778 -266.077192) (xy 96.273366 -266.055348) (xy 96.271334 -266.043918)
			(xy 96.268738 -266.029644) (xy 96.265939 -266.000766) (xy 96.265746 -265.98626) (xy 96.266268 -265.961005)
			(xy 96.274581 -265.911183) (xy 96.290982 -265.863409) (xy 96.315023 -265.818986) (xy 96.346047 -265.779126)
			(xy 96.383209 -265.744916) (xy 96.425495 -265.71729) (xy 96.471751 -265.697) (xy 96.520716 -265.6846)
			(xy 96.571054 -265.680429) (xy 96.621392 -265.6846) (xy 96.670357 -265.697) (xy 96.716613 -265.71729)
			(xy 96.758899 -265.744916) (xy 96.796061 -265.779126) (xy 96.827085 -265.818986) (xy 96.851126 -265.863409)
			(xy 96.867527 -265.911183) (xy 96.87584 -265.961005) (xy 96.876362 -265.98626) (xy 96.876165 -266.000766)
			(xy 96.873363 -266.029643) (xy 96.870774 -266.043918) (xy 96.868742 -266.055348) (xy 96.87433 -266.077192)
			(xy 96.93148 -266.14628) (xy 96.939105 -266.154636) (xy 96.95955 -266.164247) (xy 96.97085 -266.164822)
			(xy 98.051366 -266.164822) (xy 98.062659 -266.164226) (xy 98.083101 -266.154619) (xy 98.090736 -266.14628)
			(xy 98.147886 -266.077192) (xy 98.153474 -266.055348) (xy 98.151442 -266.043918) (xy 98.148846 -266.029644)
			(xy 98.146047 -266.000766) (xy 98.145854 -265.98626) (xy 98.146376 -265.961005) (xy 98.154689 -265.911183)
			(xy 98.17109 -265.863409) (xy 98.195131 -265.818986) (xy 98.226155 -265.779126) (xy 98.263317 -265.744916)
			(xy 98.305603 -265.71729) (xy 98.351859 -265.697) (xy 98.400824 -265.6846) (xy 98.451162 -265.680429)
			(xy 98.5015 -265.6846) (xy 98.550465 -265.697) (xy 98.596721 -265.71729) (xy 98.639007 -265.744916)
			(xy 98.676169 -265.779126) (xy 98.707193 -265.818986) (xy 98.731234 -265.863409) (xy 98.747635 -265.911183)
			(xy 98.755948 -265.961005) (xy 98.75647 -265.98626) (xy 98.756273 -266.000766) (xy 98.753471 -266.029643)
			(xy 98.750882 -266.043918) (xy 98.74885 -266.055348) (xy 98.754438 -266.077192) (xy 98.811588 -266.14628)
			(xy 98.819213 -266.154635) (xy 98.839659 -266.164242) (xy 98.850958 -266.164822) (xy 99.93122 -266.164822)
			(xy 99.942507 -266.164215) (xy 99.962933 -266.154595) (xy 99.97059 -266.14628) (xy 100.02774 -266.077192)
			(xy 100.033328 -266.055348) (xy 100.031296 -266.043918) (xy 100.028701 -266.029644) (xy 100.025902 -266.000766)
			(xy 100.025708 -265.98626) (xy 100.026182 -265.962271) (xy 100.033693 -265.914885) (xy 100.048524 -265.869258)
			(xy 100.07031 -265.826512) (xy 100.098514 -265.7877) (xy 100.132443 -265.753778) (xy 100.17126 -265.725581)
			(xy 100.21401 -265.703802) (xy 100.25964 -265.68898) (xy 100.307027 -265.681477) (xy 100.331016 -265.680952)
			(xy 100.356055 -265.681455) (xy 100.405462 -265.689618) (xy 100.452879 -265.705723) (xy 100.497038 -265.72934)
			(xy 100.517198 -265.744198) (xy 100.524729 -265.749505) (xy 100.542338 -265.754878) (xy 100.560711 -265.753705)
			(xy 100.577493 -265.746136) (xy 100.584254 -265.73988) (xy 100.94976 -265.374374) (xy 100.956502 -265.367003)
			(xy 100.964092 -265.348542) (xy 100.964492 -265.33856) (xy 100.964492 -265.327638) (xy 100.966016 -265.315446)
			(xy 100.971604 -265.292586) (xy 100.975668 -265.281918) (xy 100.981256 -265.270488) (xy 100.981764 -265.269726)
			(xy 100.992286 -265.247806) (xy 101.003715 -265.20056) (xy 101.00437 -265.176254) (xy 101.003688 -265.151952)
			(xy 100.992255 -265.104714) (xy 100.981764 -265.082782) (xy 100.981256 -265.08202) (xy 100.975668 -265.07059)
			(xy 100.971604 -265.059922) (xy 100.966016 -265.037062) (xy 100.964492 -265.02487) (xy 100.964492 -263.707626)
			(xy 100.966016 -263.695434) (xy 100.971604 -263.672574) (xy 100.975668 -263.661906) (xy 100.981256 -263.650476)
			(xy 100.981764 -263.649714) (xy 100.992285 -263.627794) (xy 101.003711 -263.580548) (xy 101.00437 -263.556242)
			(xy 101.003687 -263.531941) (xy 100.992252 -263.484703) (xy 100.981764 -263.46277) (xy 100.981256 -263.462008)
			(xy 100.975668 -263.450578) (xy 100.971604 -263.43991) (xy 100.966016 -263.41705) (xy 100.964492 -263.404858)
			(xy 100.964492 -263.139936) (xy 100.964991 -263.122938) (xy 100.972544 -263.08979) (xy 100.9872 -263.059113)
			(xy 101.008242 -263.032409) (xy 101.021134 -263.021318) (xy 101.030024 -263.014206) (xy 101.03993 -262.993378)
			(xy 101.03993 -262.972042) (xy 101.039858 -262.967832) (xy 101.038458 -262.959529) (xy 101.037136 -262.955532)
			(xy 101.029516 -262.93318) (xy 101.024944 -262.927084) (xy 101.01096 -262.90731) (xy 100.988762 -262.86427)
			(xy 100.973634 -262.818265) (xy 100.965954 -262.77045) (xy 100.965508 -262.746236) (xy 100.965991 -262.722024)
			(xy 100.973666 -262.674212) (xy 100.988784 -262.628208) (xy 101.010965 -262.585163) (xy 101.024944 -262.565388)
			(xy 101.029516 -262.559292) (xy 101.037136 -262.53694) (xy 101.038421 -262.532933) (xy 101.039827 -262.524637)
			(xy 101.03993 -262.52043) (xy 101.03993 -262.499094) (xy 101.030024 -262.478266) (xy 101.021134 -262.471154)
			(xy 101.008211 -262.460095) (xy 100.987156 -262.433393) (xy 100.972511 -262.402703) (xy 100.965 -262.369538)
			(xy 100.964492 -262.352536) (xy 100.964492 -262.087614) (xy 100.966016 -262.075422) (xy 100.971604 -262.052562)
			(xy 100.975668 -262.041894) (xy 100.981256 -262.030464) (xy 100.981764 -262.029702) (xy 100.992283 -262.007781)
			(xy 101.003706 -261.960535) (xy 101.00437 -261.93623) (xy 101.003697 -261.911926) (xy 100.99228 -261.864679)
			(xy 100.981764 -261.842758) (xy 100.981256 -261.841996) (xy 100.975668 -261.830566) (xy 100.971604 -261.819898)
			(xy 100.966016 -261.797038) (xy 100.964492 -261.784846) (xy 100.964492 -261.519924) (xy 100.964982 -261.502922)
			(xy 100.972519 -261.469762) (xy 100.987165 -261.439071) (xy 101.0082 -261.412351) (xy 101.021134 -261.401306)
			(xy 101.030024 -261.394194) (xy 101.03993 -261.373366) (xy 101.03993 -261.35203) (xy 101.039857 -261.34782)
			(xy 101.038455 -261.339518) (xy 101.037136 -261.33552) (xy 101.029516 -261.313168) (xy 101.024944 -261.307072)
			(xy 101.010961 -261.287298) (xy 100.988764 -261.244257) (xy 100.973638 -261.198253) (xy 100.965961 -261.150437)
			(xy 100.965508 -261.126224) (xy 100.965992 -261.102013) (xy 100.973669 -261.054201) (xy 100.988788 -261.008198)
			(xy 101.010971 -260.965154) (xy 101.024944 -260.945376) (xy 101.029516 -260.93928) (xy 101.037136 -260.916928)
			(xy 101.03842 -260.912921) (xy 101.039825 -260.904625) (xy 101.03993 -260.900418) (xy 101.03993 -260.879082)
			(xy 101.030024 -260.858254) (xy 101.021134 -260.851142) (xy 101.006879 -260.838855) (xy 100.984325 -260.808742)
			(xy 100.969776 -260.774047) (xy 100.964107 -260.736854) (xy 100.967658 -260.699399) (xy 100.973382 -260.68147)
			(xy 101.03358 -260.621272) (xy 101.040184 -260.61035) (xy 101.041962 -260.604) (xy 101.043956 -260.597889)
			(xy 101.050504 -260.586831) (xy 101.054916 -260.582156) (xy 101.259132 -260.37794) (xy 101.26653 -260.371094)
			(xy 101.285129 -260.363365) (xy 101.2952 -260.362954) (xy 102.04196 -260.362954) (xy 102.052024 -260.362519)
			(xy 102.070609 -260.354784) (xy 102.078028 -260.347968) (xy 102.371906 -260.05409) (xy 102.37875 -260.046691)
			(xy 102.38648 -260.028093) (xy 102.386892 -260.018022) (xy 102.386892 -257.703066) (xy 102.386462 -257.692999)
			(xy 102.378738 -257.674404) (xy 102.371906 -257.666998) (xy 102.285292 -257.580384) (xy 102.27818 -257.573018)
			(xy 102.259384 -257.565398) (xy 101.313996 -257.565398) (xy 101.304612 -257.565836) (xy 101.287101 -257.572592)
			(xy 101.27317 -257.585169) (xy 101.26853 -257.593338) (xy 101.221032 -257.687064) (xy 101.223318 -257.715512)
			(xy 101.231954 -257.727196) (xy 101.24763 -257.749425) (xy 101.272499 -257.797798) (xy 101.289428 -257.849487)
			(xy 101.297992 -257.9032) (xy 101.298502 -257.930396) (xy 101.298022 -257.956095) (xy 101.290361 -258.006919)
			(xy 101.275212 -258.056033) (xy 101.252911 -258.102341) (xy 101.223958 -258.144808) (xy 101.188998 -258.182485)
			(xy 101.148814 -258.214531) (xy 101.104302 -258.24023) (xy 101.056457 -258.259007) (xy 101.006348 -258.270445)
			(xy 100.955094 -258.274286) (xy 100.90384 -258.270445) (xy 100.853731 -258.259007) (xy 100.805886 -258.24023)
			(xy 100.761374 -258.214531) (xy 100.72119 -258.182485) (xy 100.68623 -258.144808) (xy 100.657277 -258.102341)
			(xy 100.634976 -258.056033) (xy 100.619827 -258.006919) (xy 100.612166 -257.956095) (xy 100.611686 -257.930396)
			(xy 100.612245 -257.901933) (xy 100.621633 -257.845785) (xy 100.640151 -257.791955) (xy 100.667292 -257.741915)
			(xy 100.702314 -257.697035) (xy 100.722938 -257.677412) (xy 100.734114 -257.666998) (xy 100.74148 -257.638296)
			(xy 100.736654 -257.624072) (xy 100.736654 -257.623564) (xy 100.72878 -257.600196) (xy 100.722938 -257.588258)
			(xy 100.715973 -257.578794) (xy 100.695731 -257.566906) (xy 100.684076 -257.565398) (xy 100.649278 -257.565398)
			(xy 100.63921 -257.564971) (xy 100.620611 -257.55725) (xy 100.61321 -257.550412) (xy 100.484686 -257.421888)
			(xy 100.477832 -257.414493) (xy 100.470088 -257.395894) (xy 100.4697 -257.38582) (xy 100.4697 -256.153158)
			(xy 100.447856 -256.125726) (xy 100.430584 -256.121662) (xy 100.407278 -256.115684) (xy 100.362774 -256.0974)
			(xy 100.321688 -256.072363) (xy 100.285036 -256.041193) (xy 100.253726 -256.004661) (xy 100.228532 -255.963671)
			(xy 100.210077 -255.919238) (xy 100.198819 -255.87246) (xy 100.195036 -255.824496) (xy 100.19882 -255.776532)
			(xy 100.21008 -255.729754) (xy 100.228536 -255.685321) (xy 100.253731 -255.644332) (xy 100.285042 -255.607801)
			(xy 100.321694 -255.576632) (xy 100.362781 -255.551597) (xy 100.407286 -255.533314) (xy 100.430584 -255.527302)
			(xy 100.447856 -255.523238) (xy 100.4697 -255.495806) (xy 100.4697 -254.533146) (xy 100.447856 -254.505714)
			(xy 100.430584 -254.50165) (xy 100.407279 -254.495672) (xy 100.362777 -254.477388) (xy 100.321692 -254.452352)
			(xy 100.285042 -254.421183) (xy 100.253734 -254.384652) (xy 100.228541 -254.343664) (xy 100.210088 -254.299232)
			(xy 100.19883 -254.252456) (xy 100.195047 -254.204493) (xy 100.198832 -254.156531) (xy 100.210092 -254.109755)
			(xy 100.228547 -254.065324) (xy 100.253742 -254.024337) (xy 100.285052 -253.987807) (xy 100.321703 -253.95664)
			(xy 100.362789 -253.931606) (xy 100.407292 -253.913324) (xy 100.430584 -253.90729) (xy 100.447856 -253.903226)
			(xy 100.4697 -253.875794) (xy 100.4697 -252.913134) (xy 100.447856 -252.885702) (xy 100.430584 -252.881638)
			(xy 100.405826 -252.875253) (xy 100.358728 -252.855367) (xy 100.315601 -252.827911) (xy 100.277651 -252.793654)
			(xy 100.245939 -252.753553) (xy 100.221352 -252.708729) (xy 100.204577 -252.660435) (xy 100.196082 -252.610021)
			(xy 100.195634 -252.584458) (xy 100.196042 -252.561916) (xy 100.202681 -252.517323) (xy 100.215809 -252.474192)
			(xy 100.225098 -252.453648) (xy 100.229162 -252.445266) (xy 100.230686 -252.427232) (xy 100.207572 -252.344936)
			(xy 100.196904 -252.330204) (xy 100.18903 -252.325124) (xy 100.170424 -252.312472) (xy 100.136795 -252.282582)
			(xy 100.107916 -252.248079) (xy 100.095812 -252.229112) (xy 100.090992 -252.221857) (xy 100.077489 -252.210877)
			(xy 100.061081 -252.20507) (xy 100.052378 -252.204728) (xy 100.009706 -252.204728) (xy 100.001003 -252.205077)
			(xy 99.984595 -252.210888) (xy 99.971071 -252.221845) (xy 99.966272 -252.229112) (xy 99.954178 -252.248086)
			(xy 99.925297 -252.282589) (xy 99.891666 -252.312479) (xy 99.873054 -252.325124) (xy 99.86518 -252.330204)
			(xy 99.854512 -252.344936) (xy 99.831398 -252.427232) (xy 99.832922 -252.445266) (xy 99.836986 -252.453648)
			(xy 99.846285 -252.474187) (xy 99.859409 -252.51732) (xy 99.866039 -252.561915) (xy 99.86645 -252.584458)
			(xy 99.865928 -252.609713) (xy 99.857615 -252.659535) (xy 99.841214 -252.707309) (xy 99.817173 -252.751732)
			(xy 99.786149 -252.791592) (xy 99.748987 -252.825802) (xy 99.706701 -252.853428) (xy 99.660445 -252.873718)
			(xy 99.61148 -252.886118) (xy 99.561142 -252.890289) (xy 99.510804 -252.886118) (xy 99.461839 -252.873718)
			(xy 99.415583 -252.853428) (xy 99.373297 -252.825802) (xy 99.336135 -252.791592) (xy 99.305111 -252.751732)
			(xy 99.28107 -252.707309) (xy 99.264669 -252.659535) (xy 99.256356 -252.609713) (xy 99.255834 -252.584458)
			(xy 99.256242 -252.561916) (xy 99.262881 -252.517323) (xy 99.276009 -252.474192) (xy 99.285298 -252.453648)
			(xy 99.289362 -252.445266) (xy 99.290886 -252.427232) (xy 99.267518 -252.344936) (xy 99.25685 -252.330458)
			(xy 99.248976 -252.325124) (xy 99.230368 -252.312474) (xy 99.196734 -252.282587) (xy 99.167852 -252.248086)
			(xy 99.155758 -252.229112) (xy 99.15094 -252.221853) (xy 99.137439 -252.21086) (xy 99.12103 -252.205038)
			(xy 99.112324 -252.204728) (xy 99.069652 -252.204728) (xy 99.060953 -252.205085) (xy 99.044559 -252.210908)
			(xy 99.031049 -252.22187) (xy 99.026218 -252.229112) (xy 99.014122 -252.248085) (xy 98.985238 -252.282583)
			(xy 98.951604 -252.312468) (xy 98.933 -252.325124) (xy 98.925126 -252.330204) (xy 98.914458 -252.344936)
			(xy 98.891344 -252.427232) (xy 98.892868 -252.445266) (xy 98.896932 -252.453648) (xy 98.906233 -252.474187)
			(xy 98.919359 -252.51732) (xy 98.92599 -252.561915) (xy 98.926396 -252.584458) (xy 98.925874 -252.609713)
			(xy 98.917561 -252.659535) (xy 98.90116 -252.707309) (xy 98.877119 -252.751732) (xy 98.846095 -252.791592)
			(xy 98.808933 -252.825802) (xy 98.766647 -252.853428) (xy 98.720391 -252.873718) (xy 98.671426 -252.886118)
			(xy 98.621088 -252.890289) (xy 98.57075 -252.886118) (xy 98.521785 -252.873718) (xy 98.475529 -252.853428)
			(xy 98.433243 -252.825802) (xy 98.396081 -252.791592) (xy 98.365057 -252.751732) (xy 98.341016 -252.707309)
			(xy 98.324615 -252.659535) (xy 98.316302 -252.609713) (xy 98.31578 -252.584458) (xy 98.316188 -252.561916)
			(xy 98.322828 -252.517323) (xy 98.335958 -252.474193) (xy 98.345244 -252.453648) (xy 98.349308 -252.445266)
			(xy 98.350832 -252.427232) (xy 98.327464 -252.344936) (xy 98.316796 -252.330458) (xy 98.308922 -252.325124)
			(xy 98.290316 -252.312472) (xy 98.256688 -252.282581) (xy 98.22781 -252.248078) (xy 98.215704 -252.229112)
			(xy 98.210884 -252.221859) (xy 98.19738 -252.21088) (xy 98.180973 -252.205076) (xy 98.17227 -252.204728)
			(xy 98.129598 -252.204728) (xy 98.120896 -252.205078) (xy 98.10449 -252.210891) (xy 98.090968 -252.221849)
			(xy 98.086164 -252.229112) (xy 98.07407 -252.248086) (xy 98.045188 -252.282588) (xy 98.011557 -252.312478)
			(xy 97.992946 -252.325124) (xy 97.985072 -252.330204) (xy 97.974404 -252.344936) (xy 97.95129 -252.427232)
			(xy 97.952814 -252.445266) (xy 97.956878 -252.453648) (xy 97.966178 -252.474187) (xy 97.979302 -252.51732)
			(xy 97.985932 -252.561915) (xy 97.986342 -252.584458) (xy 97.98582 -252.609713) (xy 97.977507 -252.659535)
			(xy 97.961106 -252.707309) (xy 97.937065 -252.751732) (xy 97.906041 -252.791592) (xy 97.868879 -252.825802)
			(xy 97.826593 -252.853428) (xy 97.780337 -252.873718) (xy 97.731372 -252.886118) (xy 97.681034 -252.890289)
			(xy 97.630696 -252.886118) (xy 97.581731 -252.873718) (xy 97.535475 -252.853428) (xy 97.493189 -252.825802)
			(xy 97.456027 -252.791592) (xy 97.425003 -252.751732) (xy 97.400962 -252.707309) (xy 97.384561 -252.659535)
			(xy 97.376248 -252.609713) (xy 97.375726 -252.584458) (xy 97.376134 -252.561916) (xy 97.382773 -252.517323)
			(xy 97.395901 -252.474192) (xy 97.40519 -252.453648) (xy 97.409254 -252.445266) (xy 97.410778 -252.427232)
			(xy 97.387664 -252.344936) (xy 97.376996 -252.330204) (xy 97.369122 -252.325124) (xy 97.350516 -252.312472)
			(xy 97.316888 -252.282581) (xy 97.28801 -252.248078) (xy 97.275904 -252.229112) (xy 97.271084 -252.221859)
			(xy 97.25758 -252.21088) (xy 97.241173 -252.205076) (xy 97.23247 -252.204728) (xy 97.189798 -252.204728)
			(xy 97.181096 -252.205078) (xy 97.16469 -252.210891) (xy 97.151168 -252.221849) (xy 97.146364 -252.229112)
			(xy 97.13427 -252.248086) (xy 97.105388 -252.282588) (xy 97.071757 -252.312478) (xy 97.053146 -252.325124)
			(xy 97.045272 -252.330458) (xy 97.034604 -252.344936) (xy 97.011236 -252.427232) (xy 97.01276 -252.445266)
			(xy 97.016824 -252.453648) (xy 97.026122 -252.474187) (xy 97.039244 -252.517321) (xy 97.045873 -252.561915)
			(xy 97.046288 -252.584458) (xy 97.045766 -252.609713) (xy 97.037453 -252.659535) (xy 97.021052 -252.707309)
			(xy 96.997011 -252.751732) (xy 96.965987 -252.791592) (xy 96.928825 -252.825802) (xy 96.886539 -252.853428)
			(xy 96.840283 -252.873718) (xy 96.791318 -252.886118) (xy 96.74098 -252.890289) (xy 96.690642 -252.886118)
			(xy 96.641677 -252.873718) (xy 96.595421 -252.853428) (xy 96.553135 -252.825802) (xy 96.515973 -252.791592)
			(xy 96.484949 -252.751732) (xy 96.460908 -252.707309) (xy 96.444507 -252.659535) (xy 96.436194 -252.609713)
			(xy 96.435672 -252.584458) (xy 96.43608 -252.561916) (xy 96.44272 -252.517323) (xy 96.455849 -252.474193)
			(xy 96.465136 -252.453648) (xy 96.4692 -252.445266) (xy 96.470724 -252.427232) (xy 96.44761 -252.344936)
			(xy 96.436942 -252.330204) (xy 96.429068 -252.325124) (xy 96.41046 -252.312474) (xy 96.376828 -252.282586)
			(xy 96.347946 -252.248085) (xy 96.33585 -252.229112) (xy 96.331032 -252.221853) (xy 96.31753 -252.210863)
			(xy 96.301121 -252.205044) (xy 96.292416 -252.204728) (xy 96.249744 -252.204728) (xy 96.241046 -252.205086)
			(xy 96.224654 -252.210911) (xy 96.211146 -252.221874) (xy 96.20631 -252.229112) (xy 96.193129 -252.249728)
			(xy 96.161268 -252.286862) (xy 96.123901 -252.318449) (xy 96.103186 -252.331474) (xy 96.095019 -252.336912)
			(xy 96.083251 -252.352589) (xy 96.080326 -252.361954) (xy 96.071944 -252.392942) (xy 96.069825 -252.402524)
			(xy 96.072169 -252.421991) (xy 96.076516 -252.430788) (xy 96.084644 -252.446028) (xy 96.094726 -252.467698)
			(xy 96.108976 -252.513318) (xy 96.116201 -252.560562) (xy 96.116648 -252.584458) (xy 96.11619 -252.609272)
			(xy 96.108432 -252.658291) (xy 96.093102 -252.705493) (xy 96.070576 -252.749715) (xy 96.04141 -252.789869)
			(xy 96.006321 -252.824966) (xy 95.966173 -252.854141) (xy 95.921956 -252.876676) (xy 95.874757 -252.892017)
			(xy 95.82574 -252.899784) (xy 95.800926 -252.90018) (xy 95.776089 -252.899719) (xy 95.727027 -252.891943)
			(xy 95.679789 -252.876579) (xy 95.635539 -252.854007) (xy 95.595371 -252.824784) (xy 95.560276 -252.78963)
			(xy 95.531119 -252.749413) (xy 95.50862 -252.705126) (xy 95.493335 -252.657862) (xy 95.485641 -252.608788)
			(xy 95.485204 -252.58395) (xy 95.485458 -252.575822) (xy 95.486434 -252.553769) (xy 95.493742 -252.510237)
			(xy 95.507033 -252.468144) (xy 95.516192 -252.44806) (xy 95.520256 -252.439932) (xy 95.52178 -252.421898)
			(xy 95.50019 -252.340872) (xy 95.489776 -252.325886) (xy 95.48241 -252.320806) (xy 95.465199 -252.30845)
			(xy 95.434039 -252.279743) (xy 95.407158 -252.246995) (xy 95.395796 -252.229112) (xy 95.390975 -252.221859)
			(xy 95.377471 -252.210883) (xy 95.361064 -252.205081) (xy 95.352362 -252.204728) (xy 95.30969 -252.204728)
			(xy 95.300988 -252.205079) (xy 95.284585 -252.210894) (xy 95.271064 -252.221853) (xy 95.266256 -252.229112)
			(xy 95.254161 -252.248086) (xy 95.22528 -252.282587) (xy 95.191647 -252.312476) (xy 95.173038 -252.325124)
			(xy 95.165164 -252.330204) (xy 95.154496 -252.344936) (xy 95.131382 -252.427232) (xy 95.132906 -252.445266)
			(xy 95.13697 -252.453648) (xy 95.14627 -252.474187) (xy 95.159394 -252.51732) (xy 95.166024 -252.561915)
			(xy 95.166434 -252.584458) (xy 95.165912 -252.609713) (xy 95.157599 -252.659535) (xy 95.141198 -252.707309)
			(xy 95.117157 -252.751732) (xy 95.086133 -252.791592) (xy 95.048971 -252.825802) (xy 95.006685 -252.853428)
			(xy 94.960429 -252.873718) (xy 94.911464 -252.886118) (xy 94.861126 -252.890289) (xy 94.810788 -252.886118)
			(xy 94.761823 -252.873718) (xy 94.715567 -252.853428) (xy 94.673281 -252.825802) (xy 94.636119 -252.791592)
			(xy 94.605095 -252.751732) (xy 94.581054 -252.707309) (xy 94.564653 -252.659535) (xy 94.55634 -252.609713)
			(xy 94.555818 -252.584458) (xy 94.556203 -252.561588) (xy 94.562996 -252.516355) (xy 94.576482 -252.472649)
			(xy 94.586044 -252.45187) (xy 94.590108 -252.443488) (xy 94.591886 -252.425454) (xy 94.569534 -252.343158)
			(xy 94.558866 -252.328426) (xy 94.551246 -252.323346) (xy 94.533184 -252.310822) (xy 94.500514 -252.28142)
			(xy 94.472398 -252.247636) (xy 94.460568 -252.229112) (xy 94.455779 -252.221884) (xy 94.442361 -252.210919)
			(xy 94.426051 -252.205068) (xy 94.417388 -252.204728) (xy 94.364556 -252.204728) (xy 94.355896 -252.205112)
			(xy 94.339586 -252.210949) (xy 94.326144 -252.221875) (xy 94.321376 -252.229112) (xy 94.304502 -252.255089)
			(xy 94.262145 -252.300272) (xy 94.237302 -252.318774) (xy 94.229682 -252.324108) (xy 94.219776 -252.33884)
			(xy 94.198948 -252.420374) (xy 94.200726 -252.4379) (xy 94.20479 -252.446282) (xy 94.21482 -252.467919)
			(xy 94.228973 -252.51346) (xy 94.236111 -252.560613) (xy 94.23654 -252.584458) (xy 94.236054 -252.609248)
			(xy 94.228298 -252.658216) (xy 94.212977 -252.705369) (xy 94.190468 -252.749544) (xy 94.161326 -252.789655)
			(xy 94.126269 -252.824712) (xy 94.086158 -252.853854) (xy 94.041983 -252.876363) (xy 93.99483 -252.891684)
			(xy 93.945862 -252.89944) (xy 93.896282 -252.89944) (xy 93.847314 -252.891684) (xy 93.800161 -252.876363)
			(xy 93.755986 -252.853854) (xy 93.715875 -252.824712) (xy 93.680818 -252.789655) (xy 93.651676 -252.749544)
			(xy 93.629167 -252.705369) (xy 93.613846 -252.658216) (xy 93.60609 -252.609248) (xy 93.605604 -252.584458)
			(xy 93.60535 -252.584458) (xy 93.605799 -252.560982) (xy 93.612789 -252.514553) (xy 93.626581 -252.469671)
			(xy 93.636338 -252.448314) (xy 93.640148 -252.440186) (xy 93.641926 -252.422152) (xy 93.620336 -252.340872)
			(xy 93.609922 -252.325886) (xy 93.602556 -252.320806) (xy 93.585295 -252.308466) (xy 93.554038 -252.279774)
			(xy 93.527067 -252.24702) (xy 93.515688 -252.229112) (xy 93.510867 -252.22186) (xy 93.497362 -252.210886)
			(xy 93.480956 -252.205087) (xy 93.472254 -252.204728) (xy 93.429582 -252.204728) (xy 93.420881 -252.20508)
			(xy 93.404479 -252.210897) (xy 93.390961 -252.221856) (xy 93.386148 -252.229112) (xy 93.374053 -252.248085)
			(xy 93.345171 -252.282586) (xy 93.311538 -252.312474) (xy 93.29293 -252.325124) (xy 93.285056 -252.330204)
			(xy 93.274388 -252.344936) (xy 93.251274 -252.427232) (xy 93.252798 -252.445266) (xy 93.256862 -252.453648)
			(xy 93.266162 -252.474187) (xy 93.279287 -252.51732) (xy 93.285917 -252.561915) (xy 93.286326 -252.584458)
			(xy 93.285804 -252.609713) (xy 93.277491 -252.659535) (xy 93.26109 -252.707309) (xy 93.237049 -252.751732)
			(xy 93.206025 -252.791592) (xy 93.168863 -252.825802) (xy 93.126577 -252.853428) (xy 93.080321 -252.873718)
			(xy 93.031356 -252.886118) (xy 92.981018 -252.890289) (xy 92.93068 -252.886118) (xy 92.881715 -252.873718)
			(xy 92.835459 -252.853428) (xy 92.793173 -252.825802) (xy 92.756011 -252.791592) (xy 92.724987 -252.751732)
			(xy 92.700946 -252.707309) (xy 92.684545 -252.659535) (xy 92.676232 -252.609713) (xy 92.67571 -252.584458)
			(xy 92.676118 -252.561916) (xy 92.682757 -252.517322) (xy 92.695884 -252.474191) (xy 92.705174 -252.453648)
			(xy 92.709238 -252.445266) (xy 92.710762 -252.427232) (xy 92.687648 -252.344936) (xy 92.67698 -252.330204)
			(xy 92.669106 -252.325124) (xy 92.650496 -252.312476) (xy 92.61686 -252.28259) (xy 92.587975 -252.248091)
			(xy 92.575888 -252.229112) (xy 92.571067 -252.22186) (xy 92.557562 -252.210886) (xy 92.541156 -252.205087)
			(xy 92.532454 -252.204728) (xy 92.489782 -252.204728) (xy 92.481081 -252.20508) (xy 92.464679 -252.210897)
			(xy 92.451161 -252.221856) (xy 92.446348 -252.229112) (xy 92.434946 -252.247004) (xy 92.407973 -252.279753)
			(xy 92.376733 -252.308458) (xy 92.35948 -252.320806) (xy 92.352114 -252.32614) (xy 92.3417 -252.340872)
			(xy 92.32011 -252.422152) (xy 92.321634 -252.440186) (xy 92.325698 -252.448314) (xy 92.335421 -252.469677)
			(xy 92.349137 -252.514564) (xy 92.356038 -252.56099) (xy 92.356432 -252.584458) (xy 92.355946 -252.609248)
			(xy 92.34819 -252.658216) (xy 92.332869 -252.705369) (xy 92.31036 -252.749544) (xy 92.281218 -252.789655)
			(xy 92.246161 -252.824712) (xy 92.20605 -252.853854) (xy 92.161875 -252.876363) (xy 92.114722 -252.891684)
			(xy 92.065754 -252.89944) (xy 92.016174 -252.89944) (xy 91.967206 -252.891684) (xy 91.920053 -252.876363)
			(xy 91.875878 -252.853854) (xy 91.835767 -252.824712) (xy 91.80071 -252.789655) (xy 91.771568 -252.749544)
			(xy 91.749059 -252.705369) (xy 91.733738 -252.658216) (xy 91.725982 -252.609248) (xy 91.725496 -252.584458)
			(xy 91.725242 -252.584458) (xy 91.725679 -252.56094) (xy 91.732664 -252.514426) (xy 91.746475 -252.469464)
			(xy 91.75623 -252.44806) (xy 91.76004 -252.439932) (xy 91.761818 -252.421898) (xy 91.740228 -252.340618)
			(xy 91.729814 -252.325886) (xy 91.722448 -252.320806) (xy 91.705235 -252.308451) (xy 91.674073 -252.279747)
			(xy 91.647188 -252.247) (xy 91.635834 -252.229112) (xy 91.631015 -252.221855) (xy 91.617513 -252.210869)
			(xy 91.601104 -252.205055) (xy 91.5924 -252.204728) (xy 91.549728 -252.204728) (xy 91.541032 -252.205089)
			(xy 91.524643 -252.210917) (xy 91.51114 -252.221881) (xy 91.506294 -252.229112) (xy 91.493113 -252.249727)
			(xy 91.461251 -252.28686) (xy 91.423882 -252.318445) (xy 91.40317 -252.331474) (xy 91.395005 -252.336913)
			(xy 91.38324 -252.352591) (xy 91.38031 -252.361954) (xy 91.371928 -252.392942) (xy 91.369809 -252.402524)
			(xy 91.372152 -252.421991) (xy 91.3765 -252.430788) (xy 91.384628 -252.446028) (xy 91.394711 -252.467698)
			(xy 91.408961 -252.513317) (xy 91.416187 -252.560562) (xy 91.416632 -252.584458) (xy 91.416174 -252.609272)
			(xy 91.408416 -252.65829) (xy 91.393086 -252.70549) (xy 91.37056 -252.749712) (xy 91.341393 -252.789864)
			(xy 91.306304 -252.824959) (xy 91.266156 -252.854133) (xy 91.221939 -252.876666) (xy 91.17474 -252.892004)
			(xy 91.125724 -252.89977) (xy 91.10091 -252.90018) (xy 91.076074 -252.899717) (xy 91.027014 -252.89194)
			(xy 90.979778 -252.876575) (xy 90.935531 -252.854002) (xy 90.895365 -252.824778) (xy 90.860271 -252.789624)
			(xy 90.831116 -252.749408) (xy 90.808618 -252.705123) (xy 90.793334 -252.65786) (xy 90.785641 -252.608787)
			(xy 90.785188 -252.58395) (xy 90.785442 -252.575822) (xy 90.786444 -252.553433) (xy 90.793993 -252.509256)
			(xy 90.80772 -252.466594) (xy 90.817192 -252.446282) (xy 90.821256 -252.4379) (xy 90.823034 -252.420374)
			(xy 90.802206 -252.338586) (xy 90.792046 -252.324108) (xy 90.78468 -252.318774) (xy 90.768013 -252.306601)
			(xy 90.737806 -252.278477) (xy 90.711676 -252.24653) (xy 90.700606 -252.229112) (xy 90.695814 -252.22189)
			(xy 90.682394 -252.210942) (xy 90.666085 -252.20511) (xy 90.657426 -252.204728) (xy 90.604594 -252.204728)
			(xy 90.59594 -252.205122) (xy 90.579645 -252.210972) (xy 90.566219 -252.221903) (xy 90.561414 -252.229112)
			(xy 90.549637 -252.247636) (xy 90.521602 -252.28141) (xy 90.489011 -252.310813) (xy 90.47099 -252.323346)
			(xy 90.463116 -252.328426) (xy 90.452702 -252.343158) (xy 90.43035 -252.425454) (xy 90.432128 -252.443488)
			(xy 90.436192 -252.45187) (xy 90.445714 -252.472663) (xy 90.459171 -252.51637) (xy 90.465979 -252.561592)
			(xy 90.466418 -252.584458) (xy 90.465896 -252.609713) (xy 90.457583 -252.659535) (xy 90.441182 -252.707309)
			(xy 90.417141 -252.751732) (xy 90.386117 -252.791592) (xy 90.348955 -252.825802) (xy 90.306669 -252.853428)
			(xy 90.260413 -252.873718) (xy 90.211448 -252.886118) (xy 90.16111 -252.890289) (xy 90.110772 -252.886118)
			(xy 90.061807 -252.873718) (xy 90.015551 -252.853428) (xy 89.973265 -252.825802) (xy 89.936103 -252.791592)
			(xy 89.905079 -252.751732) (xy 89.881038 -252.707309) (xy 89.864637 -252.659535) (xy 89.856324 -252.609713)
			(xy 89.855802 -252.584458) (xy 89.85621 -252.561916) (xy 89.862851 -252.517323) (xy 89.875981 -252.474194)
			(xy 89.885266 -252.453648) (xy 89.88933 -252.445266) (xy 89.890854 -252.427232) (xy 89.867486 -252.344936)
			(xy 89.856818 -252.330458) (xy 89.848944 -252.325124) (xy 89.830337 -252.312473) (xy 89.796707 -252.282583)
			(xy 89.767827 -252.248081) (xy 89.755726 -252.229112) (xy 89.750907 -252.221856) (xy 89.737404 -252.210871)
			(xy 89.720996 -252.20506) (xy 89.712292 -252.204728) (xy 89.66962 -252.204728) (xy 89.660924 -252.20509)
			(xy 89.644538 -252.21092) (xy 89.631036 -252.221884) (xy 89.626186 -252.229112) (xy 89.614823 -252.246994)
			(xy 89.587936 -252.279737) (xy 89.556786 -252.308455) (xy 89.539572 -252.320806) (xy 89.531952 -252.325886)
			(xy 89.521538 -252.340872) (xy 89.500202 -252.421898) (xy 89.501726 -252.439932) (xy 89.50579 -252.44806)
			(xy 89.515526 -252.469463) (xy 89.529248 -252.514435) (xy 89.536129 -252.560948) (xy 89.536524 -252.584458)
			(xy 89.536038 -252.609248) (xy 89.528282 -252.658216) (xy 89.512961 -252.705369) (xy 89.490452 -252.749544)
			(xy 89.46131 -252.789655) (xy 89.426253 -252.824712) (xy 89.386142 -252.853854) (xy 89.341967 -252.876363)
			(xy 89.294814 -252.891684) (xy 89.245846 -252.89944) (xy 89.196266 -252.89944) (xy 89.147298 -252.891684)
			(xy 89.100145 -252.876363) (xy 89.05597 -252.853854) (xy 89.015859 -252.824712) (xy 88.980802 -252.789655)
			(xy 88.95166 -252.749544) (xy 88.929151 -252.705369) (xy 88.91383 -252.658216) (xy 88.906074 -252.609248)
			(xy 88.905588 -252.584458) (xy 88.905334 -252.584458) (xy 88.905771 -252.56094) (xy 88.912756 -252.514426)
			(xy 88.926566 -252.469464) (xy 88.936322 -252.44806) (xy 88.940132 -252.439932) (xy 88.94191 -252.421898)
			(xy 88.92032 -252.340618) (xy 88.909906 -252.325886) (xy 88.90254 -252.320806) (xy 88.885328 -252.308451)
			(xy 88.854166 -252.279746) (xy 88.827282 -252.246999) (xy 88.815926 -252.229112) (xy 88.811107 -252.221856)
			(xy 88.797604 -252.210871) (xy 88.781196 -252.20506) (xy 88.772492 -252.204728) (xy 88.72982 -252.204728)
			(xy 88.721124 -252.20509) (xy 88.704738 -252.21092) (xy 88.691236 -252.221884) (xy 88.686386 -252.229112)
			(xy 88.674292 -252.248087) (xy 88.645412 -252.28259) (xy 88.611782 -252.312482) (xy 88.593168 -252.325124)
			(xy 88.585294 -252.330458) (xy 88.574626 -252.344936) (xy 88.551258 -252.427232) (xy 88.552782 -252.445266)
			(xy 88.556846 -252.453648) (xy 88.566146 -252.474187) (xy 88.579272 -252.51732) (xy 88.585903 -252.561915)
			(xy 88.58631 -252.584458) (xy 88.585788 -252.609713) (xy 88.577475 -252.659535) (xy 88.561074 -252.707309)
			(xy 88.537033 -252.751732) (xy 88.506009 -252.791592) (xy 88.468847 -252.825802) (xy 88.426561 -252.853428)
			(xy 88.380305 -252.873718) (xy 88.33134 -252.886118) (xy 88.281002 -252.890289) (xy 88.230664 -252.886118)
			(xy 88.181699 -252.873718) (xy 88.135443 -252.853428) (xy 88.093157 -252.825802) (xy 88.055995 -252.791592)
			(xy 88.024971 -252.751732) (xy 88.00093 -252.707309) (xy 87.984529 -252.659535) (xy 87.976216 -252.609713)
			(xy 87.975694 -252.584458) (xy 87.976078 -252.561588) (xy 87.982871 -252.516355) (xy 87.996356 -252.472648)
			(xy 88.00592 -252.45187) (xy 88.009984 -252.443488) (xy 88.011762 -252.425454) (xy 87.98941 -252.343158)
			(xy 87.978996 -252.328426) (xy 87.971122 -252.323346) (xy 87.953104 -252.31081) (xy 87.920517 -252.281403)
			(xy 87.892472 -252.247637) (xy 87.880698 -252.229112) (xy 87.875905 -252.221891) (xy 87.862485 -252.210945)
			(xy 87.846176 -252.205116) (xy 87.837518 -252.204728) (xy 87.784686 -252.204728) (xy 87.776032 -252.205123)
			(xy 87.759739 -252.210975) (xy 87.746316 -252.221907) (xy 87.741506 -252.229112) (xy 87.730427 -252.246561)
			(xy 87.7043 -252.278587) (xy 87.674097 -252.306801) (xy 87.657432 -252.319028) (xy 87.649812 -252.324362)
			(xy 87.639906 -252.33884) (xy 87.618824 -252.420374) (xy 87.620602 -252.4379) (xy 87.624666 -252.446282)
			(xy 87.634696 -252.467919) (xy 87.64885 -252.51346) (xy 87.655989 -252.560613) (xy 87.656416 -252.584458)
			(xy 87.65593 -252.609248) (xy 87.648174 -252.658216) (xy 87.632853 -252.705369) (xy 87.610344 -252.749544)
			(xy 87.581202 -252.789655) (xy 87.546145 -252.824712) (xy 87.506034 -252.853854) (xy 87.461859 -252.876363)
			(xy 87.414706 -252.891684) (xy 87.365738 -252.89944) (xy 87.316158 -252.89944) (xy 87.26719 -252.891684)
			(xy 87.220037 -252.876363) (xy 87.175862 -252.853854) (xy 87.135751 -252.824712) (xy 87.100694 -252.789655)
			(xy 87.071552 -252.749544) (xy 87.049043 -252.705369) (xy 87.033722 -252.658216) (xy 87.025966 -252.609248)
			(xy 87.02548 -252.584458) (xy 87.025226 -252.584458) (xy 87.025663 -252.56094) (xy 87.032648 -252.514426)
			(xy 87.046458 -252.469463) (xy 87.056214 -252.44806) (xy 87.060024 -252.439932) (xy 87.061802 -252.421898)
			(xy 87.040212 -252.340618) (xy 87.029798 -252.325886) (xy 87.022432 -252.320806) (xy 87.00522 -252.308451)
			(xy 86.974059 -252.279745) (xy 86.947175 -252.246998) (xy 86.935818 -252.229112) (xy 86.930999 -252.221857)
			(xy 86.917495 -252.210874) (xy 86.901088 -252.205066) (xy 86.892384 -252.204728) (xy 86.849712 -252.204728)
			(xy 86.841008 -252.205076) (xy 86.824599 -252.210886) (xy 86.811073 -252.221843) (xy 86.806278 -252.229112)
			(xy 86.794184 -252.248086) (xy 86.765304 -252.282589) (xy 86.731673 -252.31248) (xy 86.71306 -252.325124)
			(xy 86.705186 -252.330204) (xy 86.694518 -252.344936) (xy 86.671404 -252.427232) (xy 86.672928 -252.445266)
			(xy 86.676992 -252.453648) (xy 86.686291 -252.474187) (xy 86.699415 -252.51732) (xy 86.706044 -252.561915)
			(xy 86.706456 -252.584458) (xy 86.705934 -252.609713) (xy 86.697621 -252.659535) (xy 86.68122 -252.707309)
			(xy 86.657179 -252.751732) (xy 86.626155 -252.791592) (xy 86.588993 -252.825802) (xy 86.546707 -252.853428)
			(xy 86.500451 -252.873718) (xy 86.451486 -252.886118) (xy 86.401148 -252.890289) (xy 86.35081 -252.886118)
			(xy 86.301845 -252.873718) (xy 86.255589 -252.853428) (xy 86.213303 -252.825802) (xy 86.176141 -252.791592)
			(xy 86.145117 -252.751732) (xy 86.121076 -252.707309) (xy 86.104675 -252.659535) (xy 86.096362 -252.609713)
			(xy 86.09584 -252.584458) (xy 86.096248 -252.561916) (xy 86.102887 -252.517323) (xy 86.116016 -252.474192)
			(xy 86.125304 -252.453648) (xy 86.129368 -252.445266) (xy 86.130892 -252.427232) (xy 86.107524 -252.344936)
			(xy 86.096856 -252.330458) (xy 86.088982 -252.325124) (xy 86.070373 -252.312475) (xy 86.03674 -252.282587)
			(xy 86.007856 -252.248087) (xy 85.995764 -252.229112) (xy 85.990946 -252.221852) (xy 85.977445 -252.210857)
			(xy 85.961036 -252.205034) (xy 85.95233 -252.204728) (xy 85.909658 -252.204728) (xy 85.900959 -252.205084)
			(xy 85.884563 -252.210906) (xy 85.871052 -252.221867) (xy 85.866224 -252.229112) (xy 85.853042 -252.249694)
			(xy 85.821183 -252.286754) (xy 85.783819 -252.318256) (xy 85.7631 -252.33122) (xy 85.754968 -252.336694)
			(xy 85.743213 -252.35236) (xy 85.74024 -252.3617) (xy 85.732112 -252.392942) (xy 85.729993 -252.402524)
			(xy 85.732336 -252.421991) (xy 85.736684 -252.430788) (xy 85.744812 -252.446028) (xy 85.754895 -252.467698)
			(xy 85.769146 -252.513317) (xy 85.776372 -252.560562) (xy 85.776816 -252.584458) (xy 85.776358 -252.609272)
			(xy 85.7686 -252.658288) (xy 85.753269 -252.705488) (xy 85.730743 -252.749708) (xy 85.701576 -252.789859)
			(xy 85.666487 -252.824953) (xy 85.626339 -252.854124) (xy 85.582121 -252.876656) (xy 85.534923 -252.891992)
			(xy 85.485907 -252.899755) (xy 85.461094 -252.90018) (xy 85.436259 -252.899716) (xy 85.387201 -252.891937)
			(xy 85.339967 -252.87657) (xy 85.295722 -252.853996) (xy 85.255558 -252.824772) (xy 85.220466 -252.789619)
			(xy 85.191313 -252.749403) (xy 85.168817 -252.705119) (xy 85.153534 -252.657858) (xy 85.145841 -252.608786)
			(xy 85.145372 -252.58395) (xy 85.145626 -252.575822) (xy 85.146612 -252.553811) (xy 85.153927 -252.510364)
			(xy 85.167204 -252.468354) (xy 85.17636 -252.448314) (xy 85.18017 -252.440186) (xy 85.181948 -252.422152)
			(xy 85.160358 -252.340872) (xy 85.149944 -252.32614) (xy 85.142578 -252.320806) (xy 85.125316 -252.308467)
			(xy 85.094057 -252.279777) (xy 85.067085 -252.247023) (xy 85.05571 -252.229112) (xy 85.05089 -252.221858)
			(xy 85.037387 -252.210877) (xy 85.020979 -252.205071) (xy 85.012276 -252.204728) (xy 84.969604 -252.204728)
			(xy 84.960901 -252.205077) (xy 84.944494 -252.210889) (xy 84.93097 -252.221846) (xy 84.92617 -252.229112)
			(xy 84.914807 -252.246994) (xy 84.887918 -252.279735) (xy 84.856768 -252.308452) (xy 84.839556 -252.320806)
			(xy 84.831936 -252.325886) (xy 84.821522 -252.340872) (xy 84.800186 -252.421898) (xy 84.80171 -252.439932)
			(xy 84.805774 -252.44806) (xy 84.815507 -252.469464) (xy 84.829226 -252.514436) (xy 84.836105 -252.560948)
			(xy 84.836508 -252.584458) (xy 84.836022 -252.609248) (xy 84.828266 -252.658216) (xy 84.812945 -252.705369)
			(xy 84.790436 -252.749544) (xy 84.761294 -252.789655) (xy 84.726237 -252.824712) (xy 84.686126 -252.853854)
			(xy 84.641951 -252.876363) (xy 84.594798 -252.891684) (xy 84.54583 -252.89944) (xy 84.49625 -252.89944)
			(xy 84.447282 -252.891684) (xy 84.400129 -252.876363) (xy 84.355954 -252.853854) (xy 84.315843 -252.824712)
			(xy 84.280786 -252.789655) (xy 84.251644 -252.749544) (xy 84.229135 -252.705369) (xy 84.213814 -252.658216)
			(xy 84.206058 -252.609248) (xy 84.205572 -252.584458) (xy 84.205318 -252.584458) (xy 84.205768 -252.560602)
			(xy 84.212983 -252.513438) (xy 84.227227 -252.467901) (xy 84.237322 -252.446282) (xy 84.241386 -252.4379)
			(xy 84.243164 -252.420374) (xy 84.222336 -252.338586) (xy 84.212176 -252.324108) (xy 84.20481 -252.318774)
			(xy 84.188142 -252.306602) (xy 84.157933 -252.27848) (xy 84.131801 -252.246534) (xy 84.120736 -252.229112)
			(xy 84.115945 -252.221887) (xy 84.102526 -252.210931) (xy 84.086217 -252.20509) (xy 84.077556 -252.204728)
			(xy 84.024724 -252.204728) (xy 84.016067 -252.205117) (xy 83.999765 -252.210961) (xy 83.986331 -252.22189)
			(xy 83.981544 -252.229112) (xy 83.969728 -252.247646) (xy 83.941608 -252.281428) (xy 83.908929 -252.310822)
			(xy 83.890866 -252.323346) (xy 83.883246 -252.328426) (xy 83.872578 -252.343158) (xy 83.850226 -252.425454)
			(xy 83.852004 -252.443488) (xy 83.856068 -252.45187) (xy 83.86559 -252.472663) (xy 83.879049 -252.51637)
			(xy 83.885857 -252.561592) (xy 83.886294 -252.584458) (xy 83.885772 -252.609713) (xy 83.877459 -252.659535)
			(xy 83.861058 -252.707309) (xy 83.837017 -252.751732) (xy 83.805993 -252.791592) (xy 83.768831 -252.825802)
			(xy 83.726545 -252.853428) (xy 83.680289 -252.873718) (xy 83.631324 -252.886118) (xy 83.580986 -252.890289)
			(xy 83.530648 -252.886118) (xy 83.481683 -252.873718) (xy 83.435427 -252.853428) (xy 83.393141 -252.825802)
			(xy 83.355979 -252.791592) (xy 83.324955 -252.751732) (xy 83.300914 -252.707309) (xy 83.284513 -252.659535)
			(xy 83.2762 -252.609713) (xy 83.275678 -252.584458) (xy 83.276086 -252.561916) (xy 83.282726 -252.517323)
			(xy 83.295856 -252.474193) (xy 83.305142 -252.453648) (xy 83.309206 -252.445266) (xy 83.31073 -252.427232)
			(xy 83.287616 -252.344936) (xy 83.276948 -252.330204) (xy 83.269074 -252.325124) (xy 83.250466 -252.312474)
			(xy 83.216833 -252.282586) (xy 83.18795 -252.248086) (xy 83.175856 -252.229112) (xy 83.171038 -252.221853)
			(xy 83.157536 -252.21086) (xy 83.141128 -252.20504) (xy 83.132422 -252.204728) (xy 83.08975 -252.204728)
			(xy 83.081052 -252.205085) (xy 83.064658 -252.210909) (xy 83.051148 -252.221871) (xy 83.046316 -252.229112)
			(xy 83.034913 -252.247003) (xy 83.007939 -252.279749) (xy 82.976696 -252.308452) (xy 82.959448 -252.320806)
			(xy 82.952082 -252.32614) (xy 82.941668 -252.340872) (xy 82.920078 -252.422152) (xy 82.921602 -252.440186)
			(xy 82.925666 -252.448314) (xy 82.935387 -252.469678) (xy 82.9491 -252.514565) (xy 82.955999 -252.56099)
			(xy 82.9564 -252.584458) (xy 82.955914 -252.609248) (xy 82.948158 -252.658216) (xy 82.932837 -252.705369)
			(xy 82.910328 -252.749544) (xy 82.881186 -252.789655) (xy 82.846129 -252.824712) (xy 82.806018 -252.853854)
			(xy 82.761843 -252.876363) (xy 82.71469 -252.891684) (xy 82.665722 -252.89944) (xy 82.616142 -252.89944)
			(xy 82.567174 -252.891684) (xy 82.520021 -252.876363) (xy 82.475846 -252.853854) (xy 82.435735 -252.824712)
			(xy 82.400678 -252.789655) (xy 82.371536 -252.749544) (xy 82.349027 -252.705369) (xy 82.333706 -252.658216)
			(xy 82.32595 -252.609248) (xy 82.325464 -252.584458) (xy 82.32521 -252.584458) (xy 82.325647 -252.56094)
			(xy 82.332632 -252.514426) (xy 82.346441 -252.469463) (xy 82.356198 -252.44806) (xy 82.360008 -252.439932)
			(xy 82.361786 -252.421898) (xy 82.340196 -252.340618) (xy 82.329782 -252.325886) (xy 82.322416 -252.320806)
			(xy 82.305205 -252.30845) (xy 82.274044 -252.279743) (xy 82.247163 -252.246996) (xy 82.235802 -252.229112)
			(xy 82.230982 -252.221859) (xy 82.217478 -252.210881) (xy 82.201071 -252.205077) (xy 82.192368 -252.204728)
			(xy 82.149696 -252.204728) (xy 82.140994 -252.205078) (xy 82.124589 -252.210892) (xy 82.111067 -252.22185)
			(xy 82.106262 -252.229112) (xy 82.094168 -252.248086) (xy 82.065286 -252.282588) (xy 82.031654 -252.312477)
			(xy 82.013044 -252.325124) (xy 82.00517 -252.330204) (xy 81.994502 -252.344936) (xy 81.971388 -252.427232)
			(xy 81.972912 -252.445266) (xy 81.976976 -252.453648) (xy 81.986276 -252.474187) (xy 81.9994 -252.51732)
			(xy 82.00603 -252.561915) (xy 82.00644 -252.584458) (xy 82.005918 -252.609713) (xy 81.997605 -252.659535)
			(xy 81.981204 -252.707309) (xy 81.957163 -252.751732) (xy 81.926139 -252.791592) (xy 81.888977 -252.825802)
			(xy 81.846691 -252.853428) (xy 81.800435 -252.873718) (xy 81.75147 -252.886118) (xy 81.701132 -252.890289)
			(xy 81.650794 -252.886118) (xy 81.601829 -252.873718) (xy 81.555573 -252.853428) (xy 81.513287 -252.825802)
			(xy 81.476125 -252.791592) (xy 81.445101 -252.751732) (xy 81.42106 -252.707309) (xy 81.404659 -252.659535)
			(xy 81.396346 -252.609713) (xy 81.395824 -252.584458) (xy 81.396208 -252.561587) (xy 81.402999 -252.516354)
			(xy 81.416482 -252.472646) (xy 81.42605 -252.45187) (xy 81.430114 -252.443488) (xy 81.431892 -252.425454)
			(xy 81.40954 -252.343158) (xy 81.398872 -252.328426) (xy 81.391252 -252.323346) (xy 81.37319 -252.310822)
			(xy 81.340519 -252.28142) (xy 81.312403 -252.247637) (xy 81.300574 -252.229112) (xy 81.295785 -252.221883)
			(xy 81.282368 -252.210917) (xy 81.266057 -252.205064) (xy 81.257394 -252.204728) (xy 81.204562 -252.204728)
			(xy 81.19591 -252.205127) (xy 81.179623 -252.210984) (xy 81.166206 -252.221918) (xy 81.161382 -252.229112)
			(xy 81.148535 -252.24921) (xy 81.117595 -252.285513) (xy 81.081376 -252.316551) (xy 81.061306 -252.329442)
			(xy 81.053197 -252.334981) (xy 81.041566 -252.350784) (xy 81.0387 -252.360176) (xy 81.030826 -252.391164)
			(xy 81.028763 -252.400766) (xy 81.031254 -252.420228) (xy 81.035652 -252.42901) (xy 81.044796 -252.446028)
			(xy 81.05488 -252.467698) (xy 81.069131 -252.513317) (xy 81.076358 -252.560561) (xy 81.0768 -252.584458)
			(xy 81.076342 -252.609271) (xy 81.068584 -252.658287) (xy 81.053253 -252.705486) (xy 81.030727 -252.749704)
			(xy 81.001559 -252.789854) (xy 80.966469 -252.824946) (xy 80.926321 -252.854116) (xy 80.882104 -252.876645)
			(xy 80.834906 -252.891979) (xy 80.785891 -252.89974) (xy 80.761078 -252.90018) (xy 80.736243 -252.899715)
			(xy 80.687188 -252.891933) (xy 80.639956 -252.876566) (xy 80.595713 -252.853991) (xy 80.555551 -252.824767)
			(xy 80.520462 -252.789613) (xy 80.49131 -252.749399) (xy 80.468815 -252.705115) (xy 80.453533 -252.657855)
			(xy 80.445841 -252.608785) (xy 80.445356 -252.58395) (xy 80.44561 -252.575822) (xy 80.446586 -252.55377)
			(xy 80.453895 -252.510238) (xy 80.467188 -252.468146) (xy 80.476344 -252.44806) (xy 80.480408 -252.439932)
			(xy 80.481932 -252.421898) (xy 80.460342 -252.340872) (xy 80.449928 -252.325886) (xy 80.442562 -252.320806)
			(xy 80.425349 -252.308452) (xy 80.394185 -252.279748) (xy 80.367299 -252.247002) (xy 80.355948 -252.229112)
			(xy 80.35113 -252.221854) (xy 80.337628 -252.210863) (xy 80.321219 -252.205045) (xy 80.312514 -252.204728)
			(xy 80.269842 -252.204728) (xy 80.261144 -252.205087) (xy 80.244753 -252.210912) (xy 80.231245 -252.221874)
			(xy 80.226408 -252.229112) (xy 80.214312 -252.248084) (xy 80.185428 -252.282582) (xy 80.151793 -252.312466)
			(xy 80.13319 -252.325124) (xy 80.125316 -252.330458) (xy 80.114648 -252.344936) (xy 80.09128 -252.427232)
			(xy 80.092804 -252.445266) (xy 80.096868 -252.453648) (xy 80.106168 -252.474187) (xy 80.119292 -252.51732)
			(xy 80.125923 -252.561915) (xy 80.126332 -252.584458) (xy 80.12581 -252.609713) (xy 80.117497 -252.659535)
			(xy 80.101096 -252.707309) (xy 80.077055 -252.751732) (xy 80.046031 -252.791592) (xy 80.008869 -252.825802)
			(xy 79.966583 -252.853428) (xy 79.920327 -252.873718) (xy 79.871362 -252.886118) (xy 79.821024 -252.890289)
			(xy 79.770686 -252.886118) (xy 79.721721 -252.873718) (xy 79.675465 -252.853428) (xy 79.633179 -252.825802)
			(xy 79.596017 -252.791592) (xy 79.564993 -252.751732) (xy 79.540952 -252.707309) (xy 79.524551 -252.659535)
			(xy 79.516238 -252.609713) (xy 79.515716 -252.584458) (xy 79.516053 -252.563949) (xy 79.521539 -252.5233)
			(xy 79.526638 -252.503432) (xy 79.529686 -252.492002) (xy 79.525368 -252.468888) (xy 79.46898 -252.394974)
			(xy 79.461389 -252.385983) (xy 79.440344 -252.375512) (xy 79.428594 -252.374908) (xy 78.73619 -252.374908)
			(xy 78.710193 -252.374376) (xy 78.658951 -252.365561) (xy 78.60994 -252.348202) (xy 78.564572 -252.322801)
			(xy 78.524156 -252.29009) (xy 78.489857 -252.251012) (xy 78.47584 -252.229112) (xy 78.471021 -252.221854)
			(xy 78.457519 -252.210866) (xy 78.441111 -252.205051) (xy 78.432406 -252.204728) (xy 78.389734 -252.204728)
			(xy 78.381037 -252.205088) (xy 78.364647 -252.210915) (xy 78.351142 -252.221878) (xy 78.3463 -252.229112)
			(xy 78.332291 -252.251025) (xy 78.298033 -252.290153) (xy 78.257628 -252.322896) (xy 78.21225 -252.348303)
			(xy 78.163218 -252.365635) (xy 78.111954 -252.37439) (xy 78.08595 -252.374908) (xy 73.6854 -252.374908)
			(xy 73.675413 -252.375446) (xy 73.656981 -252.38316) (xy 73.649586 -252.389894) (xy 73.39076 -252.64872)
			(xy 73.383394 -252.655832) (xy 73.375774 -252.674628) (xy 73.375774 -252.850396) (xy 76.507098 -252.850396)
			(xy 76.511058 -252.801342) (xy 76.522835 -252.753558) (xy 76.542126 -252.708282) (xy 76.568429 -252.666686)
			(xy 76.601064 -252.629849) (xy 76.639185 -252.598724) (xy 76.681806 -252.574117) (xy 76.727822 -252.556665)
			(xy 76.776041 -252.546821) (xy 76.825216 -252.54484) (xy 76.874071 -252.550772) (xy 76.921342 -252.564464)
			(xy 76.965804 -252.585562) (xy 77.006307 -252.613518) (xy 77.0418 -252.64761) (xy 77.071365 -252.686954)
			(xy 77.094236 -252.730531) (xy 77.10982 -252.777212) (xy 77.117715 -252.825789) (xy 77.11821 -252.850396)
			(xy 77.117715 -252.875003) (xy 77.10982 -252.92358) (xy 77.094236 -252.970261) (xy 77.071365 -253.013838)
			(xy 77.0418 -253.053182) (xy 77.006307 -253.087274) (xy 76.965804 -253.11523) (xy 76.921342 -253.136328)
			(xy 76.874071 -253.15002) (xy 76.825216 -253.155952) (xy 76.776041 -253.153971) (xy 76.727822 -253.144127)
			(xy 76.681806 -253.126675) (xy 76.639185 -253.102068) (xy 76.601064 -253.070943) (xy 76.568429 -253.034106)
			(xy 76.542126 -252.99251) (xy 76.522835 -252.947234) (xy 76.511058 -252.89945) (xy 76.507098 -252.850396)
			(xy 73.375774 -252.850396) (xy 73.375774 -253.394464) (xy 78.105266 -253.394464) (xy 78.109226 -253.34541)
			(xy 78.121003 -253.297626) (xy 78.140294 -253.25235) (xy 78.166597 -253.210754) (xy 78.199232 -253.173917)
			(xy 78.237353 -253.142792) (xy 78.279974 -253.118185) (xy 78.32599 -253.100733) (xy 78.374209 -253.090889)
			(xy 78.423384 -253.088908) (xy 78.472239 -253.09484) (xy 78.51951 -253.108532) (xy 78.563972 -253.12963)
			(xy 78.604475 -253.157586) (xy 78.639968 -253.191678) (xy 78.669533 -253.231022) (xy 78.692404 -253.274599)
			(xy 78.707988 -253.32128) (xy 78.715883 -253.369857) (xy 78.716378 -253.394464) (xy 79.985374 -253.394464)
			(xy 79.989334 -253.34541) (xy 80.001111 -253.297626) (xy 80.020402 -253.25235) (xy 80.046705 -253.210754)
			(xy 80.07934 -253.173917) (xy 80.117461 -253.142792) (xy 80.160082 -253.118185) (xy 80.206098 -253.100733)
			(xy 80.254317 -253.090889) (xy 80.303492 -253.088908) (xy 80.352347 -253.09484) (xy 80.399618 -253.108532)
			(xy 80.44408 -253.12963) (xy 80.484583 -253.157586) (xy 80.520076 -253.191678) (xy 80.549641 -253.231022)
			(xy 80.572512 -253.274599) (xy 80.588096 -253.32128) (xy 80.595991 -253.369857) (xy 80.596486 -253.394464)
			(xy 80.914743 -253.394464) (xy 80.918838 -253.343736) (xy 80.931017 -253.294322) (xy 80.950965 -253.247502)
			(xy 80.978166 -253.204488) (xy 81.011914 -253.166394) (xy 81.051336 -253.134207) (xy 81.09541 -253.108761)
			(xy 81.142996 -253.090714) (xy 81.19286 -253.080534) (xy 81.243712 -253.078485) (xy 81.294233 -253.084619)
			(xy 81.343117 -253.098779) (xy 81.389096 -253.120596) (xy 81.43098 -253.149506) (xy 81.467684 -253.184761)
			(xy 81.498257 -253.225447) (xy 81.521908 -253.27051) (xy 81.538024 -253.318784) (xy 81.546188 -253.369018)
			(xy 81.5467 -253.394464) (xy 81.854797 -253.394464) (xy 81.858892 -253.343736) (xy 81.871071 -253.294322)
			(xy 81.891019 -253.247502) (xy 81.91822 -253.204488) (xy 81.951968 -253.166394) (xy 81.99139 -253.134207)
			(xy 82.035464 -253.108761) (xy 82.08305 -253.090714) (xy 82.132914 -253.080534) (xy 82.183766 -253.078485)
			(xy 82.234287 -253.084619) (xy 82.283171 -253.098779) (xy 82.32915 -253.120596) (xy 82.371034 -253.149506)
			(xy 82.407738 -253.184761) (xy 82.438311 -253.225447) (xy 82.461962 -253.27051) (xy 82.478078 -253.318784)
			(xy 82.486242 -253.369018) (xy 82.486754 -253.394464) (xy 82.805282 -253.394464) (xy 82.809242 -253.34541)
			(xy 82.821019 -253.297626) (xy 82.84031 -253.25235) (xy 82.866613 -253.210754) (xy 82.899248 -253.173917)
			(xy 82.937369 -253.142792) (xy 82.97999 -253.118185) (xy 83.026006 -253.100733) (xy 83.074225 -253.090889)
			(xy 83.1234 -253.088908) (xy 83.172255 -253.09484) (xy 83.219526 -253.108532) (xy 83.263988 -253.12963)
			(xy 83.304491 -253.157586) (xy 83.339984 -253.191678) (xy 83.369549 -253.231022) (xy 83.39242 -253.274599)
			(xy 83.408004 -253.32128) (xy 83.415899 -253.369857) (xy 83.416394 -253.394464) (xy 83.734905 -253.394464)
			(xy 83.739 -253.343736) (xy 83.751179 -253.294322) (xy 83.771127 -253.247502) (xy 83.798328 -253.204488)
			(xy 83.832076 -253.166394) (xy 83.871498 -253.134207) (xy 83.915572 -253.108761) (xy 83.963158 -253.090714)
			(xy 84.013022 -253.080534) (xy 84.063874 -253.078485) (xy 84.114395 -253.084619) (xy 84.163279 -253.098779)
			(xy 84.209258 -253.120596) (xy 84.251142 -253.149506) (xy 84.287846 -253.184761) (xy 84.318419 -253.225447)
			(xy 84.34207 -253.27051) (xy 84.358186 -253.318784) (xy 84.36635 -253.369018) (xy 84.366862 -253.394464)
			(xy 84.685136 -253.394464) (xy 84.689096 -253.34541) (xy 84.700873 -253.297626) (xy 84.720164 -253.25235)
			(xy 84.746467 -253.210754) (xy 84.779102 -253.173917) (xy 84.817223 -253.142792) (xy 84.859844 -253.118185)
			(xy 84.90586 -253.100733) (xy 84.954079 -253.090889) (xy 85.003254 -253.088908) (xy 85.052109 -253.09484)
			(xy 85.09938 -253.108532) (xy 85.143842 -253.12963) (xy 85.184345 -253.157586) (xy 85.219838 -253.191678)
			(xy 85.249403 -253.231022) (xy 85.272274 -253.274599) (xy 85.287858 -253.32128) (xy 85.295753 -253.369857)
			(xy 85.296248 -253.394464) (xy 85.614759 -253.394464) (xy 85.618854 -253.343736) (xy 85.631033 -253.294322)
			(xy 85.650981 -253.247502) (xy 85.678182 -253.204488) (xy 85.71193 -253.166394) (xy 85.751352 -253.134207)
			(xy 85.795426 -253.108761) (xy 85.843012 -253.090714) (xy 85.892876 -253.080534) (xy 85.943728 -253.078485)
			(xy 85.994249 -253.084619) (xy 86.043133 -253.098779) (xy 86.089112 -253.120596) (xy 86.130996 -253.149506)
			(xy 86.1677 -253.184761) (xy 86.198273 -253.225447) (xy 86.221924 -253.27051) (xy 86.23804 -253.318784)
			(xy 86.246204 -253.369018) (xy 86.246716 -253.394464) (xy 86.565244 -253.394464) (xy 86.569204 -253.34541)
			(xy 86.580981 -253.297626) (xy 86.600272 -253.25235) (xy 86.626575 -253.210754) (xy 86.65921 -253.173917)
			(xy 86.697331 -253.142792) (xy 86.739952 -253.118185) (xy 86.785968 -253.100733) (xy 86.834187 -253.090889)
			(xy 86.883362 -253.088908) (xy 86.932217 -253.09484) (xy 86.979488 -253.108532) (xy 87.02395 -253.12963)
			(xy 87.064453 -253.157586) (xy 87.099946 -253.191678) (xy 87.129511 -253.231022) (xy 87.152382 -253.274599)
			(xy 87.167966 -253.32128) (xy 87.175861 -253.369857) (xy 87.176356 -253.394464) (xy 87.494867 -253.394464)
			(xy 87.498962 -253.343736) (xy 87.511141 -253.294322) (xy 87.531089 -253.247502) (xy 87.55829 -253.204488)
			(xy 87.592038 -253.166394) (xy 87.63146 -253.134207) (xy 87.675534 -253.108761) (xy 87.72312 -253.090714)
			(xy 87.772984 -253.080534) (xy 87.823836 -253.078485) (xy 87.874357 -253.084619) (xy 87.923241 -253.098779)
			(xy 87.96922 -253.120596) (xy 88.011104 -253.149506) (xy 88.047808 -253.184761) (xy 88.078381 -253.225447)
			(xy 88.102032 -253.27051) (xy 88.118148 -253.318784) (xy 88.126312 -253.369018) (xy 88.126824 -253.394464)
			(xy 88.434921 -253.394464) (xy 88.439016 -253.343736) (xy 88.451195 -253.294322) (xy 88.471143 -253.247502)
			(xy 88.498344 -253.204488) (xy 88.532092 -253.166394) (xy 88.571514 -253.134207) (xy 88.615588 -253.108761)
			(xy 88.663174 -253.090714) (xy 88.713038 -253.080534) (xy 88.76389 -253.078485) (xy 88.814411 -253.084619)
			(xy 88.863295 -253.098779) (xy 88.909274 -253.120596) (xy 88.951158 -253.149506) (xy 88.987862 -253.184761)
			(xy 89.018435 -253.225447) (xy 89.042086 -253.27051) (xy 89.058202 -253.318784) (xy 89.066366 -253.369018)
			(xy 89.066878 -253.394464) (xy 89.385152 -253.394464) (xy 89.389112 -253.34541) (xy 89.400889 -253.297626)
			(xy 89.42018 -253.25235) (xy 89.446483 -253.210754) (xy 89.479118 -253.173917) (xy 89.517239 -253.142792)
			(xy 89.55986 -253.118185) (xy 89.605876 -253.100733) (xy 89.654095 -253.090889) (xy 89.70327 -253.088908)
			(xy 89.752125 -253.09484) (xy 89.799396 -253.108532) (xy 89.843858 -253.12963) (xy 89.884361 -253.157586)
			(xy 89.919854 -253.191678) (xy 89.949419 -253.231022) (xy 89.97229 -253.274599) (xy 89.987874 -253.32128)
			(xy 89.995769 -253.369857) (xy 89.996264 -253.394464) (xy 90.314775 -253.394464) (xy 90.31887 -253.343736)
			(xy 90.331049 -253.294322) (xy 90.350997 -253.247502) (xy 90.378198 -253.204488) (xy 90.411946 -253.166394)
			(xy 90.451368 -253.134207) (xy 90.495442 -253.108761) (xy 90.543028 -253.090714) (xy 90.592892 -253.080534)
			(xy 90.643744 -253.078485) (xy 90.694265 -253.084619) (xy 90.743149 -253.098779) (xy 90.789128 -253.120596)
			(xy 90.831012 -253.149506) (xy 90.867716 -253.184761) (xy 90.898289 -253.225447) (xy 90.92194 -253.27051)
			(xy 90.938056 -253.318784) (xy 90.94622 -253.369018) (xy 90.946732 -253.394464) (xy 91.26526 -253.394464)
			(xy 91.26922 -253.34541) (xy 91.280997 -253.297626) (xy 91.300288 -253.25235) (xy 91.326591 -253.210754)
			(xy 91.359226 -253.173917) (xy 91.397347 -253.142792) (xy 91.439968 -253.118185) (xy 91.485984 -253.100733)
			(xy 91.534203 -253.090889) (xy 91.583378 -253.088908) (xy 91.632233 -253.09484) (xy 91.679504 -253.108532)
			(xy 91.723966 -253.12963) (xy 91.764469 -253.157586) (xy 91.799962 -253.191678) (xy 91.829527 -253.231022)
			(xy 91.852398 -253.274599) (xy 91.867982 -253.32128) (xy 91.875877 -253.369857) (xy 91.876372 -253.394464)
			(xy 92.194883 -253.394464) (xy 92.198978 -253.343736) (xy 92.211157 -253.294322) (xy 92.231105 -253.247502)
			(xy 92.258306 -253.204488) (xy 92.292054 -253.166394) (xy 92.331476 -253.134207) (xy 92.37555 -253.108761)
			(xy 92.423136 -253.090714) (xy 92.473 -253.080534) (xy 92.523852 -253.078485) (xy 92.574373 -253.084619)
			(xy 92.623257 -253.098779) (xy 92.669236 -253.120596) (xy 92.71112 -253.149506) (xy 92.747824 -253.184761)
			(xy 92.778397 -253.225447) (xy 92.802048 -253.27051) (xy 92.818164 -253.318784) (xy 92.826328 -253.369018)
			(xy 92.82684 -253.394464) (xy 93.145114 -253.394464) (xy 93.149074 -253.34541) (xy 93.160851 -253.297626)
			(xy 93.180142 -253.25235) (xy 93.206445 -253.210754) (xy 93.23908 -253.173917) (xy 93.277201 -253.142792)
			(xy 93.319822 -253.118185) (xy 93.365838 -253.100733) (xy 93.414057 -253.090889) (xy 93.463232 -253.088908)
			(xy 93.512087 -253.09484) (xy 93.559358 -253.108532) (xy 93.60382 -253.12963) (xy 93.644323 -253.157586)
			(xy 93.679816 -253.191678) (xy 93.709381 -253.231022) (xy 93.732252 -253.274599) (xy 93.747836 -253.32128)
			(xy 93.755731 -253.369857) (xy 93.756226 -253.394464) (xy 94.074737 -253.394464) (xy 94.078832 -253.343736)
			(xy 94.091011 -253.294322) (xy 94.110959 -253.247502) (xy 94.13816 -253.204488) (xy 94.171908 -253.166394)
			(xy 94.21133 -253.134207) (xy 94.255404 -253.108761) (xy 94.30299 -253.090714) (xy 94.352854 -253.080534)
			(xy 94.403706 -253.078485) (xy 94.454227 -253.084619) (xy 94.503111 -253.098779) (xy 94.54909 -253.120596)
			(xy 94.590974 -253.149506) (xy 94.627678 -253.184761) (xy 94.658251 -253.225447) (xy 94.681902 -253.27051)
			(xy 94.698018 -253.318784) (xy 94.706182 -253.369018) (xy 94.706694 -253.394464) (xy 95.014791 -253.394464)
			(xy 95.018886 -253.343736) (xy 95.031065 -253.294322) (xy 95.051013 -253.247502) (xy 95.078214 -253.204488)
			(xy 95.111962 -253.166394) (xy 95.151384 -253.134207) (xy 95.195458 -253.108761) (xy 95.243044 -253.090714)
			(xy 95.292908 -253.080534) (xy 95.34376 -253.078485) (xy 95.394281 -253.084619) (xy 95.443165 -253.098779)
			(xy 95.489144 -253.120596) (xy 95.531028 -253.149506) (xy 95.567732 -253.184761) (xy 95.598305 -253.225447)
			(xy 95.621956 -253.27051) (xy 95.638072 -253.318784) (xy 95.646236 -253.369018) (xy 95.646748 -253.394464)
			(xy 95.965276 -253.394464) (xy 95.969236 -253.34541) (xy 95.981013 -253.297626) (xy 96.000304 -253.25235)
			(xy 96.026607 -253.210754) (xy 96.059242 -253.173917) (xy 96.097363 -253.142792) (xy 96.139984 -253.118185)
			(xy 96.186 -253.100733) (xy 96.234219 -253.090889) (xy 96.283394 -253.088908) (xy 96.332249 -253.09484)
			(xy 96.37952 -253.108532) (xy 96.423982 -253.12963) (xy 96.464485 -253.157586) (xy 96.499978 -253.191678)
			(xy 96.529543 -253.231022) (xy 96.552414 -253.274599) (xy 96.567998 -253.32128) (xy 96.575893 -253.369857)
			(xy 96.576388 -253.394464) (xy 96.90533 -253.394464) (xy 96.90929 -253.34541) (xy 96.921067 -253.297626)
			(xy 96.940358 -253.25235) (xy 96.966661 -253.210754) (xy 96.999296 -253.173917) (xy 97.037417 -253.142792)
			(xy 97.080038 -253.118185) (xy 97.126054 -253.100733) (xy 97.174273 -253.090889) (xy 97.223448 -253.088908)
			(xy 97.272303 -253.09484) (xy 97.319574 -253.108532) (xy 97.364036 -253.12963) (xy 97.404539 -253.157586)
			(xy 97.440032 -253.191678) (xy 97.469597 -253.231022) (xy 97.492468 -253.274599) (xy 97.508052 -253.32128)
			(xy 97.515947 -253.369857) (xy 97.516442 -253.394464) (xy 97.84513 -253.394464) (xy 97.84909 -253.34541)
			(xy 97.860867 -253.297626) (xy 97.880158 -253.25235) (xy 97.906461 -253.210754) (xy 97.939096 -253.173917)
			(xy 97.977217 -253.142792) (xy 98.019838 -253.118185) (xy 98.065854 -253.100733) (xy 98.114073 -253.090889)
			(xy 98.163248 -253.088908) (xy 98.212103 -253.09484) (xy 98.259374 -253.108532) (xy 98.303836 -253.12963)
			(xy 98.344339 -253.157586) (xy 98.379832 -253.191678) (xy 98.409397 -253.231022) (xy 98.432268 -253.274599)
			(xy 98.447852 -253.32128) (xy 98.455747 -253.369857) (xy 98.456242 -253.394464) (xy 98.785184 -253.394464)
			(xy 98.789144 -253.34541) (xy 98.800921 -253.297626) (xy 98.820212 -253.25235) (xy 98.846515 -253.210754)
			(xy 98.87915 -253.173917) (xy 98.917271 -253.142792) (xy 98.959892 -253.118185) (xy 99.005908 -253.100733)
			(xy 99.054127 -253.090889) (xy 99.103302 -253.088908) (xy 99.152157 -253.09484) (xy 99.199428 -253.108532)
			(xy 99.24389 -253.12963) (xy 99.284393 -253.157586) (xy 99.319886 -253.191678) (xy 99.349451 -253.231022)
			(xy 99.372322 -253.274599) (xy 99.387906 -253.32128) (xy 99.395801 -253.369857) (xy 99.396296 -253.394464)
			(xy 99.725238 -253.394464) (xy 99.729198 -253.34541) (xy 99.740975 -253.297626) (xy 99.760266 -253.25235)
			(xy 99.786569 -253.210754) (xy 99.819204 -253.173917) (xy 99.857325 -253.142792) (xy 99.899946 -253.118185)
			(xy 99.945962 -253.100733) (xy 99.994181 -253.090889) (xy 100.043356 -253.088908) (xy 100.092211 -253.09484)
			(xy 100.139482 -253.108532) (xy 100.183944 -253.12963) (xy 100.224447 -253.157586) (xy 100.25994 -253.191678)
			(xy 100.289505 -253.231022) (xy 100.312376 -253.274599) (xy 100.32796 -253.32128) (xy 100.335855 -253.369857)
			(xy 100.33635 -253.394464) (xy 100.335855 -253.419071) (xy 100.32796 -253.467648) (xy 100.312376 -253.514329)
			(xy 100.289505 -253.557906) (xy 100.25994 -253.59725) (xy 100.224447 -253.631342) (xy 100.183944 -253.659298)
			(xy 100.139482 -253.680396) (xy 100.092211 -253.694088) (xy 100.043356 -253.70002) (xy 99.994181 -253.698039)
			(xy 99.945962 -253.688195) (xy 99.899946 -253.670743) (xy 99.857325 -253.646136) (xy 99.819204 -253.615011)
			(xy 99.786569 -253.578174) (xy 99.760266 -253.536578) (xy 99.740975 -253.491302) (xy 99.729198 -253.443518)
			(xy 99.725238 -253.394464) (xy 99.396296 -253.394464) (xy 99.395801 -253.419071) (xy 99.387906 -253.467648)
			(xy 99.372322 -253.514329) (xy 99.349451 -253.557906) (xy 99.319886 -253.59725) (xy 99.284393 -253.631342)
			(xy 99.24389 -253.659298) (xy 99.199428 -253.680396) (xy 99.152157 -253.694088) (xy 99.103302 -253.70002)
			(xy 99.054127 -253.698039) (xy 99.005908 -253.688195) (xy 98.959892 -253.670743) (xy 98.917271 -253.646136)
			(xy 98.87915 -253.615011) (xy 98.846515 -253.578174) (xy 98.820212 -253.536578) (xy 98.800921 -253.491302)
			(xy 98.789144 -253.443518) (xy 98.785184 -253.394464) (xy 98.456242 -253.394464) (xy 98.455747 -253.419071)
			(xy 98.447852 -253.467648) (xy 98.432268 -253.514329) (xy 98.409397 -253.557906) (xy 98.379832 -253.59725)
			(xy 98.344339 -253.631342) (xy 98.303836 -253.659298) (xy 98.259374 -253.680396) (xy 98.212103 -253.694088)
			(xy 98.163248 -253.70002) (xy 98.114073 -253.698039) (xy 98.065854 -253.688195) (xy 98.019838 -253.670743)
			(xy 97.977217 -253.646136) (xy 97.939096 -253.615011) (xy 97.906461 -253.578174) (xy 97.880158 -253.536578)
			(xy 97.860867 -253.491302) (xy 97.84909 -253.443518) (xy 97.84513 -253.394464) (xy 97.516442 -253.394464)
			(xy 97.515947 -253.419071) (xy 97.508052 -253.467648) (xy 97.492468 -253.514329) (xy 97.469597 -253.557906)
			(xy 97.440032 -253.59725) (xy 97.404539 -253.631342) (xy 97.364036 -253.659298) (xy 97.319574 -253.680396)
			(xy 97.272303 -253.694088) (xy 97.223448 -253.70002) (xy 97.174273 -253.698039) (xy 97.126054 -253.688195)
			(xy 97.080038 -253.670743) (xy 97.037417 -253.646136) (xy 96.999296 -253.615011) (xy 96.966661 -253.578174)
			(xy 96.940358 -253.536578) (xy 96.921067 -253.491302) (xy 96.90929 -253.443518) (xy 96.90533 -253.394464)
			(xy 96.576388 -253.394464) (xy 96.575893 -253.419071) (xy 96.567998 -253.467648) (xy 96.552414 -253.514329)
			(xy 96.529543 -253.557906) (xy 96.499978 -253.59725) (xy 96.464485 -253.631342) (xy 96.423982 -253.659298)
			(xy 96.37952 -253.680396) (xy 96.332249 -253.694088) (xy 96.283394 -253.70002) (xy 96.234219 -253.698039)
			(xy 96.186 -253.688195) (xy 96.139984 -253.670743) (xy 96.097363 -253.646136) (xy 96.059242 -253.615011)
			(xy 96.026607 -253.578174) (xy 96.000304 -253.536578) (xy 95.981013 -253.491302) (xy 95.969236 -253.443518)
			(xy 95.965276 -253.394464) (xy 95.646748 -253.394464) (xy 95.646236 -253.41991) (xy 95.638072 -253.470144)
			(xy 95.621956 -253.518418) (xy 95.598305 -253.563481) (xy 95.567732 -253.604167) (xy 95.531028 -253.639422)
			(xy 95.489144 -253.668332) (xy 95.443165 -253.690149) (xy 95.394281 -253.704309) (xy 95.34376 -253.710443)
			(xy 95.292908 -253.708394) (xy 95.243044 -253.698214) (xy 95.195458 -253.680167) (xy 95.151384 -253.654721)
			(xy 95.111962 -253.622534) (xy 95.078214 -253.58444) (xy 95.051013 -253.541426) (xy 95.031065 -253.494606)
			(xy 95.018886 -253.445192) (xy 95.014791 -253.394464) (xy 94.706694 -253.394464) (xy 94.706182 -253.41991)
			(xy 94.698018 -253.470144) (xy 94.681902 -253.518418) (xy 94.658251 -253.563481) (xy 94.627678 -253.604167)
			(xy 94.590974 -253.639422) (xy 94.54909 -253.668332) (xy 94.503111 -253.690149) (xy 94.454227 -253.704309)
			(xy 94.403706 -253.710443) (xy 94.352854 -253.708394) (xy 94.30299 -253.698214) (xy 94.255404 -253.680167)
			(xy 94.21133 -253.654721) (xy 94.171908 -253.622534) (xy 94.13816 -253.58444) (xy 94.110959 -253.541426)
			(xy 94.091011 -253.494606) (xy 94.078832 -253.445192) (xy 94.074737 -253.394464) (xy 93.756226 -253.394464)
			(xy 93.755731 -253.419071) (xy 93.747836 -253.467648) (xy 93.732252 -253.514329) (xy 93.709381 -253.557906)
			(xy 93.679816 -253.59725) (xy 93.644323 -253.631342) (xy 93.60382 -253.659298) (xy 93.559358 -253.680396)
			(xy 93.512087 -253.694088) (xy 93.463232 -253.70002) (xy 93.414057 -253.698039) (xy 93.365838 -253.688195)
			(xy 93.319822 -253.670743) (xy 93.277201 -253.646136) (xy 93.23908 -253.615011) (xy 93.206445 -253.578174)
			(xy 93.180142 -253.536578) (xy 93.160851 -253.491302) (xy 93.149074 -253.443518) (xy 93.145114 -253.394464)
			(xy 92.82684 -253.394464) (xy 92.826328 -253.41991) (xy 92.818164 -253.470144) (xy 92.802048 -253.518418)
			(xy 92.778397 -253.563481) (xy 92.747824 -253.604167) (xy 92.71112 -253.639422) (xy 92.669236 -253.668332)
			(xy 92.623257 -253.690149) (xy 92.574373 -253.704309) (xy 92.523852 -253.710443) (xy 92.473 -253.708394)
			(xy 92.423136 -253.698214) (xy 92.37555 -253.680167) (xy 92.331476 -253.654721) (xy 92.292054 -253.622534)
			(xy 92.258306 -253.58444) (xy 92.231105 -253.541426) (xy 92.211157 -253.494606) (xy 92.198978 -253.445192)
			(xy 92.194883 -253.394464) (xy 91.876372 -253.394464) (xy 91.875877 -253.419071) (xy 91.867982 -253.467648)
			(xy 91.852398 -253.514329) (xy 91.829527 -253.557906) (xy 91.799962 -253.59725) (xy 91.764469 -253.631342)
			(xy 91.723966 -253.659298) (xy 91.679504 -253.680396) (xy 91.632233 -253.694088) (xy 91.583378 -253.70002)
			(xy 91.534203 -253.698039) (xy 91.485984 -253.688195) (xy 91.439968 -253.670743) (xy 91.397347 -253.646136)
			(xy 91.359226 -253.615011) (xy 91.326591 -253.578174) (xy 91.300288 -253.536578) (xy 91.280997 -253.491302)
			(xy 91.26922 -253.443518) (xy 91.26526 -253.394464) (xy 90.946732 -253.394464) (xy 90.94622 -253.41991)
			(xy 90.938056 -253.470144) (xy 90.92194 -253.518418) (xy 90.898289 -253.563481) (xy 90.867716 -253.604167)
			(xy 90.831012 -253.639422) (xy 90.789128 -253.668332) (xy 90.743149 -253.690149) (xy 90.694265 -253.704309)
			(xy 90.643744 -253.710443) (xy 90.592892 -253.708394) (xy 90.543028 -253.698214) (xy 90.495442 -253.680167)
			(xy 90.451368 -253.654721) (xy 90.411946 -253.622534) (xy 90.378198 -253.58444) (xy 90.350997 -253.541426)
			(xy 90.331049 -253.494606) (xy 90.31887 -253.445192) (xy 90.314775 -253.394464) (xy 89.996264 -253.394464)
			(xy 89.995769 -253.419071) (xy 89.987874 -253.467648) (xy 89.97229 -253.514329) (xy 89.949419 -253.557906)
			(xy 89.919854 -253.59725) (xy 89.884361 -253.631342) (xy 89.843858 -253.659298) (xy 89.799396 -253.680396)
			(xy 89.752125 -253.694088) (xy 89.70327 -253.70002) (xy 89.654095 -253.698039) (xy 89.605876 -253.688195)
			(xy 89.55986 -253.670743) (xy 89.517239 -253.646136) (xy 89.479118 -253.615011) (xy 89.446483 -253.578174)
			(xy 89.42018 -253.536578) (xy 89.400889 -253.491302) (xy 89.389112 -253.443518) (xy 89.385152 -253.394464)
			(xy 89.066878 -253.394464) (xy 89.066366 -253.41991) (xy 89.058202 -253.470144) (xy 89.042086 -253.518418)
			(xy 89.018435 -253.563481) (xy 88.987862 -253.604167) (xy 88.951158 -253.639422) (xy 88.909274 -253.668332)
			(xy 88.863295 -253.690149) (xy 88.814411 -253.704309) (xy 88.76389 -253.710443) (xy 88.713038 -253.708394)
			(xy 88.663174 -253.698214) (xy 88.615588 -253.680167) (xy 88.571514 -253.654721) (xy 88.532092 -253.622534)
			(xy 88.498344 -253.58444) (xy 88.471143 -253.541426) (xy 88.451195 -253.494606) (xy 88.439016 -253.445192)
			(xy 88.434921 -253.394464) (xy 88.126824 -253.394464) (xy 88.126312 -253.41991) (xy 88.118148 -253.470144)
			(xy 88.102032 -253.518418) (xy 88.078381 -253.563481) (xy 88.047808 -253.604167) (xy 88.011104 -253.639422)
			(xy 87.96922 -253.668332) (xy 87.923241 -253.690149) (xy 87.874357 -253.704309) (xy 87.823836 -253.710443)
			(xy 87.772984 -253.708394) (xy 87.72312 -253.698214) (xy 87.675534 -253.680167) (xy 87.63146 -253.654721)
			(xy 87.592038 -253.622534) (xy 87.55829 -253.58444) (xy 87.531089 -253.541426) (xy 87.511141 -253.494606)
			(xy 87.498962 -253.445192) (xy 87.494867 -253.394464) (xy 87.176356 -253.394464) (xy 87.175861 -253.419071)
			(xy 87.167966 -253.467648) (xy 87.152382 -253.514329) (xy 87.129511 -253.557906) (xy 87.099946 -253.59725)
			(xy 87.064453 -253.631342) (xy 87.02395 -253.659298) (xy 86.979488 -253.680396) (xy 86.932217 -253.694088)
			(xy 86.883362 -253.70002) (xy 86.834187 -253.698039) (xy 86.785968 -253.688195) (xy 86.739952 -253.670743)
			(xy 86.697331 -253.646136) (xy 86.65921 -253.615011) (xy 86.626575 -253.578174) (xy 86.600272 -253.536578)
			(xy 86.580981 -253.491302) (xy 86.569204 -253.443518) (xy 86.565244 -253.394464) (xy 86.246716 -253.394464)
			(xy 86.246204 -253.41991) (xy 86.23804 -253.470144) (xy 86.221924 -253.518418) (xy 86.198273 -253.563481)
			(xy 86.1677 -253.604167) (xy 86.130996 -253.639422) (xy 86.089112 -253.668332) (xy 86.043133 -253.690149)
			(xy 85.994249 -253.704309) (xy 85.943728 -253.710443) (xy 85.892876 -253.708394) (xy 85.843012 -253.698214)
			(xy 85.795426 -253.680167) (xy 85.751352 -253.654721) (xy 85.71193 -253.622534) (xy 85.678182 -253.58444)
			(xy 85.650981 -253.541426) (xy 85.631033 -253.494606) (xy 85.618854 -253.445192) (xy 85.614759 -253.394464)
			(xy 85.296248 -253.394464) (xy 85.295753 -253.419071) (xy 85.287858 -253.467648) (xy 85.272274 -253.514329)
			(xy 85.249403 -253.557906) (xy 85.219838 -253.59725) (xy 85.184345 -253.631342) (xy 85.143842 -253.659298)
			(xy 85.09938 -253.680396) (xy 85.052109 -253.694088) (xy 85.003254 -253.70002) (xy 84.954079 -253.698039)
			(xy 84.90586 -253.688195) (xy 84.859844 -253.670743) (xy 84.817223 -253.646136) (xy 84.779102 -253.615011)
			(xy 84.746467 -253.578174) (xy 84.720164 -253.536578) (xy 84.700873 -253.491302) (xy 84.689096 -253.443518)
			(xy 84.685136 -253.394464) (xy 84.366862 -253.394464) (xy 84.36635 -253.41991) (xy 84.358186 -253.470144)
			(xy 84.34207 -253.518418) (xy 84.318419 -253.563481) (xy 84.287846 -253.604167) (xy 84.251142 -253.639422)
			(xy 84.209258 -253.668332) (xy 84.163279 -253.690149) (xy 84.114395 -253.704309) (xy 84.063874 -253.710443)
			(xy 84.013022 -253.708394) (xy 83.963158 -253.698214) (xy 83.915572 -253.680167) (xy 83.871498 -253.654721)
			(xy 83.832076 -253.622534) (xy 83.798328 -253.58444) (xy 83.771127 -253.541426) (xy 83.751179 -253.494606)
			(xy 83.739 -253.445192) (xy 83.734905 -253.394464) (xy 83.416394 -253.394464) (xy 83.415899 -253.419071)
			(xy 83.408004 -253.467648) (xy 83.39242 -253.514329) (xy 83.369549 -253.557906) (xy 83.339984 -253.59725)
			(xy 83.304491 -253.631342) (xy 83.263988 -253.659298) (xy 83.219526 -253.680396) (xy 83.172255 -253.694088)
			(xy 83.1234 -253.70002) (xy 83.074225 -253.698039) (xy 83.026006 -253.688195) (xy 82.97999 -253.670743)
			(xy 82.937369 -253.646136) (xy 82.899248 -253.615011) (xy 82.866613 -253.578174) (xy 82.84031 -253.536578)
			(xy 82.821019 -253.491302) (xy 82.809242 -253.443518) (xy 82.805282 -253.394464) (xy 82.486754 -253.394464)
			(xy 82.486242 -253.41991) (xy 82.478078 -253.470144) (xy 82.461962 -253.518418) (xy 82.438311 -253.563481)
			(xy 82.407738 -253.604167) (xy 82.371034 -253.639422) (xy 82.32915 -253.668332) (xy 82.283171 -253.690149)
			(xy 82.234287 -253.704309) (xy 82.183766 -253.710443) (xy 82.132914 -253.708394) (xy 82.08305 -253.698214)
			(xy 82.035464 -253.680167) (xy 81.99139 -253.654721) (xy 81.951968 -253.622534) (xy 81.91822 -253.58444)
			(xy 81.891019 -253.541426) (xy 81.871071 -253.494606) (xy 81.858892 -253.445192) (xy 81.854797 -253.394464)
			(xy 81.5467 -253.394464) (xy 81.546188 -253.41991) (xy 81.538024 -253.470144) (xy 81.521908 -253.518418)
			(xy 81.498257 -253.563481) (xy 81.467684 -253.604167) (xy 81.43098 -253.639422) (xy 81.389096 -253.668332)
			(xy 81.343117 -253.690149) (xy 81.294233 -253.704309) (xy 81.243712 -253.710443) (xy 81.19286 -253.708394)
			(xy 81.142996 -253.698214) (xy 81.09541 -253.680167) (xy 81.051336 -253.654721) (xy 81.011914 -253.622534)
			(xy 80.978166 -253.58444) (xy 80.950965 -253.541426) (xy 80.931017 -253.494606) (xy 80.918838 -253.445192)
			(xy 80.914743 -253.394464) (xy 80.596486 -253.394464) (xy 80.595991 -253.419071) (xy 80.588096 -253.467648)
			(xy 80.572512 -253.514329) (xy 80.549641 -253.557906) (xy 80.520076 -253.59725) (xy 80.484583 -253.631342)
			(xy 80.44408 -253.659298) (xy 80.399618 -253.680396) (xy 80.352347 -253.694088) (xy 80.303492 -253.70002)
			(xy 80.254317 -253.698039) (xy 80.206098 -253.688195) (xy 80.160082 -253.670743) (xy 80.117461 -253.646136)
			(xy 80.07934 -253.615011) (xy 80.046705 -253.578174) (xy 80.020402 -253.536578) (xy 80.001111 -253.491302)
			(xy 79.989334 -253.443518) (xy 79.985374 -253.394464) (xy 78.716378 -253.394464) (xy 78.715883 -253.419071)
			(xy 78.707988 -253.467648) (xy 78.692404 -253.514329) (xy 78.669533 -253.557906) (xy 78.639968 -253.59725)
			(xy 78.604475 -253.631342) (xy 78.563972 -253.659298) (xy 78.51951 -253.680396) (xy 78.472239 -253.694088)
			(xy 78.423384 -253.70002) (xy 78.374209 -253.698039) (xy 78.32599 -253.688195) (xy 78.279974 -253.670743)
			(xy 78.237353 -253.646136) (xy 78.199232 -253.615011) (xy 78.166597 -253.578174) (xy 78.140294 -253.536578)
			(xy 78.121003 -253.491302) (xy 78.109226 -253.443518) (xy 78.105266 -253.394464) (xy 73.375774 -253.394464)
			(xy 73.375774 -254.470408) (xy 76.507098 -254.470408) (xy 76.511058 -254.421354) (xy 76.522835 -254.37357)
			(xy 76.542126 -254.328294) (xy 76.568429 -254.286698) (xy 76.601064 -254.249861) (xy 76.639185 -254.218736)
			(xy 76.681806 -254.194129) (xy 76.727822 -254.176677) (xy 76.776041 -254.166833) (xy 76.825216 -254.164852)
			(xy 76.874071 -254.170784) (xy 76.921342 -254.184476) (xy 76.963477 -254.20447) (xy 80.444843 -254.20447)
			(xy 80.448938 -254.153742) (xy 80.461117 -254.104328) (xy 80.481065 -254.057508) (xy 80.508266 -254.014494)
			(xy 80.542014 -253.9764) (xy 80.581436 -253.944213) (xy 80.62551 -253.918767) (xy 80.673096 -253.90072)
			(xy 80.72296 -253.89054) (xy 80.773812 -253.888491) (xy 80.824333 -253.894625) (xy 80.873217 -253.908785)
			(xy 80.919196 -253.930602) (xy 80.96108 -253.959512) (xy 80.997784 -253.994767) (xy 81.028357 -254.035453)
			(xy 81.052008 -254.080516) (xy 81.068124 -254.12879) (xy 81.076288 -254.179024) (xy 81.0768 -254.20447)
			(xy 81.395328 -254.20447) (xy 81.399288 -254.155416) (xy 81.411065 -254.107632) (xy 81.430356 -254.062356)
			(xy 81.456659 -254.02076) (xy 81.489294 -253.983923) (xy 81.527415 -253.952798) (xy 81.570036 -253.928191)
			(xy 81.616052 -253.910739) (xy 81.664271 -253.900895) (xy 81.713446 -253.898914) (xy 81.762301 -253.904846)
			(xy 81.809572 -253.918538) (xy 81.854034 -253.939636) (xy 81.894537 -253.967592) (xy 81.93003 -254.001684)
			(xy 81.959595 -254.041028) (xy 81.982466 -254.084605) (xy 81.99805 -254.131286) (xy 82.005945 -254.179863)
			(xy 82.00644 -254.20447) (xy 82.324697 -254.20447) (xy 82.328792 -254.153742) (xy 82.340971 -254.104328)
			(xy 82.360919 -254.057508) (xy 82.38812 -254.014494) (xy 82.421868 -253.9764) (xy 82.46129 -253.944213)
			(xy 82.505364 -253.918767) (xy 82.55295 -253.90072) (xy 82.602814 -253.89054) (xy 82.653666 -253.888491)
			(xy 82.704187 -253.894625) (xy 82.753071 -253.908785) (xy 82.79905 -253.930602) (xy 82.840934 -253.959512)
			(xy 82.877638 -253.994767) (xy 82.908211 -254.035453) (xy 82.931862 -254.080516) (xy 82.947978 -254.12879)
			(xy 82.956142 -254.179024) (xy 82.956654 -254.20447) (xy 83.275182 -254.20447) (xy 83.279142 -254.155416)
			(xy 83.290919 -254.107632) (xy 83.31021 -254.062356) (xy 83.336513 -254.02076) (xy 83.369148 -253.983923)
			(xy 83.407269 -253.952798) (xy 83.44989 -253.928191) (xy 83.495906 -253.910739) (xy 83.544125 -253.900895)
			(xy 83.5933 -253.898914) (xy 83.642155 -253.904846) (xy 83.689426 -253.918538) (xy 83.733888 -253.939636)
			(xy 83.774391 -253.967592) (xy 83.809884 -254.001684) (xy 83.839449 -254.041028) (xy 83.86232 -254.084605)
			(xy 83.877904 -254.131286) (xy 83.885799 -254.179863) (xy 83.886294 -254.20447) (xy 84.204805 -254.20447)
			(xy 84.2089 -254.153742) (xy 84.221079 -254.104328) (xy 84.241027 -254.057508) (xy 84.268228 -254.014494)
			(xy 84.301976 -253.9764) (xy 84.341398 -253.944213) (xy 84.385472 -253.918767) (xy 84.433058 -253.90072)
			(xy 84.482922 -253.89054) (xy 84.533774 -253.888491) (xy 84.584295 -253.894625) (xy 84.633179 -253.908785)
			(xy 84.679158 -253.930602) (xy 84.721042 -253.959512) (xy 84.757746 -253.994767) (xy 84.788319 -254.035453)
			(xy 84.81197 -254.080516) (xy 84.828086 -254.12879) (xy 84.83625 -254.179024) (xy 84.836762 -254.20447)
			(xy 85.144859 -254.20447) (xy 85.148954 -254.153742) (xy 85.161133 -254.104328) (xy 85.181081 -254.057508)
			(xy 85.208282 -254.014494) (xy 85.24203 -253.9764) (xy 85.281452 -253.944213) (xy 85.325526 -253.918767)
			(xy 85.373112 -253.90072) (xy 85.422976 -253.89054) (xy 85.473828 -253.888491) (xy 85.524349 -253.894625)
			(xy 85.573233 -253.908785) (xy 85.619212 -253.930602) (xy 85.661096 -253.959512) (xy 85.6978 -253.994767)
			(xy 85.728373 -254.035453) (xy 85.752024 -254.080516) (xy 85.76814 -254.12879) (xy 85.776304 -254.179024)
			(xy 85.776816 -254.20447) (xy 87.024713 -254.20447) (xy 87.028808 -254.153742) (xy 87.040987 -254.104328)
			(xy 87.060935 -254.057508) (xy 87.088136 -254.014494) (xy 87.121884 -253.9764) (xy 87.161306 -253.944213)
			(xy 87.20538 -253.918767) (xy 87.252966 -253.90072) (xy 87.30283 -253.89054) (xy 87.353682 -253.888491)
			(xy 87.404203 -253.894625) (xy 87.453087 -253.908785) (xy 87.499066 -253.930602) (xy 87.54095 -253.959512)
			(xy 87.577654 -253.994767) (xy 87.608227 -254.035453) (xy 87.631878 -254.080516) (xy 87.647994 -254.12879)
			(xy 87.656158 -254.179024) (xy 87.65667 -254.20447) (xy 87.975198 -254.20447) (xy 87.979158 -254.155416)
			(xy 87.990935 -254.107632) (xy 88.010226 -254.062356) (xy 88.036529 -254.02076) (xy 88.069164 -253.983923)
			(xy 88.107285 -253.952798) (xy 88.149906 -253.928191) (xy 88.195922 -253.910739) (xy 88.244141 -253.900895)
			(xy 88.293316 -253.898914) (xy 88.342171 -253.904846) (xy 88.389442 -253.918538) (xy 88.433904 -253.939636)
			(xy 88.474407 -253.967592) (xy 88.5099 -254.001684) (xy 88.539465 -254.041028) (xy 88.562336 -254.084605)
			(xy 88.57792 -254.131286) (xy 88.585815 -254.179863) (xy 88.58631 -254.20447) (xy 88.904821 -254.20447)
			(xy 88.908916 -254.153742) (xy 88.921095 -254.104328) (xy 88.941043 -254.057508) (xy 88.968244 -254.014494)
			(xy 89.001992 -253.9764) (xy 89.041414 -253.944213) (xy 89.085488 -253.918767) (xy 89.133074 -253.90072)
			(xy 89.182938 -253.89054) (xy 89.23379 -253.888491) (xy 89.284311 -253.894625) (xy 89.333195 -253.908785)
			(xy 89.379174 -253.930602) (xy 89.421058 -253.959512) (xy 89.457762 -253.994767) (xy 89.488335 -254.035453)
			(xy 89.511986 -254.080516) (xy 89.528102 -254.12879) (xy 89.536266 -254.179024) (xy 89.536778 -254.20447)
			(xy 89.855306 -254.20447) (xy 89.859266 -254.155416) (xy 89.871043 -254.107632) (xy 89.890334 -254.062356)
			(xy 89.916637 -254.02076) (xy 89.949272 -253.983923) (xy 89.987393 -253.952798) (xy 90.030014 -253.928191)
			(xy 90.07603 -253.910739) (xy 90.124249 -253.900895) (xy 90.173424 -253.898914) (xy 90.222279 -253.904846)
			(xy 90.26955 -253.918538) (xy 90.314012 -253.939636) (xy 90.354515 -253.967592) (xy 90.390008 -254.001684)
			(xy 90.419573 -254.041028) (xy 90.442444 -254.084605) (xy 90.458028 -254.131286) (xy 90.465923 -254.179863)
			(xy 90.466418 -254.20447) (xy 90.784675 -254.20447) (xy 90.78877 -254.153742) (xy 90.800949 -254.104328)
			(xy 90.820897 -254.057508) (xy 90.848098 -254.014494) (xy 90.881846 -253.9764) (xy 90.921268 -253.944213)
			(xy 90.965342 -253.918767) (xy 91.012928 -253.90072) (xy 91.062792 -253.89054) (xy 91.113644 -253.888491)
			(xy 91.164165 -253.894625) (xy 91.213049 -253.908785) (xy 91.259028 -253.930602) (xy 91.300912 -253.959512)
			(xy 91.337616 -253.994767) (xy 91.368189 -254.035453) (xy 91.39184 -254.080516) (xy 91.407956 -254.12879)
			(xy 91.41612 -254.179024) (xy 91.416632 -254.20447) (xy 91.724729 -254.20447) (xy 91.728824 -254.153742)
			(xy 91.741003 -254.104328) (xy 91.760951 -254.057508) (xy 91.788152 -254.014494) (xy 91.8219 -253.9764)
			(xy 91.861322 -253.944213) (xy 91.905396 -253.918767) (xy 91.952982 -253.90072) (xy 92.002846 -253.89054)
			(xy 92.053698 -253.888491) (xy 92.104219 -253.894625) (xy 92.153103 -253.908785) (xy 92.199082 -253.930602)
			(xy 92.240966 -253.959512) (xy 92.27767 -253.994767) (xy 92.308243 -254.035453) (xy 92.331894 -254.080516)
			(xy 92.34801 -254.12879) (xy 92.356174 -254.179024) (xy 92.356686 -254.20447) (xy 93.604837 -254.20447)
			(xy 93.608932 -254.153742) (xy 93.621111 -254.104328) (xy 93.641059 -254.057508) (xy 93.66826 -254.014494)
			(xy 93.702008 -253.9764) (xy 93.74143 -253.944213) (xy 93.785504 -253.918767) (xy 93.83309 -253.90072)
			(xy 93.882954 -253.89054) (xy 93.933806 -253.888491) (xy 93.984327 -253.894625) (xy 94.033211 -253.908785)
			(xy 94.07919 -253.930602) (xy 94.121074 -253.959512) (xy 94.157778 -253.994767) (xy 94.188351 -254.035453)
			(xy 94.212002 -254.080516) (xy 94.228118 -254.12879) (xy 94.236282 -254.179024) (xy 94.236794 -254.20447)
			(xy 94.555322 -254.20447) (xy 94.559282 -254.155416) (xy 94.571059 -254.107632) (xy 94.59035 -254.062356)
			(xy 94.616653 -254.02076) (xy 94.649288 -253.983923) (xy 94.687409 -253.952798) (xy 94.73003 -253.928191)
			(xy 94.776046 -253.910739) (xy 94.824265 -253.900895) (xy 94.87344 -253.898914) (xy 94.922295 -253.904846)
			(xy 94.969566 -253.918538) (xy 95.014028 -253.939636) (xy 95.054531 -253.967592) (xy 95.090024 -254.001684)
			(xy 95.119589 -254.041028) (xy 95.14246 -254.084605) (xy 95.158044 -254.131286) (xy 95.165939 -254.179863)
			(xy 95.166434 -254.20447) (xy 95.484691 -254.20447) (xy 95.488786 -254.153742) (xy 95.500965 -254.104328)
			(xy 95.520913 -254.057508) (xy 95.548114 -254.014494) (xy 95.581862 -253.9764) (xy 95.621284 -253.944213)
			(xy 95.665358 -253.918767) (xy 95.712944 -253.90072) (xy 95.762808 -253.89054) (xy 95.81366 -253.888491)
			(xy 95.864181 -253.894625) (xy 95.913065 -253.908785) (xy 95.959044 -253.930602) (xy 96.000928 -253.959512)
			(xy 96.037632 -253.994767) (xy 96.068205 -254.035453) (xy 96.091856 -254.080516) (xy 96.107972 -254.12879)
			(xy 96.116136 -254.179024) (xy 96.116648 -254.20447) (xy 96.435176 -254.20447) (xy 96.439136 -254.155416)
			(xy 96.450913 -254.107632) (xy 96.470204 -254.062356) (xy 96.496507 -254.02076) (xy 96.529142 -253.983923)
			(xy 96.567263 -253.952798) (xy 96.609884 -253.928191) (xy 96.6559 -253.910739) (xy 96.704119 -253.900895)
			(xy 96.753294 -253.898914) (xy 96.802149 -253.904846) (xy 96.84942 -253.918538) (xy 96.893882 -253.939636)
			(xy 96.934385 -253.967592) (xy 96.969878 -254.001684) (xy 96.999443 -254.041028) (xy 97.022314 -254.084605)
			(xy 97.037898 -254.131286) (xy 97.045793 -254.179863) (xy 97.046288 -254.20447) (xy 97.37523 -254.20447)
			(xy 97.37919 -254.155416) (xy 97.390967 -254.107632) (xy 97.410258 -254.062356) (xy 97.436561 -254.02076)
			(xy 97.469196 -253.983923) (xy 97.507317 -253.952798) (xy 97.549938 -253.928191) (xy 97.595954 -253.910739)
			(xy 97.644173 -253.900895) (xy 97.693348 -253.898914) (xy 97.742203 -253.904846) (xy 97.789474 -253.918538)
			(xy 97.833936 -253.939636) (xy 97.874439 -253.967592) (xy 97.909932 -254.001684) (xy 97.939497 -254.041028)
			(xy 97.962368 -254.084605) (xy 97.977952 -254.131286) (xy 97.985847 -254.179863) (xy 97.986342 -254.20447)
			(xy 98.315284 -254.20447) (xy 98.319244 -254.155416) (xy 98.331021 -254.107632) (xy 98.350312 -254.062356)
			(xy 98.376615 -254.02076) (xy 98.40925 -253.983923) (xy 98.447371 -253.952798) (xy 98.489992 -253.928191)
			(xy 98.536008 -253.910739) (xy 98.584227 -253.900895) (xy 98.633402 -253.898914) (xy 98.682257 -253.904846)
			(xy 98.729528 -253.918538) (xy 98.77399 -253.939636) (xy 98.814493 -253.967592) (xy 98.849986 -254.001684)
			(xy 98.879551 -254.041028) (xy 98.902422 -254.084605) (xy 98.918006 -254.131286) (xy 98.925901 -254.179863)
			(xy 98.926396 -254.20447) (xy 99.255338 -254.20447) (xy 99.259298 -254.155416) (xy 99.271075 -254.107632)
			(xy 99.290366 -254.062356) (xy 99.316669 -254.02076) (xy 99.349304 -253.983923) (xy 99.387425 -253.952798)
			(xy 99.430046 -253.928191) (xy 99.476062 -253.910739) (xy 99.524281 -253.900895) (xy 99.573456 -253.898914)
			(xy 99.622311 -253.904846) (xy 99.669582 -253.918538) (xy 99.714044 -253.939636) (xy 99.754547 -253.967592)
			(xy 99.79004 -254.001684) (xy 99.819605 -254.041028) (xy 99.842476 -254.084605) (xy 99.85806 -254.131286)
			(xy 99.865955 -254.179863) (xy 99.86645 -254.20447) (xy 99.865955 -254.229077) (xy 99.85806 -254.277654)
			(xy 99.842476 -254.324335) (xy 99.819605 -254.367912) (xy 99.79004 -254.407256) (xy 99.754547 -254.441348)
			(xy 99.714044 -254.469304) (xy 99.669582 -254.490402) (xy 99.622311 -254.504094) (xy 99.573456 -254.510026)
			(xy 99.524281 -254.508045) (xy 99.476062 -254.498201) (xy 99.430046 -254.480749) (xy 99.387425 -254.456142)
			(xy 99.349304 -254.425017) (xy 99.316669 -254.38818) (xy 99.290366 -254.346584) (xy 99.271075 -254.301308)
			(xy 99.259298 -254.253524) (xy 99.255338 -254.20447) (xy 98.926396 -254.20447) (xy 98.925901 -254.229077)
			(xy 98.918006 -254.277654) (xy 98.902422 -254.324335) (xy 98.879551 -254.367912) (xy 98.849986 -254.407256)
			(xy 98.814493 -254.441348) (xy 98.77399 -254.469304) (xy 98.729528 -254.490402) (xy 98.682257 -254.504094)
			(xy 98.633402 -254.510026) (xy 98.584227 -254.508045) (xy 98.536008 -254.498201) (xy 98.489992 -254.480749)
			(xy 98.447371 -254.456142) (xy 98.40925 -254.425017) (xy 98.376615 -254.38818) (xy 98.350312 -254.346584)
			(xy 98.331021 -254.301308) (xy 98.319244 -254.253524) (xy 98.315284 -254.20447) (xy 97.986342 -254.20447)
			(xy 97.985847 -254.229077) (xy 97.977952 -254.277654) (xy 97.962368 -254.324335) (xy 97.939497 -254.367912)
			(xy 97.909932 -254.407256) (xy 97.874439 -254.441348) (xy 97.833936 -254.469304) (xy 97.789474 -254.490402)
			(xy 97.742203 -254.504094) (xy 97.693348 -254.510026) (xy 97.644173 -254.508045) (xy 97.595954 -254.498201)
			(xy 97.549938 -254.480749) (xy 97.507317 -254.456142) (xy 97.469196 -254.425017) (xy 97.436561 -254.38818)
			(xy 97.410258 -254.346584) (xy 97.390967 -254.301308) (xy 97.37919 -254.253524) (xy 97.37523 -254.20447)
			(xy 97.046288 -254.20447) (xy 97.045793 -254.229077) (xy 97.037898 -254.277654) (xy 97.022314 -254.324335)
			(xy 96.999443 -254.367912) (xy 96.969878 -254.407256) (xy 96.934385 -254.441348) (xy 96.893882 -254.469304)
			(xy 96.84942 -254.490402) (xy 96.802149 -254.504094) (xy 96.753294 -254.510026) (xy 96.704119 -254.508045)
			(xy 96.6559 -254.498201) (xy 96.609884 -254.480749) (xy 96.567263 -254.456142) (xy 96.529142 -254.425017)
			(xy 96.496507 -254.38818) (xy 96.470204 -254.346584) (xy 96.450913 -254.301308) (xy 96.439136 -254.253524)
			(xy 96.435176 -254.20447) (xy 96.116648 -254.20447) (xy 96.116136 -254.229916) (xy 96.107972 -254.28015)
			(xy 96.091856 -254.328424) (xy 96.068205 -254.373487) (xy 96.037632 -254.414173) (xy 96.000928 -254.449428)
			(xy 95.959044 -254.478338) (xy 95.913065 -254.500155) (xy 95.864181 -254.514315) (xy 95.81366 -254.520449)
			(xy 95.762808 -254.5184) (xy 95.712944 -254.50822) (xy 95.665358 -254.490173) (xy 95.621284 -254.464727)
			(xy 95.581862 -254.43254) (xy 95.548114 -254.394446) (xy 95.520913 -254.351432) (xy 95.500965 -254.304612)
			(xy 95.488786 -254.255198) (xy 95.484691 -254.20447) (xy 95.166434 -254.20447) (xy 95.165939 -254.229077)
			(xy 95.158044 -254.277654) (xy 95.14246 -254.324335) (xy 95.119589 -254.367912) (xy 95.090024 -254.407256)
			(xy 95.054531 -254.441348) (xy 95.014028 -254.469304) (xy 94.969566 -254.490402) (xy 94.922295 -254.504094)
			(xy 94.87344 -254.510026) (xy 94.824265 -254.508045) (xy 94.776046 -254.498201) (xy 94.73003 -254.480749)
			(xy 94.687409 -254.456142) (xy 94.649288 -254.425017) (xy 94.616653 -254.38818) (xy 94.59035 -254.346584)
			(xy 94.571059 -254.301308) (xy 94.559282 -254.253524) (xy 94.555322 -254.20447) (xy 94.236794 -254.20447)
			(xy 94.236282 -254.229916) (xy 94.228118 -254.28015) (xy 94.212002 -254.328424) (xy 94.188351 -254.373487)
			(xy 94.157778 -254.414173) (xy 94.121074 -254.449428) (xy 94.07919 -254.478338) (xy 94.033211 -254.500155)
			(xy 93.984327 -254.514315) (xy 93.933806 -254.520449) (xy 93.882954 -254.5184) (xy 93.83309 -254.50822)
			(xy 93.785504 -254.490173) (xy 93.74143 -254.464727) (xy 93.702008 -254.43254) (xy 93.66826 -254.394446)
			(xy 93.641059 -254.351432) (xy 93.621111 -254.304612) (xy 93.608932 -254.255198) (xy 93.604837 -254.20447)
			(xy 92.356686 -254.20447) (xy 92.356174 -254.229916) (xy 92.34801 -254.28015) (xy 92.331894 -254.328424)
			(xy 92.308243 -254.373487) (xy 92.27767 -254.414173) (xy 92.240966 -254.449428) (xy 92.199082 -254.478338)
			(xy 92.153103 -254.500155) (xy 92.104219 -254.514315) (xy 92.053698 -254.520449) (xy 92.002846 -254.5184)
			(xy 91.952982 -254.50822) (xy 91.905396 -254.490173) (xy 91.861322 -254.464727) (xy 91.8219 -254.43254)
			(xy 91.788152 -254.394446) (xy 91.760951 -254.351432) (xy 91.741003 -254.304612) (xy 91.728824 -254.255198)
			(xy 91.724729 -254.20447) (xy 91.416632 -254.20447) (xy 91.41612 -254.229916) (xy 91.407956 -254.28015)
			(xy 91.39184 -254.328424) (xy 91.368189 -254.373487) (xy 91.337616 -254.414173) (xy 91.300912 -254.449428)
			(xy 91.259028 -254.478338) (xy 91.213049 -254.500155) (xy 91.164165 -254.514315) (xy 91.113644 -254.520449)
			(xy 91.062792 -254.5184) (xy 91.012928 -254.50822) (xy 90.965342 -254.490173) (xy 90.921268 -254.464727)
			(xy 90.881846 -254.43254) (xy 90.848098 -254.394446) (xy 90.820897 -254.351432) (xy 90.800949 -254.304612)
			(xy 90.78877 -254.255198) (xy 90.784675 -254.20447) (xy 90.466418 -254.20447) (xy 90.465923 -254.229077)
			(xy 90.458028 -254.277654) (xy 90.442444 -254.324335) (xy 90.419573 -254.367912) (xy 90.390008 -254.407256)
			(xy 90.354515 -254.441348) (xy 90.314012 -254.469304) (xy 90.26955 -254.490402) (xy 90.222279 -254.504094)
			(xy 90.173424 -254.510026) (xy 90.124249 -254.508045) (xy 90.07603 -254.498201) (xy 90.030014 -254.480749)
			(xy 89.987393 -254.456142) (xy 89.949272 -254.425017) (xy 89.916637 -254.38818) (xy 89.890334 -254.346584)
			(xy 89.871043 -254.301308) (xy 89.859266 -254.253524) (xy 89.855306 -254.20447) (xy 89.536778 -254.20447)
			(xy 89.536266 -254.229916) (xy 89.528102 -254.28015) (xy 89.511986 -254.328424) (xy 89.488335 -254.373487)
			(xy 89.457762 -254.414173) (xy 89.421058 -254.449428) (xy 89.379174 -254.478338) (xy 89.333195 -254.500155)
			(xy 89.284311 -254.514315) (xy 89.23379 -254.520449) (xy 89.182938 -254.5184) (xy 89.133074 -254.50822)
			(xy 89.085488 -254.490173) (xy 89.041414 -254.464727) (xy 89.001992 -254.43254) (xy 88.968244 -254.394446)
			(xy 88.941043 -254.351432) (xy 88.921095 -254.304612) (xy 88.908916 -254.255198) (xy 88.904821 -254.20447)
			(xy 88.58631 -254.20447) (xy 88.585815 -254.229077) (xy 88.57792 -254.277654) (xy 88.562336 -254.324335)
			(xy 88.539465 -254.367912) (xy 88.5099 -254.407256) (xy 88.474407 -254.441348) (xy 88.433904 -254.469304)
			(xy 88.389442 -254.490402) (xy 88.342171 -254.504094) (xy 88.293316 -254.510026) (xy 88.244141 -254.508045)
			(xy 88.195922 -254.498201) (xy 88.149906 -254.480749) (xy 88.107285 -254.456142) (xy 88.069164 -254.425017)
			(xy 88.036529 -254.38818) (xy 88.010226 -254.346584) (xy 87.990935 -254.301308) (xy 87.979158 -254.253524)
			(xy 87.975198 -254.20447) (xy 87.65667 -254.20447) (xy 87.656158 -254.229916) (xy 87.647994 -254.28015)
			(xy 87.631878 -254.328424) (xy 87.608227 -254.373487) (xy 87.577654 -254.414173) (xy 87.54095 -254.449428)
			(xy 87.499066 -254.478338) (xy 87.453087 -254.500155) (xy 87.404203 -254.514315) (xy 87.353682 -254.520449)
			(xy 87.30283 -254.5184) (xy 87.252966 -254.50822) (xy 87.20538 -254.490173) (xy 87.161306 -254.464727)
			(xy 87.121884 -254.43254) (xy 87.088136 -254.394446) (xy 87.060935 -254.351432) (xy 87.040987 -254.304612)
			(xy 87.028808 -254.255198) (xy 87.024713 -254.20447) (xy 85.776816 -254.20447) (xy 85.776304 -254.229916)
			(xy 85.76814 -254.28015) (xy 85.752024 -254.328424) (xy 85.728373 -254.373487) (xy 85.6978 -254.414173)
			(xy 85.661096 -254.449428) (xy 85.619212 -254.478338) (xy 85.573233 -254.500155) (xy 85.524349 -254.514315)
			(xy 85.473828 -254.520449) (xy 85.422976 -254.5184) (xy 85.373112 -254.50822) (xy 85.325526 -254.490173)
			(xy 85.281452 -254.464727) (xy 85.24203 -254.43254) (xy 85.208282 -254.394446) (xy 85.181081 -254.351432)
			(xy 85.161133 -254.304612) (xy 85.148954 -254.255198) (xy 85.144859 -254.20447) (xy 84.836762 -254.20447)
			(xy 84.83625 -254.229916) (xy 84.828086 -254.28015) (xy 84.81197 -254.328424) (xy 84.788319 -254.373487)
			(xy 84.757746 -254.414173) (xy 84.721042 -254.449428) (xy 84.679158 -254.478338) (xy 84.633179 -254.500155)
			(xy 84.584295 -254.514315) (xy 84.533774 -254.520449) (xy 84.482922 -254.5184) (xy 84.433058 -254.50822)
			(xy 84.385472 -254.490173) (xy 84.341398 -254.464727) (xy 84.301976 -254.43254) (xy 84.268228 -254.394446)
			(xy 84.241027 -254.351432) (xy 84.221079 -254.304612) (xy 84.2089 -254.255198) (xy 84.204805 -254.20447)
			(xy 83.886294 -254.20447) (xy 83.885799 -254.229077) (xy 83.877904 -254.277654) (xy 83.86232 -254.324335)
			(xy 83.839449 -254.367912) (xy 83.809884 -254.407256) (xy 83.774391 -254.441348) (xy 83.733888 -254.469304)
			(xy 83.689426 -254.490402) (xy 83.642155 -254.504094) (xy 83.5933 -254.510026) (xy 83.544125 -254.508045)
			(xy 83.495906 -254.498201) (xy 83.44989 -254.480749) (xy 83.407269 -254.456142) (xy 83.369148 -254.425017)
			(xy 83.336513 -254.38818) (xy 83.31021 -254.346584) (xy 83.290919 -254.301308) (xy 83.279142 -254.253524)
			(xy 83.275182 -254.20447) (xy 82.956654 -254.20447) (xy 82.956142 -254.229916) (xy 82.947978 -254.28015)
			(xy 82.931862 -254.328424) (xy 82.908211 -254.373487) (xy 82.877638 -254.414173) (xy 82.840934 -254.449428)
			(xy 82.79905 -254.478338) (xy 82.753071 -254.500155) (xy 82.704187 -254.514315) (xy 82.653666 -254.520449)
			(xy 82.602814 -254.5184) (xy 82.55295 -254.50822) (xy 82.505364 -254.490173) (xy 82.46129 -254.464727)
			(xy 82.421868 -254.43254) (xy 82.38812 -254.394446) (xy 82.360919 -254.351432) (xy 82.340971 -254.304612)
			(xy 82.328792 -254.255198) (xy 82.324697 -254.20447) (xy 82.00644 -254.20447) (xy 82.005945 -254.229077)
			(xy 81.99805 -254.277654) (xy 81.982466 -254.324335) (xy 81.959595 -254.367912) (xy 81.93003 -254.407256)
			(xy 81.894537 -254.441348) (xy 81.854034 -254.469304) (xy 81.809572 -254.490402) (xy 81.762301 -254.504094)
			(xy 81.713446 -254.510026) (xy 81.664271 -254.508045) (xy 81.616052 -254.498201) (xy 81.570036 -254.480749)
			(xy 81.527415 -254.456142) (xy 81.489294 -254.425017) (xy 81.456659 -254.38818) (xy 81.430356 -254.346584)
			(xy 81.411065 -254.301308) (xy 81.399288 -254.253524) (xy 81.395328 -254.20447) (xy 81.0768 -254.20447)
			(xy 81.076288 -254.229916) (xy 81.068124 -254.28015) (xy 81.052008 -254.328424) (xy 81.028357 -254.373487)
			(xy 80.997784 -254.414173) (xy 80.96108 -254.449428) (xy 80.919196 -254.478338) (xy 80.873217 -254.500155)
			(xy 80.824333 -254.514315) (xy 80.773812 -254.520449) (xy 80.72296 -254.5184) (xy 80.673096 -254.50822)
			(xy 80.62551 -254.490173) (xy 80.581436 -254.464727) (xy 80.542014 -254.43254) (xy 80.508266 -254.394446)
			(xy 80.481065 -254.351432) (xy 80.461117 -254.304612) (xy 80.448938 -254.255198) (xy 80.444843 -254.20447)
			(xy 76.963477 -254.20447) (xy 76.965804 -254.205574) (xy 77.006307 -254.23353) (xy 77.0418 -254.267622)
			(xy 77.071365 -254.306966) (xy 77.094236 -254.350543) (xy 77.10982 -254.397224) (xy 77.117715 -254.445801)
			(xy 77.11821 -254.470408) (xy 77.117715 -254.495015) (xy 77.10982 -254.543592) (xy 77.094236 -254.590273)
			(xy 77.071365 -254.63385) (xy 77.0418 -254.673194) (xy 77.006307 -254.707286) (xy 76.965804 -254.735242)
			(xy 76.921342 -254.75634) (xy 76.874071 -254.770032) (xy 76.825216 -254.775964) (xy 76.776041 -254.773983)
			(xy 76.727822 -254.764139) (xy 76.681806 -254.746687) (xy 76.639185 -254.72208) (xy 76.601064 -254.690955)
			(xy 76.568429 -254.654118) (xy 76.542126 -254.612522) (xy 76.522835 -254.567246) (xy 76.511058 -254.519462)
			(xy 76.507098 -254.470408) (xy 73.375774 -254.470408) (xy 73.375774 -255.014476) (xy 78.105266 -255.014476)
			(xy 78.109226 -254.965422) (xy 78.121003 -254.917638) (xy 78.140294 -254.872362) (xy 78.166597 -254.830766)
			(xy 78.199232 -254.793929) (xy 78.237353 -254.762804) (xy 78.279974 -254.738197) (xy 78.32599 -254.720745)
			(xy 78.374209 -254.710901) (xy 78.423384 -254.70892) (xy 78.472239 -254.714852) (xy 78.51951 -254.728544)
			(xy 78.563972 -254.749642) (xy 78.604475 -254.777598) (xy 78.639968 -254.81169) (xy 78.669533 -254.851034)
			(xy 78.692404 -254.894611) (xy 78.707988 -254.941292) (xy 78.715883 -254.989869) (xy 78.716378 -255.014476)
			(xy 79.985374 -255.014476) (xy 79.989334 -254.965422) (xy 80.001111 -254.917638) (xy 80.020402 -254.872362)
			(xy 80.046705 -254.830766) (xy 80.07934 -254.793929) (xy 80.117461 -254.762804) (xy 80.160082 -254.738197)
			(xy 80.206098 -254.720745) (xy 80.254317 -254.710901) (xy 80.303492 -254.70892) (xy 80.352347 -254.714852)
			(xy 80.399618 -254.728544) (xy 80.44408 -254.749642) (xy 80.484583 -254.777598) (xy 80.520076 -254.81169)
			(xy 80.549641 -254.851034) (xy 80.572512 -254.894611) (xy 80.588096 -254.941292) (xy 80.595991 -254.989869)
			(xy 80.596486 -255.014476) (xy 80.914743 -255.014476) (xy 80.918838 -254.963748) (xy 80.931017 -254.914334)
			(xy 80.950965 -254.867514) (xy 80.978166 -254.8245) (xy 81.011914 -254.786406) (xy 81.051336 -254.754219)
			(xy 81.09541 -254.728773) (xy 81.142996 -254.710726) (xy 81.19286 -254.700546) (xy 81.243712 -254.698497)
			(xy 81.294233 -254.704631) (xy 81.343117 -254.718791) (xy 81.389096 -254.740608) (xy 81.43098 -254.769518)
			(xy 81.467684 -254.804773) (xy 81.498257 -254.845459) (xy 81.521908 -254.890522) (xy 81.538024 -254.938796)
			(xy 81.546188 -254.98903) (xy 81.5467 -255.014476) (xy 81.854797 -255.014476) (xy 81.858892 -254.963748)
			(xy 81.871071 -254.914334) (xy 81.891019 -254.867514) (xy 81.91822 -254.8245) (xy 81.951968 -254.786406)
			(xy 81.99139 -254.754219) (xy 82.035464 -254.728773) (xy 82.08305 -254.710726) (xy 82.132914 -254.700546)
			(xy 82.183766 -254.698497) (xy 82.234287 -254.704631) (xy 82.283171 -254.718791) (xy 82.32915 -254.740608)
			(xy 82.371034 -254.769518) (xy 82.407738 -254.804773) (xy 82.438311 -254.845459) (xy 82.461962 -254.890522)
			(xy 82.478078 -254.938796) (xy 82.486242 -254.98903) (xy 82.486754 -255.014476) (xy 82.805282 -255.014476)
			(xy 82.809242 -254.965422) (xy 82.821019 -254.917638) (xy 82.84031 -254.872362) (xy 82.866613 -254.830766)
			(xy 82.899248 -254.793929) (xy 82.937369 -254.762804) (xy 82.97999 -254.738197) (xy 83.026006 -254.720745)
			(xy 83.074225 -254.710901) (xy 83.1234 -254.70892) (xy 83.172255 -254.714852) (xy 83.219526 -254.728544)
			(xy 83.263988 -254.749642) (xy 83.304491 -254.777598) (xy 83.339984 -254.81169) (xy 83.369549 -254.851034)
			(xy 83.39242 -254.894611) (xy 83.408004 -254.941292) (xy 83.415899 -254.989869) (xy 83.416394 -255.014476)
			(xy 83.734905 -255.014476) (xy 83.739 -254.963748) (xy 83.751179 -254.914334) (xy 83.771127 -254.867514)
			(xy 83.798328 -254.8245) (xy 83.832076 -254.786406) (xy 83.871498 -254.754219) (xy 83.915572 -254.728773)
			(xy 83.963158 -254.710726) (xy 84.013022 -254.700546) (xy 84.063874 -254.698497) (xy 84.114395 -254.704631)
			(xy 84.163279 -254.718791) (xy 84.209258 -254.740608) (xy 84.251142 -254.769518) (xy 84.287846 -254.804773)
			(xy 84.318419 -254.845459) (xy 84.34207 -254.890522) (xy 84.358186 -254.938796) (xy 84.36635 -254.98903)
			(xy 84.366862 -255.014476) (xy 84.685136 -255.014476) (xy 84.689096 -254.965422) (xy 84.700873 -254.917638)
			(xy 84.720164 -254.872362) (xy 84.746467 -254.830766) (xy 84.779102 -254.793929) (xy 84.817223 -254.762804)
			(xy 84.859844 -254.738197) (xy 84.90586 -254.720745) (xy 84.954079 -254.710901) (xy 85.003254 -254.70892)
			(xy 85.052109 -254.714852) (xy 85.09938 -254.728544) (xy 85.143842 -254.749642) (xy 85.184345 -254.777598)
			(xy 85.219838 -254.81169) (xy 85.249403 -254.851034) (xy 85.272274 -254.894611) (xy 85.287858 -254.941292)
			(xy 85.295753 -254.989869) (xy 85.296248 -255.014476) (xy 85.614759 -255.014476) (xy 85.618854 -254.963748)
			(xy 85.631033 -254.914334) (xy 85.650981 -254.867514) (xy 85.678182 -254.8245) (xy 85.71193 -254.786406)
			(xy 85.751352 -254.754219) (xy 85.795426 -254.728773) (xy 85.843012 -254.710726) (xy 85.892876 -254.700546)
			(xy 85.943728 -254.698497) (xy 85.994249 -254.704631) (xy 86.043133 -254.718791) (xy 86.089112 -254.740608)
			(xy 86.130996 -254.769518) (xy 86.1677 -254.804773) (xy 86.198273 -254.845459) (xy 86.221924 -254.890522)
			(xy 86.23804 -254.938796) (xy 86.246204 -254.98903) (xy 86.246716 -255.014476) (xy 86.565244 -255.014476)
			(xy 86.569204 -254.965422) (xy 86.580981 -254.917638) (xy 86.600272 -254.872362) (xy 86.626575 -254.830766)
			(xy 86.65921 -254.793929) (xy 86.697331 -254.762804) (xy 86.739952 -254.738197) (xy 86.785968 -254.720745)
			(xy 86.834187 -254.710901) (xy 86.883362 -254.70892) (xy 86.932217 -254.714852) (xy 86.979488 -254.728544)
			(xy 87.02395 -254.749642) (xy 87.064453 -254.777598) (xy 87.099946 -254.81169) (xy 87.129511 -254.851034)
			(xy 87.152382 -254.894611) (xy 87.167966 -254.941292) (xy 87.175861 -254.989869) (xy 87.176356 -255.014476)
			(xy 87.494867 -255.014476) (xy 87.498962 -254.963748) (xy 87.511141 -254.914334) (xy 87.531089 -254.867514)
			(xy 87.55829 -254.8245) (xy 87.592038 -254.786406) (xy 87.63146 -254.754219) (xy 87.675534 -254.728773)
			(xy 87.72312 -254.710726) (xy 87.772984 -254.700546) (xy 87.823836 -254.698497) (xy 87.874357 -254.704631)
			(xy 87.923241 -254.718791) (xy 87.96922 -254.740608) (xy 88.011104 -254.769518) (xy 88.047808 -254.804773)
			(xy 88.078381 -254.845459) (xy 88.102032 -254.890522) (xy 88.118148 -254.938796) (xy 88.126312 -254.98903)
			(xy 88.126824 -255.014476) (xy 88.434921 -255.014476) (xy 88.439016 -254.963748) (xy 88.451195 -254.914334)
			(xy 88.471143 -254.867514) (xy 88.498344 -254.8245) (xy 88.532092 -254.786406) (xy 88.571514 -254.754219)
			(xy 88.615588 -254.728773) (xy 88.663174 -254.710726) (xy 88.713038 -254.700546) (xy 88.76389 -254.698497)
			(xy 88.814411 -254.704631) (xy 88.863295 -254.718791) (xy 88.909274 -254.740608) (xy 88.951158 -254.769518)
			(xy 88.987862 -254.804773) (xy 89.018435 -254.845459) (xy 89.042086 -254.890522) (xy 89.058202 -254.938796)
			(xy 89.066366 -254.98903) (xy 89.066878 -255.014476) (xy 89.385152 -255.014476) (xy 89.389112 -254.965422)
			(xy 89.400889 -254.917638) (xy 89.42018 -254.872362) (xy 89.446483 -254.830766) (xy 89.479118 -254.793929)
			(xy 89.517239 -254.762804) (xy 89.55986 -254.738197) (xy 89.605876 -254.720745) (xy 89.654095 -254.710901)
			(xy 89.70327 -254.70892) (xy 89.752125 -254.714852) (xy 89.799396 -254.728544) (xy 89.843858 -254.749642)
			(xy 89.884361 -254.777598) (xy 89.919854 -254.81169) (xy 89.949419 -254.851034) (xy 89.97229 -254.894611)
			(xy 89.987874 -254.941292) (xy 89.995769 -254.989869) (xy 89.996264 -255.014476) (xy 90.314775 -255.014476)
			(xy 90.31887 -254.963748) (xy 90.331049 -254.914334) (xy 90.350997 -254.867514) (xy 90.378198 -254.8245)
			(xy 90.411946 -254.786406) (xy 90.451368 -254.754219) (xy 90.495442 -254.728773) (xy 90.543028 -254.710726)
			(xy 90.592892 -254.700546) (xy 90.643744 -254.698497) (xy 90.694265 -254.704631) (xy 90.743149 -254.718791)
			(xy 90.789128 -254.740608) (xy 90.831012 -254.769518) (xy 90.867716 -254.804773) (xy 90.898289 -254.845459)
			(xy 90.92194 -254.890522) (xy 90.938056 -254.938796) (xy 90.94622 -254.98903) (xy 90.946732 -255.014476)
			(xy 91.26526 -255.014476) (xy 91.26922 -254.965422) (xy 91.280997 -254.917638) (xy 91.300288 -254.872362)
			(xy 91.326591 -254.830766) (xy 91.359226 -254.793929) (xy 91.397347 -254.762804) (xy 91.439968 -254.738197)
			(xy 91.485984 -254.720745) (xy 91.534203 -254.710901) (xy 91.583378 -254.70892) (xy 91.632233 -254.714852)
			(xy 91.679504 -254.728544) (xy 91.723966 -254.749642) (xy 91.764469 -254.777598) (xy 91.799962 -254.81169)
			(xy 91.829527 -254.851034) (xy 91.852398 -254.894611) (xy 91.867982 -254.941292) (xy 91.875877 -254.989869)
			(xy 91.876372 -255.014476) (xy 92.194883 -255.014476) (xy 92.198978 -254.963748) (xy 92.211157 -254.914334)
			(xy 92.231105 -254.867514) (xy 92.258306 -254.8245) (xy 92.292054 -254.786406) (xy 92.331476 -254.754219)
			(xy 92.37555 -254.728773) (xy 92.423136 -254.710726) (xy 92.473 -254.700546) (xy 92.523852 -254.698497)
			(xy 92.574373 -254.704631) (xy 92.623257 -254.718791) (xy 92.669236 -254.740608) (xy 92.71112 -254.769518)
			(xy 92.747824 -254.804773) (xy 92.778397 -254.845459) (xy 92.802048 -254.890522) (xy 92.818164 -254.938796)
			(xy 92.826328 -254.98903) (xy 92.82684 -255.014476) (xy 93.145114 -255.014476) (xy 93.149074 -254.965422)
			(xy 93.160851 -254.917638) (xy 93.180142 -254.872362) (xy 93.206445 -254.830766) (xy 93.23908 -254.793929)
			(xy 93.277201 -254.762804) (xy 93.319822 -254.738197) (xy 93.365838 -254.720745) (xy 93.414057 -254.710901)
			(xy 93.463232 -254.70892) (xy 93.512087 -254.714852) (xy 93.559358 -254.728544) (xy 93.60382 -254.749642)
			(xy 93.644323 -254.777598) (xy 93.679816 -254.81169) (xy 93.709381 -254.851034) (xy 93.732252 -254.894611)
			(xy 93.747836 -254.941292) (xy 93.755731 -254.989869) (xy 93.756226 -255.014476) (xy 94.074737 -255.014476)
			(xy 94.078832 -254.963748) (xy 94.091011 -254.914334) (xy 94.110959 -254.867514) (xy 94.13816 -254.8245)
			(xy 94.171908 -254.786406) (xy 94.21133 -254.754219) (xy 94.255404 -254.728773) (xy 94.30299 -254.710726)
			(xy 94.352854 -254.700546) (xy 94.403706 -254.698497) (xy 94.454227 -254.704631) (xy 94.503111 -254.718791)
			(xy 94.54909 -254.740608) (xy 94.590974 -254.769518) (xy 94.627678 -254.804773) (xy 94.658251 -254.845459)
			(xy 94.681902 -254.890522) (xy 94.698018 -254.938796) (xy 94.706182 -254.98903) (xy 94.706694 -255.014476)
			(xy 95.014791 -255.014476) (xy 95.018886 -254.963748) (xy 95.031065 -254.914334) (xy 95.051013 -254.867514)
			(xy 95.078214 -254.8245) (xy 95.111962 -254.786406) (xy 95.151384 -254.754219) (xy 95.195458 -254.728773)
			(xy 95.243044 -254.710726) (xy 95.292908 -254.700546) (xy 95.34376 -254.698497) (xy 95.394281 -254.704631)
			(xy 95.443165 -254.718791) (xy 95.489144 -254.740608) (xy 95.531028 -254.769518) (xy 95.567732 -254.804773)
			(xy 95.598305 -254.845459) (xy 95.621956 -254.890522) (xy 95.638072 -254.938796) (xy 95.646236 -254.98903)
			(xy 95.646748 -255.014476) (xy 95.965276 -255.014476) (xy 95.969236 -254.965422) (xy 95.981013 -254.917638)
			(xy 96.000304 -254.872362) (xy 96.026607 -254.830766) (xy 96.059242 -254.793929) (xy 96.097363 -254.762804)
			(xy 96.139984 -254.738197) (xy 96.186 -254.720745) (xy 96.234219 -254.710901) (xy 96.283394 -254.70892)
			(xy 96.332249 -254.714852) (xy 96.37952 -254.728544) (xy 96.423982 -254.749642) (xy 96.464485 -254.777598)
			(xy 96.499978 -254.81169) (xy 96.529543 -254.851034) (xy 96.552414 -254.894611) (xy 96.567998 -254.941292)
			(xy 96.575893 -254.989869) (xy 96.576388 -255.014476) (xy 96.90533 -255.014476) (xy 96.90929 -254.965422)
			(xy 96.921067 -254.917638) (xy 96.940358 -254.872362) (xy 96.966661 -254.830766) (xy 96.999296 -254.793929)
			(xy 97.037417 -254.762804) (xy 97.080038 -254.738197) (xy 97.126054 -254.720745) (xy 97.174273 -254.710901)
			(xy 97.223448 -254.70892) (xy 97.272303 -254.714852) (xy 97.319574 -254.728544) (xy 97.364036 -254.749642)
			(xy 97.404539 -254.777598) (xy 97.440032 -254.81169) (xy 97.469597 -254.851034) (xy 97.492468 -254.894611)
			(xy 97.508052 -254.941292) (xy 97.515947 -254.989869) (xy 97.516442 -255.014476) (xy 97.84513 -255.014476)
			(xy 97.84909 -254.965422) (xy 97.860867 -254.917638) (xy 97.880158 -254.872362) (xy 97.906461 -254.830766)
			(xy 97.939096 -254.793929) (xy 97.977217 -254.762804) (xy 98.019838 -254.738197) (xy 98.065854 -254.720745)
			(xy 98.114073 -254.710901) (xy 98.163248 -254.70892) (xy 98.212103 -254.714852) (xy 98.259374 -254.728544)
			(xy 98.303836 -254.749642) (xy 98.344339 -254.777598) (xy 98.379832 -254.81169) (xy 98.409397 -254.851034)
			(xy 98.432268 -254.894611) (xy 98.447852 -254.941292) (xy 98.455747 -254.989869) (xy 98.456242 -255.014476)
			(xy 98.785184 -255.014476) (xy 98.789144 -254.965422) (xy 98.800921 -254.917638) (xy 98.820212 -254.872362)
			(xy 98.846515 -254.830766) (xy 98.87915 -254.793929) (xy 98.917271 -254.762804) (xy 98.959892 -254.738197)
			(xy 99.005908 -254.720745) (xy 99.054127 -254.710901) (xy 99.103302 -254.70892) (xy 99.152157 -254.714852)
			(xy 99.199428 -254.728544) (xy 99.24389 -254.749642) (xy 99.284393 -254.777598) (xy 99.319886 -254.81169)
			(xy 99.349451 -254.851034) (xy 99.372322 -254.894611) (xy 99.387906 -254.941292) (xy 99.395801 -254.989869)
			(xy 99.396296 -255.014476) (xy 99.725238 -255.014476) (xy 99.729198 -254.965422) (xy 99.740975 -254.917638)
			(xy 99.760266 -254.872362) (xy 99.786569 -254.830766) (xy 99.819204 -254.793929) (xy 99.857325 -254.762804)
			(xy 99.899946 -254.738197) (xy 99.945962 -254.720745) (xy 99.994181 -254.710901) (xy 100.043356 -254.70892)
			(xy 100.092211 -254.714852) (xy 100.139482 -254.728544) (xy 100.183944 -254.749642) (xy 100.224447 -254.777598)
			(xy 100.25994 -254.81169) (xy 100.289505 -254.851034) (xy 100.312376 -254.894611) (xy 100.32796 -254.941292)
			(xy 100.335855 -254.989869) (xy 100.33635 -255.014476) (xy 100.335855 -255.039083) (xy 100.32796 -255.08766)
			(xy 100.312376 -255.134341) (xy 100.289505 -255.177918) (xy 100.25994 -255.217262) (xy 100.224447 -255.251354)
			(xy 100.183944 -255.27931) (xy 100.139482 -255.300408) (xy 100.092211 -255.3141) (xy 100.043356 -255.320032)
			(xy 99.994181 -255.318051) (xy 99.945962 -255.308207) (xy 99.899946 -255.290755) (xy 99.857325 -255.266148)
			(xy 99.819204 -255.235023) (xy 99.786569 -255.198186) (xy 99.760266 -255.15659) (xy 99.740975 -255.111314)
			(xy 99.729198 -255.06353) (xy 99.725238 -255.014476) (xy 99.396296 -255.014476) (xy 99.395801 -255.039083)
			(xy 99.387906 -255.08766) (xy 99.372322 -255.134341) (xy 99.349451 -255.177918) (xy 99.319886 -255.217262)
			(xy 99.284393 -255.251354) (xy 99.24389 -255.27931) (xy 99.199428 -255.300408) (xy 99.152157 -255.3141)
			(xy 99.103302 -255.320032) (xy 99.054127 -255.318051) (xy 99.005908 -255.308207) (xy 98.959892 -255.290755)
			(xy 98.917271 -255.266148) (xy 98.87915 -255.235023) (xy 98.846515 -255.198186) (xy 98.820212 -255.15659)
			(xy 98.800921 -255.111314) (xy 98.789144 -255.06353) (xy 98.785184 -255.014476) (xy 98.456242 -255.014476)
			(xy 98.455747 -255.039083) (xy 98.447852 -255.08766) (xy 98.432268 -255.134341) (xy 98.409397 -255.177918)
			(xy 98.379832 -255.217262) (xy 98.344339 -255.251354) (xy 98.303836 -255.27931) (xy 98.259374 -255.300408)
			(xy 98.212103 -255.3141) (xy 98.163248 -255.320032) (xy 98.114073 -255.318051) (xy 98.065854 -255.308207)
			(xy 98.019838 -255.290755) (xy 97.977217 -255.266148) (xy 97.939096 -255.235023) (xy 97.906461 -255.198186)
			(xy 97.880158 -255.15659) (xy 97.860867 -255.111314) (xy 97.84909 -255.06353) (xy 97.84513 -255.014476)
			(xy 97.516442 -255.014476) (xy 97.515947 -255.039083) (xy 97.508052 -255.08766) (xy 97.492468 -255.134341)
			(xy 97.469597 -255.177918) (xy 97.440032 -255.217262) (xy 97.404539 -255.251354) (xy 97.364036 -255.27931)
			(xy 97.319574 -255.300408) (xy 97.272303 -255.3141) (xy 97.223448 -255.320032) (xy 97.174273 -255.318051)
			(xy 97.126054 -255.308207) (xy 97.080038 -255.290755) (xy 97.037417 -255.266148) (xy 96.999296 -255.235023)
			(xy 96.966661 -255.198186) (xy 96.940358 -255.15659) (xy 96.921067 -255.111314) (xy 96.90929 -255.06353)
			(xy 96.90533 -255.014476) (xy 96.576388 -255.014476) (xy 96.575893 -255.039083) (xy 96.567998 -255.08766)
			(xy 96.552414 -255.134341) (xy 96.529543 -255.177918) (xy 96.499978 -255.217262) (xy 96.464485 -255.251354)
			(xy 96.423982 -255.27931) (xy 96.37952 -255.300408) (xy 96.332249 -255.3141) (xy 96.283394 -255.320032)
			(xy 96.234219 -255.318051) (xy 96.186 -255.308207) (xy 96.139984 -255.290755) (xy 96.097363 -255.266148)
			(xy 96.059242 -255.235023) (xy 96.026607 -255.198186) (xy 96.000304 -255.15659) (xy 95.981013 -255.111314)
			(xy 95.969236 -255.06353) (xy 95.965276 -255.014476) (xy 95.646748 -255.014476) (xy 95.646236 -255.039922)
			(xy 95.638072 -255.090156) (xy 95.621956 -255.13843) (xy 95.598305 -255.183493) (xy 95.567732 -255.224179)
			(xy 95.531028 -255.259434) (xy 95.489144 -255.288344) (xy 95.443165 -255.310161) (xy 95.394281 -255.324321)
			(xy 95.34376 -255.330455) (xy 95.292908 -255.328406) (xy 95.243044 -255.318226) (xy 95.195458 -255.300179)
			(xy 95.151384 -255.274733) (xy 95.111962 -255.242546) (xy 95.078214 -255.204452) (xy 95.051013 -255.161438)
			(xy 95.031065 -255.114618) (xy 95.018886 -255.065204) (xy 95.014791 -255.014476) (xy 94.706694 -255.014476)
			(xy 94.706182 -255.039922) (xy 94.698018 -255.090156) (xy 94.681902 -255.13843) (xy 94.658251 -255.183493)
			(xy 94.627678 -255.224179) (xy 94.590974 -255.259434) (xy 94.54909 -255.288344) (xy 94.503111 -255.310161)
			(xy 94.454227 -255.324321) (xy 94.403706 -255.330455) (xy 94.352854 -255.328406) (xy 94.30299 -255.318226)
			(xy 94.255404 -255.300179) (xy 94.21133 -255.274733) (xy 94.171908 -255.242546) (xy 94.13816 -255.204452)
			(xy 94.110959 -255.161438) (xy 94.091011 -255.114618) (xy 94.078832 -255.065204) (xy 94.074737 -255.014476)
			(xy 93.756226 -255.014476) (xy 93.755731 -255.039083) (xy 93.747836 -255.08766) (xy 93.732252 -255.134341)
			(xy 93.709381 -255.177918) (xy 93.679816 -255.217262) (xy 93.644323 -255.251354) (xy 93.60382 -255.27931)
			(xy 93.559358 -255.300408) (xy 93.512087 -255.3141) (xy 93.463232 -255.320032) (xy 93.414057 -255.318051)
			(xy 93.365838 -255.308207) (xy 93.319822 -255.290755) (xy 93.277201 -255.266148) (xy 93.23908 -255.235023)
			(xy 93.206445 -255.198186) (xy 93.180142 -255.15659) (xy 93.160851 -255.111314) (xy 93.149074 -255.06353)
			(xy 93.145114 -255.014476) (xy 92.82684 -255.014476) (xy 92.826328 -255.039922) (xy 92.818164 -255.090156)
			(xy 92.802048 -255.13843) (xy 92.778397 -255.183493) (xy 92.747824 -255.224179) (xy 92.71112 -255.259434)
			(xy 92.669236 -255.288344) (xy 92.623257 -255.310161) (xy 92.574373 -255.324321) (xy 92.523852 -255.330455)
			(xy 92.473 -255.328406) (xy 92.423136 -255.318226) (xy 92.37555 -255.300179) (xy 92.331476 -255.274733)
			(xy 92.292054 -255.242546) (xy 92.258306 -255.204452) (xy 92.231105 -255.161438) (xy 92.211157 -255.114618)
			(xy 92.198978 -255.065204) (xy 92.194883 -255.014476) (xy 91.876372 -255.014476) (xy 91.875877 -255.039083)
			(xy 91.867982 -255.08766) (xy 91.852398 -255.134341) (xy 91.829527 -255.177918) (xy 91.799962 -255.217262)
			(xy 91.764469 -255.251354) (xy 91.723966 -255.27931) (xy 91.679504 -255.300408) (xy 91.632233 -255.3141)
			(xy 91.583378 -255.320032) (xy 91.534203 -255.318051) (xy 91.485984 -255.308207) (xy 91.439968 -255.290755)
			(xy 91.397347 -255.266148) (xy 91.359226 -255.235023) (xy 91.326591 -255.198186) (xy 91.300288 -255.15659)
			(xy 91.280997 -255.111314) (xy 91.26922 -255.06353) (xy 91.26526 -255.014476) (xy 90.946732 -255.014476)
			(xy 90.94622 -255.039922) (xy 90.938056 -255.090156) (xy 90.92194 -255.13843) (xy 90.898289 -255.183493)
			(xy 90.867716 -255.224179) (xy 90.831012 -255.259434) (xy 90.789128 -255.288344) (xy 90.743149 -255.310161)
			(xy 90.694265 -255.324321) (xy 90.643744 -255.330455) (xy 90.592892 -255.328406) (xy 90.543028 -255.318226)
			(xy 90.495442 -255.300179) (xy 90.451368 -255.274733) (xy 90.411946 -255.242546) (xy 90.378198 -255.204452)
			(xy 90.350997 -255.161438) (xy 90.331049 -255.114618) (xy 90.31887 -255.065204) (xy 90.314775 -255.014476)
			(xy 89.996264 -255.014476) (xy 89.995769 -255.039083) (xy 89.987874 -255.08766) (xy 89.97229 -255.134341)
			(xy 89.949419 -255.177918) (xy 89.919854 -255.217262) (xy 89.884361 -255.251354) (xy 89.843858 -255.27931)
			(xy 89.799396 -255.300408) (xy 89.752125 -255.3141) (xy 89.70327 -255.320032) (xy 89.654095 -255.318051)
			(xy 89.605876 -255.308207) (xy 89.55986 -255.290755) (xy 89.517239 -255.266148) (xy 89.479118 -255.235023)
			(xy 89.446483 -255.198186) (xy 89.42018 -255.15659) (xy 89.400889 -255.111314) (xy 89.389112 -255.06353)
			(xy 89.385152 -255.014476) (xy 89.066878 -255.014476) (xy 89.066366 -255.039922) (xy 89.058202 -255.090156)
			(xy 89.042086 -255.13843) (xy 89.018435 -255.183493) (xy 88.987862 -255.224179) (xy 88.951158 -255.259434)
			(xy 88.909274 -255.288344) (xy 88.863295 -255.310161) (xy 88.814411 -255.324321) (xy 88.76389 -255.330455)
			(xy 88.713038 -255.328406) (xy 88.663174 -255.318226) (xy 88.615588 -255.300179) (xy 88.571514 -255.274733)
			(xy 88.532092 -255.242546) (xy 88.498344 -255.204452) (xy 88.471143 -255.161438) (xy 88.451195 -255.114618)
			(xy 88.439016 -255.065204) (xy 88.434921 -255.014476) (xy 88.126824 -255.014476) (xy 88.126312 -255.039922)
			(xy 88.118148 -255.090156) (xy 88.102032 -255.13843) (xy 88.078381 -255.183493) (xy 88.047808 -255.224179)
			(xy 88.011104 -255.259434) (xy 87.96922 -255.288344) (xy 87.923241 -255.310161) (xy 87.874357 -255.324321)
			(xy 87.823836 -255.330455) (xy 87.772984 -255.328406) (xy 87.72312 -255.318226) (xy 87.675534 -255.300179)
			(xy 87.63146 -255.274733) (xy 87.592038 -255.242546) (xy 87.55829 -255.204452) (xy 87.531089 -255.161438)
			(xy 87.511141 -255.114618) (xy 87.498962 -255.065204) (xy 87.494867 -255.014476) (xy 87.176356 -255.014476)
			(xy 87.175861 -255.039083) (xy 87.167966 -255.08766) (xy 87.152382 -255.134341) (xy 87.129511 -255.177918)
			(xy 87.099946 -255.217262) (xy 87.064453 -255.251354) (xy 87.02395 -255.27931) (xy 86.979488 -255.300408)
			(xy 86.932217 -255.3141) (xy 86.883362 -255.320032) (xy 86.834187 -255.318051) (xy 86.785968 -255.308207)
			(xy 86.739952 -255.290755) (xy 86.697331 -255.266148) (xy 86.65921 -255.235023) (xy 86.626575 -255.198186)
			(xy 86.600272 -255.15659) (xy 86.580981 -255.111314) (xy 86.569204 -255.06353) (xy 86.565244 -255.014476)
			(xy 86.246716 -255.014476) (xy 86.246204 -255.039922) (xy 86.23804 -255.090156) (xy 86.221924 -255.13843)
			(xy 86.198273 -255.183493) (xy 86.1677 -255.224179) (xy 86.130996 -255.259434) (xy 86.089112 -255.288344)
			(xy 86.043133 -255.310161) (xy 85.994249 -255.324321) (xy 85.943728 -255.330455) (xy 85.892876 -255.328406)
			(xy 85.843012 -255.318226) (xy 85.795426 -255.300179) (xy 85.751352 -255.274733) (xy 85.71193 -255.242546)
			(xy 85.678182 -255.204452) (xy 85.650981 -255.161438) (xy 85.631033 -255.114618) (xy 85.618854 -255.065204)
			(xy 85.614759 -255.014476) (xy 85.296248 -255.014476) (xy 85.295753 -255.039083) (xy 85.287858 -255.08766)
			(xy 85.272274 -255.134341) (xy 85.249403 -255.177918) (xy 85.219838 -255.217262) (xy 85.184345 -255.251354)
			(xy 85.143842 -255.27931) (xy 85.09938 -255.300408) (xy 85.052109 -255.3141) (xy 85.003254 -255.320032)
			(xy 84.954079 -255.318051) (xy 84.90586 -255.308207) (xy 84.859844 -255.290755) (xy 84.817223 -255.266148)
			(xy 84.779102 -255.235023) (xy 84.746467 -255.198186) (xy 84.720164 -255.15659) (xy 84.700873 -255.111314)
			(xy 84.689096 -255.06353) (xy 84.685136 -255.014476) (xy 84.366862 -255.014476) (xy 84.36635 -255.039922)
			(xy 84.358186 -255.090156) (xy 84.34207 -255.13843) (xy 84.318419 -255.183493) (xy 84.287846 -255.224179)
			(xy 84.251142 -255.259434) (xy 84.209258 -255.288344) (xy 84.163279 -255.310161) (xy 84.114395 -255.324321)
			(xy 84.063874 -255.330455) (xy 84.013022 -255.328406) (xy 83.963158 -255.318226) (xy 83.915572 -255.300179)
			(xy 83.871498 -255.274733) (xy 83.832076 -255.242546) (xy 83.798328 -255.204452) (xy 83.771127 -255.161438)
			(xy 83.751179 -255.114618) (xy 83.739 -255.065204) (xy 83.734905 -255.014476) (xy 83.416394 -255.014476)
			(xy 83.415899 -255.039083) (xy 83.408004 -255.08766) (xy 83.39242 -255.134341) (xy 83.369549 -255.177918)
			(xy 83.339984 -255.217262) (xy 83.304491 -255.251354) (xy 83.263988 -255.27931) (xy 83.219526 -255.300408)
			(xy 83.172255 -255.3141) (xy 83.1234 -255.320032) (xy 83.074225 -255.318051) (xy 83.026006 -255.308207)
			(xy 82.97999 -255.290755) (xy 82.937369 -255.266148) (xy 82.899248 -255.235023) (xy 82.866613 -255.198186)
			(xy 82.84031 -255.15659) (xy 82.821019 -255.111314) (xy 82.809242 -255.06353) (xy 82.805282 -255.014476)
			(xy 82.486754 -255.014476) (xy 82.486242 -255.039922) (xy 82.478078 -255.090156) (xy 82.461962 -255.13843)
			(xy 82.438311 -255.183493) (xy 82.407738 -255.224179) (xy 82.371034 -255.259434) (xy 82.32915 -255.288344)
			(xy 82.283171 -255.310161) (xy 82.234287 -255.324321) (xy 82.183766 -255.330455) (xy 82.132914 -255.328406)
			(xy 82.08305 -255.318226) (xy 82.035464 -255.300179) (xy 81.99139 -255.274733) (xy 81.951968 -255.242546)
			(xy 81.91822 -255.204452) (xy 81.891019 -255.161438) (xy 81.871071 -255.114618) (xy 81.858892 -255.065204)
			(xy 81.854797 -255.014476) (xy 81.5467 -255.014476) (xy 81.546188 -255.039922) (xy 81.538024 -255.090156)
			(xy 81.521908 -255.13843) (xy 81.498257 -255.183493) (xy 81.467684 -255.224179) (xy 81.43098 -255.259434)
			(xy 81.389096 -255.288344) (xy 81.343117 -255.310161) (xy 81.294233 -255.324321) (xy 81.243712 -255.330455)
			(xy 81.19286 -255.328406) (xy 81.142996 -255.318226) (xy 81.09541 -255.300179) (xy 81.051336 -255.274733)
			(xy 81.011914 -255.242546) (xy 80.978166 -255.204452) (xy 80.950965 -255.161438) (xy 80.931017 -255.114618)
			(xy 80.918838 -255.065204) (xy 80.914743 -255.014476) (xy 80.596486 -255.014476) (xy 80.595991 -255.039083)
			(xy 80.588096 -255.08766) (xy 80.572512 -255.134341) (xy 80.549641 -255.177918) (xy 80.520076 -255.217262)
			(xy 80.484583 -255.251354) (xy 80.44408 -255.27931) (xy 80.399618 -255.300408) (xy 80.352347 -255.3141)
			(xy 80.303492 -255.320032) (xy 80.254317 -255.318051) (xy 80.206098 -255.308207) (xy 80.160082 -255.290755)
			(xy 80.117461 -255.266148) (xy 80.07934 -255.235023) (xy 80.046705 -255.198186) (xy 80.020402 -255.15659)
			(xy 80.001111 -255.111314) (xy 79.989334 -255.06353) (xy 79.985374 -255.014476) (xy 78.716378 -255.014476)
			(xy 78.715883 -255.039083) (xy 78.707988 -255.08766) (xy 78.692404 -255.134341) (xy 78.669533 -255.177918)
			(xy 78.639968 -255.217262) (xy 78.604475 -255.251354) (xy 78.563972 -255.27931) (xy 78.51951 -255.300408)
			(xy 78.472239 -255.3141) (xy 78.423384 -255.320032) (xy 78.374209 -255.318051) (xy 78.32599 -255.308207)
			(xy 78.279974 -255.290755) (xy 78.237353 -255.266148) (xy 78.199232 -255.235023) (xy 78.166597 -255.198186)
			(xy 78.140294 -255.15659) (xy 78.121003 -255.111314) (xy 78.109226 -255.06353) (xy 78.105266 -255.014476)
			(xy 73.375774 -255.014476) (xy 73.375774 -256.09042) (xy 76.507098 -256.09042) (xy 76.511058 -256.041366)
			(xy 76.522835 -255.993582) (xy 76.542126 -255.948306) (xy 76.568429 -255.90671) (xy 76.601064 -255.869873)
			(xy 76.639185 -255.838748) (xy 76.681806 -255.814141) (xy 76.727822 -255.796689) (xy 76.776041 -255.786845)
			(xy 76.825216 -255.784864) (xy 76.874071 -255.790796) (xy 76.921342 -255.804488) (xy 76.963477 -255.824482)
			(xy 79.51522 -255.824482) (xy 79.51918 -255.775428) (xy 79.530957 -255.727644) (xy 79.550248 -255.682368)
			(xy 79.576551 -255.640772) (xy 79.609186 -255.603935) (xy 79.647307 -255.57281) (xy 79.689928 -255.548203)
			(xy 79.735944 -255.530751) (xy 79.784163 -255.520907) (xy 79.833338 -255.518926) (xy 79.882193 -255.524858)
			(xy 79.929464 -255.53855) (xy 79.973926 -255.559648) (xy 80.014429 -255.587604) (xy 80.049922 -255.621696)
			(xy 80.079487 -255.66104) (xy 80.102358 -255.704617) (xy 80.117942 -255.751298) (xy 80.125837 -255.799875)
			(xy 80.126332 -255.824482) (xy 80.444843 -255.824482) (xy 80.448938 -255.773754) (xy 80.461117 -255.72434)
			(xy 80.481065 -255.67752) (xy 80.508266 -255.634506) (xy 80.542014 -255.596412) (xy 80.581436 -255.564225)
			(xy 80.62551 -255.538779) (xy 80.673096 -255.520732) (xy 80.72296 -255.510552) (xy 80.773812 -255.508503)
			(xy 80.824333 -255.514637) (xy 80.873217 -255.528797) (xy 80.919196 -255.550614) (xy 80.96108 -255.579524)
			(xy 80.997784 -255.614779) (xy 81.028357 -255.655465) (xy 81.052008 -255.700528) (xy 81.068124 -255.748802)
			(xy 81.076288 -255.799036) (xy 81.0768 -255.824482) (xy 81.395328 -255.824482) (xy 81.399288 -255.775428)
			(xy 81.411065 -255.727644) (xy 81.430356 -255.682368) (xy 81.456659 -255.640772) (xy 81.489294 -255.603935)
			(xy 81.527415 -255.57281) (xy 81.570036 -255.548203) (xy 81.616052 -255.530751) (xy 81.664271 -255.520907)
			(xy 81.713446 -255.518926) (xy 81.762301 -255.524858) (xy 81.809572 -255.53855) (xy 81.854034 -255.559648)
			(xy 81.894537 -255.587604) (xy 81.93003 -255.621696) (xy 81.959595 -255.66104) (xy 81.982466 -255.704617)
			(xy 81.99805 -255.751298) (xy 82.005945 -255.799875) (xy 82.00644 -255.824482) (xy 82.324697 -255.824482)
			(xy 82.328792 -255.773754) (xy 82.340971 -255.72434) (xy 82.360919 -255.67752) (xy 82.38812 -255.634506)
			(xy 82.421868 -255.596412) (xy 82.46129 -255.564225) (xy 82.505364 -255.538779) (xy 82.55295 -255.520732)
			(xy 82.602814 -255.510552) (xy 82.653666 -255.508503) (xy 82.704187 -255.514637) (xy 82.753071 -255.528797)
			(xy 82.79905 -255.550614) (xy 82.840934 -255.579524) (xy 82.877638 -255.614779) (xy 82.908211 -255.655465)
			(xy 82.931862 -255.700528) (xy 82.947978 -255.748802) (xy 82.956142 -255.799036) (xy 82.956654 -255.824482)
			(xy 83.275182 -255.824482) (xy 83.279142 -255.775428) (xy 83.290919 -255.727644) (xy 83.31021 -255.682368)
			(xy 83.336513 -255.640772) (xy 83.369148 -255.603935) (xy 83.407269 -255.57281) (xy 83.44989 -255.548203)
			(xy 83.495906 -255.530751) (xy 83.544125 -255.520907) (xy 83.5933 -255.518926) (xy 83.642155 -255.524858)
			(xy 83.689426 -255.53855) (xy 83.733888 -255.559648) (xy 83.774391 -255.587604) (xy 83.809884 -255.621696)
			(xy 83.839449 -255.66104) (xy 83.86232 -255.704617) (xy 83.877904 -255.751298) (xy 83.885799 -255.799875)
			(xy 83.886294 -255.824482) (xy 84.204805 -255.824482) (xy 84.2089 -255.773754) (xy 84.221079 -255.72434)
			(xy 84.241027 -255.67752) (xy 84.268228 -255.634506) (xy 84.301976 -255.596412) (xy 84.341398 -255.564225)
			(xy 84.385472 -255.538779) (xy 84.433058 -255.520732) (xy 84.482922 -255.510552) (xy 84.533774 -255.508503)
			(xy 84.584295 -255.514637) (xy 84.633179 -255.528797) (xy 84.679158 -255.550614) (xy 84.721042 -255.579524)
			(xy 84.757746 -255.614779) (xy 84.788319 -255.655465) (xy 84.81197 -255.700528) (xy 84.828086 -255.748802)
			(xy 84.83625 -255.799036) (xy 84.836762 -255.824482) (xy 85.144859 -255.824482) (xy 85.148954 -255.773754)
			(xy 85.161133 -255.72434) (xy 85.181081 -255.67752) (xy 85.208282 -255.634506) (xy 85.24203 -255.596412)
			(xy 85.281452 -255.564225) (xy 85.325526 -255.538779) (xy 85.373112 -255.520732) (xy 85.422976 -255.510552)
			(xy 85.473828 -255.508503) (xy 85.524349 -255.514637) (xy 85.573233 -255.528797) (xy 85.619212 -255.550614)
			(xy 85.661096 -255.579524) (xy 85.6978 -255.614779) (xy 85.728373 -255.655465) (xy 85.752024 -255.700528)
			(xy 85.76814 -255.748802) (xy 85.776304 -255.799036) (xy 85.776816 -255.824482) (xy 86.095344 -255.824482)
			(xy 86.099304 -255.775428) (xy 86.111081 -255.727644) (xy 86.130372 -255.682368) (xy 86.156675 -255.640772)
			(xy 86.18931 -255.603935) (xy 86.227431 -255.57281) (xy 86.270052 -255.548203) (xy 86.316068 -255.530751)
			(xy 86.364287 -255.520907) (xy 86.413462 -255.518926) (xy 86.462317 -255.524858) (xy 86.509588 -255.53855)
			(xy 86.55405 -255.559648) (xy 86.594553 -255.587604) (xy 86.630046 -255.621696) (xy 86.659611 -255.66104)
			(xy 86.682482 -255.704617) (xy 86.698066 -255.751298) (xy 86.705961 -255.799875) (xy 86.706456 -255.824482)
			(xy 87.024713 -255.824482) (xy 87.028808 -255.773754) (xy 87.040987 -255.72434) (xy 87.060935 -255.67752)
			(xy 87.088136 -255.634506) (xy 87.121884 -255.596412) (xy 87.161306 -255.564225) (xy 87.20538 -255.538779)
			(xy 87.252966 -255.520732) (xy 87.30283 -255.510552) (xy 87.353682 -255.508503) (xy 87.404203 -255.514637)
			(xy 87.453087 -255.528797) (xy 87.499066 -255.550614) (xy 87.54095 -255.579524) (xy 87.577654 -255.614779)
			(xy 87.608227 -255.655465) (xy 87.631878 -255.700528) (xy 87.647994 -255.748802) (xy 87.656158 -255.799036)
			(xy 87.65667 -255.824482) (xy 87.975198 -255.824482) (xy 87.979158 -255.775428) (xy 87.990935 -255.727644)
			(xy 88.010226 -255.682368) (xy 88.036529 -255.640772) (xy 88.069164 -255.603935) (xy 88.107285 -255.57281)
			(xy 88.149906 -255.548203) (xy 88.195922 -255.530751) (xy 88.244141 -255.520907) (xy 88.293316 -255.518926)
			(xy 88.342171 -255.524858) (xy 88.389442 -255.53855) (xy 88.433904 -255.559648) (xy 88.474407 -255.587604)
			(xy 88.5099 -255.621696) (xy 88.539465 -255.66104) (xy 88.562336 -255.704617) (xy 88.57792 -255.751298)
			(xy 88.585815 -255.799875) (xy 88.58631 -255.824482) (xy 88.904821 -255.824482) (xy 88.908916 -255.773754)
			(xy 88.921095 -255.72434) (xy 88.941043 -255.67752) (xy 88.968244 -255.634506) (xy 89.001992 -255.596412)
			(xy 89.041414 -255.564225) (xy 89.085488 -255.538779) (xy 89.133074 -255.520732) (xy 89.182938 -255.510552)
			(xy 89.23379 -255.508503) (xy 89.284311 -255.514637) (xy 89.333195 -255.528797) (xy 89.379174 -255.550614)
			(xy 89.421058 -255.579524) (xy 89.457762 -255.614779) (xy 89.488335 -255.655465) (xy 89.511986 -255.700528)
			(xy 89.528102 -255.748802) (xy 89.536266 -255.799036) (xy 89.536778 -255.824482) (xy 89.855306 -255.824482)
			(xy 89.859266 -255.775428) (xy 89.871043 -255.727644) (xy 89.890334 -255.682368) (xy 89.916637 -255.640772)
			(xy 89.949272 -255.603935) (xy 89.987393 -255.57281) (xy 90.030014 -255.548203) (xy 90.07603 -255.530751)
			(xy 90.124249 -255.520907) (xy 90.173424 -255.518926) (xy 90.222279 -255.524858) (xy 90.26955 -255.53855)
			(xy 90.314012 -255.559648) (xy 90.354515 -255.587604) (xy 90.390008 -255.621696) (xy 90.419573 -255.66104)
			(xy 90.442444 -255.704617) (xy 90.458028 -255.751298) (xy 90.465923 -255.799875) (xy 90.466418 -255.824482)
			(xy 90.784675 -255.824482) (xy 90.78877 -255.773754) (xy 90.800949 -255.72434) (xy 90.820897 -255.67752)
			(xy 90.848098 -255.634506) (xy 90.881846 -255.596412) (xy 90.921268 -255.564225) (xy 90.965342 -255.538779)
			(xy 91.012928 -255.520732) (xy 91.062792 -255.510552) (xy 91.113644 -255.508503) (xy 91.164165 -255.514637)
			(xy 91.213049 -255.528797) (xy 91.259028 -255.550614) (xy 91.300912 -255.579524) (xy 91.337616 -255.614779)
			(xy 91.368189 -255.655465) (xy 91.39184 -255.700528) (xy 91.407956 -255.748802) (xy 91.41612 -255.799036)
			(xy 91.416632 -255.824482) (xy 91.724729 -255.824482) (xy 91.728824 -255.773754) (xy 91.741003 -255.72434)
			(xy 91.760951 -255.67752) (xy 91.788152 -255.634506) (xy 91.8219 -255.596412) (xy 91.861322 -255.564225)
			(xy 91.905396 -255.538779) (xy 91.952982 -255.520732) (xy 92.002846 -255.510552) (xy 92.053698 -255.508503)
			(xy 92.104219 -255.514637) (xy 92.153103 -255.528797) (xy 92.199082 -255.550614) (xy 92.240966 -255.579524)
			(xy 92.27767 -255.614779) (xy 92.308243 -255.655465) (xy 92.331894 -255.700528) (xy 92.34801 -255.748802)
			(xy 92.356174 -255.799036) (xy 92.356686 -255.824482) (xy 92.675214 -255.824482) (xy 92.679174 -255.775428)
			(xy 92.690951 -255.727644) (xy 92.710242 -255.682368) (xy 92.736545 -255.640772) (xy 92.76918 -255.603935)
			(xy 92.807301 -255.57281) (xy 92.849922 -255.548203) (xy 92.895938 -255.530751) (xy 92.944157 -255.520907)
			(xy 92.993332 -255.518926) (xy 93.042187 -255.524858) (xy 93.089458 -255.53855) (xy 93.13392 -255.559648)
			(xy 93.174423 -255.587604) (xy 93.209916 -255.621696) (xy 93.239481 -255.66104) (xy 93.262352 -255.704617)
			(xy 93.277936 -255.751298) (xy 93.285831 -255.799875) (xy 93.286326 -255.824482) (xy 93.604837 -255.824482)
			(xy 93.608932 -255.773754) (xy 93.621111 -255.72434) (xy 93.641059 -255.67752) (xy 93.66826 -255.634506)
			(xy 93.702008 -255.596412) (xy 93.74143 -255.564225) (xy 93.785504 -255.538779) (xy 93.83309 -255.520732)
			(xy 93.882954 -255.510552) (xy 93.933806 -255.508503) (xy 93.984327 -255.514637) (xy 94.033211 -255.528797)
			(xy 94.07919 -255.550614) (xy 94.121074 -255.579524) (xy 94.157778 -255.614779) (xy 94.188351 -255.655465)
			(xy 94.212002 -255.700528) (xy 94.228118 -255.748802) (xy 94.236282 -255.799036) (xy 94.236794 -255.824482)
			(xy 94.555322 -255.824482) (xy 94.559282 -255.775428) (xy 94.571059 -255.727644) (xy 94.59035 -255.682368)
			(xy 94.616653 -255.640772) (xy 94.649288 -255.603935) (xy 94.687409 -255.57281) (xy 94.73003 -255.548203)
			(xy 94.776046 -255.530751) (xy 94.824265 -255.520907) (xy 94.87344 -255.518926) (xy 94.922295 -255.524858)
			(xy 94.969566 -255.53855) (xy 95.014028 -255.559648) (xy 95.054531 -255.587604) (xy 95.090024 -255.621696)
			(xy 95.119589 -255.66104) (xy 95.14246 -255.704617) (xy 95.158044 -255.751298) (xy 95.165939 -255.799875)
			(xy 95.166434 -255.824482) (xy 95.484691 -255.824482) (xy 95.488786 -255.773754) (xy 95.500965 -255.72434)
			(xy 95.520913 -255.67752) (xy 95.548114 -255.634506) (xy 95.581862 -255.596412) (xy 95.621284 -255.564225)
			(xy 95.665358 -255.538779) (xy 95.712944 -255.520732) (xy 95.762808 -255.510552) (xy 95.81366 -255.508503)
			(xy 95.864181 -255.514637) (xy 95.913065 -255.528797) (xy 95.959044 -255.550614) (xy 96.000928 -255.579524)
			(xy 96.037632 -255.614779) (xy 96.068205 -255.655465) (xy 96.091856 -255.700528) (xy 96.107972 -255.748802)
			(xy 96.116136 -255.799036) (xy 96.116648 -255.824482) (xy 96.435176 -255.824482) (xy 96.439136 -255.775428)
			(xy 96.450913 -255.727644) (xy 96.470204 -255.682368) (xy 96.496507 -255.640772) (xy 96.529142 -255.603935)
			(xy 96.567263 -255.57281) (xy 96.609884 -255.548203) (xy 96.6559 -255.530751) (xy 96.704119 -255.520907)
			(xy 96.753294 -255.518926) (xy 96.802149 -255.524858) (xy 96.84942 -255.53855) (xy 96.893882 -255.559648)
			(xy 96.934385 -255.587604) (xy 96.969878 -255.621696) (xy 96.999443 -255.66104) (xy 97.022314 -255.704617)
			(xy 97.037898 -255.751298) (xy 97.045793 -255.799875) (xy 97.046288 -255.824482) (xy 97.37523 -255.824482)
			(xy 97.37919 -255.775428) (xy 97.390967 -255.727644) (xy 97.410258 -255.682368) (xy 97.436561 -255.640772)
			(xy 97.469196 -255.603935) (xy 97.507317 -255.57281) (xy 97.549938 -255.548203) (xy 97.595954 -255.530751)
			(xy 97.644173 -255.520907) (xy 97.693348 -255.518926) (xy 97.742203 -255.524858) (xy 97.789474 -255.53855)
			(xy 97.833936 -255.559648) (xy 97.874439 -255.587604) (xy 97.909932 -255.621696) (xy 97.939497 -255.66104)
			(xy 97.962368 -255.704617) (xy 97.977952 -255.751298) (xy 97.985847 -255.799875) (xy 97.986342 -255.824482)
			(xy 98.315284 -255.824482) (xy 98.319244 -255.775428) (xy 98.331021 -255.727644) (xy 98.350312 -255.682368)
			(xy 98.376615 -255.640772) (xy 98.40925 -255.603935) (xy 98.447371 -255.57281) (xy 98.489992 -255.548203)
			(xy 98.536008 -255.530751) (xy 98.584227 -255.520907) (xy 98.633402 -255.518926) (xy 98.682257 -255.524858)
			(xy 98.729528 -255.53855) (xy 98.77399 -255.559648) (xy 98.814493 -255.587604) (xy 98.849986 -255.621696)
			(xy 98.879551 -255.66104) (xy 98.902422 -255.704617) (xy 98.918006 -255.751298) (xy 98.925901 -255.799875)
			(xy 98.926396 -255.824482) (xy 99.255338 -255.824482) (xy 99.259298 -255.775428) (xy 99.271075 -255.727644)
			(xy 99.290366 -255.682368) (xy 99.316669 -255.640772) (xy 99.349304 -255.603935) (xy 99.387425 -255.57281)
			(xy 99.430046 -255.548203) (xy 99.476062 -255.530751) (xy 99.524281 -255.520907) (xy 99.573456 -255.518926)
			(xy 99.622311 -255.524858) (xy 99.669582 -255.53855) (xy 99.714044 -255.559648) (xy 99.754547 -255.587604)
			(xy 99.79004 -255.621696) (xy 99.819605 -255.66104) (xy 99.842476 -255.704617) (xy 99.85806 -255.751298)
			(xy 99.865955 -255.799875) (xy 99.86645 -255.824482) (xy 99.865955 -255.849089) (xy 99.85806 -255.897666)
			(xy 99.842476 -255.944347) (xy 99.819605 -255.987924) (xy 99.79004 -256.027268) (xy 99.754547 -256.06136)
			(xy 99.714044 -256.089316) (xy 99.669582 -256.110414) (xy 99.622311 -256.124106) (xy 99.573456 -256.130038)
			(xy 99.524281 -256.128057) (xy 99.476062 -256.118213) (xy 99.430046 -256.100761) (xy 99.387425 -256.076154)
			(xy 99.349304 -256.045029) (xy 99.316669 -256.008192) (xy 99.290366 -255.966596) (xy 99.271075 -255.92132)
			(xy 99.259298 -255.873536) (xy 99.255338 -255.824482) (xy 98.926396 -255.824482) (xy 98.925901 -255.849089)
			(xy 98.918006 -255.897666) (xy 98.902422 -255.944347) (xy 98.879551 -255.987924) (xy 98.849986 -256.027268)
			(xy 98.814493 -256.06136) (xy 98.77399 -256.089316) (xy 98.729528 -256.110414) (xy 98.682257 -256.124106)
			(xy 98.633402 -256.130038) (xy 98.584227 -256.128057) (xy 98.536008 -256.118213) (xy 98.489992 -256.100761)
			(xy 98.447371 -256.076154) (xy 98.40925 -256.045029) (xy 98.376615 -256.008192) (xy 98.350312 -255.966596)
			(xy 98.331021 -255.92132) (xy 98.319244 -255.873536) (xy 98.315284 -255.824482) (xy 97.986342 -255.824482)
			(xy 97.985847 -255.849089) (xy 97.977952 -255.897666) (xy 97.962368 -255.944347) (xy 97.939497 -255.987924)
			(xy 97.909932 -256.027268) (xy 97.874439 -256.06136) (xy 97.833936 -256.089316) (xy 97.789474 -256.110414)
			(xy 97.742203 -256.124106) (xy 97.693348 -256.130038) (xy 97.644173 -256.128057) (xy 97.595954 -256.118213)
			(xy 97.549938 -256.100761) (xy 97.507317 -256.076154) (xy 97.469196 -256.045029) (xy 97.436561 -256.008192)
			(xy 97.410258 -255.966596) (xy 97.390967 -255.92132) (xy 97.37919 -255.873536) (xy 97.37523 -255.824482)
			(xy 97.046288 -255.824482) (xy 97.045793 -255.849089) (xy 97.037898 -255.897666) (xy 97.022314 -255.944347)
			(xy 96.999443 -255.987924) (xy 96.969878 -256.027268) (xy 96.934385 -256.06136) (xy 96.893882 -256.089316)
			(xy 96.84942 -256.110414) (xy 96.802149 -256.124106) (xy 96.753294 -256.130038) (xy 96.704119 -256.128057)
			(xy 96.6559 -256.118213) (xy 96.609884 -256.100761) (xy 96.567263 -256.076154) (xy 96.529142 -256.045029)
			(xy 96.496507 -256.008192) (xy 96.470204 -255.966596) (xy 96.450913 -255.92132) (xy 96.439136 -255.873536)
			(xy 96.435176 -255.824482) (xy 96.116648 -255.824482) (xy 96.116136 -255.849928) (xy 96.107972 -255.900162)
			(xy 96.091856 -255.948436) (xy 96.068205 -255.993499) (xy 96.037632 -256.034185) (xy 96.000928 -256.06944)
			(xy 95.959044 -256.09835) (xy 95.913065 -256.120167) (xy 95.864181 -256.134327) (xy 95.81366 -256.140461)
			(xy 95.762808 -256.138412) (xy 95.712944 -256.128232) (xy 95.665358 -256.110185) (xy 95.621284 -256.084739)
			(xy 95.581862 -256.052552) (xy 95.548114 -256.014458) (xy 95.520913 -255.971444) (xy 95.500965 -255.924624)
			(xy 95.488786 -255.87521) (xy 95.484691 -255.824482) (xy 95.166434 -255.824482) (xy 95.165939 -255.849089)
			(xy 95.158044 -255.897666) (xy 95.14246 -255.944347) (xy 95.119589 -255.987924) (xy 95.090024 -256.027268)
			(xy 95.054531 -256.06136) (xy 95.014028 -256.089316) (xy 94.969566 -256.110414) (xy 94.922295 -256.124106)
			(xy 94.87344 -256.130038) (xy 94.824265 -256.128057) (xy 94.776046 -256.118213) (xy 94.73003 -256.100761)
			(xy 94.687409 -256.076154) (xy 94.649288 -256.045029) (xy 94.616653 -256.008192) (xy 94.59035 -255.966596)
			(xy 94.571059 -255.92132) (xy 94.559282 -255.873536) (xy 94.555322 -255.824482) (xy 94.236794 -255.824482)
			(xy 94.236282 -255.849928) (xy 94.228118 -255.900162) (xy 94.212002 -255.948436) (xy 94.188351 -255.993499)
			(xy 94.157778 -256.034185) (xy 94.121074 -256.06944) (xy 94.07919 -256.09835) (xy 94.033211 -256.120167)
			(xy 93.984327 -256.134327) (xy 93.933806 -256.140461) (xy 93.882954 -256.138412) (xy 93.83309 -256.128232)
			(xy 93.785504 -256.110185) (xy 93.74143 -256.084739) (xy 93.702008 -256.052552) (xy 93.66826 -256.014458)
			(xy 93.641059 -255.971444) (xy 93.621111 -255.924624) (xy 93.608932 -255.87521) (xy 93.604837 -255.824482)
			(xy 93.286326 -255.824482) (xy 93.285831 -255.849089) (xy 93.277936 -255.897666) (xy 93.262352 -255.944347)
			(xy 93.239481 -255.987924) (xy 93.209916 -256.027268) (xy 93.174423 -256.06136) (xy 93.13392 -256.089316)
			(xy 93.089458 -256.110414) (xy 93.042187 -256.124106) (xy 92.993332 -256.130038) (xy 92.944157 -256.128057)
			(xy 92.895938 -256.118213) (xy 92.849922 -256.100761) (xy 92.807301 -256.076154) (xy 92.76918 -256.045029)
			(xy 92.736545 -256.008192) (xy 92.710242 -255.966596) (xy 92.690951 -255.92132) (xy 92.679174 -255.873536)
			(xy 92.675214 -255.824482) (xy 92.356686 -255.824482) (xy 92.356174 -255.849928) (xy 92.34801 -255.900162)
			(xy 92.331894 -255.948436) (xy 92.308243 -255.993499) (xy 92.27767 -256.034185) (xy 92.240966 -256.06944)
			(xy 92.199082 -256.09835) (xy 92.153103 -256.120167) (xy 92.104219 -256.134327) (xy 92.053698 -256.140461)
			(xy 92.002846 -256.138412) (xy 91.952982 -256.128232) (xy 91.905396 -256.110185) (xy 91.861322 -256.084739)
			(xy 91.8219 -256.052552) (xy 91.788152 -256.014458) (xy 91.760951 -255.971444) (xy 91.741003 -255.924624)
			(xy 91.728824 -255.87521) (xy 91.724729 -255.824482) (xy 91.416632 -255.824482) (xy 91.41612 -255.849928)
			(xy 91.407956 -255.900162) (xy 91.39184 -255.948436) (xy 91.368189 -255.993499) (xy 91.337616 -256.034185)
			(xy 91.300912 -256.06944) (xy 91.259028 -256.09835) (xy 91.213049 -256.120167) (xy 91.164165 -256.134327)
			(xy 91.113644 -256.140461) (xy 91.062792 -256.138412) (xy 91.012928 -256.128232) (xy 90.965342 -256.110185)
			(xy 90.921268 -256.084739) (xy 90.881846 -256.052552) (xy 90.848098 -256.014458) (xy 90.820897 -255.971444)
			(xy 90.800949 -255.924624) (xy 90.78877 -255.87521) (xy 90.784675 -255.824482) (xy 90.466418 -255.824482)
			(xy 90.465923 -255.849089) (xy 90.458028 -255.897666) (xy 90.442444 -255.944347) (xy 90.419573 -255.987924)
			(xy 90.390008 -256.027268) (xy 90.354515 -256.06136) (xy 90.314012 -256.089316) (xy 90.26955 -256.110414)
			(xy 90.222279 -256.124106) (xy 90.173424 -256.130038) (xy 90.124249 -256.128057) (xy 90.07603 -256.118213)
			(xy 90.030014 -256.100761) (xy 89.987393 -256.076154) (xy 89.949272 -256.045029) (xy 89.916637 -256.008192)
			(xy 89.890334 -255.966596) (xy 89.871043 -255.92132) (xy 89.859266 -255.873536) (xy 89.855306 -255.824482)
			(xy 89.536778 -255.824482) (xy 89.536266 -255.849928) (xy 89.528102 -255.900162) (xy 89.511986 -255.948436)
			(xy 89.488335 -255.993499) (xy 89.457762 -256.034185) (xy 89.421058 -256.06944) (xy 89.379174 -256.09835)
			(xy 89.333195 -256.120167) (xy 89.284311 -256.134327) (xy 89.23379 -256.140461) (xy 89.182938 -256.138412)
			(xy 89.133074 -256.128232) (xy 89.085488 -256.110185) (xy 89.041414 -256.084739) (xy 89.001992 -256.052552)
			(xy 88.968244 -256.014458) (xy 88.941043 -255.971444) (xy 88.921095 -255.924624) (xy 88.908916 -255.87521)
			(xy 88.904821 -255.824482) (xy 88.58631 -255.824482) (xy 88.585815 -255.849089) (xy 88.57792 -255.897666)
			(xy 88.562336 -255.944347) (xy 88.539465 -255.987924) (xy 88.5099 -256.027268) (xy 88.474407 -256.06136)
			(xy 88.433904 -256.089316) (xy 88.389442 -256.110414) (xy 88.342171 -256.124106) (xy 88.293316 -256.130038)
			(xy 88.244141 -256.128057) (xy 88.195922 -256.118213) (xy 88.149906 -256.100761) (xy 88.107285 -256.076154)
			(xy 88.069164 -256.045029) (xy 88.036529 -256.008192) (xy 88.010226 -255.966596) (xy 87.990935 -255.92132)
			(xy 87.979158 -255.873536) (xy 87.975198 -255.824482) (xy 87.65667 -255.824482) (xy 87.656158 -255.849928)
			(xy 87.647994 -255.900162) (xy 87.631878 -255.948436) (xy 87.608227 -255.993499) (xy 87.577654 -256.034185)
			(xy 87.54095 -256.06944) (xy 87.499066 -256.09835) (xy 87.453087 -256.120167) (xy 87.404203 -256.134327)
			(xy 87.353682 -256.140461) (xy 87.30283 -256.138412) (xy 87.252966 -256.128232) (xy 87.20538 -256.110185)
			(xy 87.161306 -256.084739) (xy 87.121884 -256.052552) (xy 87.088136 -256.014458) (xy 87.060935 -255.971444)
			(xy 87.040987 -255.924624) (xy 87.028808 -255.87521) (xy 87.024713 -255.824482) (xy 86.706456 -255.824482)
			(xy 86.705961 -255.849089) (xy 86.698066 -255.897666) (xy 86.682482 -255.944347) (xy 86.659611 -255.987924)
			(xy 86.630046 -256.027268) (xy 86.594553 -256.06136) (xy 86.55405 -256.089316) (xy 86.509588 -256.110414)
			(xy 86.462317 -256.124106) (xy 86.413462 -256.130038) (xy 86.364287 -256.128057) (xy 86.316068 -256.118213)
			(xy 86.270052 -256.100761) (xy 86.227431 -256.076154) (xy 86.18931 -256.045029) (xy 86.156675 -256.008192)
			(xy 86.130372 -255.966596) (xy 86.111081 -255.92132) (xy 86.099304 -255.873536) (xy 86.095344 -255.824482)
			(xy 85.776816 -255.824482) (xy 85.776304 -255.849928) (xy 85.76814 -255.900162) (xy 85.752024 -255.948436)
			(xy 85.728373 -255.993499) (xy 85.6978 -256.034185) (xy 85.661096 -256.06944) (xy 85.619212 -256.09835)
			(xy 85.573233 -256.120167) (xy 85.524349 -256.134327) (xy 85.473828 -256.140461) (xy 85.422976 -256.138412)
			(xy 85.373112 -256.128232) (xy 85.325526 -256.110185) (xy 85.281452 -256.084739) (xy 85.24203 -256.052552)
			(xy 85.208282 -256.014458) (xy 85.181081 -255.971444) (xy 85.161133 -255.924624) (xy 85.148954 -255.87521)
			(xy 85.144859 -255.824482) (xy 84.836762 -255.824482) (xy 84.83625 -255.849928) (xy 84.828086 -255.900162)
			(xy 84.81197 -255.948436) (xy 84.788319 -255.993499) (xy 84.757746 -256.034185) (xy 84.721042 -256.06944)
			(xy 84.679158 -256.09835) (xy 84.633179 -256.120167) (xy 84.584295 -256.134327) (xy 84.533774 -256.140461)
			(xy 84.482922 -256.138412) (xy 84.433058 -256.128232) (xy 84.385472 -256.110185) (xy 84.341398 -256.084739)
			(xy 84.301976 -256.052552) (xy 84.268228 -256.014458) (xy 84.241027 -255.971444) (xy 84.221079 -255.924624)
			(xy 84.2089 -255.87521) (xy 84.204805 -255.824482) (xy 83.886294 -255.824482) (xy 83.885799 -255.849089)
			(xy 83.877904 -255.897666) (xy 83.86232 -255.944347) (xy 83.839449 -255.987924) (xy 83.809884 -256.027268)
			(xy 83.774391 -256.06136) (xy 83.733888 -256.089316) (xy 83.689426 -256.110414) (xy 83.642155 -256.124106)
			(xy 83.5933 -256.130038) (xy 83.544125 -256.128057) (xy 83.495906 -256.118213) (xy 83.44989 -256.100761)
			(xy 83.407269 -256.076154) (xy 83.369148 -256.045029) (xy 83.336513 -256.008192) (xy 83.31021 -255.966596)
			(xy 83.290919 -255.92132) (xy 83.279142 -255.873536) (xy 83.275182 -255.824482) (xy 82.956654 -255.824482)
			(xy 82.956142 -255.849928) (xy 82.947978 -255.900162) (xy 82.931862 -255.948436) (xy 82.908211 -255.993499)
			(xy 82.877638 -256.034185) (xy 82.840934 -256.06944) (xy 82.79905 -256.09835) (xy 82.753071 -256.120167)
			(xy 82.704187 -256.134327) (xy 82.653666 -256.140461) (xy 82.602814 -256.138412) (xy 82.55295 -256.128232)
			(xy 82.505364 -256.110185) (xy 82.46129 -256.084739) (xy 82.421868 -256.052552) (xy 82.38812 -256.014458)
			(xy 82.360919 -255.971444) (xy 82.340971 -255.924624) (xy 82.328792 -255.87521) (xy 82.324697 -255.824482)
			(xy 82.00644 -255.824482) (xy 82.005945 -255.849089) (xy 81.99805 -255.897666) (xy 81.982466 -255.944347)
			(xy 81.959595 -255.987924) (xy 81.93003 -256.027268) (xy 81.894537 -256.06136) (xy 81.854034 -256.089316)
			(xy 81.809572 -256.110414) (xy 81.762301 -256.124106) (xy 81.713446 -256.130038) (xy 81.664271 -256.128057)
			(xy 81.616052 -256.118213) (xy 81.570036 -256.100761) (xy 81.527415 -256.076154) (xy 81.489294 -256.045029)
			(xy 81.456659 -256.008192) (xy 81.430356 -255.966596) (xy 81.411065 -255.92132) (xy 81.399288 -255.873536)
			(xy 81.395328 -255.824482) (xy 81.0768 -255.824482) (xy 81.076288 -255.849928) (xy 81.068124 -255.900162)
			(xy 81.052008 -255.948436) (xy 81.028357 -255.993499) (xy 80.997784 -256.034185) (xy 80.96108 -256.06944)
			(xy 80.919196 -256.09835) (xy 80.873217 -256.120167) (xy 80.824333 -256.134327) (xy 80.773812 -256.140461)
			(xy 80.72296 -256.138412) (xy 80.673096 -256.128232) (xy 80.62551 -256.110185) (xy 80.581436 -256.084739)
			(xy 80.542014 -256.052552) (xy 80.508266 -256.014458) (xy 80.481065 -255.971444) (xy 80.461117 -255.924624)
			(xy 80.448938 -255.87521) (xy 80.444843 -255.824482) (xy 80.126332 -255.824482) (xy 80.125837 -255.849089)
			(xy 80.117942 -255.897666) (xy 80.102358 -255.944347) (xy 80.079487 -255.987924) (xy 80.049922 -256.027268)
			(xy 80.014429 -256.06136) (xy 79.973926 -256.089316) (xy 79.929464 -256.110414) (xy 79.882193 -256.124106)
			(xy 79.833338 -256.130038) (xy 79.784163 -256.128057) (xy 79.735944 -256.118213) (xy 79.689928 -256.100761)
			(xy 79.647307 -256.076154) (xy 79.609186 -256.045029) (xy 79.576551 -256.008192) (xy 79.550248 -255.966596)
			(xy 79.530957 -255.92132) (xy 79.51918 -255.873536) (xy 79.51522 -255.824482) (xy 76.963477 -255.824482)
			(xy 76.965804 -255.825586) (xy 77.006307 -255.853542) (xy 77.0418 -255.887634) (xy 77.071365 -255.926978)
			(xy 77.094236 -255.970555) (xy 77.10982 -256.017236) (xy 77.117715 -256.065813) (xy 77.11821 -256.09042)
			(xy 77.117715 -256.115027) (xy 77.10982 -256.163604) (xy 77.094236 -256.210285) (xy 77.071365 -256.253862)
			(xy 77.0418 -256.293206) (xy 77.006307 -256.327298) (xy 76.965804 -256.355254) (xy 76.921342 -256.376352)
			(xy 76.874071 -256.390044) (xy 76.825216 -256.395976) (xy 76.776041 -256.393995) (xy 76.727822 -256.384151)
			(xy 76.681806 -256.366699) (xy 76.639185 -256.342092) (xy 76.601064 -256.310967) (xy 76.568429 -256.27413)
			(xy 76.542126 -256.232534) (xy 76.522835 -256.187258) (xy 76.511058 -256.139474) (xy 76.507098 -256.09042)
			(xy 73.375774 -256.09042) (xy 73.375774 -256.634488) (xy 78.105266 -256.634488) (xy 78.109226 -256.585434)
			(xy 78.121003 -256.53765) (xy 78.140294 -256.492374) (xy 78.166597 -256.450778) (xy 78.199232 -256.413941)
			(xy 78.237353 -256.382816) (xy 78.279974 -256.358209) (xy 78.32599 -256.340757) (xy 78.374209 -256.330913)
			(xy 78.423384 -256.328932) (xy 78.472239 -256.334864) (xy 78.51951 -256.348556) (xy 78.563972 -256.369654)
			(xy 78.604475 -256.39761) (xy 78.639968 -256.431702) (xy 78.669533 -256.471046) (xy 78.692404 -256.514623)
			(xy 78.707988 -256.561304) (xy 78.715883 -256.609881) (xy 78.716378 -256.634488) (xy 79.985374 -256.634488)
			(xy 79.989334 -256.585434) (xy 80.001111 -256.53765) (xy 80.020402 -256.492374) (xy 80.046705 -256.450778)
			(xy 80.07934 -256.413941) (xy 80.117461 -256.382816) (xy 80.160082 -256.358209) (xy 80.206098 -256.340757)
			(xy 80.254317 -256.330913) (xy 80.303492 -256.328932) (xy 80.352347 -256.334864) (xy 80.399618 -256.348556)
			(xy 80.44408 -256.369654) (xy 80.484583 -256.39761) (xy 80.520076 -256.431702) (xy 80.549641 -256.471046)
			(xy 80.572512 -256.514623) (xy 80.588096 -256.561304) (xy 80.595991 -256.609881) (xy 80.596486 -256.634488)
			(xy 80.914743 -256.634488) (xy 80.918838 -256.58376) (xy 80.931017 -256.534346) (xy 80.950965 -256.487526)
			(xy 80.978166 -256.444512) (xy 81.011914 -256.406418) (xy 81.051336 -256.374231) (xy 81.09541 -256.348785)
			(xy 81.142996 -256.330738) (xy 81.19286 -256.320558) (xy 81.243712 -256.318509) (xy 81.294233 -256.324643)
			(xy 81.343117 -256.338803) (xy 81.389096 -256.36062) (xy 81.43098 -256.38953) (xy 81.467684 -256.424785)
			(xy 81.498257 -256.465471) (xy 81.521908 -256.510534) (xy 81.538024 -256.558808) (xy 81.546188 -256.609042)
			(xy 81.5467 -256.634488) (xy 81.865228 -256.634488) (xy 81.869188 -256.585434) (xy 81.880965 -256.53765)
			(xy 81.900256 -256.492374) (xy 81.926559 -256.450778) (xy 81.959194 -256.413941) (xy 81.997315 -256.382816)
			(xy 82.039936 -256.358209) (xy 82.085952 -256.340757) (xy 82.134171 -256.330913) (xy 82.183346 -256.328932)
			(xy 82.232201 -256.334864) (xy 82.279472 -256.348556) (xy 82.323934 -256.369654) (xy 82.364437 -256.39761)
			(xy 82.39993 -256.431702) (xy 82.429495 -256.471046) (xy 82.452366 -256.514623) (xy 82.46795 -256.561304)
			(xy 82.475845 -256.609881) (xy 82.47634 -256.634488) (xy 82.805282 -256.634488) (xy 82.809242 -256.585434)
			(xy 82.821019 -256.53765) (xy 82.84031 -256.492374) (xy 82.866613 -256.450778) (xy 82.899248 -256.413941)
			(xy 82.937369 -256.382816) (xy 82.97999 -256.358209) (xy 83.026006 -256.340757) (xy 83.074225 -256.330913)
			(xy 83.1234 -256.328932) (xy 83.172255 -256.334864) (xy 83.219526 -256.348556) (xy 83.263988 -256.369654)
			(xy 83.304491 -256.39761) (xy 83.339984 -256.431702) (xy 83.369549 -256.471046) (xy 83.39242 -256.514623)
			(xy 83.408004 -256.561304) (xy 83.415899 -256.609881) (xy 83.416394 -256.634488) (xy 83.734905 -256.634488)
			(xy 83.739 -256.58376) (xy 83.751179 -256.534346) (xy 83.771127 -256.487526) (xy 83.798328 -256.444512)
			(xy 83.832076 -256.406418) (xy 83.871498 -256.374231) (xy 83.915572 -256.348785) (xy 83.963158 -256.330738)
			(xy 84.013022 -256.320558) (xy 84.063874 -256.318509) (xy 84.114395 -256.324643) (xy 84.163279 -256.338803)
			(xy 84.209258 -256.36062) (xy 84.251142 -256.38953) (xy 84.287846 -256.424785) (xy 84.318419 -256.465471)
			(xy 84.34207 -256.510534) (xy 84.358186 -256.558808) (xy 84.36635 -256.609042) (xy 84.366862 -256.634488)
			(xy 84.685136 -256.634488) (xy 84.689096 -256.585434) (xy 84.700873 -256.53765) (xy 84.720164 -256.492374)
			(xy 84.746467 -256.450778) (xy 84.779102 -256.413941) (xy 84.817223 -256.382816) (xy 84.859844 -256.358209)
			(xy 84.90586 -256.340757) (xy 84.954079 -256.330913) (xy 85.003254 -256.328932) (xy 85.052109 -256.334864)
			(xy 85.09938 -256.348556) (xy 85.143842 -256.369654) (xy 85.184345 -256.39761) (xy 85.219838 -256.431702)
			(xy 85.249403 -256.471046) (xy 85.272274 -256.514623) (xy 85.287858 -256.561304) (xy 85.295753 -256.609881)
			(xy 85.296248 -256.634488) (xy 85.62519 -256.634488) (xy 85.62915 -256.585434) (xy 85.640927 -256.53765)
			(xy 85.660218 -256.492374) (xy 85.686521 -256.450778) (xy 85.719156 -256.413941) (xy 85.757277 -256.382816)
			(xy 85.799898 -256.358209) (xy 85.845914 -256.340757) (xy 85.894133 -256.330913) (xy 85.943308 -256.328932)
			(xy 85.992163 -256.334864) (xy 86.039434 -256.348556) (xy 86.083896 -256.369654) (xy 86.124399 -256.39761)
			(xy 86.159892 -256.431702) (xy 86.189457 -256.471046) (xy 86.212328 -256.514623) (xy 86.227912 -256.561304)
			(xy 86.235807 -256.609881) (xy 86.236302 -256.634488) (xy 86.565244 -256.634488) (xy 86.569204 -256.585434)
			(xy 86.580981 -256.53765) (xy 86.600272 -256.492374) (xy 86.626575 -256.450778) (xy 86.65921 -256.413941)
			(xy 86.697331 -256.382816) (xy 86.739952 -256.358209) (xy 86.785968 -256.340757) (xy 86.834187 -256.330913)
			(xy 86.883362 -256.328932) (xy 86.932217 -256.334864) (xy 86.979488 -256.348556) (xy 87.02395 -256.369654)
			(xy 87.064453 -256.39761) (xy 87.099946 -256.431702) (xy 87.129511 -256.471046) (xy 87.152382 -256.514623)
			(xy 87.167966 -256.561304) (xy 87.175861 -256.609881) (xy 87.176356 -256.634488) (xy 87.494867 -256.634488)
			(xy 87.498962 -256.58376) (xy 87.511141 -256.534346) (xy 87.531089 -256.487526) (xy 87.55829 -256.444512)
			(xy 87.592038 -256.406418) (xy 87.63146 -256.374231) (xy 87.675534 -256.348785) (xy 87.72312 -256.330738)
			(xy 87.772984 -256.320558) (xy 87.823836 -256.318509) (xy 87.874357 -256.324643) (xy 87.923241 -256.338803)
			(xy 87.96922 -256.36062) (xy 88.011104 -256.38953) (xy 88.047808 -256.424785) (xy 88.078381 -256.465471)
			(xy 88.102032 -256.510534) (xy 88.118148 -256.558808) (xy 88.126312 -256.609042) (xy 88.126824 -256.634488)
			(xy 88.445352 -256.634488) (xy 88.449312 -256.585434) (xy 88.461089 -256.53765) (xy 88.48038 -256.492374)
			(xy 88.506683 -256.450778) (xy 88.539318 -256.413941) (xy 88.577439 -256.382816) (xy 88.62006 -256.358209)
			(xy 88.666076 -256.340757) (xy 88.714295 -256.330913) (xy 88.76347 -256.328932) (xy 88.812325 -256.334864)
			(xy 88.859596 -256.348556) (xy 88.904058 -256.369654) (xy 88.944561 -256.39761) (xy 88.980054 -256.431702)
			(xy 89.009619 -256.471046) (xy 89.03249 -256.514623) (xy 89.048074 -256.561304) (xy 89.055969 -256.609881)
			(xy 89.056464 -256.634488) (xy 89.385152 -256.634488) (xy 89.389112 -256.585434) (xy 89.400889 -256.53765)
			(xy 89.42018 -256.492374) (xy 89.446483 -256.450778) (xy 89.479118 -256.413941) (xy 89.517239 -256.382816)
			(xy 89.55986 -256.358209) (xy 89.605876 -256.340757) (xy 89.654095 -256.330913) (xy 89.70327 -256.328932)
			(xy 89.752125 -256.334864) (xy 89.799396 -256.348556) (xy 89.843858 -256.369654) (xy 89.884361 -256.39761)
			(xy 89.919854 -256.431702) (xy 89.949419 -256.471046) (xy 89.97229 -256.514623) (xy 89.987874 -256.561304)
			(xy 89.995769 -256.609881) (xy 89.996264 -256.634488) (xy 90.314775 -256.634488) (xy 90.31887 -256.58376)
			(xy 90.331049 -256.534346) (xy 90.350997 -256.487526) (xy 90.378198 -256.444512) (xy 90.411946 -256.406418)
			(xy 90.451368 -256.374231) (xy 90.495442 -256.348785) (xy 90.543028 -256.330738) (xy 90.592892 -256.320558)
			(xy 90.643744 -256.318509) (xy 90.694265 -256.324643) (xy 90.743149 -256.338803) (xy 90.789128 -256.36062)
			(xy 90.831012 -256.38953) (xy 90.867716 -256.424785) (xy 90.898289 -256.465471) (xy 90.92194 -256.510534)
			(xy 90.938056 -256.558808) (xy 90.94622 -256.609042) (xy 90.946732 -256.634488) (xy 91.26526 -256.634488)
			(xy 91.26922 -256.585434) (xy 91.280997 -256.53765) (xy 91.300288 -256.492374) (xy 91.326591 -256.450778)
			(xy 91.359226 -256.413941) (xy 91.397347 -256.382816) (xy 91.439968 -256.358209) (xy 91.485984 -256.340757)
			(xy 91.534203 -256.330913) (xy 91.583378 -256.328932) (xy 91.632233 -256.334864) (xy 91.679504 -256.348556)
			(xy 91.723966 -256.369654) (xy 91.764469 -256.39761) (xy 91.799962 -256.431702) (xy 91.829527 -256.471046)
			(xy 91.852398 -256.514623) (xy 91.867982 -256.561304) (xy 91.875877 -256.609881) (xy 91.876372 -256.634488)
			(xy 92.205314 -256.634488) (xy 92.209274 -256.585434) (xy 92.221051 -256.53765) (xy 92.240342 -256.492374)
			(xy 92.266645 -256.450778) (xy 92.29928 -256.413941) (xy 92.337401 -256.382816) (xy 92.380022 -256.358209)
			(xy 92.426038 -256.340757) (xy 92.474257 -256.330913) (xy 92.523432 -256.328932) (xy 92.572287 -256.334864)
			(xy 92.619558 -256.348556) (xy 92.66402 -256.369654) (xy 92.704523 -256.39761) (xy 92.740016 -256.431702)
			(xy 92.769581 -256.471046) (xy 92.792452 -256.514623) (xy 92.808036 -256.561304) (xy 92.815931 -256.609881)
			(xy 92.816426 -256.634488) (xy 93.145114 -256.634488) (xy 93.149074 -256.585434) (xy 93.160851 -256.53765)
			(xy 93.180142 -256.492374) (xy 93.206445 -256.450778) (xy 93.23908 -256.413941) (xy 93.277201 -256.382816)
			(xy 93.319822 -256.358209) (xy 93.365838 -256.340757) (xy 93.414057 -256.330913) (xy 93.463232 -256.328932)
			(xy 93.512087 -256.334864) (xy 93.559358 -256.348556) (xy 93.60382 -256.369654) (xy 93.644323 -256.39761)
			(xy 93.679816 -256.431702) (xy 93.709381 -256.471046) (xy 93.732252 -256.514623) (xy 93.747836 -256.561304)
			(xy 93.755731 -256.609881) (xy 93.756226 -256.634488) (xy 94.074737 -256.634488) (xy 94.078832 -256.58376)
			(xy 94.091011 -256.534346) (xy 94.110959 -256.487526) (xy 94.13816 -256.444512) (xy 94.171908 -256.406418)
			(xy 94.21133 -256.374231) (xy 94.255404 -256.348785) (xy 94.30299 -256.330738) (xy 94.352854 -256.320558)
			(xy 94.403706 -256.318509) (xy 94.454227 -256.324643) (xy 94.503111 -256.338803) (xy 94.54909 -256.36062)
			(xy 94.590974 -256.38953) (xy 94.627678 -256.424785) (xy 94.658251 -256.465471) (xy 94.681902 -256.510534)
			(xy 94.698018 -256.558808) (xy 94.706182 -256.609042) (xy 94.706694 -256.634488) (xy 95.025222 -256.634488)
			(xy 95.029182 -256.585434) (xy 95.040959 -256.53765) (xy 95.06025 -256.492374) (xy 95.086553 -256.450778)
			(xy 95.119188 -256.413941) (xy 95.157309 -256.382816) (xy 95.19993 -256.358209) (xy 95.245946 -256.340757)
			(xy 95.294165 -256.330913) (xy 95.34334 -256.328932) (xy 95.392195 -256.334864) (xy 95.439466 -256.348556)
			(xy 95.483928 -256.369654) (xy 95.524431 -256.39761) (xy 95.559924 -256.431702) (xy 95.589489 -256.471046)
			(xy 95.61236 -256.514623) (xy 95.627944 -256.561304) (xy 95.635839 -256.609881) (xy 95.636334 -256.634488)
			(xy 96.90533 -256.634488) (xy 96.90929 -256.585434) (xy 96.921067 -256.53765) (xy 96.940358 -256.492374)
			(xy 96.966661 -256.450778) (xy 96.999296 -256.413941) (xy 97.037417 -256.382816) (xy 97.080038 -256.358209)
			(xy 97.126054 -256.340757) (xy 97.174273 -256.330913) (xy 97.223448 -256.328932) (xy 97.272303 -256.334864)
			(xy 97.319574 -256.348556) (xy 97.364036 -256.369654) (xy 97.404539 -256.39761) (xy 97.440032 -256.431702)
			(xy 97.469597 -256.471046) (xy 97.492468 -256.514623) (xy 97.508052 -256.561304) (xy 97.515947 -256.609881)
			(xy 97.516442 -256.634488) (xy 98.785184 -256.634488) (xy 98.789144 -256.585434) (xy 98.800921 -256.53765)
			(xy 98.820212 -256.492374) (xy 98.846515 -256.450778) (xy 98.87915 -256.413941) (xy 98.917271 -256.382816)
			(xy 98.959892 -256.358209) (xy 99.005908 -256.340757) (xy 99.054127 -256.330913) (xy 99.103302 -256.328932)
			(xy 99.152157 -256.334864) (xy 99.199428 -256.348556) (xy 99.24389 -256.369654) (xy 99.284393 -256.39761)
			(xy 99.319886 -256.431702) (xy 99.349451 -256.471046) (xy 99.372322 -256.514623) (xy 99.387906 -256.561304)
			(xy 99.395801 -256.609881) (xy 99.396296 -256.634488) (xy 99.395801 -256.659095) (xy 99.387906 -256.707672)
			(xy 99.372322 -256.754353) (xy 99.349451 -256.79793) (xy 99.319886 -256.837274) (xy 99.284393 -256.871366)
			(xy 99.24389 -256.899322) (xy 99.199428 -256.92042) (xy 99.152157 -256.934112) (xy 99.103302 -256.940044)
			(xy 99.054127 -256.938063) (xy 99.005908 -256.928219) (xy 98.959892 -256.910767) (xy 98.917271 -256.88616)
			(xy 98.87915 -256.855035) (xy 98.846515 -256.818198) (xy 98.820212 -256.776602) (xy 98.800921 -256.731326)
			(xy 98.789144 -256.683542) (xy 98.785184 -256.634488) (xy 97.516442 -256.634488) (xy 97.515947 -256.659095)
			(xy 97.508052 -256.707672) (xy 97.492468 -256.754353) (xy 97.469597 -256.79793) (xy 97.440032 -256.837274)
			(xy 97.404539 -256.871366) (xy 97.364036 -256.899322) (xy 97.319574 -256.92042) (xy 97.272303 -256.934112)
			(xy 97.223448 -256.940044) (xy 97.174273 -256.938063) (xy 97.126054 -256.928219) (xy 97.080038 -256.910767)
			(xy 97.037417 -256.88616) (xy 96.999296 -256.855035) (xy 96.966661 -256.818198) (xy 96.940358 -256.776602)
			(xy 96.921067 -256.731326) (xy 96.90929 -256.683542) (xy 96.90533 -256.634488) (xy 95.636334 -256.634488)
			(xy 95.635839 -256.659095) (xy 95.627944 -256.707672) (xy 95.61236 -256.754353) (xy 95.589489 -256.79793)
			(xy 95.559924 -256.837274) (xy 95.524431 -256.871366) (xy 95.483928 -256.899322) (xy 95.439466 -256.92042)
			(xy 95.392195 -256.934112) (xy 95.34334 -256.940044) (xy 95.294165 -256.938063) (xy 95.245946 -256.928219)
			(xy 95.19993 -256.910767) (xy 95.157309 -256.88616) (xy 95.119188 -256.855035) (xy 95.086553 -256.818198)
			(xy 95.06025 -256.776602) (xy 95.040959 -256.731326) (xy 95.029182 -256.683542) (xy 95.025222 -256.634488)
			(xy 94.706694 -256.634488) (xy 94.706182 -256.659934) (xy 94.698018 -256.710168) (xy 94.681902 -256.758442)
			(xy 94.658251 -256.803505) (xy 94.627678 -256.844191) (xy 94.590974 -256.879446) (xy 94.54909 -256.908356)
			(xy 94.503111 -256.930173) (xy 94.454227 -256.944333) (xy 94.403706 -256.950467) (xy 94.352854 -256.948418)
			(xy 94.30299 -256.938238) (xy 94.255404 -256.920191) (xy 94.21133 -256.894745) (xy 94.171908 -256.862558)
			(xy 94.13816 -256.824464) (xy 94.110959 -256.78145) (xy 94.091011 -256.73463) (xy 94.078832 -256.685216)
			(xy 94.074737 -256.634488) (xy 93.756226 -256.634488) (xy 93.755731 -256.659095) (xy 93.747836 -256.707672)
			(xy 93.732252 -256.754353) (xy 93.709381 -256.79793) (xy 93.679816 -256.837274) (xy 93.644323 -256.871366)
			(xy 93.60382 -256.899322) (xy 93.559358 -256.92042) (xy 93.512087 -256.934112) (xy 93.463232 -256.940044)
			(xy 93.414057 -256.938063) (xy 93.365838 -256.928219) (xy 93.319822 -256.910767) (xy 93.277201 -256.88616)
			(xy 93.23908 -256.855035) (xy 93.206445 -256.818198) (xy 93.180142 -256.776602) (xy 93.160851 -256.731326)
			(xy 93.149074 -256.683542) (xy 93.145114 -256.634488) (xy 92.816426 -256.634488) (xy 92.815931 -256.659095)
			(xy 92.808036 -256.707672) (xy 92.792452 -256.754353) (xy 92.769581 -256.79793) (xy 92.740016 -256.837274)
			(xy 92.704523 -256.871366) (xy 92.66402 -256.899322) (xy 92.619558 -256.92042) (xy 92.572287 -256.934112)
			(xy 92.523432 -256.940044) (xy 92.474257 -256.938063) (xy 92.426038 -256.928219) (xy 92.380022 -256.910767)
			(xy 92.337401 -256.88616) (xy 92.29928 -256.855035) (xy 92.266645 -256.818198) (xy 92.240342 -256.776602)
			(xy 92.221051 -256.731326) (xy 92.209274 -256.683542) (xy 92.205314 -256.634488) (xy 91.876372 -256.634488)
			(xy 91.875877 -256.659095) (xy 91.867982 -256.707672) (xy 91.852398 -256.754353) (xy 91.829527 -256.79793)
			(xy 91.799962 -256.837274) (xy 91.764469 -256.871366) (xy 91.723966 -256.899322) (xy 91.679504 -256.92042)
			(xy 91.632233 -256.934112) (xy 91.583378 -256.940044) (xy 91.534203 -256.938063) (xy 91.485984 -256.928219)
			(xy 91.439968 -256.910767) (xy 91.397347 -256.88616) (xy 91.359226 -256.855035) (xy 91.326591 -256.818198)
			(xy 91.300288 -256.776602) (xy 91.280997 -256.731326) (xy 91.26922 -256.683542) (xy 91.26526 -256.634488)
			(xy 90.946732 -256.634488) (xy 90.94622 -256.659934) (xy 90.938056 -256.710168) (xy 90.92194 -256.758442)
			(xy 90.898289 -256.803505) (xy 90.867716 -256.844191) (xy 90.831012 -256.879446) (xy 90.789128 -256.908356)
			(xy 90.743149 -256.930173) (xy 90.694265 -256.944333) (xy 90.643744 -256.950467) (xy 90.592892 -256.948418)
			(xy 90.543028 -256.938238) (xy 90.495442 -256.920191) (xy 90.451368 -256.894745) (xy 90.411946 -256.862558)
			(xy 90.378198 -256.824464) (xy 90.350997 -256.78145) (xy 90.331049 -256.73463) (xy 90.31887 -256.685216)
			(xy 90.314775 -256.634488) (xy 89.996264 -256.634488) (xy 89.995769 -256.659095) (xy 89.987874 -256.707672)
			(xy 89.97229 -256.754353) (xy 89.949419 -256.79793) (xy 89.919854 -256.837274) (xy 89.884361 -256.871366)
			(xy 89.843858 -256.899322) (xy 89.799396 -256.92042) (xy 89.752125 -256.934112) (xy 89.70327 -256.940044)
			(xy 89.654095 -256.938063) (xy 89.605876 -256.928219) (xy 89.55986 -256.910767) (xy 89.517239 -256.88616)
			(xy 89.479118 -256.855035) (xy 89.446483 -256.818198) (xy 89.42018 -256.776602) (xy 89.400889 -256.731326)
			(xy 89.389112 -256.683542) (xy 89.385152 -256.634488) (xy 89.056464 -256.634488) (xy 89.055969 -256.659095)
			(xy 89.048074 -256.707672) (xy 89.03249 -256.754353) (xy 89.009619 -256.79793) (xy 88.980054 -256.837274)
			(xy 88.944561 -256.871366) (xy 88.904058 -256.899322) (xy 88.859596 -256.92042) (xy 88.812325 -256.934112)
			(xy 88.76347 -256.940044) (xy 88.714295 -256.938063) (xy 88.666076 -256.928219) (xy 88.62006 -256.910767)
			(xy 88.577439 -256.88616) (xy 88.539318 -256.855035) (xy 88.506683 -256.818198) (xy 88.48038 -256.776602)
			(xy 88.461089 -256.731326) (xy 88.449312 -256.683542) (xy 88.445352 -256.634488) (xy 88.126824 -256.634488)
			(xy 88.126312 -256.659934) (xy 88.118148 -256.710168) (xy 88.102032 -256.758442) (xy 88.078381 -256.803505)
			(xy 88.047808 -256.844191) (xy 88.011104 -256.879446) (xy 87.96922 -256.908356) (xy 87.923241 -256.930173)
			(xy 87.874357 -256.944333) (xy 87.823836 -256.950467) (xy 87.772984 -256.948418) (xy 87.72312 -256.938238)
			(xy 87.675534 -256.920191) (xy 87.63146 -256.894745) (xy 87.592038 -256.862558) (xy 87.55829 -256.824464)
			(xy 87.531089 -256.78145) (xy 87.511141 -256.73463) (xy 87.498962 -256.685216) (xy 87.494867 -256.634488)
			(xy 87.176356 -256.634488) (xy 87.175861 -256.659095) (xy 87.167966 -256.707672) (xy 87.152382 -256.754353)
			(xy 87.129511 -256.79793) (xy 87.099946 -256.837274) (xy 87.064453 -256.871366) (xy 87.02395 -256.899322)
			(xy 86.979488 -256.92042) (xy 86.932217 -256.934112) (xy 86.883362 -256.940044) (xy 86.834187 -256.938063)
			(xy 86.785968 -256.928219) (xy 86.739952 -256.910767) (xy 86.697331 -256.88616) (xy 86.65921 -256.855035)
			(xy 86.626575 -256.818198) (xy 86.600272 -256.776602) (xy 86.580981 -256.731326) (xy 86.569204 -256.683542)
			(xy 86.565244 -256.634488) (xy 86.236302 -256.634488) (xy 86.235807 -256.659095) (xy 86.227912 -256.707672)
			(xy 86.212328 -256.754353) (xy 86.189457 -256.79793) (xy 86.159892 -256.837274) (xy 86.124399 -256.871366)
			(xy 86.083896 -256.899322) (xy 86.039434 -256.92042) (xy 85.992163 -256.934112) (xy 85.943308 -256.940044)
			(xy 85.894133 -256.938063) (xy 85.845914 -256.928219) (xy 85.799898 -256.910767) (xy 85.757277 -256.88616)
			(xy 85.719156 -256.855035) (xy 85.686521 -256.818198) (xy 85.660218 -256.776602) (xy 85.640927 -256.731326)
			(xy 85.62915 -256.683542) (xy 85.62519 -256.634488) (xy 85.296248 -256.634488) (xy 85.295753 -256.659095)
			(xy 85.287858 -256.707672) (xy 85.272274 -256.754353) (xy 85.249403 -256.79793) (xy 85.219838 -256.837274)
			(xy 85.184345 -256.871366) (xy 85.143842 -256.899322) (xy 85.09938 -256.92042) (xy 85.052109 -256.934112)
			(xy 85.003254 -256.940044) (xy 84.954079 -256.938063) (xy 84.90586 -256.928219) (xy 84.859844 -256.910767)
			(xy 84.817223 -256.88616) (xy 84.779102 -256.855035) (xy 84.746467 -256.818198) (xy 84.720164 -256.776602)
			(xy 84.700873 -256.731326) (xy 84.689096 -256.683542) (xy 84.685136 -256.634488) (xy 84.366862 -256.634488)
			(xy 84.36635 -256.659934) (xy 84.358186 -256.710168) (xy 84.34207 -256.758442) (xy 84.318419 -256.803505)
			(xy 84.287846 -256.844191) (xy 84.251142 -256.879446) (xy 84.209258 -256.908356) (xy 84.163279 -256.930173)
			(xy 84.114395 -256.944333) (xy 84.063874 -256.950467) (xy 84.013022 -256.948418) (xy 83.963158 -256.938238)
			(xy 83.915572 -256.920191) (xy 83.871498 -256.894745) (xy 83.832076 -256.862558) (xy 83.798328 -256.824464)
			(xy 83.771127 -256.78145) (xy 83.751179 -256.73463) (xy 83.739 -256.685216) (xy 83.734905 -256.634488)
			(xy 83.416394 -256.634488) (xy 83.415899 -256.659095) (xy 83.408004 -256.707672) (xy 83.39242 -256.754353)
			(xy 83.369549 -256.79793) (xy 83.339984 -256.837274) (xy 83.304491 -256.871366) (xy 83.263988 -256.899322)
			(xy 83.219526 -256.92042) (xy 83.172255 -256.934112) (xy 83.1234 -256.940044) (xy 83.074225 -256.938063)
			(xy 83.026006 -256.928219) (xy 82.97999 -256.910767) (xy 82.937369 -256.88616) (xy 82.899248 -256.855035)
			(xy 82.866613 -256.818198) (xy 82.84031 -256.776602) (xy 82.821019 -256.731326) (xy 82.809242 -256.683542)
			(xy 82.805282 -256.634488) (xy 82.47634 -256.634488) (xy 82.475845 -256.659095) (xy 82.46795 -256.707672)
			(xy 82.452366 -256.754353) (xy 82.429495 -256.79793) (xy 82.39993 -256.837274) (xy 82.364437 -256.871366)
			(xy 82.323934 -256.899322) (xy 82.279472 -256.92042) (xy 82.232201 -256.934112) (xy 82.183346 -256.940044)
			(xy 82.134171 -256.938063) (xy 82.085952 -256.928219) (xy 82.039936 -256.910767) (xy 81.997315 -256.88616)
			(xy 81.959194 -256.855035) (xy 81.926559 -256.818198) (xy 81.900256 -256.776602) (xy 81.880965 -256.731326)
			(xy 81.869188 -256.683542) (xy 81.865228 -256.634488) (xy 81.5467 -256.634488) (xy 81.546188 -256.659934)
			(xy 81.538024 -256.710168) (xy 81.521908 -256.758442) (xy 81.498257 -256.803505) (xy 81.467684 -256.844191)
			(xy 81.43098 -256.879446) (xy 81.389096 -256.908356) (xy 81.343117 -256.930173) (xy 81.294233 -256.944333)
			(xy 81.243712 -256.950467) (xy 81.19286 -256.948418) (xy 81.142996 -256.938238) (xy 81.09541 -256.920191)
			(xy 81.051336 -256.894745) (xy 81.011914 -256.862558) (xy 80.978166 -256.824464) (xy 80.950965 -256.78145)
			(xy 80.931017 -256.73463) (xy 80.918838 -256.685216) (xy 80.914743 -256.634488) (xy 80.596486 -256.634488)
			(xy 80.595991 -256.659095) (xy 80.588096 -256.707672) (xy 80.572512 -256.754353) (xy 80.549641 -256.79793)
			(xy 80.520076 -256.837274) (xy 80.484583 -256.871366) (xy 80.44408 -256.899322) (xy 80.399618 -256.92042)
			(xy 80.352347 -256.934112) (xy 80.303492 -256.940044) (xy 80.254317 -256.938063) (xy 80.206098 -256.928219)
			(xy 80.160082 -256.910767) (xy 80.117461 -256.88616) (xy 80.07934 -256.855035) (xy 80.046705 -256.818198)
			(xy 80.020402 -256.776602) (xy 80.001111 -256.731326) (xy 79.989334 -256.683542) (xy 79.985374 -256.634488)
			(xy 78.716378 -256.634488) (xy 78.715883 -256.659095) (xy 78.707988 -256.707672) (xy 78.692404 -256.754353)
			(xy 78.669533 -256.79793) (xy 78.639968 -256.837274) (xy 78.604475 -256.871366) (xy 78.563972 -256.899322)
			(xy 78.51951 -256.92042) (xy 78.472239 -256.934112) (xy 78.423384 -256.940044) (xy 78.374209 -256.938063)
			(xy 78.32599 -256.928219) (xy 78.279974 -256.910767) (xy 78.237353 -256.88616) (xy 78.199232 -256.855035)
			(xy 78.166597 -256.818198) (xy 78.140294 -256.776602) (xy 78.121003 -256.731326) (xy 78.109226 -256.683542)
			(xy 78.105266 -256.634488) (xy 73.375774 -256.634488) (xy 73.375774 -257.930396) (xy 98.711261 -257.930396)
			(xy 98.715291 -257.877898) (xy 98.727288 -257.82663) (xy 98.746971 -257.777795) (xy 98.773877 -257.732536)
			(xy 98.807377 -257.691915) (xy 98.846685 -257.656884) (xy 98.89088 -257.628264) (xy 98.938925 -257.606725)
			(xy 98.989696 -257.592773) (xy 99.042001 -257.586735) (xy 99.094615 -257.588752) (xy 99.146305 -257.598776)
			(xy 99.195858 -257.616574) (xy 99.242114 -257.641727) (xy 99.283988 -257.673646) (xy 99.3205 -257.711584)
			(xy 99.350792 -257.75465) (xy 99.374155 -257.801835) (xy 99.390041 -257.852034) (xy 99.398078 -257.90407)
			(xy 99.398582 -257.930396) (xy 99.398078 -257.956722) (xy 99.390041 -258.008758) (xy 99.374155 -258.058957)
			(xy 99.350792 -258.106142) (xy 99.3205 -258.149208) (xy 99.283988 -258.187146) (xy 99.242114 -258.219065)
			(xy 99.195858 -258.244218) (xy 99.146305 -258.262016) (xy 99.094615 -258.27204) (xy 99.042001 -258.274057)
			(xy 98.989696 -258.268019) (xy 98.938925 -258.254067) (xy 98.89088 -258.232528) (xy 98.846685 -258.203908)
			(xy 98.807377 -258.168877) (xy 98.773877 -258.128256) (xy 98.746971 -258.082997) (xy 98.727288 -258.034162)
			(xy 98.715291 -257.982894) (xy 98.711261 -257.930396) (xy 73.375774 -257.930396) (xy 73.375774 -258.830318)
			(xy 98.711261 -258.830318) (xy 98.715291 -258.77782) (xy 98.727288 -258.726552) (xy 98.746971 -258.677717)
			(xy 98.773877 -258.632458) (xy 98.807377 -258.591837) (xy 98.846685 -258.556806) (xy 98.89088 -258.528186)
			(xy 98.938925 -258.506647) (xy 98.989696 -258.492695) (xy 99.042001 -258.486657) (xy 99.094615 -258.488674)
			(xy 99.146305 -258.498698) (xy 99.195858 -258.516496) (xy 99.242114 -258.541649) (xy 99.283988 -258.573568)
			(xy 99.3205 -258.611506) (xy 99.350792 -258.654572) (xy 99.374155 -258.701757) (xy 99.390041 -258.751956)
			(xy 99.398078 -258.803992) (xy 99.398582 -258.830318) (xy 100.611181 -258.830318) (xy 100.615211 -258.77782)
			(xy 100.627208 -258.726552) (xy 100.646891 -258.677717) (xy 100.673797 -258.632458) (xy 100.707297 -258.591837)
			(xy 100.746605 -258.556806) (xy 100.7908 -258.528186) (xy 100.838845 -258.506647) (xy 100.889616 -258.492695)
			(xy 100.941921 -258.486657) (xy 100.994535 -258.488674) (xy 101.046225 -258.498698) (xy 101.095778 -258.516496)
			(xy 101.142034 -258.541649) (xy 101.183908 -258.573568) (xy 101.22042 -258.611506) (xy 101.250712 -258.654572)
			(xy 101.274075 -258.701757) (xy 101.289961 -258.751956) (xy 101.297998 -258.803992) (xy 101.298502 -258.830318)
			(xy 101.297998 -258.856644) (xy 101.289961 -258.90868) (xy 101.274075 -258.958879) (xy 101.250712 -259.006064)
			(xy 101.22042 -259.04913) (xy 101.183908 -259.087068) (xy 101.142034 -259.118987) (xy 101.095778 -259.14414)
			(xy 101.046225 -259.161938) (xy 100.994535 -259.171962) (xy 100.941921 -259.173979) (xy 100.889616 -259.167941)
			(xy 100.838845 -259.153989) (xy 100.7908 -259.13245) (xy 100.746605 -259.10383) (xy 100.707297 -259.068799)
			(xy 100.673797 -259.028178) (xy 100.646891 -258.982919) (xy 100.627208 -258.934084) (xy 100.615211 -258.882816)
			(xy 100.611181 -258.830318) (xy 99.398582 -258.830318) (xy 99.398078 -258.856644) (xy 99.390041 -258.90868)
			(xy 99.374155 -258.958879) (xy 99.350792 -259.006064) (xy 99.3205 -259.04913) (xy 99.283988 -259.087068)
			(xy 99.242114 -259.118987) (xy 99.195858 -259.14414) (xy 99.146305 -259.161938) (xy 99.094615 -259.171962)
			(xy 99.042001 -259.173979) (xy 98.989696 -259.167941) (xy 98.938925 -259.153989) (xy 98.89088 -259.13245)
			(xy 98.846685 -259.10383) (xy 98.807377 -259.068799) (xy 98.773877 -259.028178) (xy 98.746971 -258.982919)
			(xy 98.727288 -258.934084) (xy 98.715291 -258.882816) (xy 98.711261 -258.830318) (xy 73.375774 -258.830318)
			(xy 73.375774 -259.73024) (xy 98.711261 -259.73024) (xy 98.715291 -259.677742) (xy 98.727288 -259.626474)
			(xy 98.746971 -259.577639) (xy 98.773877 -259.53238) (xy 98.807377 -259.491759) (xy 98.846685 -259.456728)
			(xy 98.89088 -259.428108) (xy 98.938925 -259.406569) (xy 98.989696 -259.392617) (xy 99.042001 -259.386579)
			(xy 99.094615 -259.388596) (xy 99.146305 -259.39862) (xy 99.195858 -259.416418) (xy 99.242114 -259.441571)
			(xy 99.283988 -259.47349) (xy 99.3205 -259.511428) (xy 99.350792 -259.554494) (xy 99.374155 -259.601679)
			(xy 99.390041 -259.651878) (xy 99.398078 -259.703914) (xy 99.398582 -259.73024) (xy 100.611181 -259.73024)
			(xy 100.615211 -259.677742) (xy 100.627208 -259.626474) (xy 100.646891 -259.577639) (xy 100.673797 -259.53238)
			(xy 100.707297 -259.491759) (xy 100.746605 -259.456728) (xy 100.7908 -259.428108) (xy 100.838845 -259.406569)
			(xy 100.889616 -259.392617) (xy 100.941921 -259.386579) (xy 100.994535 -259.388596) (xy 101.046225 -259.39862)
			(xy 101.095778 -259.416418) (xy 101.142034 -259.441571) (xy 101.183908 -259.47349) (xy 101.22042 -259.511428)
			(xy 101.250712 -259.554494) (xy 101.274075 -259.601679) (xy 101.289961 -259.651878) (xy 101.297998 -259.703914)
			(xy 101.298502 -259.73024) (xy 101.297998 -259.756566) (xy 101.289961 -259.808602) (xy 101.274075 -259.858801)
			(xy 101.250712 -259.905986) (xy 101.22042 -259.949052) (xy 101.183908 -259.98699) (xy 101.142034 -260.018909)
			(xy 101.095778 -260.044062) (xy 101.046225 -260.06186) (xy 100.994535 -260.071884) (xy 100.941921 -260.073901)
			(xy 100.889616 -260.067863) (xy 100.838845 -260.053911) (xy 100.7908 -260.032372) (xy 100.746605 -260.003752)
			(xy 100.707297 -259.968721) (xy 100.673797 -259.9281) (xy 100.646891 -259.882841) (xy 100.627208 -259.834006)
			(xy 100.615211 -259.782738) (xy 100.611181 -259.73024) (xy 99.398582 -259.73024) (xy 99.398078 -259.756566)
			(xy 99.390041 -259.808602) (xy 99.374155 -259.858801) (xy 99.350792 -259.905986) (xy 99.3205 -259.949052)
			(xy 99.283988 -259.98699) (xy 99.242114 -260.018909) (xy 99.195858 -260.044062) (xy 99.146305 -260.06186)
			(xy 99.094615 -260.071884) (xy 99.042001 -260.073901) (xy 98.989696 -260.067863) (xy 98.938925 -260.053911)
			(xy 98.89088 -260.032372) (xy 98.846685 -260.003752) (xy 98.807377 -259.968721) (xy 98.773877 -259.9281)
			(xy 98.746971 -259.882841) (xy 98.727288 -259.834006) (xy 98.715291 -259.782738) (xy 98.711261 -259.73024)
			(xy 73.375774 -259.73024) (xy 73.375774 -261.126224) (xy 78.40524 -261.126224) (xy 78.4092 -261.07717)
			(xy 78.420977 -261.029386) (xy 78.440268 -260.98411) (xy 78.466571 -260.942514) (xy 78.499206 -260.905677)
			(xy 78.537327 -260.874552) (xy 78.579948 -260.849945) (xy 78.625964 -260.832493) (xy 78.674183 -260.822649)
			(xy 78.723358 -260.820668) (xy 78.772213 -260.8266) (xy 78.819484 -260.840292) (xy 78.863946 -260.86139)
			(xy 78.904449 -260.889346) (xy 78.939942 -260.923438) (xy 78.969507 -260.962782) (xy 78.992378 -261.006359)
			(xy 79.007962 -261.05304) (xy 79.015857 -261.101617) (xy 79.016352 -261.126224) (xy 79.345294 -261.126224)
			(xy 79.349254 -261.07717) (xy 79.361031 -261.029386) (xy 79.380322 -260.98411) (xy 79.406625 -260.942514)
			(xy 79.43926 -260.905677) (xy 79.477381 -260.874552) (xy 79.520002 -260.849945) (xy 79.566018 -260.832493)
			(xy 79.614237 -260.822649) (xy 79.663412 -260.820668) (xy 79.712267 -260.8266) (xy 79.759538 -260.840292)
			(xy 79.804 -260.86139) (xy 79.844503 -260.889346) (xy 79.879996 -260.923438) (xy 79.909561 -260.962782)
			(xy 79.932432 -261.006359) (xy 79.948016 -261.05304) (xy 79.955911 -261.101617) (xy 79.956406 -261.126224)
			(xy 81.225148 -261.126224) (xy 81.229108 -261.07717) (xy 81.240885 -261.029386) (xy 81.260176 -260.98411)
			(xy 81.286479 -260.942514) (xy 81.319114 -260.905677) (xy 81.357235 -260.874552) (xy 81.399856 -260.849945)
			(xy 81.445872 -260.832493) (xy 81.494091 -260.822649) (xy 81.543266 -260.820668) (xy 81.592121 -260.8266)
			(xy 81.639392 -260.840292) (xy 81.683854 -260.86139) (xy 81.724357 -260.889346) (xy 81.75985 -260.923438)
			(xy 81.789415 -260.962782) (xy 81.812286 -261.006359) (xy 81.82787 -261.05304) (xy 81.835765 -261.101617)
			(xy 81.83626 -261.126224) (xy 82.165202 -261.126224) (xy 82.169162 -261.07717) (xy 82.180939 -261.029386)
			(xy 82.20023 -260.98411) (xy 82.226533 -260.942514) (xy 82.259168 -260.905677) (xy 82.297289 -260.874552)
			(xy 82.33991 -260.849945) (xy 82.385926 -260.832493) (xy 82.434145 -260.822649) (xy 82.48332 -260.820668)
			(xy 82.532175 -260.8266) (xy 82.579446 -260.840292) (xy 82.623908 -260.86139) (xy 82.664411 -260.889346)
			(xy 82.699904 -260.923438) (xy 82.729469 -260.962782) (xy 82.75234 -261.006359) (xy 82.767924 -261.05304)
			(xy 82.775819 -261.101617) (xy 82.776314 -261.126224) (xy 83.105256 -261.126224) (xy 83.109216 -261.07717)
			(xy 83.120993 -261.029386) (xy 83.140284 -260.98411) (xy 83.166587 -260.942514) (xy 83.199222 -260.905677)
			(xy 83.237343 -260.874552) (xy 83.279964 -260.849945) (xy 83.32598 -260.832493) (xy 83.374199 -260.822649)
			(xy 83.423374 -260.820668) (xy 83.472229 -260.8266) (xy 83.5195 -260.840292) (xy 83.563962 -260.86139)
			(xy 83.604465 -260.889346) (xy 83.639958 -260.923438) (xy 83.669523 -260.962782) (xy 83.692394 -261.006359)
			(xy 83.707978 -261.05304) (xy 83.715873 -261.101617) (xy 83.716368 -261.126224) (xy 84.04531 -261.126224)
			(xy 84.04927 -261.07717) (xy 84.061047 -261.029386) (xy 84.080338 -260.98411) (xy 84.106641 -260.942514)
			(xy 84.139276 -260.905677) (xy 84.177397 -260.874552) (xy 84.220018 -260.849945) (xy 84.266034 -260.832493)
			(xy 84.314253 -260.822649) (xy 84.363428 -260.820668) (xy 84.412283 -260.8266) (xy 84.459554 -260.840292)
			(xy 84.504016 -260.86139) (xy 84.544519 -260.889346) (xy 84.580012 -260.923438) (xy 84.609577 -260.962782)
			(xy 84.632448 -261.006359) (xy 84.648032 -261.05304) (xy 84.655927 -261.101617) (xy 84.656422 -261.126224)
			(xy 84.98511 -261.126224) (xy 84.98907 -261.07717) (xy 85.000847 -261.029386) (xy 85.020138 -260.98411)
			(xy 85.046441 -260.942514) (xy 85.079076 -260.905677) (xy 85.117197 -260.874552) (xy 85.159818 -260.849945)
			(xy 85.205834 -260.832493) (xy 85.254053 -260.822649) (xy 85.303228 -260.820668) (xy 85.352083 -260.8266)
			(xy 85.399354 -260.840292) (xy 85.443816 -260.86139) (xy 85.484319 -260.889346) (xy 85.519812 -260.923438)
			(xy 85.549377 -260.962782) (xy 85.572248 -261.006359) (xy 85.587832 -261.05304) (xy 85.595727 -261.101617)
			(xy 85.596222 -261.126224) (xy 85.925164 -261.126224) (xy 85.929124 -261.07717) (xy 85.940901 -261.029386)
			(xy 85.960192 -260.98411) (xy 85.986495 -260.942514) (xy 86.01913 -260.905677) (xy 86.057251 -260.874552)
			(xy 86.099872 -260.849945) (xy 86.145888 -260.832493) (xy 86.194107 -260.822649) (xy 86.243282 -260.820668)
			(xy 86.292137 -260.8266) (xy 86.339408 -260.840292) (xy 86.38387 -260.86139) (xy 86.424373 -260.889346)
			(xy 86.459866 -260.923438) (xy 86.489431 -260.962782) (xy 86.512302 -261.006359) (xy 86.527886 -261.05304)
			(xy 86.535781 -261.101617) (xy 86.536276 -261.126224) (xy 87.805272 -261.126224) (xy 87.809232 -261.07717)
			(xy 87.821009 -261.029386) (xy 87.8403 -260.98411) (xy 87.866603 -260.942514) (xy 87.899238 -260.905677)
			(xy 87.937359 -260.874552) (xy 87.97998 -260.849945) (xy 88.025996 -260.832493) (xy 88.074215 -260.822649)
			(xy 88.12339 -260.820668) (xy 88.172245 -260.8266) (xy 88.219516 -260.840292) (xy 88.263978 -260.86139)
			(xy 88.304481 -260.889346) (xy 88.339974 -260.923438) (xy 88.369539 -260.962782) (xy 88.39241 -261.006359)
			(xy 88.407994 -261.05304) (xy 88.415889 -261.101617) (xy 88.416384 -261.126224) (xy 88.745326 -261.126224)
			(xy 88.749286 -261.07717) (xy 88.761063 -261.029386) (xy 88.780354 -260.98411) (xy 88.806657 -260.942514)
			(xy 88.839292 -260.905677) (xy 88.877413 -260.874552) (xy 88.920034 -260.849945) (xy 88.96605 -260.832493)
			(xy 89.014269 -260.822649) (xy 89.063444 -260.820668) (xy 89.112299 -260.8266) (xy 89.15957 -260.840292)
			(xy 89.204032 -260.86139) (xy 89.244535 -260.889346) (xy 89.280028 -260.923438) (xy 89.309593 -260.962782)
			(xy 89.332464 -261.006359) (xy 89.348048 -261.05304) (xy 89.355943 -261.101617) (xy 89.356438 -261.126224)
			(xy 89.685126 -261.126224) (xy 89.689086 -261.07717) (xy 89.700863 -261.029386) (xy 89.720154 -260.98411)
			(xy 89.746457 -260.942514) (xy 89.779092 -260.905677) (xy 89.817213 -260.874552) (xy 89.859834 -260.849945)
			(xy 89.90585 -260.832493) (xy 89.954069 -260.822649) (xy 90.003244 -260.820668) (xy 90.052099 -260.8266)
			(xy 90.09937 -260.840292) (xy 90.143832 -260.86139) (xy 90.184335 -260.889346) (xy 90.219828 -260.923438)
			(xy 90.249393 -260.962782) (xy 90.272264 -261.006359) (xy 90.287848 -261.05304) (xy 90.295743 -261.101617)
			(xy 90.296238 -261.126224) (xy 90.62518 -261.126224) (xy 90.62914 -261.07717) (xy 90.640917 -261.029386)
			(xy 90.660208 -260.98411) (xy 90.686511 -260.942514) (xy 90.719146 -260.905677) (xy 90.757267 -260.874552)
			(xy 90.799888 -260.849945) (xy 90.845904 -260.832493) (xy 90.894123 -260.822649) (xy 90.943298 -260.820668)
			(xy 90.992153 -260.8266) (xy 91.039424 -260.840292) (xy 91.083886 -260.86139) (xy 91.124389 -260.889346)
			(xy 91.159882 -260.923438) (xy 91.189447 -260.962782) (xy 91.212318 -261.006359) (xy 91.227902 -261.05304)
			(xy 91.235797 -261.101617) (xy 91.236292 -261.126224) (xy 91.565234 -261.126224) (xy 91.569194 -261.07717)
			(xy 91.580971 -261.029386) (xy 91.600262 -260.98411) (xy 91.626565 -260.942514) (xy 91.6592 -260.905677)
			(xy 91.697321 -260.874552) (xy 91.739942 -260.849945) (xy 91.785958 -260.832493) (xy 91.834177 -260.822649)
			(xy 91.883352 -260.820668) (xy 91.932207 -260.8266) (xy 91.979478 -260.840292) (xy 92.02394 -260.86139)
			(xy 92.064443 -260.889346) (xy 92.099936 -260.923438) (xy 92.129501 -260.962782) (xy 92.152372 -261.006359)
			(xy 92.167956 -261.05304) (xy 92.175851 -261.101617) (xy 92.176346 -261.126224) (xy 92.505288 -261.126224)
			(xy 92.509248 -261.07717) (xy 92.521025 -261.029386) (xy 92.540316 -260.98411) (xy 92.566619 -260.942514)
			(xy 92.599254 -260.905677) (xy 92.637375 -260.874552) (xy 92.679996 -260.849945) (xy 92.726012 -260.832493)
			(xy 92.774231 -260.822649) (xy 92.823406 -260.820668) (xy 92.872261 -260.8266) (xy 92.919532 -260.840292)
			(xy 92.963994 -260.86139) (xy 93.004497 -260.889346) (xy 93.03999 -260.923438) (xy 93.069555 -260.962782)
			(xy 93.092426 -261.006359) (xy 93.10801 -261.05304) (xy 93.115905 -261.101617) (xy 93.1164 -261.126224)
			(xy 94.385142 -261.126224) (xy 94.389102 -261.07717) (xy 94.400879 -261.029386) (xy 94.42017 -260.98411)
			(xy 94.446473 -260.942514) (xy 94.479108 -260.905677) (xy 94.517229 -260.874552) (xy 94.55985 -260.849945)
			(xy 94.605866 -260.832493) (xy 94.654085 -260.822649) (xy 94.70326 -260.820668) (xy 94.752115 -260.8266)
			(xy 94.799386 -260.840292) (xy 94.843848 -260.86139) (xy 94.884351 -260.889346) (xy 94.919844 -260.923438)
			(xy 94.949409 -260.962782) (xy 94.97228 -261.006359) (xy 94.987864 -261.05304) (xy 94.995759 -261.101617)
			(xy 94.996254 -261.126224) (xy 95.325196 -261.126224) (xy 95.329156 -261.07717) (xy 95.340933 -261.029386)
			(xy 95.360224 -260.98411) (xy 95.386527 -260.942514) (xy 95.419162 -260.905677) (xy 95.457283 -260.874552)
			(xy 95.499904 -260.849945) (xy 95.54592 -260.832493) (xy 95.594139 -260.822649) (xy 95.643314 -260.820668)
			(xy 95.692169 -260.8266) (xy 95.73944 -260.840292) (xy 95.783902 -260.86139) (xy 95.824405 -260.889346)
			(xy 95.859898 -260.923438) (xy 95.889463 -260.962782) (xy 95.912334 -261.006359) (xy 95.927918 -261.05304)
			(xy 95.935813 -261.101617) (xy 95.936308 -261.126224) (xy 96.26525 -261.126224) (xy 96.26921 -261.07717)
			(xy 96.280987 -261.029386) (xy 96.300278 -260.98411) (xy 96.326581 -260.942514) (xy 96.359216 -260.905677)
			(xy 96.397337 -260.874552) (xy 96.439958 -260.849945) (xy 96.485974 -260.832493) (xy 96.534193 -260.822649)
			(xy 96.583368 -260.820668) (xy 96.632223 -260.8266) (xy 96.679494 -260.840292) (xy 96.723956 -260.86139)
			(xy 96.764459 -260.889346) (xy 96.799952 -260.923438) (xy 96.829517 -260.962782) (xy 96.852388 -261.006359)
			(xy 96.867972 -261.05304) (xy 96.875867 -261.101617) (xy 96.876362 -261.126224) (xy 98.145358 -261.126224)
			(xy 98.149318 -261.07717) (xy 98.161095 -261.029386) (xy 98.180386 -260.98411) (xy 98.206689 -260.942514)
			(xy 98.239324 -260.905677) (xy 98.277445 -260.874552) (xy 98.320066 -260.849945) (xy 98.366082 -260.832493)
			(xy 98.414301 -260.822649) (xy 98.463476 -260.820668) (xy 98.512331 -260.8266) (xy 98.559602 -260.840292)
			(xy 98.604064 -260.86139) (xy 98.644567 -260.889346) (xy 98.68006 -260.923438) (xy 98.709625 -260.962782)
			(xy 98.732496 -261.006359) (xy 98.74808 -261.05304) (xy 98.755975 -261.101617) (xy 98.75647 -261.126224)
			(xy 100.025212 -261.126224) (xy 100.029172 -261.07717) (xy 100.040949 -261.029386) (xy 100.06024 -260.98411)
			(xy 100.086543 -260.942514) (xy 100.119178 -260.905677) (xy 100.157299 -260.874552) (xy 100.19992 -260.849945)
			(xy 100.245936 -260.832493) (xy 100.294155 -260.822649) (xy 100.34333 -260.820668) (xy 100.392185 -260.8266)
			(xy 100.439456 -260.840292) (xy 100.483918 -260.86139) (xy 100.524421 -260.889346) (xy 100.559914 -260.923438)
			(xy 100.589479 -260.962782) (xy 100.61235 -261.006359) (xy 100.627934 -261.05304) (xy 100.635829 -261.101617)
			(xy 100.636324 -261.126224) (xy 100.635829 -261.150831) (xy 100.627934 -261.199408) (xy 100.61235 -261.246089)
			(xy 100.589479 -261.289666) (xy 100.559914 -261.32901) (xy 100.524421 -261.363102) (xy 100.483918 -261.391058)
			(xy 100.439456 -261.412156) (xy 100.392185 -261.425848) (xy 100.34333 -261.43178) (xy 100.294155 -261.429799)
			(xy 100.245936 -261.419955) (xy 100.19992 -261.402503) (xy 100.157299 -261.377896) (xy 100.119178 -261.346771)
			(xy 100.086543 -261.309934) (xy 100.06024 -261.268338) (xy 100.040949 -261.223062) (xy 100.029172 -261.175278)
			(xy 100.025212 -261.126224) (xy 98.75647 -261.126224) (xy 98.755975 -261.150831) (xy 98.74808 -261.199408)
			(xy 98.732496 -261.246089) (xy 98.709625 -261.289666) (xy 98.68006 -261.32901) (xy 98.644567 -261.363102)
			(xy 98.604064 -261.391058) (xy 98.559602 -261.412156) (xy 98.512331 -261.425848) (xy 98.463476 -261.43178)
			(xy 98.414301 -261.429799) (xy 98.366082 -261.419955) (xy 98.320066 -261.402503) (xy 98.277445 -261.377896)
			(xy 98.239324 -261.346771) (xy 98.206689 -261.309934) (xy 98.180386 -261.268338) (xy 98.161095 -261.223062)
			(xy 98.149318 -261.175278) (xy 98.145358 -261.126224) (xy 96.876362 -261.126224) (xy 96.875867 -261.150831)
			(xy 96.867972 -261.199408) (xy 96.852388 -261.246089) (xy 96.829517 -261.289666) (xy 96.799952 -261.32901)
			(xy 96.764459 -261.363102) (xy 96.723956 -261.391058) (xy 96.679494 -261.412156) (xy 96.632223 -261.425848)
			(xy 96.583368 -261.43178) (xy 96.534193 -261.429799) (xy 96.485974 -261.419955) (xy 96.439958 -261.402503)
			(xy 96.397337 -261.377896) (xy 96.359216 -261.346771) (xy 96.326581 -261.309934) (xy 96.300278 -261.268338)
			(xy 96.280987 -261.223062) (xy 96.26921 -261.175278) (xy 96.26525 -261.126224) (xy 95.936308 -261.126224)
			(xy 95.935813 -261.150831) (xy 95.927918 -261.199408) (xy 95.912334 -261.246089) (xy 95.889463 -261.289666)
			(xy 95.859898 -261.32901) (xy 95.824405 -261.363102) (xy 95.783902 -261.391058) (xy 95.73944 -261.412156)
			(xy 95.692169 -261.425848) (xy 95.643314 -261.43178) (xy 95.594139 -261.429799) (xy 95.54592 -261.419955)
			(xy 95.499904 -261.402503) (xy 95.457283 -261.377896) (xy 95.419162 -261.346771) (xy 95.386527 -261.309934)
			(xy 95.360224 -261.268338) (xy 95.340933 -261.223062) (xy 95.329156 -261.175278) (xy 95.325196 -261.126224)
			(xy 94.996254 -261.126224) (xy 94.995759 -261.150831) (xy 94.987864 -261.199408) (xy 94.97228 -261.246089)
			(xy 94.949409 -261.289666) (xy 94.919844 -261.32901) (xy 94.884351 -261.363102) (xy 94.843848 -261.391058)
			(xy 94.799386 -261.412156) (xy 94.752115 -261.425848) (xy 94.70326 -261.43178) (xy 94.654085 -261.429799)
			(xy 94.605866 -261.419955) (xy 94.55985 -261.402503) (xy 94.517229 -261.377896) (xy 94.479108 -261.346771)
			(xy 94.446473 -261.309934) (xy 94.42017 -261.268338) (xy 94.400879 -261.223062) (xy 94.389102 -261.175278)
			(xy 94.385142 -261.126224) (xy 93.1164 -261.126224) (xy 93.115905 -261.150831) (xy 93.10801 -261.199408)
			(xy 93.092426 -261.246089) (xy 93.069555 -261.289666) (xy 93.03999 -261.32901) (xy 93.004497 -261.363102)
			(xy 92.963994 -261.391058) (xy 92.919532 -261.412156) (xy 92.872261 -261.425848) (xy 92.823406 -261.43178)
			(xy 92.774231 -261.429799) (xy 92.726012 -261.419955) (xy 92.679996 -261.402503) (xy 92.637375 -261.377896)
			(xy 92.599254 -261.346771) (xy 92.566619 -261.309934) (xy 92.540316 -261.268338) (xy 92.521025 -261.223062)
			(xy 92.509248 -261.175278) (xy 92.505288 -261.126224) (xy 92.176346 -261.126224) (xy 92.175851 -261.150831)
			(xy 92.167956 -261.199408) (xy 92.152372 -261.246089) (xy 92.129501 -261.289666) (xy 92.099936 -261.32901)
			(xy 92.064443 -261.363102) (xy 92.02394 -261.391058) (xy 91.979478 -261.412156) (xy 91.932207 -261.425848)
			(xy 91.883352 -261.43178) (xy 91.834177 -261.429799) (xy 91.785958 -261.419955) (xy 91.739942 -261.402503)
			(xy 91.697321 -261.377896) (xy 91.6592 -261.346771) (xy 91.626565 -261.309934) (xy 91.600262 -261.268338)
			(xy 91.580971 -261.223062) (xy 91.569194 -261.175278) (xy 91.565234 -261.126224) (xy 91.236292 -261.126224)
			(xy 91.235797 -261.150831) (xy 91.227902 -261.199408) (xy 91.212318 -261.246089) (xy 91.189447 -261.289666)
			(xy 91.159882 -261.32901) (xy 91.124389 -261.363102) (xy 91.083886 -261.391058) (xy 91.039424 -261.412156)
			(xy 90.992153 -261.425848) (xy 90.943298 -261.43178) (xy 90.894123 -261.429799) (xy 90.845904 -261.419955)
			(xy 90.799888 -261.402503) (xy 90.757267 -261.377896) (xy 90.719146 -261.346771) (xy 90.686511 -261.309934)
			(xy 90.660208 -261.268338) (xy 90.640917 -261.223062) (xy 90.62914 -261.175278) (xy 90.62518 -261.126224)
			(xy 90.296238 -261.126224) (xy 90.295743 -261.150831) (xy 90.287848 -261.199408) (xy 90.272264 -261.246089)
			(xy 90.249393 -261.289666) (xy 90.219828 -261.32901) (xy 90.184335 -261.363102) (xy 90.143832 -261.391058)
			(xy 90.09937 -261.412156) (xy 90.052099 -261.425848) (xy 90.003244 -261.43178) (xy 89.954069 -261.429799)
			(xy 89.90585 -261.419955) (xy 89.859834 -261.402503) (xy 89.817213 -261.377896) (xy 89.779092 -261.346771)
			(xy 89.746457 -261.309934) (xy 89.720154 -261.268338) (xy 89.700863 -261.223062) (xy 89.689086 -261.175278)
			(xy 89.685126 -261.126224) (xy 89.356438 -261.126224) (xy 89.355943 -261.150831) (xy 89.348048 -261.199408)
			(xy 89.332464 -261.246089) (xy 89.309593 -261.289666) (xy 89.280028 -261.32901) (xy 89.244535 -261.363102)
			(xy 89.204032 -261.391058) (xy 89.15957 -261.412156) (xy 89.112299 -261.425848) (xy 89.063444 -261.43178)
			(xy 89.014269 -261.429799) (xy 88.96605 -261.419955) (xy 88.920034 -261.402503) (xy 88.877413 -261.377896)
			(xy 88.839292 -261.346771) (xy 88.806657 -261.309934) (xy 88.780354 -261.268338) (xy 88.761063 -261.223062)
			(xy 88.749286 -261.175278) (xy 88.745326 -261.126224) (xy 88.416384 -261.126224) (xy 88.415889 -261.150831)
			(xy 88.407994 -261.199408) (xy 88.39241 -261.246089) (xy 88.369539 -261.289666) (xy 88.339974 -261.32901)
			(xy 88.304481 -261.363102) (xy 88.263978 -261.391058) (xy 88.219516 -261.412156) (xy 88.172245 -261.425848)
			(xy 88.12339 -261.43178) (xy 88.074215 -261.429799) (xy 88.025996 -261.419955) (xy 87.97998 -261.402503)
			(xy 87.937359 -261.377896) (xy 87.899238 -261.346771) (xy 87.866603 -261.309934) (xy 87.8403 -261.268338)
			(xy 87.821009 -261.223062) (xy 87.809232 -261.175278) (xy 87.805272 -261.126224) (xy 86.536276 -261.126224)
			(xy 86.535781 -261.150831) (xy 86.527886 -261.199408) (xy 86.512302 -261.246089) (xy 86.489431 -261.289666)
			(xy 86.459866 -261.32901) (xy 86.424373 -261.363102) (xy 86.38387 -261.391058) (xy 86.339408 -261.412156)
			(xy 86.292137 -261.425848) (xy 86.243282 -261.43178) (xy 86.194107 -261.429799) (xy 86.145888 -261.419955)
			(xy 86.099872 -261.402503) (xy 86.057251 -261.377896) (xy 86.01913 -261.346771) (xy 85.986495 -261.309934)
			(xy 85.960192 -261.268338) (xy 85.940901 -261.223062) (xy 85.929124 -261.175278) (xy 85.925164 -261.126224)
			(xy 85.596222 -261.126224) (xy 85.595727 -261.150831) (xy 85.587832 -261.199408) (xy 85.572248 -261.246089)
			(xy 85.549377 -261.289666) (xy 85.519812 -261.32901) (xy 85.484319 -261.363102) (xy 85.443816 -261.391058)
			(xy 85.399354 -261.412156) (xy 85.352083 -261.425848) (xy 85.303228 -261.43178) (xy 85.254053 -261.429799)
			(xy 85.205834 -261.419955) (xy 85.159818 -261.402503) (xy 85.117197 -261.377896) (xy 85.079076 -261.346771)
			(xy 85.046441 -261.309934) (xy 85.020138 -261.268338) (xy 85.000847 -261.223062) (xy 84.98907 -261.175278)
			(xy 84.98511 -261.126224) (xy 84.656422 -261.126224) (xy 84.655927 -261.150831) (xy 84.648032 -261.199408)
			(xy 84.632448 -261.246089) (xy 84.609577 -261.289666) (xy 84.580012 -261.32901) (xy 84.544519 -261.363102)
			(xy 84.504016 -261.391058) (xy 84.459554 -261.412156) (xy 84.412283 -261.425848) (xy 84.363428 -261.43178)
			(xy 84.314253 -261.429799) (xy 84.266034 -261.419955) (xy 84.220018 -261.402503) (xy 84.177397 -261.377896)
			(xy 84.139276 -261.346771) (xy 84.106641 -261.309934) (xy 84.080338 -261.268338) (xy 84.061047 -261.223062)
			(xy 84.04927 -261.175278) (xy 84.04531 -261.126224) (xy 83.716368 -261.126224) (xy 83.715873 -261.150831)
			(xy 83.707978 -261.199408) (xy 83.692394 -261.246089) (xy 83.669523 -261.289666) (xy 83.639958 -261.32901)
			(xy 83.604465 -261.363102) (xy 83.563962 -261.391058) (xy 83.5195 -261.412156) (xy 83.472229 -261.425848)
			(xy 83.423374 -261.43178) (xy 83.374199 -261.429799) (xy 83.32598 -261.419955) (xy 83.279964 -261.402503)
			(xy 83.237343 -261.377896) (xy 83.199222 -261.346771) (xy 83.166587 -261.309934) (xy 83.140284 -261.268338)
			(xy 83.120993 -261.223062) (xy 83.109216 -261.175278) (xy 83.105256 -261.126224) (xy 82.776314 -261.126224)
			(xy 82.775819 -261.150831) (xy 82.767924 -261.199408) (xy 82.75234 -261.246089) (xy 82.729469 -261.289666)
			(xy 82.699904 -261.32901) (xy 82.664411 -261.363102) (xy 82.623908 -261.391058) (xy 82.579446 -261.412156)
			(xy 82.532175 -261.425848) (xy 82.48332 -261.43178) (xy 82.434145 -261.429799) (xy 82.385926 -261.419955)
			(xy 82.33991 -261.402503) (xy 82.297289 -261.377896) (xy 82.259168 -261.346771) (xy 82.226533 -261.309934)
			(xy 82.20023 -261.268338) (xy 82.180939 -261.223062) (xy 82.169162 -261.175278) (xy 82.165202 -261.126224)
			(xy 81.83626 -261.126224) (xy 81.835765 -261.150831) (xy 81.82787 -261.199408) (xy 81.812286 -261.246089)
			(xy 81.789415 -261.289666) (xy 81.75985 -261.32901) (xy 81.724357 -261.363102) (xy 81.683854 -261.391058)
			(xy 81.639392 -261.412156) (xy 81.592121 -261.425848) (xy 81.543266 -261.43178) (xy 81.494091 -261.429799)
			(xy 81.445872 -261.419955) (xy 81.399856 -261.402503) (xy 81.357235 -261.377896) (xy 81.319114 -261.346771)
			(xy 81.286479 -261.309934) (xy 81.260176 -261.268338) (xy 81.240885 -261.223062) (xy 81.229108 -261.175278)
			(xy 81.225148 -261.126224) (xy 79.956406 -261.126224) (xy 79.955911 -261.150831) (xy 79.948016 -261.199408)
			(xy 79.932432 -261.246089) (xy 79.909561 -261.289666) (xy 79.879996 -261.32901) (xy 79.844503 -261.363102)
			(xy 79.804 -261.391058) (xy 79.759538 -261.412156) (xy 79.712267 -261.425848) (xy 79.663412 -261.43178)
			(xy 79.614237 -261.429799) (xy 79.566018 -261.419955) (xy 79.520002 -261.402503) (xy 79.477381 -261.377896)
			(xy 79.43926 -261.346771) (xy 79.406625 -261.309934) (xy 79.380322 -261.268338) (xy 79.361031 -261.223062)
			(xy 79.349254 -261.175278) (xy 79.345294 -261.126224) (xy 79.016352 -261.126224) (xy 79.015857 -261.150831)
			(xy 79.007962 -261.199408) (xy 78.992378 -261.246089) (xy 78.969507 -261.289666) (xy 78.939942 -261.32901)
			(xy 78.904449 -261.363102) (xy 78.863946 -261.391058) (xy 78.819484 -261.412156) (xy 78.772213 -261.425848)
			(xy 78.723358 -261.43178) (xy 78.674183 -261.429799) (xy 78.625964 -261.419955) (xy 78.579948 -261.402503)
			(xy 78.537327 -261.377896) (xy 78.499206 -261.346771) (xy 78.466571 -261.309934) (xy 78.440268 -261.268338)
			(xy 78.420977 -261.223062) (xy 78.4092 -261.175278) (xy 78.40524 -261.126224) (xy 73.375774 -261.126224)
			(xy 73.375774 -261.670292) (xy 76.807072 -261.670292) (xy 76.811032 -261.621238) (xy 76.822809 -261.573454)
			(xy 76.8421 -261.528178) (xy 76.868403 -261.486582) (xy 76.901038 -261.449745) (xy 76.939159 -261.41862)
			(xy 76.98178 -261.394013) (xy 77.027796 -261.376561) (xy 77.076015 -261.366717) (xy 77.12519 -261.364736)
			(xy 77.174045 -261.370668) (xy 77.221316 -261.38436) (xy 77.265778 -261.405458) (xy 77.306281 -261.433414)
			(xy 77.341774 -261.467506) (xy 77.371339 -261.50685) (xy 77.39421 -261.550427) (xy 77.409794 -261.597108)
			(xy 77.417689 -261.645685) (xy 77.418184 -261.670292) (xy 77.417689 -261.694899) (xy 77.409794 -261.743476)
			(xy 77.39421 -261.790157) (xy 77.371339 -261.833734) (xy 77.341774 -261.873078) (xy 77.306281 -261.90717)
			(xy 77.265778 -261.935126) (xy 77.263451 -261.93623) (xy 79.815194 -261.93623) (xy 79.819154 -261.887176)
			(xy 79.830931 -261.839392) (xy 79.850222 -261.794116) (xy 79.876525 -261.75252) (xy 79.90916 -261.715683)
			(xy 79.947281 -261.684558) (xy 79.989902 -261.659951) (xy 80.035918 -261.642499) (xy 80.084137 -261.632655)
			(xy 80.133312 -261.630674) (xy 80.182167 -261.636606) (xy 80.229438 -261.650298) (xy 80.2739 -261.671396)
			(xy 80.314403 -261.699352) (xy 80.349896 -261.733444) (xy 80.379461 -261.772788) (xy 80.402332 -261.816365)
			(xy 80.417916 -261.863046) (xy 80.425811 -261.911623) (xy 80.426306 -261.93623) (xy 80.755248 -261.93623)
			(xy 80.759208 -261.887176) (xy 80.770985 -261.839392) (xy 80.790276 -261.794116) (xy 80.816579 -261.75252)
			(xy 80.849214 -261.715683) (xy 80.887335 -261.684558) (xy 80.929956 -261.659951) (xy 80.975972 -261.642499)
			(xy 81.024191 -261.632655) (xy 81.073366 -261.630674) (xy 81.122221 -261.636606) (xy 81.169492 -261.650298)
			(xy 81.213954 -261.671396) (xy 81.254457 -261.699352) (xy 81.28995 -261.733444) (xy 81.319515 -261.772788)
			(xy 81.342386 -261.816365) (xy 81.35797 -261.863046) (xy 81.365865 -261.911623) (xy 81.36636 -261.93623)
			(xy 81.695302 -261.93623) (xy 81.699262 -261.887176) (xy 81.711039 -261.839392) (xy 81.73033 -261.794116)
			(xy 81.756633 -261.75252) (xy 81.789268 -261.715683) (xy 81.827389 -261.684558) (xy 81.87001 -261.659951)
			(xy 81.916026 -261.642499) (xy 81.964245 -261.632655) (xy 82.01342 -261.630674) (xy 82.062275 -261.636606)
			(xy 82.109546 -261.650298) (xy 82.154008 -261.671396) (xy 82.194511 -261.699352) (xy 82.230004 -261.733444)
			(xy 82.259569 -261.772788) (xy 82.28244 -261.816365) (xy 82.298024 -261.863046) (xy 82.305919 -261.911623)
			(xy 82.306414 -261.93623) (xy 82.624671 -261.93623) (xy 82.628766 -261.885502) (xy 82.640945 -261.836088)
			(xy 82.660893 -261.789268) (xy 82.688094 -261.746254) (xy 82.721842 -261.70816) (xy 82.761264 -261.675973)
			(xy 82.805338 -261.650527) (xy 82.852924 -261.63248) (xy 82.902788 -261.6223) (xy 82.95364 -261.620251)
			(xy 83.004161 -261.626385) (xy 83.053045 -261.640545) (xy 83.099024 -261.662362) (xy 83.140908 -261.691272)
			(xy 83.177612 -261.726527) (xy 83.208185 -261.767213) (xy 83.231836 -261.812276) (xy 83.247952 -261.86055)
			(xy 83.256116 -261.910784) (xy 83.256628 -261.93623) (xy 83.575156 -261.93623) (xy 83.579116 -261.887176)
			(xy 83.590893 -261.839392) (xy 83.610184 -261.794116) (xy 83.636487 -261.75252) (xy 83.669122 -261.715683)
			(xy 83.707243 -261.684558) (xy 83.749864 -261.659951) (xy 83.79588 -261.642499) (xy 83.844099 -261.632655)
			(xy 83.893274 -261.630674) (xy 83.942129 -261.636606) (xy 83.9894 -261.650298) (xy 84.033862 -261.671396)
			(xy 84.074365 -261.699352) (xy 84.109858 -261.733444) (xy 84.139423 -261.772788) (xy 84.162294 -261.816365)
			(xy 84.177878 -261.863046) (xy 84.185773 -261.911623) (xy 84.186268 -261.93623) (xy 84.51521 -261.93623)
			(xy 84.51917 -261.887176) (xy 84.530947 -261.839392) (xy 84.550238 -261.794116) (xy 84.576541 -261.75252)
			(xy 84.609176 -261.715683) (xy 84.647297 -261.684558) (xy 84.689918 -261.659951) (xy 84.735934 -261.642499)
			(xy 84.784153 -261.632655) (xy 84.833328 -261.630674) (xy 84.882183 -261.636606) (xy 84.929454 -261.650298)
			(xy 84.973916 -261.671396) (xy 85.014419 -261.699352) (xy 85.049912 -261.733444) (xy 85.079477 -261.772788)
			(xy 85.102348 -261.816365) (xy 85.117932 -261.863046) (xy 85.125827 -261.911623) (xy 85.126322 -261.93623)
			(xy 85.444833 -261.93623) (xy 85.448928 -261.885502) (xy 85.461107 -261.836088) (xy 85.481055 -261.789268)
			(xy 85.508256 -261.746254) (xy 85.542004 -261.70816) (xy 85.581426 -261.675973) (xy 85.6255 -261.650527)
			(xy 85.673086 -261.63248) (xy 85.72295 -261.6223) (xy 85.773802 -261.620251) (xy 85.824323 -261.626385)
			(xy 85.873207 -261.640545) (xy 85.919186 -261.662362) (xy 85.96107 -261.691272) (xy 85.997774 -261.726527)
			(xy 86.028347 -261.767213) (xy 86.051998 -261.812276) (xy 86.068114 -261.86055) (xy 86.076278 -261.910784)
			(xy 86.07679 -261.93623) (xy 86.395318 -261.93623) (xy 86.399278 -261.887176) (xy 86.411055 -261.839392)
			(xy 86.430346 -261.794116) (xy 86.456649 -261.75252) (xy 86.489284 -261.715683) (xy 86.527405 -261.684558)
			(xy 86.570026 -261.659951) (xy 86.616042 -261.642499) (xy 86.664261 -261.632655) (xy 86.713436 -261.630674)
			(xy 86.762291 -261.636606) (xy 86.809562 -261.650298) (xy 86.854024 -261.671396) (xy 86.894527 -261.699352)
			(xy 86.93002 -261.733444) (xy 86.959585 -261.772788) (xy 86.982456 -261.816365) (xy 86.99804 -261.863046)
			(xy 87.005935 -261.911623) (xy 87.00643 -261.93623) (xy 87.335118 -261.93623) (xy 87.339078 -261.887176)
			(xy 87.350855 -261.839392) (xy 87.370146 -261.794116) (xy 87.396449 -261.75252) (xy 87.429084 -261.715683)
			(xy 87.467205 -261.684558) (xy 87.509826 -261.659951) (xy 87.555842 -261.642499) (xy 87.604061 -261.632655)
			(xy 87.653236 -261.630674) (xy 87.702091 -261.636606) (xy 87.749362 -261.650298) (xy 87.793824 -261.671396)
			(xy 87.834327 -261.699352) (xy 87.86982 -261.733444) (xy 87.899385 -261.772788) (xy 87.922256 -261.816365)
			(xy 87.93784 -261.863046) (xy 87.945735 -261.911623) (xy 87.94623 -261.93623) (xy 88.275172 -261.93623)
			(xy 88.279132 -261.887176) (xy 88.290909 -261.839392) (xy 88.3102 -261.794116) (xy 88.336503 -261.75252)
			(xy 88.369138 -261.715683) (xy 88.407259 -261.684558) (xy 88.44988 -261.659951) (xy 88.495896 -261.642499)
			(xy 88.544115 -261.632655) (xy 88.59329 -261.630674) (xy 88.642145 -261.636606) (xy 88.689416 -261.650298)
			(xy 88.733878 -261.671396) (xy 88.774381 -261.699352) (xy 88.809874 -261.733444) (xy 88.839439 -261.772788)
			(xy 88.86231 -261.816365) (xy 88.877894 -261.863046) (xy 88.885789 -261.911623) (xy 88.886284 -261.93623)
			(xy 89.204795 -261.93623) (xy 89.20889 -261.885502) (xy 89.221069 -261.836088) (xy 89.241017 -261.789268)
			(xy 89.268218 -261.746254) (xy 89.301966 -261.70816) (xy 89.341388 -261.675973) (xy 89.385462 -261.650527)
			(xy 89.433048 -261.63248) (xy 89.482912 -261.6223) (xy 89.533764 -261.620251) (xy 89.584285 -261.626385)
			(xy 89.633169 -261.640545) (xy 89.679148 -261.662362) (xy 89.721032 -261.691272) (xy 89.757736 -261.726527)
			(xy 89.788309 -261.767213) (xy 89.81196 -261.812276) (xy 89.828076 -261.86055) (xy 89.83624 -261.910784)
			(xy 89.836752 -261.93623) (xy 90.15528 -261.93623) (xy 90.15924 -261.887176) (xy 90.171017 -261.839392)
			(xy 90.190308 -261.794116) (xy 90.216611 -261.75252) (xy 90.249246 -261.715683) (xy 90.287367 -261.684558)
			(xy 90.329988 -261.659951) (xy 90.376004 -261.642499) (xy 90.424223 -261.632655) (xy 90.473398 -261.630674)
			(xy 90.522253 -261.636606) (xy 90.569524 -261.650298) (xy 90.613986 -261.671396) (xy 90.654489 -261.699352)
			(xy 90.689982 -261.733444) (xy 90.719547 -261.772788) (xy 90.742418 -261.816365) (xy 90.758002 -261.863046)
			(xy 90.765897 -261.911623) (xy 90.766392 -261.93623) (xy 91.095334 -261.93623) (xy 91.099294 -261.887176)
			(xy 91.111071 -261.839392) (xy 91.130362 -261.794116) (xy 91.156665 -261.75252) (xy 91.1893 -261.715683)
			(xy 91.227421 -261.684558) (xy 91.270042 -261.659951) (xy 91.316058 -261.642499) (xy 91.364277 -261.632655)
			(xy 91.413452 -261.630674) (xy 91.462307 -261.636606) (xy 91.509578 -261.650298) (xy 91.55404 -261.671396)
			(xy 91.594543 -261.699352) (xy 91.630036 -261.733444) (xy 91.659601 -261.772788) (xy 91.682472 -261.816365)
			(xy 91.698056 -261.863046) (xy 91.705951 -261.911623) (xy 91.706446 -261.93623) (xy 92.024703 -261.93623)
			(xy 92.028798 -261.885502) (xy 92.040977 -261.836088) (xy 92.060925 -261.789268) (xy 92.088126 -261.746254)
			(xy 92.121874 -261.70816) (xy 92.161296 -261.675973) (xy 92.20537 -261.650527) (xy 92.252956 -261.63248)
			(xy 92.30282 -261.6223) (xy 92.353672 -261.620251) (xy 92.404193 -261.626385) (xy 92.453077 -261.640545)
			(xy 92.499056 -261.662362) (xy 92.54094 -261.691272) (xy 92.577644 -261.726527) (xy 92.608217 -261.767213)
			(xy 92.631868 -261.812276) (xy 92.647984 -261.86055) (xy 92.656148 -261.910784) (xy 92.65666 -261.93623)
			(xy 92.975188 -261.93623) (xy 92.979148 -261.887176) (xy 92.990925 -261.839392) (xy 93.010216 -261.794116)
			(xy 93.036519 -261.75252) (xy 93.069154 -261.715683) (xy 93.107275 -261.684558) (xy 93.149896 -261.659951)
			(xy 93.195912 -261.642499) (xy 93.244131 -261.632655) (xy 93.293306 -261.630674) (xy 93.342161 -261.636606)
			(xy 93.389432 -261.650298) (xy 93.433894 -261.671396) (xy 93.474397 -261.699352) (xy 93.50989 -261.733444)
			(xy 93.539455 -261.772788) (xy 93.562326 -261.816365) (xy 93.57791 -261.863046) (xy 93.585805 -261.911623)
			(xy 93.5863 -261.93623) (xy 93.915242 -261.93623) (xy 93.919202 -261.887176) (xy 93.930979 -261.839392)
			(xy 93.95027 -261.794116) (xy 93.976573 -261.75252) (xy 94.009208 -261.715683) (xy 94.047329 -261.684558)
			(xy 94.08995 -261.659951) (xy 94.135966 -261.642499) (xy 94.184185 -261.632655) (xy 94.23336 -261.630674)
			(xy 94.282215 -261.636606) (xy 94.329486 -261.650298) (xy 94.373948 -261.671396) (xy 94.414451 -261.699352)
			(xy 94.449944 -261.733444) (xy 94.479509 -261.772788) (xy 94.50238 -261.816365) (xy 94.517964 -261.863046)
			(xy 94.525859 -261.911623) (xy 94.526354 -261.93623) (xy 94.855296 -261.93623) (xy 94.859256 -261.887176)
			(xy 94.871033 -261.839392) (xy 94.890324 -261.794116) (xy 94.916627 -261.75252) (xy 94.949262 -261.715683)
			(xy 94.987383 -261.684558) (xy 95.030004 -261.659951) (xy 95.07602 -261.642499) (xy 95.124239 -261.632655)
			(xy 95.173414 -261.630674) (xy 95.222269 -261.636606) (xy 95.26954 -261.650298) (xy 95.314002 -261.671396)
			(xy 95.354505 -261.699352) (xy 95.389998 -261.733444) (xy 95.419563 -261.772788) (xy 95.442434 -261.816365)
			(xy 95.458018 -261.863046) (xy 95.465913 -261.911623) (xy 95.466408 -261.93623) (xy 95.784919 -261.93623)
			(xy 95.789014 -261.885502) (xy 95.801193 -261.836088) (xy 95.821141 -261.789268) (xy 95.848342 -261.746254)
			(xy 95.88209 -261.70816) (xy 95.921512 -261.675973) (xy 95.965586 -261.650527) (xy 96.013172 -261.63248)
			(xy 96.063036 -261.6223) (xy 96.113888 -261.620251) (xy 96.164409 -261.626385) (xy 96.213293 -261.640545)
			(xy 96.259272 -261.662362) (xy 96.301156 -261.691272) (xy 96.33786 -261.726527) (xy 96.368433 -261.767213)
			(xy 96.392084 -261.812276) (xy 96.4082 -261.86055) (xy 96.416364 -261.910784) (xy 96.416876 -261.93623)
			(xy 97.675204 -261.93623) (xy 97.679164 -261.887176) (xy 97.690941 -261.839392) (xy 97.710232 -261.794116)
			(xy 97.736535 -261.75252) (xy 97.76917 -261.715683) (xy 97.807291 -261.684558) (xy 97.849912 -261.659951)
			(xy 97.895928 -261.642499) (xy 97.944147 -261.632655) (xy 97.993322 -261.630674) (xy 98.042177 -261.636606)
			(xy 98.089448 -261.650298) (xy 98.13391 -261.671396) (xy 98.174413 -261.699352) (xy 98.209906 -261.733444)
			(xy 98.239471 -261.772788) (xy 98.262342 -261.816365) (xy 98.277926 -261.863046) (xy 98.285821 -261.911623)
			(xy 98.286316 -261.93623) (xy 99.555312 -261.93623) (xy 99.559272 -261.887176) (xy 99.571049 -261.839392)
			(xy 99.59034 -261.794116) (xy 99.616643 -261.75252) (xy 99.649278 -261.715683) (xy 99.687399 -261.684558)
			(xy 99.73002 -261.659951) (xy 99.776036 -261.642499) (xy 99.824255 -261.632655) (xy 99.87343 -261.630674)
			(xy 99.922285 -261.636606) (xy 99.969556 -261.650298) (xy 100.014018 -261.671396) (xy 100.054521 -261.699352)
			(xy 100.090014 -261.733444) (xy 100.119579 -261.772788) (xy 100.14245 -261.816365) (xy 100.158034 -261.863046)
			(xy 100.165929 -261.911623) (xy 100.166424 -261.93623) (xy 100.165929 -261.960837) (xy 100.158034 -262.009414)
			(xy 100.14245 -262.056095) (xy 100.119579 -262.099672) (xy 100.090014 -262.139016) (xy 100.054521 -262.173108)
			(xy 100.014018 -262.201064) (xy 99.969556 -262.222162) (xy 99.922285 -262.235854) (xy 99.87343 -262.241786)
			(xy 99.824255 -262.239805) (xy 99.776036 -262.229961) (xy 99.73002 -262.212509) (xy 99.687399 -262.187902)
			(xy 99.649278 -262.156777) (xy 99.616643 -262.11994) (xy 99.59034 -262.078344) (xy 99.571049 -262.033068)
			(xy 99.559272 -261.985284) (xy 99.555312 -261.93623) (xy 98.286316 -261.93623) (xy 98.285821 -261.960837)
			(xy 98.277926 -262.009414) (xy 98.262342 -262.056095) (xy 98.239471 -262.099672) (xy 98.209906 -262.139016)
			(xy 98.174413 -262.173108) (xy 98.13391 -262.201064) (xy 98.089448 -262.222162) (xy 98.042177 -262.235854)
			(xy 97.993322 -262.241786) (xy 97.944147 -262.239805) (xy 97.895928 -262.229961) (xy 97.849912 -262.212509)
			(xy 97.807291 -262.187902) (xy 97.76917 -262.156777) (xy 97.736535 -262.11994) (xy 97.710232 -262.078344)
			(xy 97.690941 -262.033068) (xy 97.679164 -261.985284) (xy 97.675204 -261.93623) (xy 96.416876 -261.93623)
			(xy 96.416364 -261.961676) (xy 96.4082 -262.01191) (xy 96.392084 -262.060184) (xy 96.368433 -262.105247)
			(xy 96.33786 -262.145933) (xy 96.301156 -262.181188) (xy 96.259272 -262.210098) (xy 96.213293 -262.231915)
			(xy 96.164409 -262.246075) (xy 96.113888 -262.252209) (xy 96.063036 -262.25016) (xy 96.013172 -262.23998)
			(xy 95.965586 -262.221933) (xy 95.921512 -262.196487) (xy 95.88209 -262.1643) (xy 95.848342 -262.126206)
			(xy 95.821141 -262.083192) (xy 95.801193 -262.036372) (xy 95.789014 -261.986958) (xy 95.784919 -261.93623)
			(xy 95.466408 -261.93623) (xy 95.465913 -261.960837) (xy 95.458018 -262.009414) (xy 95.442434 -262.056095)
			(xy 95.419563 -262.099672) (xy 95.389998 -262.139016) (xy 95.354505 -262.173108) (xy 95.314002 -262.201064)
			(xy 95.26954 -262.222162) (xy 95.222269 -262.235854) (xy 95.173414 -262.241786) (xy 95.124239 -262.239805)
			(xy 95.07602 -262.229961) (xy 95.030004 -262.212509) (xy 94.987383 -262.187902) (xy 94.949262 -262.156777)
			(xy 94.916627 -262.11994) (xy 94.890324 -262.078344) (xy 94.871033 -262.033068) (xy 94.859256 -261.985284)
			(xy 94.855296 -261.93623) (xy 94.526354 -261.93623) (xy 94.525859 -261.960837) (xy 94.517964 -262.009414)
			(xy 94.50238 -262.056095) (xy 94.479509 -262.099672) (xy 94.449944 -262.139016) (xy 94.414451 -262.173108)
			(xy 94.373948 -262.201064) (xy 94.329486 -262.222162) (xy 94.282215 -262.235854) (xy 94.23336 -262.241786)
			(xy 94.184185 -262.239805) (xy 94.135966 -262.229961) (xy 94.08995 -262.212509) (xy 94.047329 -262.187902)
			(xy 94.009208 -262.156777) (xy 93.976573 -262.11994) (xy 93.95027 -262.078344) (xy 93.930979 -262.033068)
			(xy 93.919202 -261.985284) (xy 93.915242 -261.93623) (xy 93.5863 -261.93623) (xy 93.585805 -261.960837)
			(xy 93.57791 -262.009414) (xy 93.562326 -262.056095) (xy 93.539455 -262.099672) (xy 93.50989 -262.139016)
			(xy 93.474397 -262.173108) (xy 93.433894 -262.201064) (xy 93.389432 -262.222162) (xy 93.342161 -262.235854)
			(xy 93.293306 -262.241786) (xy 93.244131 -262.239805) (xy 93.195912 -262.229961) (xy 93.149896 -262.212509)
			(xy 93.107275 -262.187902) (xy 93.069154 -262.156777) (xy 93.036519 -262.11994) (xy 93.010216 -262.078344)
			(xy 92.990925 -262.033068) (xy 92.979148 -261.985284) (xy 92.975188 -261.93623) (xy 92.65666 -261.93623)
			(xy 92.656148 -261.961676) (xy 92.647984 -262.01191) (xy 92.631868 -262.060184) (xy 92.608217 -262.105247)
			(xy 92.577644 -262.145933) (xy 92.54094 -262.181188) (xy 92.499056 -262.210098) (xy 92.453077 -262.231915)
			(xy 92.404193 -262.246075) (xy 92.353672 -262.252209) (xy 92.30282 -262.25016) (xy 92.252956 -262.23998)
			(xy 92.20537 -262.221933) (xy 92.161296 -262.196487) (xy 92.121874 -262.1643) (xy 92.088126 -262.126206)
			(xy 92.060925 -262.083192) (xy 92.040977 -262.036372) (xy 92.028798 -261.986958) (xy 92.024703 -261.93623)
			(xy 91.706446 -261.93623) (xy 91.705951 -261.960837) (xy 91.698056 -262.009414) (xy 91.682472 -262.056095)
			(xy 91.659601 -262.099672) (xy 91.630036 -262.139016) (xy 91.594543 -262.173108) (xy 91.55404 -262.201064)
			(xy 91.509578 -262.222162) (xy 91.462307 -262.235854) (xy 91.413452 -262.241786) (xy 91.364277 -262.239805)
			(xy 91.316058 -262.229961) (xy 91.270042 -262.212509) (xy 91.227421 -262.187902) (xy 91.1893 -262.156777)
			(xy 91.156665 -262.11994) (xy 91.130362 -262.078344) (xy 91.111071 -262.033068) (xy 91.099294 -261.985284)
			(xy 91.095334 -261.93623) (xy 90.766392 -261.93623) (xy 90.765897 -261.960837) (xy 90.758002 -262.009414)
			(xy 90.742418 -262.056095) (xy 90.719547 -262.099672) (xy 90.689982 -262.139016) (xy 90.654489 -262.173108)
			(xy 90.613986 -262.201064) (xy 90.569524 -262.222162) (xy 90.522253 -262.235854) (xy 90.473398 -262.241786)
			(xy 90.424223 -262.239805) (xy 90.376004 -262.229961) (xy 90.329988 -262.212509) (xy 90.287367 -262.187902)
			(xy 90.249246 -262.156777) (xy 90.216611 -262.11994) (xy 90.190308 -262.078344) (xy 90.171017 -262.033068)
			(xy 90.15924 -261.985284) (xy 90.15528 -261.93623) (xy 89.836752 -261.93623) (xy 89.83624 -261.961676)
			(xy 89.828076 -262.01191) (xy 89.81196 -262.060184) (xy 89.788309 -262.105247) (xy 89.757736 -262.145933)
			(xy 89.721032 -262.181188) (xy 89.679148 -262.210098) (xy 89.633169 -262.231915) (xy 89.584285 -262.246075)
			(xy 89.533764 -262.252209) (xy 89.482912 -262.25016) (xy 89.433048 -262.23998) (xy 89.385462 -262.221933)
			(xy 89.341388 -262.196487) (xy 89.301966 -262.1643) (xy 89.268218 -262.126206) (xy 89.241017 -262.083192)
			(xy 89.221069 -262.036372) (xy 89.20889 -261.986958) (xy 89.204795 -261.93623) (xy 88.886284 -261.93623)
			(xy 88.885789 -261.960837) (xy 88.877894 -262.009414) (xy 88.86231 -262.056095) (xy 88.839439 -262.099672)
			(xy 88.809874 -262.139016) (xy 88.774381 -262.173108) (xy 88.733878 -262.201064) (xy 88.689416 -262.222162)
			(xy 88.642145 -262.235854) (xy 88.59329 -262.241786) (xy 88.544115 -262.239805) (xy 88.495896 -262.229961)
			(xy 88.44988 -262.212509) (xy 88.407259 -262.187902) (xy 88.369138 -262.156777) (xy 88.336503 -262.11994)
			(xy 88.3102 -262.078344) (xy 88.290909 -262.033068) (xy 88.279132 -261.985284) (xy 88.275172 -261.93623)
			(xy 87.94623 -261.93623) (xy 87.945735 -261.960837) (xy 87.93784 -262.009414) (xy 87.922256 -262.056095)
			(xy 87.899385 -262.099672) (xy 87.86982 -262.139016) (xy 87.834327 -262.173108) (xy 87.793824 -262.201064)
			(xy 87.749362 -262.222162) (xy 87.702091 -262.235854) (xy 87.653236 -262.241786) (xy 87.604061 -262.239805)
			(xy 87.555842 -262.229961) (xy 87.509826 -262.212509) (xy 87.467205 -262.187902) (xy 87.429084 -262.156777)
			(xy 87.396449 -262.11994) (xy 87.370146 -262.078344) (xy 87.350855 -262.033068) (xy 87.339078 -261.985284)
			(xy 87.335118 -261.93623) (xy 87.00643 -261.93623) (xy 87.005935 -261.960837) (xy 86.99804 -262.009414)
			(xy 86.982456 -262.056095) (xy 86.959585 -262.099672) (xy 86.93002 -262.139016) (xy 86.894527 -262.173108)
			(xy 86.854024 -262.201064) (xy 86.809562 -262.222162) (xy 86.762291 -262.235854) (xy 86.713436 -262.241786)
			(xy 86.664261 -262.239805) (xy 86.616042 -262.229961) (xy 86.570026 -262.212509) (xy 86.527405 -262.187902)
			(xy 86.489284 -262.156777) (xy 86.456649 -262.11994) (xy 86.430346 -262.078344) (xy 86.411055 -262.033068)
			(xy 86.399278 -261.985284) (xy 86.395318 -261.93623) (xy 86.07679 -261.93623) (xy 86.076278 -261.961676)
			(xy 86.068114 -262.01191) (xy 86.051998 -262.060184) (xy 86.028347 -262.105247) (xy 85.997774 -262.145933)
			(xy 85.96107 -262.181188) (xy 85.919186 -262.210098) (xy 85.873207 -262.231915) (xy 85.824323 -262.246075)
			(xy 85.773802 -262.252209) (xy 85.72295 -262.25016) (xy 85.673086 -262.23998) (xy 85.6255 -262.221933)
			(xy 85.581426 -262.196487) (xy 85.542004 -262.1643) (xy 85.508256 -262.126206) (xy 85.481055 -262.083192)
			(xy 85.461107 -262.036372) (xy 85.448928 -261.986958) (xy 85.444833 -261.93623) (xy 85.126322 -261.93623)
			(xy 85.125827 -261.960837) (xy 85.117932 -262.009414) (xy 85.102348 -262.056095) (xy 85.079477 -262.099672)
			(xy 85.049912 -262.139016) (xy 85.014419 -262.173108) (xy 84.973916 -262.201064) (xy 84.929454 -262.222162)
			(xy 84.882183 -262.235854) (xy 84.833328 -262.241786) (xy 84.784153 -262.239805) (xy 84.735934 -262.229961)
			(xy 84.689918 -262.212509) (xy 84.647297 -262.187902) (xy 84.609176 -262.156777) (xy 84.576541 -262.11994)
			(xy 84.550238 -262.078344) (xy 84.530947 -262.033068) (xy 84.51917 -261.985284) (xy 84.51521 -261.93623)
			(xy 84.186268 -261.93623) (xy 84.185773 -261.960837) (xy 84.177878 -262.009414) (xy 84.162294 -262.056095)
			(xy 84.139423 -262.099672) (xy 84.109858 -262.139016) (xy 84.074365 -262.173108) (xy 84.033862 -262.201064)
			(xy 83.9894 -262.222162) (xy 83.942129 -262.235854) (xy 83.893274 -262.241786) (xy 83.844099 -262.239805)
			(xy 83.79588 -262.229961) (xy 83.749864 -262.212509) (xy 83.707243 -262.187902) (xy 83.669122 -262.156777)
			(xy 83.636487 -262.11994) (xy 83.610184 -262.078344) (xy 83.590893 -262.033068) (xy 83.579116 -261.985284)
			(xy 83.575156 -261.93623) (xy 83.256628 -261.93623) (xy 83.256116 -261.961676) (xy 83.247952 -262.01191)
			(xy 83.231836 -262.060184) (xy 83.208185 -262.105247) (xy 83.177612 -262.145933) (xy 83.140908 -262.181188)
			(xy 83.099024 -262.210098) (xy 83.053045 -262.231915) (xy 83.004161 -262.246075) (xy 82.95364 -262.252209)
			(xy 82.902788 -262.25016) (xy 82.852924 -262.23998) (xy 82.805338 -262.221933) (xy 82.761264 -262.196487)
			(xy 82.721842 -262.1643) (xy 82.688094 -262.126206) (xy 82.660893 -262.083192) (xy 82.640945 -262.036372)
			(xy 82.628766 -261.986958) (xy 82.624671 -261.93623) (xy 82.306414 -261.93623) (xy 82.305919 -261.960837)
			(xy 82.298024 -262.009414) (xy 82.28244 -262.056095) (xy 82.259569 -262.099672) (xy 82.230004 -262.139016)
			(xy 82.194511 -262.173108) (xy 82.154008 -262.201064) (xy 82.109546 -262.222162) (xy 82.062275 -262.235854)
			(xy 82.01342 -262.241786) (xy 81.964245 -262.239805) (xy 81.916026 -262.229961) (xy 81.87001 -262.212509)
			(xy 81.827389 -262.187902) (xy 81.789268 -262.156777) (xy 81.756633 -262.11994) (xy 81.73033 -262.078344)
			(xy 81.711039 -262.033068) (xy 81.699262 -261.985284) (xy 81.695302 -261.93623) (xy 81.36636 -261.93623)
			(xy 81.365865 -261.960837) (xy 81.35797 -262.009414) (xy 81.342386 -262.056095) (xy 81.319515 -262.099672)
			(xy 81.28995 -262.139016) (xy 81.254457 -262.173108) (xy 81.213954 -262.201064) (xy 81.169492 -262.222162)
			(xy 81.122221 -262.235854) (xy 81.073366 -262.241786) (xy 81.024191 -262.239805) (xy 80.975972 -262.229961)
			(xy 80.929956 -262.212509) (xy 80.887335 -262.187902) (xy 80.849214 -262.156777) (xy 80.816579 -262.11994)
			(xy 80.790276 -262.078344) (xy 80.770985 -262.033068) (xy 80.759208 -261.985284) (xy 80.755248 -261.93623)
			(xy 80.426306 -261.93623) (xy 80.425811 -261.960837) (xy 80.417916 -262.009414) (xy 80.402332 -262.056095)
			(xy 80.379461 -262.099672) (xy 80.349896 -262.139016) (xy 80.314403 -262.173108) (xy 80.2739 -262.201064)
			(xy 80.229438 -262.222162) (xy 80.182167 -262.235854) (xy 80.133312 -262.241786) (xy 80.084137 -262.239805)
			(xy 80.035918 -262.229961) (xy 79.989902 -262.212509) (xy 79.947281 -262.187902) (xy 79.90916 -262.156777)
			(xy 79.876525 -262.11994) (xy 79.850222 -262.078344) (xy 79.830931 -262.033068) (xy 79.819154 -261.985284)
			(xy 79.815194 -261.93623) (xy 77.263451 -261.93623) (xy 77.221316 -261.956224) (xy 77.174045 -261.969916)
			(xy 77.12519 -261.975848) (xy 77.076015 -261.973867) (xy 77.027796 -261.964023) (xy 76.98178 -261.946571)
			(xy 76.939159 -261.921964) (xy 76.901038 -261.890839) (xy 76.868403 -261.854002) (xy 76.8421 -261.812406)
			(xy 76.822809 -261.76713) (xy 76.811032 -261.719346) (xy 76.807072 -261.670292) (xy 73.375774 -261.670292)
			(xy 73.375774 -262.746236) (xy 78.40524 -262.746236) (xy 78.4092 -262.697182) (xy 78.420977 -262.649398)
			(xy 78.440268 -262.604122) (xy 78.466571 -262.562526) (xy 78.499206 -262.525689) (xy 78.537327 -262.494564)
			(xy 78.579948 -262.469957) (xy 78.625964 -262.452505) (xy 78.674183 -262.442661) (xy 78.723358 -262.44068)
			(xy 78.772213 -262.446612) (xy 78.819484 -262.460304) (xy 78.863946 -262.481402) (xy 78.904449 -262.509358)
			(xy 78.939942 -262.54345) (xy 78.969507 -262.582794) (xy 78.992378 -262.626371) (xy 79.007962 -262.673052)
			(xy 79.015857 -262.721629) (xy 79.016352 -262.746236) (xy 80.285348 -262.746236) (xy 80.289308 -262.697182)
			(xy 80.301085 -262.649398) (xy 80.320376 -262.604122) (xy 80.346679 -262.562526) (xy 80.379314 -262.525689)
			(xy 80.417435 -262.494564) (xy 80.460056 -262.469957) (xy 80.506072 -262.452505) (xy 80.554291 -262.442661)
			(xy 80.603466 -262.44068) (xy 80.652321 -262.446612) (xy 80.699592 -262.460304) (xy 80.744054 -262.481402)
			(xy 80.784557 -262.509358) (xy 80.82005 -262.54345) (xy 80.849615 -262.582794) (xy 80.872486 -262.626371)
			(xy 80.88807 -262.673052) (xy 80.895965 -262.721629) (xy 80.89646 -262.746236) (xy 81.214717 -262.746236)
			(xy 81.218812 -262.695508) (xy 81.230991 -262.646094) (xy 81.250939 -262.599274) (xy 81.27814 -262.55626)
			(xy 81.311888 -262.518166) (xy 81.35131 -262.485979) (xy 81.395384 -262.460533) (xy 81.44297 -262.442486)
			(xy 81.492834 -262.432306) (xy 81.543686 -262.430257) (xy 81.594207 -262.436391) (xy 81.643091 -262.450551)
			(xy 81.68907 -262.472368) (xy 81.730954 -262.501278) (xy 81.767658 -262.536533) (xy 81.798231 -262.577219)
			(xy 81.821882 -262.622282) (xy 81.837998 -262.670556) (xy 81.846162 -262.72079) (xy 81.846674 -262.746236)
			(xy 82.154771 -262.746236) (xy 82.158866 -262.695508) (xy 82.171045 -262.646094) (xy 82.190993 -262.599274)
			(xy 82.218194 -262.55626) (xy 82.251942 -262.518166) (xy 82.291364 -262.485979) (xy 82.335438 -262.460533)
			(xy 82.383024 -262.442486) (xy 82.432888 -262.432306) (xy 82.48374 -262.430257) (xy 82.534261 -262.436391)
			(xy 82.583145 -262.450551) (xy 82.629124 -262.472368) (xy 82.671008 -262.501278) (xy 82.707712 -262.536533)
			(xy 82.738285 -262.577219) (xy 82.761936 -262.622282) (xy 82.778052 -262.670556) (xy 82.786216 -262.72079)
			(xy 82.786728 -262.746236) (xy 83.105256 -262.746236) (xy 83.109216 -262.697182) (xy 83.120993 -262.649398)
			(xy 83.140284 -262.604122) (xy 83.166587 -262.562526) (xy 83.199222 -262.525689) (xy 83.237343 -262.494564)
			(xy 83.279964 -262.469957) (xy 83.32598 -262.452505) (xy 83.374199 -262.442661) (xy 83.423374 -262.44068)
			(xy 83.472229 -262.446612) (xy 83.5195 -262.460304) (xy 83.563962 -262.481402) (xy 83.604465 -262.509358)
			(xy 83.639958 -262.54345) (xy 83.669523 -262.582794) (xy 83.692394 -262.626371) (xy 83.707978 -262.673052)
			(xy 83.715873 -262.721629) (xy 83.716368 -262.746236) (xy 84.034879 -262.746236) (xy 84.038974 -262.695508)
			(xy 84.051153 -262.646094) (xy 84.071101 -262.599274) (xy 84.098302 -262.55626) (xy 84.13205 -262.518166)
			(xy 84.171472 -262.485979) (xy 84.215546 -262.460533) (xy 84.263132 -262.442486) (xy 84.312996 -262.432306)
			(xy 84.363848 -262.430257) (xy 84.414369 -262.436391) (xy 84.463253 -262.450551) (xy 84.509232 -262.472368)
			(xy 84.551116 -262.501278) (xy 84.58782 -262.536533) (xy 84.618393 -262.577219) (xy 84.642044 -262.622282)
			(xy 84.65816 -262.670556) (xy 84.666324 -262.72079) (xy 84.666836 -262.746236) (xy 84.98511 -262.746236)
			(xy 84.98907 -262.697182) (xy 85.000847 -262.649398) (xy 85.020138 -262.604122) (xy 85.046441 -262.562526)
			(xy 85.079076 -262.525689) (xy 85.117197 -262.494564) (xy 85.159818 -262.469957) (xy 85.205834 -262.452505)
			(xy 85.254053 -262.442661) (xy 85.303228 -262.44068) (xy 85.352083 -262.446612) (xy 85.399354 -262.460304)
			(xy 85.443816 -262.481402) (xy 85.484319 -262.509358) (xy 85.519812 -262.54345) (xy 85.549377 -262.582794)
			(xy 85.572248 -262.626371) (xy 85.587832 -262.673052) (xy 85.595727 -262.721629) (xy 85.596222 -262.746236)
			(xy 85.914733 -262.746236) (xy 85.918828 -262.695508) (xy 85.931007 -262.646094) (xy 85.950955 -262.599274)
			(xy 85.978156 -262.55626) (xy 86.011904 -262.518166) (xy 86.051326 -262.485979) (xy 86.0954 -262.460533)
			(xy 86.142986 -262.442486) (xy 86.19285 -262.432306) (xy 86.243702 -262.430257) (xy 86.294223 -262.436391)
			(xy 86.343107 -262.450551) (xy 86.389086 -262.472368) (xy 86.43097 -262.501278) (xy 86.467674 -262.536533)
			(xy 86.498247 -262.577219) (xy 86.521898 -262.622282) (xy 86.538014 -262.670556) (xy 86.546178 -262.72079)
			(xy 86.54669 -262.746236) (xy 86.865218 -262.746236) (xy 86.869178 -262.697182) (xy 86.880955 -262.649398)
			(xy 86.900246 -262.604122) (xy 86.926549 -262.562526) (xy 86.959184 -262.525689) (xy 86.997305 -262.494564)
			(xy 87.039926 -262.469957) (xy 87.085942 -262.452505) (xy 87.134161 -262.442661) (xy 87.183336 -262.44068)
			(xy 87.232191 -262.446612) (xy 87.279462 -262.460304) (xy 87.323924 -262.481402) (xy 87.364427 -262.509358)
			(xy 87.39992 -262.54345) (xy 87.429485 -262.582794) (xy 87.452356 -262.626371) (xy 87.46794 -262.673052)
			(xy 87.475835 -262.721629) (xy 87.47633 -262.746236) (xy 87.794841 -262.746236) (xy 87.798936 -262.695508)
			(xy 87.811115 -262.646094) (xy 87.831063 -262.599274) (xy 87.858264 -262.55626) (xy 87.892012 -262.518166)
			(xy 87.931434 -262.485979) (xy 87.975508 -262.460533) (xy 88.023094 -262.442486) (xy 88.072958 -262.432306)
			(xy 88.12381 -262.430257) (xy 88.174331 -262.436391) (xy 88.223215 -262.450551) (xy 88.269194 -262.472368)
			(xy 88.311078 -262.501278) (xy 88.347782 -262.536533) (xy 88.378355 -262.577219) (xy 88.402006 -262.622282)
			(xy 88.418122 -262.670556) (xy 88.426286 -262.72079) (xy 88.426798 -262.746236) (xy 88.734895 -262.746236)
			(xy 88.73899 -262.695508) (xy 88.751169 -262.646094) (xy 88.771117 -262.599274) (xy 88.798318 -262.55626)
			(xy 88.832066 -262.518166) (xy 88.871488 -262.485979) (xy 88.915562 -262.460533) (xy 88.963148 -262.442486)
			(xy 89.013012 -262.432306) (xy 89.063864 -262.430257) (xy 89.114385 -262.436391) (xy 89.163269 -262.450551)
			(xy 89.209248 -262.472368) (xy 89.251132 -262.501278) (xy 89.287836 -262.536533) (xy 89.318409 -262.577219)
			(xy 89.34206 -262.622282) (xy 89.358176 -262.670556) (xy 89.36634 -262.72079) (xy 89.366852 -262.746236)
			(xy 89.685126 -262.746236) (xy 89.689086 -262.697182) (xy 89.700863 -262.649398) (xy 89.720154 -262.604122)
			(xy 89.746457 -262.562526) (xy 89.779092 -262.525689) (xy 89.817213 -262.494564) (xy 89.859834 -262.469957)
			(xy 89.90585 -262.452505) (xy 89.954069 -262.442661) (xy 90.003244 -262.44068) (xy 90.052099 -262.446612)
			(xy 90.09937 -262.460304) (xy 90.143832 -262.481402) (xy 90.184335 -262.509358) (xy 90.219828 -262.54345)
			(xy 90.249393 -262.582794) (xy 90.272264 -262.626371) (xy 90.287848 -262.673052) (xy 90.295743 -262.721629)
			(xy 90.296238 -262.746236) (xy 90.614749 -262.746236) (xy 90.618844 -262.695508) (xy 90.631023 -262.646094)
			(xy 90.650971 -262.599274) (xy 90.678172 -262.55626) (xy 90.71192 -262.518166) (xy 90.751342 -262.485979)
			(xy 90.795416 -262.460533) (xy 90.843002 -262.442486) (xy 90.892866 -262.432306) (xy 90.943718 -262.430257)
			(xy 90.994239 -262.436391) (xy 91.043123 -262.450551) (xy 91.089102 -262.472368) (xy 91.130986 -262.501278)
			(xy 91.16769 -262.536533) (xy 91.198263 -262.577219) (xy 91.221914 -262.622282) (xy 91.23803 -262.670556)
			(xy 91.246194 -262.72079) (xy 91.246706 -262.746236) (xy 91.565234 -262.746236) (xy 91.569194 -262.697182)
			(xy 91.580971 -262.649398) (xy 91.600262 -262.604122) (xy 91.626565 -262.562526) (xy 91.6592 -262.525689)
			(xy 91.697321 -262.494564) (xy 91.739942 -262.469957) (xy 91.785958 -262.452505) (xy 91.834177 -262.442661)
			(xy 91.883352 -262.44068) (xy 91.932207 -262.446612) (xy 91.979478 -262.460304) (xy 92.02394 -262.481402)
			(xy 92.064443 -262.509358) (xy 92.099936 -262.54345) (xy 92.129501 -262.582794) (xy 92.152372 -262.626371)
			(xy 92.167956 -262.673052) (xy 92.175851 -262.721629) (xy 92.176346 -262.746236) (xy 92.494857 -262.746236)
			(xy 92.498952 -262.695508) (xy 92.511131 -262.646094) (xy 92.531079 -262.599274) (xy 92.55828 -262.55626)
			(xy 92.592028 -262.518166) (xy 92.63145 -262.485979) (xy 92.675524 -262.460533) (xy 92.72311 -262.442486)
			(xy 92.772974 -262.432306) (xy 92.823826 -262.430257) (xy 92.874347 -262.436391) (xy 92.923231 -262.450551)
			(xy 92.96921 -262.472368) (xy 93.011094 -262.501278) (xy 93.047798 -262.536533) (xy 93.078371 -262.577219)
			(xy 93.102022 -262.622282) (xy 93.118138 -262.670556) (xy 93.126302 -262.72079) (xy 93.126814 -262.746236)
			(xy 93.445342 -262.746236) (xy 93.449302 -262.697182) (xy 93.461079 -262.649398) (xy 93.48037 -262.604122)
			(xy 93.506673 -262.562526) (xy 93.539308 -262.525689) (xy 93.577429 -262.494564) (xy 93.62005 -262.469957)
			(xy 93.666066 -262.452505) (xy 93.714285 -262.442661) (xy 93.76346 -262.44068) (xy 93.812315 -262.446612)
			(xy 93.859586 -262.460304) (xy 93.904048 -262.481402) (xy 93.944551 -262.509358) (xy 93.980044 -262.54345)
			(xy 94.009609 -262.582794) (xy 94.03248 -262.626371) (xy 94.048064 -262.673052) (xy 94.055959 -262.721629)
			(xy 94.056454 -262.746236) (xy 94.374711 -262.746236) (xy 94.378806 -262.695508) (xy 94.390985 -262.646094)
			(xy 94.410933 -262.599274) (xy 94.438134 -262.55626) (xy 94.471882 -262.518166) (xy 94.511304 -262.485979)
			(xy 94.555378 -262.460533) (xy 94.602964 -262.442486) (xy 94.652828 -262.432306) (xy 94.70368 -262.430257)
			(xy 94.754201 -262.436391) (xy 94.803085 -262.450551) (xy 94.849064 -262.472368) (xy 94.890948 -262.501278)
			(xy 94.927652 -262.536533) (xy 94.958225 -262.577219) (xy 94.981876 -262.622282) (xy 94.997992 -262.670556)
			(xy 95.006156 -262.72079) (xy 95.006668 -262.746236) (xy 95.314765 -262.746236) (xy 95.31886 -262.695508)
			(xy 95.331039 -262.646094) (xy 95.350987 -262.599274) (xy 95.378188 -262.55626) (xy 95.411936 -262.518166)
			(xy 95.451358 -262.485979) (xy 95.495432 -262.460533) (xy 95.543018 -262.442486) (xy 95.592882 -262.432306)
			(xy 95.643734 -262.430257) (xy 95.694255 -262.436391) (xy 95.743139 -262.450551) (xy 95.789118 -262.472368)
			(xy 95.831002 -262.501278) (xy 95.867706 -262.536533) (xy 95.898279 -262.577219) (xy 95.92193 -262.622282)
			(xy 95.938046 -262.670556) (xy 95.94621 -262.72079) (xy 95.946722 -262.746236) (xy 96.26525 -262.746236)
			(xy 96.26921 -262.697182) (xy 96.280987 -262.649398) (xy 96.300278 -262.604122) (xy 96.326581 -262.562526)
			(xy 96.359216 -262.525689) (xy 96.397337 -262.494564) (xy 96.439958 -262.469957) (xy 96.485974 -262.452505)
			(xy 96.534193 -262.442661) (xy 96.583368 -262.44068) (xy 96.632223 -262.446612) (xy 96.679494 -262.460304)
			(xy 96.723956 -262.481402) (xy 96.764459 -262.509358) (xy 96.799952 -262.54345) (xy 96.829517 -262.582794)
			(xy 96.852388 -262.626371) (xy 96.867972 -262.673052) (xy 96.875867 -262.721629) (xy 96.876362 -262.746236)
			(xy 98.145358 -262.746236) (xy 98.149318 -262.697182) (xy 98.161095 -262.649398) (xy 98.180386 -262.604122)
			(xy 98.206689 -262.562526) (xy 98.239324 -262.525689) (xy 98.277445 -262.494564) (xy 98.320066 -262.469957)
			(xy 98.366082 -262.452505) (xy 98.414301 -262.442661) (xy 98.463476 -262.44068) (xy 98.512331 -262.446612)
			(xy 98.559602 -262.460304) (xy 98.604064 -262.481402) (xy 98.644567 -262.509358) (xy 98.68006 -262.54345)
			(xy 98.709625 -262.582794) (xy 98.732496 -262.626371) (xy 98.74808 -262.673052) (xy 98.755975 -262.721629)
			(xy 98.75647 -262.746236) (xy 100.025212 -262.746236) (xy 100.029172 -262.697182) (xy 100.040949 -262.649398)
			(xy 100.06024 -262.604122) (xy 100.086543 -262.562526) (xy 100.119178 -262.525689) (xy 100.157299 -262.494564)
			(xy 100.19992 -262.469957) (xy 100.245936 -262.452505) (xy 100.294155 -262.442661) (xy 100.34333 -262.44068)
			(xy 100.392185 -262.446612) (xy 100.439456 -262.460304) (xy 100.483918 -262.481402) (xy 100.524421 -262.509358)
			(xy 100.559914 -262.54345) (xy 100.589479 -262.582794) (xy 100.61235 -262.626371) (xy 100.627934 -262.673052)
			(xy 100.635829 -262.721629) (xy 100.636324 -262.746236) (xy 100.635829 -262.770843) (xy 100.627934 -262.81942)
			(xy 100.61235 -262.866101) (xy 100.589479 -262.909678) (xy 100.559914 -262.949022) (xy 100.524421 -262.983114)
			(xy 100.483918 -263.01107) (xy 100.439456 -263.032168) (xy 100.392185 -263.04586) (xy 100.34333 -263.051792)
			(xy 100.294155 -263.049811) (xy 100.245936 -263.039967) (xy 100.19992 -263.022515) (xy 100.157299 -262.997908)
			(xy 100.119178 -262.966783) (xy 100.086543 -262.929946) (xy 100.06024 -262.88835) (xy 100.040949 -262.843074)
			(xy 100.029172 -262.79529) (xy 100.025212 -262.746236) (xy 98.75647 -262.746236) (xy 98.755975 -262.770843)
			(xy 98.74808 -262.81942) (xy 98.732496 -262.866101) (xy 98.709625 -262.909678) (xy 98.68006 -262.949022)
			(xy 98.644567 -262.983114) (xy 98.604064 -263.01107) (xy 98.559602 -263.032168) (xy 98.512331 -263.04586)
			(xy 98.463476 -263.051792) (xy 98.414301 -263.049811) (xy 98.366082 -263.039967) (xy 98.320066 -263.022515)
			(xy 98.277445 -262.997908) (xy 98.239324 -262.966783) (xy 98.206689 -262.929946) (xy 98.180386 -262.88835)
			(xy 98.161095 -262.843074) (xy 98.149318 -262.79529) (xy 98.145358 -262.746236) (xy 96.876362 -262.746236)
			(xy 96.875867 -262.770843) (xy 96.867972 -262.81942) (xy 96.852388 -262.866101) (xy 96.829517 -262.909678)
			(xy 96.799952 -262.949022) (xy 96.764459 -262.983114) (xy 96.723956 -263.01107) (xy 96.679494 -263.032168)
			(xy 96.632223 -263.04586) (xy 96.583368 -263.051792) (xy 96.534193 -263.049811) (xy 96.485974 -263.039967)
			(xy 96.439958 -263.022515) (xy 96.397337 -262.997908) (xy 96.359216 -262.966783) (xy 96.326581 -262.929946)
			(xy 96.300278 -262.88835) (xy 96.280987 -262.843074) (xy 96.26921 -262.79529) (xy 96.26525 -262.746236)
			(xy 95.946722 -262.746236) (xy 95.94621 -262.771682) (xy 95.938046 -262.821916) (xy 95.92193 -262.87019)
			(xy 95.898279 -262.915253) (xy 95.867706 -262.955939) (xy 95.831002 -262.991194) (xy 95.789118 -263.020104)
			(xy 95.743139 -263.041921) (xy 95.694255 -263.056081) (xy 95.643734 -263.062215) (xy 95.592882 -263.060166)
			(xy 95.543018 -263.049986) (xy 95.495432 -263.031939) (xy 95.451358 -263.006493) (xy 95.411936 -262.974306)
			(xy 95.378188 -262.936212) (xy 95.350987 -262.893198) (xy 95.331039 -262.846378) (xy 95.31886 -262.796964)
			(xy 95.314765 -262.746236) (xy 95.006668 -262.746236) (xy 95.006156 -262.771682) (xy 94.997992 -262.821916)
			(xy 94.981876 -262.87019) (xy 94.958225 -262.915253) (xy 94.927652 -262.955939) (xy 94.890948 -262.991194)
			(xy 94.849064 -263.020104) (xy 94.803085 -263.041921) (xy 94.754201 -263.056081) (xy 94.70368 -263.062215)
			(xy 94.652828 -263.060166) (xy 94.602964 -263.049986) (xy 94.555378 -263.031939) (xy 94.511304 -263.006493)
			(xy 94.471882 -262.974306) (xy 94.438134 -262.936212) (xy 94.410933 -262.893198) (xy 94.390985 -262.846378)
			(xy 94.378806 -262.796964) (xy 94.374711 -262.746236) (xy 94.056454 -262.746236) (xy 94.055959 -262.770843)
			(xy 94.048064 -262.81942) (xy 94.03248 -262.866101) (xy 94.009609 -262.909678) (xy 93.980044 -262.949022)
			(xy 93.944551 -262.983114) (xy 93.904048 -263.01107) (xy 93.859586 -263.032168) (xy 93.812315 -263.04586)
			(xy 93.76346 -263.051792) (xy 93.714285 -263.049811) (xy 93.666066 -263.039967) (xy 93.62005 -263.022515)
			(xy 93.577429 -262.997908) (xy 93.539308 -262.966783) (xy 93.506673 -262.929946) (xy 93.48037 -262.88835)
			(xy 93.461079 -262.843074) (xy 93.449302 -262.79529) (xy 93.445342 -262.746236) (xy 93.126814 -262.746236)
			(xy 93.126302 -262.771682) (xy 93.118138 -262.821916) (xy 93.102022 -262.87019) (xy 93.078371 -262.915253)
			(xy 93.047798 -262.955939) (xy 93.011094 -262.991194) (xy 92.96921 -263.020104) (xy 92.923231 -263.041921)
			(xy 92.874347 -263.056081) (xy 92.823826 -263.062215) (xy 92.772974 -263.060166) (xy 92.72311 -263.049986)
			(xy 92.675524 -263.031939) (xy 92.63145 -263.006493) (xy 92.592028 -262.974306) (xy 92.55828 -262.936212)
			(xy 92.531079 -262.893198) (xy 92.511131 -262.846378) (xy 92.498952 -262.796964) (xy 92.494857 -262.746236)
			(xy 92.176346 -262.746236) (xy 92.175851 -262.770843) (xy 92.167956 -262.81942) (xy 92.152372 -262.866101)
			(xy 92.129501 -262.909678) (xy 92.099936 -262.949022) (xy 92.064443 -262.983114) (xy 92.02394 -263.01107)
			(xy 91.979478 -263.032168) (xy 91.932207 -263.04586) (xy 91.883352 -263.051792) (xy 91.834177 -263.049811)
			(xy 91.785958 -263.039967) (xy 91.739942 -263.022515) (xy 91.697321 -262.997908) (xy 91.6592 -262.966783)
			(xy 91.626565 -262.929946) (xy 91.600262 -262.88835) (xy 91.580971 -262.843074) (xy 91.569194 -262.79529)
			(xy 91.565234 -262.746236) (xy 91.246706 -262.746236) (xy 91.246194 -262.771682) (xy 91.23803 -262.821916)
			(xy 91.221914 -262.87019) (xy 91.198263 -262.915253) (xy 91.16769 -262.955939) (xy 91.130986 -262.991194)
			(xy 91.089102 -263.020104) (xy 91.043123 -263.041921) (xy 90.994239 -263.056081) (xy 90.943718 -263.062215)
			(xy 90.892866 -263.060166) (xy 90.843002 -263.049986) (xy 90.795416 -263.031939) (xy 90.751342 -263.006493)
			(xy 90.71192 -262.974306) (xy 90.678172 -262.936212) (xy 90.650971 -262.893198) (xy 90.631023 -262.846378)
			(xy 90.618844 -262.796964) (xy 90.614749 -262.746236) (xy 90.296238 -262.746236) (xy 90.295743 -262.770843)
			(xy 90.287848 -262.81942) (xy 90.272264 -262.866101) (xy 90.249393 -262.909678) (xy 90.219828 -262.949022)
			(xy 90.184335 -262.983114) (xy 90.143832 -263.01107) (xy 90.09937 -263.032168) (xy 90.052099 -263.04586)
			(xy 90.003244 -263.051792) (xy 89.954069 -263.049811) (xy 89.90585 -263.039967) (xy 89.859834 -263.022515)
			(xy 89.817213 -262.997908) (xy 89.779092 -262.966783) (xy 89.746457 -262.929946) (xy 89.720154 -262.88835)
			(xy 89.700863 -262.843074) (xy 89.689086 -262.79529) (xy 89.685126 -262.746236) (xy 89.366852 -262.746236)
			(xy 89.36634 -262.771682) (xy 89.358176 -262.821916) (xy 89.34206 -262.87019) (xy 89.318409 -262.915253)
			(xy 89.287836 -262.955939) (xy 89.251132 -262.991194) (xy 89.209248 -263.020104) (xy 89.163269 -263.041921)
			(xy 89.114385 -263.056081) (xy 89.063864 -263.062215) (xy 89.013012 -263.060166) (xy 88.963148 -263.049986)
			(xy 88.915562 -263.031939) (xy 88.871488 -263.006493) (xy 88.832066 -262.974306) (xy 88.798318 -262.936212)
			(xy 88.771117 -262.893198) (xy 88.751169 -262.846378) (xy 88.73899 -262.796964) (xy 88.734895 -262.746236)
			(xy 88.426798 -262.746236) (xy 88.426286 -262.771682) (xy 88.418122 -262.821916) (xy 88.402006 -262.87019)
			(xy 88.378355 -262.915253) (xy 88.347782 -262.955939) (xy 88.311078 -262.991194) (xy 88.269194 -263.020104)
			(xy 88.223215 -263.041921) (xy 88.174331 -263.056081) (xy 88.12381 -263.062215) (xy 88.072958 -263.060166)
			(xy 88.023094 -263.049986) (xy 87.975508 -263.031939) (xy 87.931434 -263.006493) (xy 87.892012 -262.974306)
			(xy 87.858264 -262.936212) (xy 87.831063 -262.893198) (xy 87.811115 -262.846378) (xy 87.798936 -262.796964)
			(xy 87.794841 -262.746236) (xy 87.47633 -262.746236) (xy 87.475835 -262.770843) (xy 87.46794 -262.81942)
			(xy 87.452356 -262.866101) (xy 87.429485 -262.909678) (xy 87.39992 -262.949022) (xy 87.364427 -262.983114)
			(xy 87.323924 -263.01107) (xy 87.279462 -263.032168) (xy 87.232191 -263.04586) (xy 87.183336 -263.051792)
			(xy 87.134161 -263.049811) (xy 87.085942 -263.039967) (xy 87.039926 -263.022515) (xy 86.997305 -262.997908)
			(xy 86.959184 -262.966783) (xy 86.926549 -262.929946) (xy 86.900246 -262.88835) (xy 86.880955 -262.843074)
			(xy 86.869178 -262.79529) (xy 86.865218 -262.746236) (xy 86.54669 -262.746236) (xy 86.546178 -262.771682)
			(xy 86.538014 -262.821916) (xy 86.521898 -262.87019) (xy 86.498247 -262.915253) (xy 86.467674 -262.955939)
			(xy 86.43097 -262.991194) (xy 86.389086 -263.020104) (xy 86.343107 -263.041921) (xy 86.294223 -263.056081)
			(xy 86.243702 -263.062215) (xy 86.19285 -263.060166) (xy 86.142986 -263.049986) (xy 86.0954 -263.031939)
			(xy 86.051326 -263.006493) (xy 86.011904 -262.974306) (xy 85.978156 -262.936212) (xy 85.950955 -262.893198)
			(xy 85.931007 -262.846378) (xy 85.918828 -262.796964) (xy 85.914733 -262.746236) (xy 85.596222 -262.746236)
			(xy 85.595727 -262.770843) (xy 85.587832 -262.81942) (xy 85.572248 -262.866101) (xy 85.549377 -262.909678)
			(xy 85.519812 -262.949022) (xy 85.484319 -262.983114) (xy 85.443816 -263.01107) (xy 85.399354 -263.032168)
			(xy 85.352083 -263.04586) (xy 85.303228 -263.051792) (xy 85.254053 -263.049811) (xy 85.205834 -263.039967)
			(xy 85.159818 -263.022515) (xy 85.117197 -262.997908) (xy 85.079076 -262.966783) (xy 85.046441 -262.929946)
			(xy 85.020138 -262.88835) (xy 85.000847 -262.843074) (xy 84.98907 -262.79529) (xy 84.98511 -262.746236)
			(xy 84.666836 -262.746236) (xy 84.666324 -262.771682) (xy 84.65816 -262.821916) (xy 84.642044 -262.87019)
			(xy 84.618393 -262.915253) (xy 84.58782 -262.955939) (xy 84.551116 -262.991194) (xy 84.509232 -263.020104)
			(xy 84.463253 -263.041921) (xy 84.414369 -263.056081) (xy 84.363848 -263.062215) (xy 84.312996 -263.060166)
			(xy 84.263132 -263.049986) (xy 84.215546 -263.031939) (xy 84.171472 -263.006493) (xy 84.13205 -262.974306)
			(xy 84.098302 -262.936212) (xy 84.071101 -262.893198) (xy 84.051153 -262.846378) (xy 84.038974 -262.796964)
			(xy 84.034879 -262.746236) (xy 83.716368 -262.746236) (xy 83.715873 -262.770843) (xy 83.707978 -262.81942)
			(xy 83.692394 -262.866101) (xy 83.669523 -262.909678) (xy 83.639958 -262.949022) (xy 83.604465 -262.983114)
			(xy 83.563962 -263.01107) (xy 83.5195 -263.032168) (xy 83.472229 -263.04586) (xy 83.423374 -263.051792)
			(xy 83.374199 -263.049811) (xy 83.32598 -263.039967) (xy 83.279964 -263.022515) (xy 83.237343 -262.997908)
			(xy 83.199222 -262.966783) (xy 83.166587 -262.929946) (xy 83.140284 -262.88835) (xy 83.120993 -262.843074)
			(xy 83.109216 -262.79529) (xy 83.105256 -262.746236) (xy 82.786728 -262.746236) (xy 82.786216 -262.771682)
			(xy 82.778052 -262.821916) (xy 82.761936 -262.87019) (xy 82.738285 -262.915253) (xy 82.707712 -262.955939)
			(xy 82.671008 -262.991194) (xy 82.629124 -263.020104) (xy 82.583145 -263.041921) (xy 82.534261 -263.056081)
			(xy 82.48374 -263.062215) (xy 82.432888 -263.060166) (xy 82.383024 -263.049986) (xy 82.335438 -263.031939)
			(xy 82.291364 -263.006493) (xy 82.251942 -262.974306) (xy 82.218194 -262.936212) (xy 82.190993 -262.893198)
			(xy 82.171045 -262.846378) (xy 82.158866 -262.796964) (xy 82.154771 -262.746236) (xy 81.846674 -262.746236)
			(xy 81.846162 -262.771682) (xy 81.837998 -262.821916) (xy 81.821882 -262.87019) (xy 81.798231 -262.915253)
			(xy 81.767658 -262.955939) (xy 81.730954 -262.991194) (xy 81.68907 -263.020104) (xy 81.643091 -263.041921)
			(xy 81.594207 -263.056081) (xy 81.543686 -263.062215) (xy 81.492834 -263.060166) (xy 81.44297 -263.049986)
			(xy 81.395384 -263.031939) (xy 81.35131 -263.006493) (xy 81.311888 -262.974306) (xy 81.27814 -262.936212)
			(xy 81.250939 -262.893198) (xy 81.230991 -262.846378) (xy 81.218812 -262.796964) (xy 81.214717 -262.746236)
			(xy 80.89646 -262.746236) (xy 80.895965 -262.770843) (xy 80.88807 -262.81942) (xy 80.872486 -262.866101)
			(xy 80.849615 -262.909678) (xy 80.82005 -262.949022) (xy 80.784557 -262.983114) (xy 80.744054 -263.01107)
			(xy 80.699592 -263.032168) (xy 80.652321 -263.04586) (xy 80.603466 -263.051792) (xy 80.554291 -263.049811)
			(xy 80.506072 -263.039967) (xy 80.460056 -263.022515) (xy 80.417435 -262.997908) (xy 80.379314 -262.966783)
			(xy 80.346679 -262.929946) (xy 80.320376 -262.88835) (xy 80.301085 -262.843074) (xy 80.289308 -262.79529)
			(xy 80.285348 -262.746236) (xy 79.016352 -262.746236) (xy 79.015857 -262.770843) (xy 79.007962 -262.81942)
			(xy 78.992378 -262.866101) (xy 78.969507 -262.909678) (xy 78.939942 -262.949022) (xy 78.904449 -262.983114)
			(xy 78.863946 -263.01107) (xy 78.819484 -263.032168) (xy 78.772213 -263.04586) (xy 78.723358 -263.051792)
			(xy 78.674183 -263.049811) (xy 78.625964 -263.039967) (xy 78.579948 -263.022515) (xy 78.537327 -262.997908)
			(xy 78.499206 -262.966783) (xy 78.466571 -262.929946) (xy 78.440268 -262.88835) (xy 78.420977 -262.843074)
			(xy 78.4092 -262.79529) (xy 78.40524 -262.746236) (xy 73.375774 -262.746236) (xy 73.375774 -263.290304)
			(xy 76.807072 -263.290304) (xy 76.811032 -263.24125) (xy 76.822809 -263.193466) (xy 76.8421 -263.14819)
			(xy 76.868403 -263.106594) (xy 76.901038 -263.069757) (xy 76.939159 -263.038632) (xy 76.98178 -263.014025)
			(xy 77.027796 -262.996573) (xy 77.076015 -262.986729) (xy 77.12519 -262.984748) (xy 77.174045 -262.99068)
			(xy 77.221316 -263.004372) (xy 77.265778 -263.02547) (xy 77.306281 -263.053426) (xy 77.341774 -263.087518)
			(xy 77.371339 -263.126862) (xy 77.39421 -263.170439) (xy 77.409794 -263.21712) (xy 77.417689 -263.265697)
			(xy 77.418184 -263.290304) (xy 77.417689 -263.314911) (xy 77.409794 -263.363488) (xy 77.39421 -263.410169)
			(xy 77.371339 -263.453746) (xy 77.341774 -263.49309) (xy 77.306281 -263.527182) (xy 77.265778 -263.555138)
			(xy 77.263451 -263.556242) (xy 80.744817 -263.556242) (xy 80.748912 -263.505514) (xy 80.761091 -263.4561)
			(xy 80.781039 -263.40928) (xy 80.80824 -263.366266) (xy 80.841988 -263.328172) (xy 80.88141 -263.295985)
			(xy 80.925484 -263.270539) (xy 80.97307 -263.252492) (xy 81.022934 -263.242312) (xy 81.073786 -263.240263)
			(xy 81.124307 -263.246397) (xy 81.173191 -263.260557) (xy 81.21917 -263.282374) (xy 81.261054 -263.311284)
			(xy 81.297758 -263.346539) (xy 81.328331 -263.387225) (xy 81.351982 -263.432288) (xy 81.368098 -263.480562)
			(xy 81.376262 -263.530796) (xy 81.376774 -263.556242) (xy 81.695302 -263.556242) (xy 81.699262 -263.507188)
			(xy 81.711039 -263.459404) (xy 81.73033 -263.414128) (xy 81.756633 -263.372532) (xy 81.789268 -263.335695)
			(xy 81.827389 -263.30457) (xy 81.87001 -263.279963) (xy 81.916026 -263.262511) (xy 81.964245 -263.252667)
			(xy 82.01342 -263.250686) (xy 82.062275 -263.256618) (xy 82.109546 -263.27031) (xy 82.154008 -263.291408)
			(xy 82.194511 -263.319364) (xy 82.230004 -263.353456) (xy 82.259569 -263.3928) (xy 82.28244 -263.436377)
			(xy 82.298024 -263.483058) (xy 82.305919 -263.531635) (xy 82.306414 -263.556242) (xy 82.624671 -263.556242)
			(xy 82.628766 -263.505514) (xy 82.640945 -263.4561) (xy 82.660893 -263.40928) (xy 82.688094 -263.366266)
			(xy 82.721842 -263.328172) (xy 82.761264 -263.295985) (xy 82.805338 -263.270539) (xy 82.852924 -263.252492)
			(xy 82.902788 -263.242312) (xy 82.95364 -263.240263) (xy 83.004161 -263.246397) (xy 83.053045 -263.260557)
			(xy 83.099024 -263.282374) (xy 83.140908 -263.311284) (xy 83.177612 -263.346539) (xy 83.208185 -263.387225)
			(xy 83.231836 -263.432288) (xy 83.247952 -263.480562) (xy 83.256116 -263.530796) (xy 83.256628 -263.556242)
			(xy 83.575156 -263.556242) (xy 83.579116 -263.507188) (xy 83.590893 -263.459404) (xy 83.610184 -263.414128)
			(xy 83.636487 -263.372532) (xy 83.669122 -263.335695) (xy 83.707243 -263.30457) (xy 83.749864 -263.279963)
			(xy 83.79588 -263.262511) (xy 83.844099 -263.252667) (xy 83.893274 -263.250686) (xy 83.942129 -263.256618)
			(xy 83.9894 -263.27031) (xy 84.033862 -263.291408) (xy 84.074365 -263.319364) (xy 84.109858 -263.353456)
			(xy 84.139423 -263.3928) (xy 84.162294 -263.436377) (xy 84.177878 -263.483058) (xy 84.185773 -263.531635)
			(xy 84.186268 -263.556242) (xy 84.504779 -263.556242) (xy 84.508874 -263.505514) (xy 84.521053 -263.4561)
			(xy 84.541001 -263.40928) (xy 84.568202 -263.366266) (xy 84.60195 -263.328172) (xy 84.641372 -263.295985)
			(xy 84.685446 -263.270539) (xy 84.733032 -263.252492) (xy 84.782896 -263.242312) (xy 84.833748 -263.240263)
			(xy 84.884269 -263.246397) (xy 84.933153 -263.260557) (xy 84.979132 -263.282374) (xy 85.021016 -263.311284)
			(xy 85.05772 -263.346539) (xy 85.088293 -263.387225) (xy 85.111944 -263.432288) (xy 85.12806 -263.480562)
			(xy 85.136224 -263.530796) (xy 85.136736 -263.556242) (xy 85.444833 -263.556242) (xy 85.448928 -263.505514)
			(xy 85.461107 -263.4561) (xy 85.481055 -263.40928) (xy 85.508256 -263.366266) (xy 85.542004 -263.328172)
			(xy 85.581426 -263.295985) (xy 85.6255 -263.270539) (xy 85.673086 -263.252492) (xy 85.72295 -263.242312)
			(xy 85.773802 -263.240263) (xy 85.824323 -263.246397) (xy 85.873207 -263.260557) (xy 85.919186 -263.282374)
			(xy 85.96107 -263.311284) (xy 85.997774 -263.346539) (xy 86.028347 -263.387225) (xy 86.051998 -263.432288)
			(xy 86.068114 -263.480562) (xy 86.076278 -263.530796) (xy 86.07679 -263.556242) (xy 87.324687 -263.556242)
			(xy 87.328782 -263.505514) (xy 87.340961 -263.4561) (xy 87.360909 -263.40928) (xy 87.38811 -263.366266)
			(xy 87.421858 -263.328172) (xy 87.46128 -263.295985) (xy 87.505354 -263.270539) (xy 87.55294 -263.252492)
			(xy 87.602804 -263.242312) (xy 87.653656 -263.240263) (xy 87.704177 -263.246397) (xy 87.753061 -263.260557)
			(xy 87.79904 -263.282374) (xy 87.840924 -263.311284) (xy 87.877628 -263.346539) (xy 87.908201 -263.387225)
			(xy 87.931852 -263.432288) (xy 87.947968 -263.480562) (xy 87.956132 -263.530796) (xy 87.956644 -263.556242)
			(xy 88.275172 -263.556242) (xy 88.279132 -263.507188) (xy 88.290909 -263.459404) (xy 88.3102 -263.414128)
			(xy 88.336503 -263.372532) (xy 88.369138 -263.335695) (xy 88.407259 -263.30457) (xy 88.44988 -263.279963)
			(xy 88.495896 -263.262511) (xy 88.544115 -263.252667) (xy 88.59329 -263.250686) (xy 88.642145 -263.256618)
			(xy 88.689416 -263.27031) (xy 88.733878 -263.291408) (xy 88.774381 -263.319364) (xy 88.809874 -263.353456)
			(xy 88.839439 -263.3928) (xy 88.86231 -263.436377) (xy 88.877894 -263.483058) (xy 88.885789 -263.531635)
			(xy 88.886284 -263.556242) (xy 89.204795 -263.556242) (xy 89.20889 -263.505514) (xy 89.221069 -263.4561)
			(xy 89.241017 -263.40928) (xy 89.268218 -263.366266) (xy 89.301966 -263.328172) (xy 89.341388 -263.295985)
			(xy 89.385462 -263.270539) (xy 89.433048 -263.252492) (xy 89.482912 -263.242312) (xy 89.533764 -263.240263)
			(xy 89.584285 -263.246397) (xy 89.633169 -263.260557) (xy 89.679148 -263.282374) (xy 89.721032 -263.311284)
			(xy 89.757736 -263.346539) (xy 89.788309 -263.387225) (xy 89.81196 -263.432288) (xy 89.828076 -263.480562)
			(xy 89.83624 -263.530796) (xy 89.836752 -263.556242) (xy 90.15528 -263.556242) (xy 90.15924 -263.507188)
			(xy 90.171017 -263.459404) (xy 90.190308 -263.414128) (xy 90.216611 -263.372532) (xy 90.249246 -263.335695)
			(xy 90.287367 -263.30457) (xy 90.329988 -263.279963) (xy 90.376004 -263.262511) (xy 90.424223 -263.252667)
			(xy 90.473398 -263.250686) (xy 90.522253 -263.256618) (xy 90.569524 -263.27031) (xy 90.613986 -263.291408)
			(xy 90.654489 -263.319364) (xy 90.689982 -263.353456) (xy 90.719547 -263.3928) (xy 90.742418 -263.436377)
			(xy 90.758002 -263.483058) (xy 90.765897 -263.531635) (xy 90.766392 -263.556242) (xy 91.084903 -263.556242)
			(xy 91.088998 -263.505514) (xy 91.101177 -263.4561) (xy 91.121125 -263.40928) (xy 91.148326 -263.366266)
			(xy 91.182074 -263.328172) (xy 91.221496 -263.295985) (xy 91.26557 -263.270539) (xy 91.313156 -263.252492)
			(xy 91.36302 -263.242312) (xy 91.413872 -263.240263) (xy 91.464393 -263.246397) (xy 91.513277 -263.260557)
			(xy 91.559256 -263.282374) (xy 91.60114 -263.311284) (xy 91.637844 -263.346539) (xy 91.668417 -263.387225)
			(xy 91.692068 -263.432288) (xy 91.708184 -263.480562) (xy 91.716348 -263.530796) (xy 91.71686 -263.556242)
			(xy 92.024703 -263.556242) (xy 92.028798 -263.505514) (xy 92.040977 -263.4561) (xy 92.060925 -263.40928)
			(xy 92.088126 -263.366266) (xy 92.121874 -263.328172) (xy 92.161296 -263.295985) (xy 92.20537 -263.270539)
			(xy 92.252956 -263.252492) (xy 92.30282 -263.242312) (xy 92.353672 -263.240263) (xy 92.404193 -263.246397)
			(xy 92.453077 -263.260557) (xy 92.499056 -263.282374) (xy 92.54094 -263.311284) (xy 92.577644 -263.346539)
			(xy 92.608217 -263.387225) (xy 92.631868 -263.432288) (xy 92.647984 -263.480562) (xy 92.656148 -263.530796)
			(xy 92.65666 -263.556242) (xy 93.904811 -263.556242) (xy 93.908906 -263.505514) (xy 93.921085 -263.4561)
			(xy 93.941033 -263.40928) (xy 93.968234 -263.366266) (xy 94.001982 -263.328172) (xy 94.041404 -263.295985)
			(xy 94.085478 -263.270539) (xy 94.133064 -263.252492) (xy 94.182928 -263.242312) (xy 94.23378 -263.240263)
			(xy 94.284301 -263.246397) (xy 94.333185 -263.260557) (xy 94.379164 -263.282374) (xy 94.421048 -263.311284)
			(xy 94.457752 -263.346539) (xy 94.488325 -263.387225) (xy 94.511976 -263.432288) (xy 94.528092 -263.480562)
			(xy 94.536256 -263.530796) (xy 94.536768 -263.556242) (xy 94.855296 -263.556242) (xy 94.859256 -263.507188)
			(xy 94.871033 -263.459404) (xy 94.890324 -263.414128) (xy 94.916627 -263.372532) (xy 94.949262 -263.335695)
			(xy 94.987383 -263.30457) (xy 95.030004 -263.279963) (xy 95.07602 -263.262511) (xy 95.124239 -263.252667)
			(xy 95.173414 -263.250686) (xy 95.222269 -263.256618) (xy 95.26954 -263.27031) (xy 95.314002 -263.291408)
			(xy 95.354505 -263.319364) (xy 95.389998 -263.353456) (xy 95.419563 -263.3928) (xy 95.442434 -263.436377)
			(xy 95.458018 -263.483058) (xy 95.465913 -263.531635) (xy 95.466408 -263.556242) (xy 95.784919 -263.556242)
			(xy 95.789014 -263.505514) (xy 95.801193 -263.4561) (xy 95.821141 -263.40928) (xy 95.848342 -263.366266)
			(xy 95.88209 -263.328172) (xy 95.921512 -263.295985) (xy 95.965586 -263.270539) (xy 96.013172 -263.252492)
			(xy 96.063036 -263.242312) (xy 96.113888 -263.240263) (xy 96.164409 -263.246397) (xy 96.213293 -263.260557)
			(xy 96.259272 -263.282374) (xy 96.301156 -263.311284) (xy 96.33786 -263.346539) (xy 96.368433 -263.387225)
			(xy 96.392084 -263.432288) (xy 96.4082 -263.480562) (xy 96.416364 -263.530796) (xy 96.416876 -263.556242)
			(xy 97.675204 -263.556242) (xy 97.679164 -263.507188) (xy 97.690941 -263.459404) (xy 97.710232 -263.414128)
			(xy 97.736535 -263.372532) (xy 97.76917 -263.335695) (xy 97.807291 -263.30457) (xy 97.849912 -263.279963)
			(xy 97.895928 -263.262511) (xy 97.944147 -263.252667) (xy 97.993322 -263.250686) (xy 98.042177 -263.256618)
			(xy 98.089448 -263.27031) (xy 98.13391 -263.291408) (xy 98.174413 -263.319364) (xy 98.209906 -263.353456)
			(xy 98.239471 -263.3928) (xy 98.262342 -263.436377) (xy 98.277926 -263.483058) (xy 98.285821 -263.531635)
			(xy 98.286316 -263.556242) (xy 99.555312 -263.556242) (xy 99.559272 -263.507188) (xy 99.571049 -263.459404)
			(xy 99.59034 -263.414128) (xy 99.616643 -263.372532) (xy 99.649278 -263.335695) (xy 99.687399 -263.30457)
			(xy 99.73002 -263.279963) (xy 99.776036 -263.262511) (xy 99.824255 -263.252667) (xy 99.87343 -263.250686)
			(xy 99.922285 -263.256618) (xy 99.969556 -263.27031) (xy 100.014018 -263.291408) (xy 100.054521 -263.319364)
			(xy 100.090014 -263.353456) (xy 100.119579 -263.3928) (xy 100.14245 -263.436377) (xy 100.158034 -263.483058)
			(xy 100.165929 -263.531635) (xy 100.166424 -263.556242) (xy 100.165929 -263.580849) (xy 100.158034 -263.629426)
			(xy 100.14245 -263.676107) (xy 100.119579 -263.719684) (xy 100.090014 -263.759028) (xy 100.054521 -263.79312)
			(xy 100.014018 -263.821076) (xy 99.969556 -263.842174) (xy 99.922285 -263.855866) (xy 99.87343 -263.861798)
			(xy 99.824255 -263.859817) (xy 99.776036 -263.849973) (xy 99.73002 -263.832521) (xy 99.687399 -263.807914)
			(xy 99.649278 -263.776789) (xy 99.616643 -263.739952) (xy 99.59034 -263.698356) (xy 99.571049 -263.65308)
			(xy 99.559272 -263.605296) (xy 99.555312 -263.556242) (xy 98.286316 -263.556242) (xy 98.285821 -263.580849)
			(xy 98.277926 -263.629426) (xy 98.262342 -263.676107) (xy 98.239471 -263.719684) (xy 98.209906 -263.759028)
			(xy 98.174413 -263.79312) (xy 98.13391 -263.821076) (xy 98.089448 -263.842174) (xy 98.042177 -263.855866)
			(xy 97.993322 -263.861798) (xy 97.944147 -263.859817) (xy 97.895928 -263.849973) (xy 97.849912 -263.832521)
			(xy 97.807291 -263.807914) (xy 97.76917 -263.776789) (xy 97.736535 -263.739952) (xy 97.710232 -263.698356)
			(xy 97.690941 -263.65308) (xy 97.679164 -263.605296) (xy 97.675204 -263.556242) (xy 96.416876 -263.556242)
			(xy 96.416364 -263.581688) (xy 96.4082 -263.631922) (xy 96.392084 -263.680196) (xy 96.368433 -263.725259)
			(xy 96.33786 -263.765945) (xy 96.301156 -263.8012) (xy 96.259272 -263.83011) (xy 96.213293 -263.851927)
			(xy 96.164409 -263.866087) (xy 96.113888 -263.872221) (xy 96.063036 -263.870172) (xy 96.013172 -263.859992)
			(xy 95.965586 -263.841945) (xy 95.921512 -263.816499) (xy 95.88209 -263.784312) (xy 95.848342 -263.746218)
			(xy 95.821141 -263.703204) (xy 95.801193 -263.656384) (xy 95.789014 -263.60697) (xy 95.784919 -263.556242)
			(xy 95.466408 -263.556242) (xy 95.465913 -263.580849) (xy 95.458018 -263.629426) (xy 95.442434 -263.676107)
			(xy 95.419563 -263.719684) (xy 95.389998 -263.759028) (xy 95.354505 -263.79312) (xy 95.314002 -263.821076)
			(xy 95.26954 -263.842174) (xy 95.222269 -263.855866) (xy 95.173414 -263.861798) (xy 95.124239 -263.859817)
			(xy 95.07602 -263.849973) (xy 95.030004 -263.832521) (xy 94.987383 -263.807914) (xy 94.949262 -263.776789)
			(xy 94.916627 -263.739952) (xy 94.890324 -263.698356) (xy 94.871033 -263.65308) (xy 94.859256 -263.605296)
			(xy 94.855296 -263.556242) (xy 94.536768 -263.556242) (xy 94.536256 -263.581688) (xy 94.528092 -263.631922)
			(xy 94.511976 -263.680196) (xy 94.488325 -263.725259) (xy 94.457752 -263.765945) (xy 94.421048 -263.8012)
			(xy 94.379164 -263.83011) (xy 94.333185 -263.851927) (xy 94.284301 -263.866087) (xy 94.23378 -263.872221)
			(xy 94.182928 -263.870172) (xy 94.133064 -263.859992) (xy 94.085478 -263.841945) (xy 94.041404 -263.816499)
			(xy 94.001982 -263.784312) (xy 93.968234 -263.746218) (xy 93.941033 -263.703204) (xy 93.921085 -263.656384)
			(xy 93.908906 -263.60697) (xy 93.904811 -263.556242) (xy 92.65666 -263.556242) (xy 92.656148 -263.581688)
			(xy 92.647984 -263.631922) (xy 92.631868 -263.680196) (xy 92.608217 -263.725259) (xy 92.577644 -263.765945)
			(xy 92.54094 -263.8012) (xy 92.499056 -263.83011) (xy 92.453077 -263.851927) (xy 92.404193 -263.866087)
			(xy 92.353672 -263.872221) (xy 92.30282 -263.870172) (xy 92.252956 -263.859992) (xy 92.20537 -263.841945)
			(xy 92.161296 -263.816499) (xy 92.121874 -263.784312) (xy 92.088126 -263.746218) (xy 92.060925 -263.703204)
			(xy 92.040977 -263.656384) (xy 92.028798 -263.60697) (xy 92.024703 -263.556242) (xy 91.71686 -263.556242)
			(xy 91.716348 -263.581688) (xy 91.708184 -263.631922) (xy 91.692068 -263.680196) (xy 91.668417 -263.725259)
			(xy 91.637844 -263.765945) (xy 91.60114 -263.8012) (xy 91.559256 -263.83011) (xy 91.513277 -263.851927)
			(xy 91.464393 -263.866087) (xy 91.413872 -263.872221) (xy 91.36302 -263.870172) (xy 91.313156 -263.859992)
			(xy 91.26557 -263.841945) (xy 91.221496 -263.816499) (xy 91.182074 -263.784312) (xy 91.148326 -263.746218)
			(xy 91.121125 -263.703204) (xy 91.101177 -263.656384) (xy 91.088998 -263.60697) (xy 91.084903 -263.556242)
			(xy 90.766392 -263.556242) (xy 90.765897 -263.580849) (xy 90.758002 -263.629426) (xy 90.742418 -263.676107)
			(xy 90.719547 -263.719684) (xy 90.689982 -263.759028) (xy 90.654489 -263.79312) (xy 90.613986 -263.821076)
			(xy 90.569524 -263.842174) (xy 90.522253 -263.855866) (xy 90.473398 -263.861798) (xy 90.424223 -263.859817)
			(xy 90.376004 -263.849973) (xy 90.329988 -263.832521) (xy 90.287367 -263.807914) (xy 90.249246 -263.776789)
			(xy 90.216611 -263.739952) (xy 90.190308 -263.698356) (xy 90.171017 -263.65308) (xy 90.15924 -263.605296)
			(xy 90.15528 -263.556242) (xy 89.836752 -263.556242) (xy 89.83624 -263.581688) (xy 89.828076 -263.631922)
			(xy 89.81196 -263.680196) (xy 89.788309 -263.725259) (xy 89.757736 -263.765945) (xy 89.721032 -263.8012)
			(xy 89.679148 -263.83011) (xy 89.633169 -263.851927) (xy 89.584285 -263.866087) (xy 89.533764 -263.872221)
			(xy 89.482912 -263.870172) (xy 89.433048 -263.859992) (xy 89.385462 -263.841945) (xy 89.341388 -263.816499)
			(xy 89.301966 -263.784312) (xy 89.268218 -263.746218) (xy 89.241017 -263.703204) (xy 89.221069 -263.656384)
			(xy 89.20889 -263.60697) (xy 89.204795 -263.556242) (xy 88.886284 -263.556242) (xy 88.885789 -263.580849)
			(xy 88.877894 -263.629426) (xy 88.86231 -263.676107) (xy 88.839439 -263.719684) (xy 88.809874 -263.759028)
			(xy 88.774381 -263.79312) (xy 88.733878 -263.821076) (xy 88.689416 -263.842174) (xy 88.642145 -263.855866)
			(xy 88.59329 -263.861798) (xy 88.544115 -263.859817) (xy 88.495896 -263.849973) (xy 88.44988 -263.832521)
			(xy 88.407259 -263.807914) (xy 88.369138 -263.776789) (xy 88.336503 -263.739952) (xy 88.3102 -263.698356)
			(xy 88.290909 -263.65308) (xy 88.279132 -263.605296) (xy 88.275172 -263.556242) (xy 87.956644 -263.556242)
			(xy 87.956132 -263.581688) (xy 87.947968 -263.631922) (xy 87.931852 -263.680196) (xy 87.908201 -263.725259)
			(xy 87.877628 -263.765945) (xy 87.840924 -263.8012) (xy 87.79904 -263.83011) (xy 87.753061 -263.851927)
			(xy 87.704177 -263.866087) (xy 87.653656 -263.872221) (xy 87.602804 -263.870172) (xy 87.55294 -263.859992)
			(xy 87.505354 -263.841945) (xy 87.46128 -263.816499) (xy 87.421858 -263.784312) (xy 87.38811 -263.746218)
			(xy 87.360909 -263.703204) (xy 87.340961 -263.656384) (xy 87.328782 -263.60697) (xy 87.324687 -263.556242)
			(xy 86.07679 -263.556242) (xy 86.076278 -263.581688) (xy 86.068114 -263.631922) (xy 86.051998 -263.680196)
			(xy 86.028347 -263.725259) (xy 85.997774 -263.765945) (xy 85.96107 -263.8012) (xy 85.919186 -263.83011)
			(xy 85.873207 -263.851927) (xy 85.824323 -263.866087) (xy 85.773802 -263.872221) (xy 85.72295 -263.870172)
			(xy 85.673086 -263.859992) (xy 85.6255 -263.841945) (xy 85.581426 -263.816499) (xy 85.542004 -263.784312)
			(xy 85.508256 -263.746218) (xy 85.481055 -263.703204) (xy 85.461107 -263.656384) (xy 85.448928 -263.60697)
			(xy 85.444833 -263.556242) (xy 85.136736 -263.556242) (xy 85.136224 -263.581688) (xy 85.12806 -263.631922)
			(xy 85.111944 -263.680196) (xy 85.088293 -263.725259) (xy 85.05772 -263.765945) (xy 85.021016 -263.8012)
			(xy 84.979132 -263.83011) (xy 84.933153 -263.851927) (xy 84.884269 -263.866087) (xy 84.833748 -263.872221)
			(xy 84.782896 -263.870172) (xy 84.733032 -263.859992) (xy 84.685446 -263.841945) (xy 84.641372 -263.816499)
			(xy 84.60195 -263.784312) (xy 84.568202 -263.746218) (xy 84.541001 -263.703204) (xy 84.521053 -263.656384)
			(xy 84.508874 -263.60697) (xy 84.504779 -263.556242) (xy 84.186268 -263.556242) (xy 84.185773 -263.580849)
			(xy 84.177878 -263.629426) (xy 84.162294 -263.676107) (xy 84.139423 -263.719684) (xy 84.109858 -263.759028)
			(xy 84.074365 -263.79312) (xy 84.033862 -263.821076) (xy 83.9894 -263.842174) (xy 83.942129 -263.855866)
			(xy 83.893274 -263.861798) (xy 83.844099 -263.859817) (xy 83.79588 -263.849973) (xy 83.749864 -263.832521)
			(xy 83.707243 -263.807914) (xy 83.669122 -263.776789) (xy 83.636487 -263.739952) (xy 83.610184 -263.698356)
			(xy 83.590893 -263.65308) (xy 83.579116 -263.605296) (xy 83.575156 -263.556242) (xy 83.256628 -263.556242)
			(xy 83.256116 -263.581688) (xy 83.247952 -263.631922) (xy 83.231836 -263.680196) (xy 83.208185 -263.725259)
			(xy 83.177612 -263.765945) (xy 83.140908 -263.8012) (xy 83.099024 -263.83011) (xy 83.053045 -263.851927)
			(xy 83.004161 -263.866087) (xy 82.95364 -263.872221) (xy 82.902788 -263.870172) (xy 82.852924 -263.859992)
			(xy 82.805338 -263.841945) (xy 82.761264 -263.816499) (xy 82.721842 -263.784312) (xy 82.688094 -263.746218)
			(xy 82.660893 -263.703204) (xy 82.640945 -263.656384) (xy 82.628766 -263.60697) (xy 82.624671 -263.556242)
			(xy 82.306414 -263.556242) (xy 82.305919 -263.580849) (xy 82.298024 -263.629426) (xy 82.28244 -263.676107)
			(xy 82.259569 -263.719684) (xy 82.230004 -263.759028) (xy 82.194511 -263.79312) (xy 82.154008 -263.821076)
			(xy 82.109546 -263.842174) (xy 82.062275 -263.855866) (xy 82.01342 -263.861798) (xy 81.964245 -263.859817)
			(xy 81.916026 -263.849973) (xy 81.87001 -263.832521) (xy 81.827389 -263.807914) (xy 81.789268 -263.776789)
			(xy 81.756633 -263.739952) (xy 81.73033 -263.698356) (xy 81.711039 -263.65308) (xy 81.699262 -263.605296)
			(xy 81.695302 -263.556242) (xy 81.376774 -263.556242) (xy 81.376262 -263.581688) (xy 81.368098 -263.631922)
			(xy 81.351982 -263.680196) (xy 81.328331 -263.725259) (xy 81.297758 -263.765945) (xy 81.261054 -263.8012)
			(xy 81.21917 -263.83011) (xy 81.173191 -263.851927) (xy 81.124307 -263.866087) (xy 81.073786 -263.872221)
			(xy 81.022934 -263.870172) (xy 80.97307 -263.859992) (xy 80.925484 -263.841945) (xy 80.88141 -263.816499)
			(xy 80.841988 -263.784312) (xy 80.80824 -263.746218) (xy 80.781039 -263.703204) (xy 80.761091 -263.656384)
			(xy 80.748912 -263.60697) (xy 80.744817 -263.556242) (xy 77.263451 -263.556242) (xy 77.221316 -263.576236)
			(xy 77.174045 -263.589928) (xy 77.12519 -263.59586) (xy 77.076015 -263.593879) (xy 77.027796 -263.584035)
			(xy 76.98178 -263.566583) (xy 76.939159 -263.541976) (xy 76.901038 -263.510851) (xy 76.868403 -263.474014)
			(xy 76.8421 -263.432418) (xy 76.822809 -263.387142) (xy 76.811032 -263.339358) (xy 76.807072 -263.290304)
			(xy 73.375774 -263.290304) (xy 73.375774 -264.366248) (xy 78.40524 -264.366248) (xy 78.4092 -264.317194)
			(xy 78.420977 -264.26941) (xy 78.440268 -264.224134) (xy 78.466571 -264.182538) (xy 78.499206 -264.145701)
			(xy 78.537327 -264.114576) (xy 78.579948 -264.089969) (xy 78.625964 -264.072517) (xy 78.674183 -264.062673)
			(xy 78.723358 -264.060692) (xy 78.772213 -264.066624) (xy 78.819484 -264.080316) (xy 78.863946 -264.101414)
			(xy 78.904449 -264.12937) (xy 78.939942 -264.163462) (xy 78.969507 -264.202806) (xy 78.992378 -264.246383)
			(xy 79.007962 -264.293064) (xy 79.015857 -264.341641) (xy 79.016352 -264.366248) (xy 80.285348 -264.366248)
			(xy 80.289308 -264.317194) (xy 80.301085 -264.26941) (xy 80.320376 -264.224134) (xy 80.346679 -264.182538)
			(xy 80.379314 -264.145701) (xy 80.417435 -264.114576) (xy 80.460056 -264.089969) (xy 80.506072 -264.072517)
			(xy 80.554291 -264.062673) (xy 80.603466 -264.060692) (xy 80.652321 -264.066624) (xy 80.699592 -264.080316)
			(xy 80.744054 -264.101414) (xy 80.784557 -264.12937) (xy 80.82005 -264.163462) (xy 80.849615 -264.202806)
			(xy 80.872486 -264.246383) (xy 80.88807 -264.293064) (xy 80.895965 -264.341641) (xy 80.89646 -264.366248)
			(xy 81.214717 -264.366248) (xy 81.218812 -264.31552) (xy 81.230991 -264.266106) (xy 81.250939 -264.219286)
			(xy 81.27814 -264.176272) (xy 81.311888 -264.138178) (xy 81.35131 -264.105991) (xy 81.395384 -264.080545)
			(xy 81.44297 -264.062498) (xy 81.492834 -264.052318) (xy 81.543686 -264.050269) (xy 81.594207 -264.056403)
			(xy 81.643091 -264.070563) (xy 81.68907 -264.09238) (xy 81.730954 -264.12129) (xy 81.767658 -264.156545)
			(xy 81.798231 -264.197231) (xy 81.821882 -264.242294) (xy 81.837998 -264.290568) (xy 81.846162 -264.340802)
			(xy 81.846674 -264.366248) (xy 82.154771 -264.366248) (xy 82.158866 -264.31552) (xy 82.171045 -264.266106)
			(xy 82.190993 -264.219286) (xy 82.218194 -264.176272) (xy 82.251942 -264.138178) (xy 82.291364 -264.105991)
			(xy 82.335438 -264.080545) (xy 82.383024 -264.062498) (xy 82.432888 -264.052318) (xy 82.48374 -264.050269)
			(xy 82.534261 -264.056403) (xy 82.583145 -264.070563) (xy 82.629124 -264.09238) (xy 82.671008 -264.12129)
			(xy 82.707712 -264.156545) (xy 82.738285 -264.197231) (xy 82.761936 -264.242294) (xy 82.778052 -264.290568)
			(xy 82.786216 -264.340802) (xy 82.786728 -264.366248) (xy 83.105256 -264.366248) (xy 83.109216 -264.317194)
			(xy 83.120993 -264.26941) (xy 83.140284 -264.224134) (xy 83.166587 -264.182538) (xy 83.199222 -264.145701)
			(xy 83.237343 -264.114576) (xy 83.279964 -264.089969) (xy 83.32598 -264.072517) (xy 83.374199 -264.062673)
			(xy 83.423374 -264.060692) (xy 83.472229 -264.066624) (xy 83.5195 -264.080316) (xy 83.563962 -264.101414)
			(xy 83.604465 -264.12937) (xy 83.639958 -264.163462) (xy 83.669523 -264.202806) (xy 83.692394 -264.246383)
			(xy 83.707978 -264.293064) (xy 83.715873 -264.341641) (xy 83.716368 -264.366248) (xy 84.034879 -264.366248)
			(xy 84.038974 -264.31552) (xy 84.051153 -264.266106) (xy 84.071101 -264.219286) (xy 84.098302 -264.176272)
			(xy 84.13205 -264.138178) (xy 84.171472 -264.105991) (xy 84.215546 -264.080545) (xy 84.263132 -264.062498)
			(xy 84.312996 -264.052318) (xy 84.363848 -264.050269) (xy 84.414369 -264.056403) (xy 84.463253 -264.070563)
			(xy 84.509232 -264.09238) (xy 84.551116 -264.12129) (xy 84.58782 -264.156545) (xy 84.618393 -264.197231)
			(xy 84.642044 -264.242294) (xy 84.65816 -264.290568) (xy 84.666324 -264.340802) (xy 84.666836 -264.366248)
			(xy 84.98511 -264.366248) (xy 84.98907 -264.317194) (xy 85.000847 -264.26941) (xy 85.020138 -264.224134)
			(xy 85.046441 -264.182538) (xy 85.079076 -264.145701) (xy 85.117197 -264.114576) (xy 85.159818 -264.089969)
			(xy 85.205834 -264.072517) (xy 85.254053 -264.062673) (xy 85.303228 -264.060692) (xy 85.352083 -264.066624)
			(xy 85.399354 -264.080316) (xy 85.443816 -264.101414) (xy 85.484319 -264.12937) (xy 85.519812 -264.163462)
			(xy 85.549377 -264.202806) (xy 85.572248 -264.246383) (xy 85.587832 -264.293064) (xy 85.595727 -264.341641)
			(xy 85.596222 -264.366248) (xy 85.914733 -264.366248) (xy 85.918828 -264.31552) (xy 85.931007 -264.266106)
			(xy 85.950955 -264.219286) (xy 85.978156 -264.176272) (xy 86.011904 -264.138178) (xy 86.051326 -264.105991)
			(xy 86.0954 -264.080545) (xy 86.142986 -264.062498) (xy 86.19285 -264.052318) (xy 86.243702 -264.050269)
			(xy 86.294223 -264.056403) (xy 86.343107 -264.070563) (xy 86.389086 -264.09238) (xy 86.43097 -264.12129)
			(xy 86.467674 -264.156545) (xy 86.498247 -264.197231) (xy 86.521898 -264.242294) (xy 86.538014 -264.290568)
			(xy 86.546178 -264.340802) (xy 86.54669 -264.366248) (xy 86.865218 -264.366248) (xy 86.869178 -264.317194)
			(xy 86.880955 -264.26941) (xy 86.900246 -264.224134) (xy 86.926549 -264.182538) (xy 86.959184 -264.145701)
			(xy 86.997305 -264.114576) (xy 87.039926 -264.089969) (xy 87.085942 -264.072517) (xy 87.134161 -264.062673)
			(xy 87.183336 -264.060692) (xy 87.232191 -264.066624) (xy 87.279462 -264.080316) (xy 87.323924 -264.101414)
			(xy 87.364427 -264.12937) (xy 87.39992 -264.163462) (xy 87.429485 -264.202806) (xy 87.452356 -264.246383)
			(xy 87.46794 -264.293064) (xy 87.475835 -264.341641) (xy 87.47633 -264.366248) (xy 87.794841 -264.366248)
			(xy 87.798936 -264.31552) (xy 87.811115 -264.266106) (xy 87.831063 -264.219286) (xy 87.858264 -264.176272)
			(xy 87.892012 -264.138178) (xy 87.931434 -264.105991) (xy 87.975508 -264.080545) (xy 88.023094 -264.062498)
			(xy 88.072958 -264.052318) (xy 88.12381 -264.050269) (xy 88.174331 -264.056403) (xy 88.223215 -264.070563)
			(xy 88.269194 -264.09238) (xy 88.311078 -264.12129) (xy 88.347782 -264.156545) (xy 88.378355 -264.197231)
			(xy 88.402006 -264.242294) (xy 88.418122 -264.290568) (xy 88.426286 -264.340802) (xy 88.426798 -264.366248)
			(xy 88.734895 -264.366248) (xy 88.73899 -264.31552) (xy 88.751169 -264.266106) (xy 88.771117 -264.219286)
			(xy 88.798318 -264.176272) (xy 88.832066 -264.138178) (xy 88.871488 -264.105991) (xy 88.915562 -264.080545)
			(xy 88.963148 -264.062498) (xy 89.013012 -264.052318) (xy 89.063864 -264.050269) (xy 89.114385 -264.056403)
			(xy 89.163269 -264.070563) (xy 89.209248 -264.09238) (xy 89.251132 -264.12129) (xy 89.287836 -264.156545)
			(xy 89.318409 -264.197231) (xy 89.34206 -264.242294) (xy 89.358176 -264.290568) (xy 89.36634 -264.340802)
			(xy 89.366852 -264.366248) (xy 89.685126 -264.366248) (xy 89.689086 -264.317194) (xy 89.700863 -264.26941)
			(xy 89.720154 -264.224134) (xy 89.746457 -264.182538) (xy 89.779092 -264.145701) (xy 89.817213 -264.114576)
			(xy 89.859834 -264.089969) (xy 89.90585 -264.072517) (xy 89.954069 -264.062673) (xy 90.003244 -264.060692)
			(xy 90.052099 -264.066624) (xy 90.09937 -264.080316) (xy 90.143832 -264.101414) (xy 90.184335 -264.12937)
			(xy 90.219828 -264.163462) (xy 90.249393 -264.202806) (xy 90.272264 -264.246383) (xy 90.287848 -264.293064)
			(xy 90.295743 -264.341641) (xy 90.296238 -264.366248) (xy 90.614749 -264.366248) (xy 90.618844 -264.31552)
			(xy 90.631023 -264.266106) (xy 90.650971 -264.219286) (xy 90.678172 -264.176272) (xy 90.71192 -264.138178)
			(xy 90.751342 -264.105991) (xy 90.795416 -264.080545) (xy 90.843002 -264.062498) (xy 90.892866 -264.052318)
			(xy 90.943718 -264.050269) (xy 90.994239 -264.056403) (xy 91.043123 -264.070563) (xy 91.089102 -264.09238)
			(xy 91.130986 -264.12129) (xy 91.16769 -264.156545) (xy 91.198263 -264.197231) (xy 91.221914 -264.242294)
			(xy 91.23803 -264.290568) (xy 91.246194 -264.340802) (xy 91.246706 -264.366248) (xy 91.565234 -264.366248)
			(xy 91.569194 -264.317194) (xy 91.580971 -264.26941) (xy 91.600262 -264.224134) (xy 91.626565 -264.182538)
			(xy 91.6592 -264.145701) (xy 91.697321 -264.114576) (xy 91.739942 -264.089969) (xy 91.785958 -264.072517)
			(xy 91.834177 -264.062673) (xy 91.883352 -264.060692) (xy 91.932207 -264.066624) (xy 91.979478 -264.080316)
			(xy 92.02394 -264.101414) (xy 92.064443 -264.12937) (xy 92.099936 -264.163462) (xy 92.129501 -264.202806)
			(xy 92.152372 -264.246383) (xy 92.167956 -264.293064) (xy 92.175851 -264.341641) (xy 92.176346 -264.366248)
			(xy 92.494857 -264.366248) (xy 92.498952 -264.31552) (xy 92.511131 -264.266106) (xy 92.531079 -264.219286)
			(xy 92.55828 -264.176272) (xy 92.592028 -264.138178) (xy 92.63145 -264.105991) (xy 92.675524 -264.080545)
			(xy 92.72311 -264.062498) (xy 92.772974 -264.052318) (xy 92.823826 -264.050269) (xy 92.874347 -264.056403)
			(xy 92.923231 -264.070563) (xy 92.96921 -264.09238) (xy 93.011094 -264.12129) (xy 93.047798 -264.156545)
			(xy 93.078371 -264.197231) (xy 93.102022 -264.242294) (xy 93.118138 -264.290568) (xy 93.126302 -264.340802)
			(xy 93.126814 -264.366248) (xy 93.445342 -264.366248) (xy 93.449302 -264.317194) (xy 93.461079 -264.26941)
			(xy 93.48037 -264.224134) (xy 93.506673 -264.182538) (xy 93.539308 -264.145701) (xy 93.577429 -264.114576)
			(xy 93.62005 -264.089969) (xy 93.666066 -264.072517) (xy 93.714285 -264.062673) (xy 93.76346 -264.060692)
			(xy 93.812315 -264.066624) (xy 93.859586 -264.080316) (xy 93.904048 -264.101414) (xy 93.944551 -264.12937)
			(xy 93.980044 -264.163462) (xy 94.009609 -264.202806) (xy 94.03248 -264.246383) (xy 94.048064 -264.293064)
			(xy 94.055959 -264.341641) (xy 94.056454 -264.366248) (xy 94.374711 -264.366248) (xy 94.378806 -264.31552)
			(xy 94.390985 -264.266106) (xy 94.410933 -264.219286) (xy 94.438134 -264.176272) (xy 94.471882 -264.138178)
			(xy 94.511304 -264.105991) (xy 94.555378 -264.080545) (xy 94.602964 -264.062498) (xy 94.652828 -264.052318)
			(xy 94.70368 -264.050269) (xy 94.754201 -264.056403) (xy 94.803085 -264.070563) (xy 94.849064 -264.09238)
			(xy 94.890948 -264.12129) (xy 94.927652 -264.156545) (xy 94.958225 -264.197231) (xy 94.981876 -264.242294)
			(xy 94.997992 -264.290568) (xy 95.006156 -264.340802) (xy 95.006668 -264.366248) (xy 95.314765 -264.366248)
			(xy 95.31886 -264.31552) (xy 95.331039 -264.266106) (xy 95.350987 -264.219286) (xy 95.378188 -264.176272)
			(xy 95.411936 -264.138178) (xy 95.451358 -264.105991) (xy 95.495432 -264.080545) (xy 95.543018 -264.062498)
			(xy 95.592882 -264.052318) (xy 95.643734 -264.050269) (xy 95.694255 -264.056403) (xy 95.743139 -264.070563)
			(xy 95.789118 -264.09238) (xy 95.831002 -264.12129) (xy 95.867706 -264.156545) (xy 95.898279 -264.197231)
			(xy 95.92193 -264.242294) (xy 95.938046 -264.290568) (xy 95.94621 -264.340802) (xy 95.946722 -264.366248)
			(xy 96.26525 -264.366248) (xy 96.26921 -264.317194) (xy 96.280987 -264.26941) (xy 96.300278 -264.224134)
			(xy 96.326581 -264.182538) (xy 96.359216 -264.145701) (xy 96.397337 -264.114576) (xy 96.439958 -264.089969)
			(xy 96.485974 -264.072517) (xy 96.534193 -264.062673) (xy 96.583368 -264.060692) (xy 96.632223 -264.066624)
			(xy 96.679494 -264.080316) (xy 96.723956 -264.101414) (xy 96.764459 -264.12937) (xy 96.799952 -264.163462)
			(xy 96.829517 -264.202806) (xy 96.852388 -264.246383) (xy 96.867972 -264.293064) (xy 96.875867 -264.341641)
			(xy 96.876362 -264.366248) (xy 98.145358 -264.366248) (xy 98.149318 -264.317194) (xy 98.161095 -264.26941)
			(xy 98.180386 -264.224134) (xy 98.206689 -264.182538) (xy 98.239324 -264.145701) (xy 98.277445 -264.114576)
			(xy 98.320066 -264.089969) (xy 98.366082 -264.072517) (xy 98.414301 -264.062673) (xy 98.463476 -264.060692)
			(xy 98.512331 -264.066624) (xy 98.559602 -264.080316) (xy 98.604064 -264.101414) (xy 98.644567 -264.12937)
			(xy 98.68006 -264.163462) (xy 98.709625 -264.202806) (xy 98.732496 -264.246383) (xy 98.74808 -264.293064)
			(xy 98.755975 -264.341641) (xy 98.75647 -264.366248) (xy 100.025212 -264.366248) (xy 100.029172 -264.317194)
			(xy 100.040949 -264.26941) (xy 100.06024 -264.224134) (xy 100.086543 -264.182538) (xy 100.119178 -264.145701)
			(xy 100.157299 -264.114576) (xy 100.19992 -264.089969) (xy 100.245936 -264.072517) (xy 100.294155 -264.062673)
			(xy 100.34333 -264.060692) (xy 100.392185 -264.066624) (xy 100.439456 -264.080316) (xy 100.483918 -264.101414)
			(xy 100.524421 -264.12937) (xy 100.559914 -264.163462) (xy 100.589479 -264.202806) (xy 100.61235 -264.246383)
			(xy 100.627934 -264.293064) (xy 100.635829 -264.341641) (xy 100.636324 -264.366248) (xy 100.635829 -264.390855)
			(xy 100.627934 -264.439432) (xy 100.61235 -264.486113) (xy 100.589479 -264.52969) (xy 100.559914 -264.569034)
			(xy 100.524421 -264.603126) (xy 100.483918 -264.631082) (xy 100.439456 -264.65218) (xy 100.392185 -264.665872)
			(xy 100.34333 -264.671804) (xy 100.294155 -264.669823) (xy 100.245936 -264.659979) (xy 100.19992 -264.642527)
			(xy 100.157299 -264.61792) (xy 100.119178 -264.586795) (xy 100.086543 -264.549958) (xy 100.06024 -264.508362)
			(xy 100.040949 -264.463086) (xy 100.029172 -264.415302) (xy 100.025212 -264.366248) (xy 98.75647 -264.366248)
			(xy 98.755975 -264.390855) (xy 98.74808 -264.439432) (xy 98.732496 -264.486113) (xy 98.709625 -264.52969)
			(xy 98.68006 -264.569034) (xy 98.644567 -264.603126) (xy 98.604064 -264.631082) (xy 98.559602 -264.65218)
			(xy 98.512331 -264.665872) (xy 98.463476 -264.671804) (xy 98.414301 -264.669823) (xy 98.366082 -264.659979)
			(xy 98.320066 -264.642527) (xy 98.277445 -264.61792) (xy 98.239324 -264.586795) (xy 98.206689 -264.549958)
			(xy 98.180386 -264.508362) (xy 98.161095 -264.463086) (xy 98.149318 -264.415302) (xy 98.145358 -264.366248)
			(xy 96.876362 -264.366248) (xy 96.875867 -264.390855) (xy 96.867972 -264.439432) (xy 96.852388 -264.486113)
			(xy 96.829517 -264.52969) (xy 96.799952 -264.569034) (xy 96.764459 -264.603126) (xy 96.723956 -264.631082)
			(xy 96.679494 -264.65218) (xy 96.632223 -264.665872) (xy 96.583368 -264.671804) (xy 96.534193 -264.669823)
			(xy 96.485974 -264.659979) (xy 96.439958 -264.642527) (xy 96.397337 -264.61792) (xy 96.359216 -264.586795)
			(xy 96.326581 -264.549958) (xy 96.300278 -264.508362) (xy 96.280987 -264.463086) (xy 96.26921 -264.415302)
			(xy 96.26525 -264.366248) (xy 95.946722 -264.366248) (xy 95.94621 -264.391694) (xy 95.938046 -264.441928)
			(xy 95.92193 -264.490202) (xy 95.898279 -264.535265) (xy 95.867706 -264.575951) (xy 95.831002 -264.611206)
			(xy 95.789118 -264.640116) (xy 95.743139 -264.661933) (xy 95.694255 -264.676093) (xy 95.643734 -264.682227)
			(xy 95.592882 -264.680178) (xy 95.543018 -264.669998) (xy 95.495432 -264.651951) (xy 95.451358 -264.626505)
			(xy 95.411936 -264.594318) (xy 95.378188 -264.556224) (xy 95.350987 -264.51321) (xy 95.331039 -264.46639)
			(xy 95.31886 -264.416976) (xy 95.314765 -264.366248) (xy 95.006668 -264.366248) (xy 95.006156 -264.391694)
			(xy 94.997992 -264.441928) (xy 94.981876 -264.490202) (xy 94.958225 -264.535265) (xy 94.927652 -264.575951)
			(xy 94.890948 -264.611206) (xy 94.849064 -264.640116) (xy 94.803085 -264.661933) (xy 94.754201 -264.676093)
			(xy 94.70368 -264.682227) (xy 94.652828 -264.680178) (xy 94.602964 -264.669998) (xy 94.555378 -264.651951)
			(xy 94.511304 -264.626505) (xy 94.471882 -264.594318) (xy 94.438134 -264.556224) (xy 94.410933 -264.51321)
			(xy 94.390985 -264.46639) (xy 94.378806 -264.416976) (xy 94.374711 -264.366248) (xy 94.056454 -264.366248)
			(xy 94.055959 -264.390855) (xy 94.048064 -264.439432) (xy 94.03248 -264.486113) (xy 94.009609 -264.52969)
			(xy 93.980044 -264.569034) (xy 93.944551 -264.603126) (xy 93.904048 -264.631082) (xy 93.859586 -264.65218)
			(xy 93.812315 -264.665872) (xy 93.76346 -264.671804) (xy 93.714285 -264.669823) (xy 93.666066 -264.659979)
			(xy 93.62005 -264.642527) (xy 93.577429 -264.61792) (xy 93.539308 -264.586795) (xy 93.506673 -264.549958)
			(xy 93.48037 -264.508362) (xy 93.461079 -264.463086) (xy 93.449302 -264.415302) (xy 93.445342 -264.366248)
			(xy 93.126814 -264.366248) (xy 93.126302 -264.391694) (xy 93.118138 -264.441928) (xy 93.102022 -264.490202)
			(xy 93.078371 -264.535265) (xy 93.047798 -264.575951) (xy 93.011094 -264.611206) (xy 92.96921 -264.640116)
			(xy 92.923231 -264.661933) (xy 92.874347 -264.676093) (xy 92.823826 -264.682227) (xy 92.772974 -264.680178)
			(xy 92.72311 -264.669998) (xy 92.675524 -264.651951) (xy 92.63145 -264.626505) (xy 92.592028 -264.594318)
			(xy 92.55828 -264.556224) (xy 92.531079 -264.51321) (xy 92.511131 -264.46639) (xy 92.498952 -264.416976)
			(xy 92.494857 -264.366248) (xy 92.176346 -264.366248) (xy 92.175851 -264.390855) (xy 92.167956 -264.439432)
			(xy 92.152372 -264.486113) (xy 92.129501 -264.52969) (xy 92.099936 -264.569034) (xy 92.064443 -264.603126)
			(xy 92.02394 -264.631082) (xy 91.979478 -264.65218) (xy 91.932207 -264.665872) (xy 91.883352 -264.671804)
			(xy 91.834177 -264.669823) (xy 91.785958 -264.659979) (xy 91.739942 -264.642527) (xy 91.697321 -264.61792)
			(xy 91.6592 -264.586795) (xy 91.626565 -264.549958) (xy 91.600262 -264.508362) (xy 91.580971 -264.463086)
			(xy 91.569194 -264.415302) (xy 91.565234 -264.366248) (xy 91.246706 -264.366248) (xy 91.246194 -264.391694)
			(xy 91.23803 -264.441928) (xy 91.221914 -264.490202) (xy 91.198263 -264.535265) (xy 91.16769 -264.575951)
			(xy 91.130986 -264.611206) (xy 91.089102 -264.640116) (xy 91.043123 -264.661933) (xy 90.994239 -264.676093)
			(xy 90.943718 -264.682227) (xy 90.892866 -264.680178) (xy 90.843002 -264.669998) (xy 90.795416 -264.651951)
			(xy 90.751342 -264.626505) (xy 90.71192 -264.594318) (xy 90.678172 -264.556224) (xy 90.650971 -264.51321)
			(xy 90.631023 -264.46639) (xy 90.618844 -264.416976) (xy 90.614749 -264.366248) (xy 90.296238 -264.366248)
			(xy 90.295743 -264.390855) (xy 90.287848 -264.439432) (xy 90.272264 -264.486113) (xy 90.249393 -264.52969)
			(xy 90.219828 -264.569034) (xy 90.184335 -264.603126) (xy 90.143832 -264.631082) (xy 90.09937 -264.65218)
			(xy 90.052099 -264.665872) (xy 90.003244 -264.671804) (xy 89.954069 -264.669823) (xy 89.90585 -264.659979)
			(xy 89.859834 -264.642527) (xy 89.817213 -264.61792) (xy 89.779092 -264.586795) (xy 89.746457 -264.549958)
			(xy 89.720154 -264.508362) (xy 89.700863 -264.463086) (xy 89.689086 -264.415302) (xy 89.685126 -264.366248)
			(xy 89.366852 -264.366248) (xy 89.36634 -264.391694) (xy 89.358176 -264.441928) (xy 89.34206 -264.490202)
			(xy 89.318409 -264.535265) (xy 89.287836 -264.575951) (xy 89.251132 -264.611206) (xy 89.209248 -264.640116)
			(xy 89.163269 -264.661933) (xy 89.114385 -264.676093) (xy 89.063864 -264.682227) (xy 89.013012 -264.680178)
			(xy 88.963148 -264.669998) (xy 88.915562 -264.651951) (xy 88.871488 -264.626505) (xy 88.832066 -264.594318)
			(xy 88.798318 -264.556224) (xy 88.771117 -264.51321) (xy 88.751169 -264.46639) (xy 88.73899 -264.416976)
			(xy 88.734895 -264.366248) (xy 88.426798 -264.366248) (xy 88.426286 -264.391694) (xy 88.418122 -264.441928)
			(xy 88.402006 -264.490202) (xy 88.378355 -264.535265) (xy 88.347782 -264.575951) (xy 88.311078 -264.611206)
			(xy 88.269194 -264.640116) (xy 88.223215 -264.661933) (xy 88.174331 -264.676093) (xy 88.12381 -264.682227)
			(xy 88.072958 -264.680178) (xy 88.023094 -264.669998) (xy 87.975508 -264.651951) (xy 87.931434 -264.626505)
			(xy 87.892012 -264.594318) (xy 87.858264 -264.556224) (xy 87.831063 -264.51321) (xy 87.811115 -264.46639)
			(xy 87.798936 -264.416976) (xy 87.794841 -264.366248) (xy 87.47633 -264.366248) (xy 87.475835 -264.390855)
			(xy 87.46794 -264.439432) (xy 87.452356 -264.486113) (xy 87.429485 -264.52969) (xy 87.39992 -264.569034)
			(xy 87.364427 -264.603126) (xy 87.323924 -264.631082) (xy 87.279462 -264.65218) (xy 87.232191 -264.665872)
			(xy 87.183336 -264.671804) (xy 87.134161 -264.669823) (xy 87.085942 -264.659979) (xy 87.039926 -264.642527)
			(xy 86.997305 -264.61792) (xy 86.959184 -264.586795) (xy 86.926549 -264.549958) (xy 86.900246 -264.508362)
			(xy 86.880955 -264.463086) (xy 86.869178 -264.415302) (xy 86.865218 -264.366248) (xy 86.54669 -264.366248)
			(xy 86.546178 -264.391694) (xy 86.538014 -264.441928) (xy 86.521898 -264.490202) (xy 86.498247 -264.535265)
			(xy 86.467674 -264.575951) (xy 86.43097 -264.611206) (xy 86.389086 -264.640116) (xy 86.343107 -264.661933)
			(xy 86.294223 -264.676093) (xy 86.243702 -264.682227) (xy 86.19285 -264.680178) (xy 86.142986 -264.669998)
			(xy 86.0954 -264.651951) (xy 86.051326 -264.626505) (xy 86.011904 -264.594318) (xy 85.978156 -264.556224)
			(xy 85.950955 -264.51321) (xy 85.931007 -264.46639) (xy 85.918828 -264.416976) (xy 85.914733 -264.366248)
			(xy 85.596222 -264.366248) (xy 85.595727 -264.390855) (xy 85.587832 -264.439432) (xy 85.572248 -264.486113)
			(xy 85.549377 -264.52969) (xy 85.519812 -264.569034) (xy 85.484319 -264.603126) (xy 85.443816 -264.631082)
			(xy 85.399354 -264.65218) (xy 85.352083 -264.665872) (xy 85.303228 -264.671804) (xy 85.254053 -264.669823)
			(xy 85.205834 -264.659979) (xy 85.159818 -264.642527) (xy 85.117197 -264.61792) (xy 85.079076 -264.586795)
			(xy 85.046441 -264.549958) (xy 85.020138 -264.508362) (xy 85.000847 -264.463086) (xy 84.98907 -264.415302)
			(xy 84.98511 -264.366248) (xy 84.666836 -264.366248) (xy 84.666324 -264.391694) (xy 84.65816 -264.441928)
			(xy 84.642044 -264.490202) (xy 84.618393 -264.535265) (xy 84.58782 -264.575951) (xy 84.551116 -264.611206)
			(xy 84.509232 -264.640116) (xy 84.463253 -264.661933) (xy 84.414369 -264.676093) (xy 84.363848 -264.682227)
			(xy 84.312996 -264.680178) (xy 84.263132 -264.669998) (xy 84.215546 -264.651951) (xy 84.171472 -264.626505)
			(xy 84.13205 -264.594318) (xy 84.098302 -264.556224) (xy 84.071101 -264.51321) (xy 84.051153 -264.46639)
			(xy 84.038974 -264.416976) (xy 84.034879 -264.366248) (xy 83.716368 -264.366248) (xy 83.715873 -264.390855)
			(xy 83.707978 -264.439432) (xy 83.692394 -264.486113) (xy 83.669523 -264.52969) (xy 83.639958 -264.569034)
			(xy 83.604465 -264.603126) (xy 83.563962 -264.631082) (xy 83.5195 -264.65218) (xy 83.472229 -264.665872)
			(xy 83.423374 -264.671804) (xy 83.374199 -264.669823) (xy 83.32598 -264.659979) (xy 83.279964 -264.642527)
			(xy 83.237343 -264.61792) (xy 83.199222 -264.586795) (xy 83.166587 -264.549958) (xy 83.140284 -264.508362)
			(xy 83.120993 -264.463086) (xy 83.109216 -264.415302) (xy 83.105256 -264.366248) (xy 82.786728 -264.366248)
			(xy 82.786216 -264.391694) (xy 82.778052 -264.441928) (xy 82.761936 -264.490202) (xy 82.738285 -264.535265)
			(xy 82.707712 -264.575951) (xy 82.671008 -264.611206) (xy 82.629124 -264.640116) (xy 82.583145 -264.661933)
			(xy 82.534261 -264.676093) (xy 82.48374 -264.682227) (xy 82.432888 -264.680178) (xy 82.383024 -264.669998)
			(xy 82.335438 -264.651951) (xy 82.291364 -264.626505) (xy 82.251942 -264.594318) (xy 82.218194 -264.556224)
			(xy 82.190993 -264.51321) (xy 82.171045 -264.46639) (xy 82.158866 -264.416976) (xy 82.154771 -264.366248)
			(xy 81.846674 -264.366248) (xy 81.846162 -264.391694) (xy 81.837998 -264.441928) (xy 81.821882 -264.490202)
			(xy 81.798231 -264.535265) (xy 81.767658 -264.575951) (xy 81.730954 -264.611206) (xy 81.68907 -264.640116)
			(xy 81.643091 -264.661933) (xy 81.594207 -264.676093) (xy 81.543686 -264.682227) (xy 81.492834 -264.680178)
			(xy 81.44297 -264.669998) (xy 81.395384 -264.651951) (xy 81.35131 -264.626505) (xy 81.311888 -264.594318)
			(xy 81.27814 -264.556224) (xy 81.250939 -264.51321) (xy 81.230991 -264.46639) (xy 81.218812 -264.416976)
			(xy 81.214717 -264.366248) (xy 80.89646 -264.366248) (xy 80.895965 -264.390855) (xy 80.88807 -264.439432)
			(xy 80.872486 -264.486113) (xy 80.849615 -264.52969) (xy 80.82005 -264.569034) (xy 80.784557 -264.603126)
			(xy 80.744054 -264.631082) (xy 80.699592 -264.65218) (xy 80.652321 -264.665872) (xy 80.603466 -264.671804)
			(xy 80.554291 -264.669823) (xy 80.506072 -264.659979) (xy 80.460056 -264.642527) (xy 80.417435 -264.61792)
			(xy 80.379314 -264.586795) (xy 80.346679 -264.549958) (xy 80.320376 -264.508362) (xy 80.301085 -264.463086)
			(xy 80.289308 -264.415302) (xy 80.285348 -264.366248) (xy 79.016352 -264.366248) (xy 79.015857 -264.390855)
			(xy 79.007962 -264.439432) (xy 78.992378 -264.486113) (xy 78.969507 -264.52969) (xy 78.939942 -264.569034)
			(xy 78.904449 -264.603126) (xy 78.863946 -264.631082) (xy 78.819484 -264.65218) (xy 78.772213 -264.665872)
			(xy 78.723358 -264.671804) (xy 78.674183 -264.669823) (xy 78.625964 -264.659979) (xy 78.579948 -264.642527)
			(xy 78.537327 -264.61792) (xy 78.499206 -264.586795) (xy 78.466571 -264.549958) (xy 78.440268 -264.508362)
			(xy 78.420977 -264.463086) (xy 78.4092 -264.415302) (xy 78.40524 -264.366248) (xy 73.375774 -264.366248)
			(xy 73.375774 -264.910316) (xy 76.807072 -264.910316) (xy 76.811032 -264.861262) (xy 76.822809 -264.813478)
			(xy 76.8421 -264.768202) (xy 76.868403 -264.726606) (xy 76.901038 -264.689769) (xy 76.939159 -264.658644)
			(xy 76.98178 -264.634037) (xy 77.027796 -264.616585) (xy 77.076015 -264.606741) (xy 77.12519 -264.60476)
			(xy 77.174045 -264.610692) (xy 77.221316 -264.624384) (xy 77.265778 -264.645482) (xy 77.306281 -264.673438)
			(xy 77.341774 -264.70753) (xy 77.371339 -264.746874) (xy 77.39421 -264.790451) (xy 77.409794 -264.837132)
			(xy 77.417689 -264.885709) (xy 77.418184 -264.910316) (xy 77.417689 -264.934923) (xy 77.409794 -264.9835)
			(xy 77.39421 -265.030181) (xy 77.371339 -265.073758) (xy 77.341774 -265.113102) (xy 77.306281 -265.147194)
			(xy 77.265778 -265.17515) (xy 77.263451 -265.176254) (xy 79.815194 -265.176254) (xy 79.819154 -265.1272)
			(xy 79.830931 -265.079416) (xy 79.850222 -265.03414) (xy 79.876525 -264.992544) (xy 79.90916 -264.955707)
			(xy 79.947281 -264.924582) (xy 79.989902 -264.899975) (xy 80.035918 -264.882523) (xy 80.084137 -264.872679)
			(xy 80.133312 -264.870698) (xy 80.182167 -264.87663) (xy 80.229438 -264.890322) (xy 80.2739 -264.91142)
			(xy 80.314403 -264.939376) (xy 80.349896 -264.973468) (xy 80.379461 -265.012812) (xy 80.402332 -265.056389)
			(xy 80.417916 -265.10307) (xy 80.425811 -265.151647) (xy 80.426306 -265.176254) (xy 80.744817 -265.176254)
			(xy 80.748912 -265.125526) (xy 80.761091 -265.076112) (xy 80.781039 -265.029292) (xy 80.80824 -264.986278)
			(xy 80.841988 -264.948184) (xy 80.88141 -264.915997) (xy 80.925484 -264.890551) (xy 80.97307 -264.872504)
			(xy 81.022934 -264.862324) (xy 81.073786 -264.860275) (xy 81.124307 -264.866409) (xy 81.173191 -264.880569)
			(xy 81.21917 -264.902386) (xy 81.261054 -264.931296) (xy 81.297758 -264.966551) (xy 81.328331 -265.007237)
			(xy 81.351982 -265.0523) (xy 81.368098 -265.100574) (xy 81.376262 -265.150808) (xy 81.376774 -265.176254)
			(xy 81.695302 -265.176254) (xy 81.699262 -265.1272) (xy 81.711039 -265.079416) (xy 81.73033 -265.03414)
			(xy 81.756633 -264.992544) (xy 81.789268 -264.955707) (xy 81.827389 -264.924582) (xy 81.87001 -264.899975)
			(xy 81.916026 -264.882523) (xy 81.964245 -264.872679) (xy 82.01342 -264.870698) (xy 82.062275 -264.87663)
			(xy 82.109546 -264.890322) (xy 82.154008 -264.91142) (xy 82.194511 -264.939376) (xy 82.230004 -264.973468)
			(xy 82.259569 -265.012812) (xy 82.28244 -265.056389) (xy 82.298024 -265.10307) (xy 82.305919 -265.151647)
			(xy 82.306414 -265.176254) (xy 82.635356 -265.176254) (xy 82.639316 -265.1272) (xy 82.651093 -265.079416)
			(xy 82.670384 -265.03414) (xy 82.696687 -264.992544) (xy 82.729322 -264.955707) (xy 82.767443 -264.924582)
			(xy 82.810064 -264.899975) (xy 82.85608 -264.882523) (xy 82.904299 -264.872679) (xy 82.953474 -264.870698)
			(xy 83.002329 -264.87663) (xy 83.0496 -264.890322) (xy 83.094062 -264.91142) (xy 83.134565 -264.939376)
			(xy 83.170058 -264.973468) (xy 83.199623 -265.012812) (xy 83.222494 -265.056389) (xy 83.238078 -265.10307)
			(xy 83.245973 -265.151647) (xy 83.246468 -265.176254) (xy 83.575156 -265.176254) (xy 83.579116 -265.1272)
			(xy 83.590893 -265.079416) (xy 83.610184 -265.03414) (xy 83.636487 -264.992544) (xy 83.669122 -264.955707)
			(xy 83.707243 -264.924582) (xy 83.749864 -264.899975) (xy 83.79588 -264.882523) (xy 83.844099 -264.872679)
			(xy 83.893274 -264.870698) (xy 83.942129 -264.87663) (xy 83.9894 -264.890322) (xy 84.033862 -264.91142)
			(xy 84.074365 -264.939376) (xy 84.109858 -264.973468) (xy 84.139423 -265.012812) (xy 84.162294 -265.056389)
			(xy 84.177878 -265.10307) (xy 84.185773 -265.151647) (xy 84.186268 -265.176254) (xy 84.504779 -265.176254)
			(xy 84.508874 -265.125526) (xy 84.521053 -265.076112) (xy 84.541001 -265.029292) (xy 84.568202 -264.986278)
			(xy 84.60195 -264.948184) (xy 84.641372 -264.915997) (xy 84.685446 -264.890551) (xy 84.733032 -264.872504)
			(xy 84.782896 -264.862324) (xy 84.833748 -264.860275) (xy 84.884269 -264.866409) (xy 84.933153 -264.880569)
			(xy 84.979132 -264.902386) (xy 85.021016 -264.931296) (xy 85.05772 -264.966551) (xy 85.088293 -265.007237)
			(xy 85.111944 -265.0523) (xy 85.12806 -265.100574) (xy 85.136224 -265.150808) (xy 85.136736 -265.176254)
			(xy 85.455264 -265.176254) (xy 85.459224 -265.1272) (xy 85.471001 -265.079416) (xy 85.490292 -265.03414)
			(xy 85.516595 -264.992544) (xy 85.54923 -264.955707) (xy 85.587351 -264.924582) (xy 85.629972 -264.899975)
			(xy 85.675988 -264.882523) (xy 85.724207 -264.872679) (xy 85.773382 -264.870698) (xy 85.822237 -264.87663)
			(xy 85.869508 -264.890322) (xy 85.91397 -264.91142) (xy 85.954473 -264.939376) (xy 85.989966 -264.973468)
			(xy 86.019531 -265.012812) (xy 86.042402 -265.056389) (xy 86.057986 -265.10307) (xy 86.065881 -265.151647)
			(xy 86.066376 -265.176254) (xy 86.395318 -265.176254) (xy 86.399278 -265.1272) (xy 86.411055 -265.079416)
			(xy 86.430346 -265.03414) (xy 86.456649 -264.992544) (xy 86.489284 -264.955707) (xy 86.527405 -264.924582)
			(xy 86.570026 -264.899975) (xy 86.616042 -264.882523) (xy 86.664261 -264.872679) (xy 86.713436 -264.870698)
			(xy 86.762291 -264.87663) (xy 86.809562 -264.890322) (xy 86.854024 -264.91142) (xy 86.894527 -264.939376)
			(xy 86.93002 -264.973468) (xy 86.959585 -265.012812) (xy 86.982456 -265.056389) (xy 86.99804 -265.10307)
			(xy 87.005935 -265.151647) (xy 87.00643 -265.176254) (xy 87.324687 -265.176254) (xy 87.328782 -265.125526)
			(xy 87.340961 -265.076112) (xy 87.360909 -265.029292) (xy 87.38811 -264.986278) (xy 87.421858 -264.948184)
			(xy 87.46128 -264.915997) (xy 87.505354 -264.890551) (xy 87.55294 -264.872504) (xy 87.602804 -264.862324)
			(xy 87.653656 -264.860275) (xy 87.704177 -264.866409) (xy 87.753061 -264.880569) (xy 87.79904 -264.902386)
			(xy 87.840924 -264.931296) (xy 87.877628 -264.966551) (xy 87.908201 -265.007237) (xy 87.931852 -265.0523)
			(xy 87.947968 -265.100574) (xy 87.956132 -265.150808) (xy 87.956644 -265.176254) (xy 88.275172 -265.176254)
			(xy 88.279132 -265.1272) (xy 88.290909 -265.079416) (xy 88.3102 -265.03414) (xy 88.336503 -264.992544)
			(xy 88.369138 -264.955707) (xy 88.407259 -264.924582) (xy 88.44988 -264.899975) (xy 88.495896 -264.882523)
			(xy 88.544115 -264.872679) (xy 88.59329 -264.870698) (xy 88.642145 -264.87663) (xy 88.689416 -264.890322)
			(xy 88.733878 -264.91142) (xy 88.774381 -264.939376) (xy 88.809874 -264.973468) (xy 88.839439 -265.012812)
			(xy 88.86231 -265.056389) (xy 88.877894 -265.10307) (xy 88.885789 -265.151647) (xy 88.886284 -265.176254)
			(xy 89.215226 -265.176254) (xy 89.219186 -265.1272) (xy 89.230963 -265.079416) (xy 89.250254 -265.03414)
			(xy 89.276557 -264.992544) (xy 89.309192 -264.955707) (xy 89.347313 -264.924582) (xy 89.389934 -264.899975)
			(xy 89.43595 -264.882523) (xy 89.484169 -264.872679) (xy 89.533344 -264.870698) (xy 89.582199 -264.87663)
			(xy 89.62947 -264.890322) (xy 89.673932 -264.91142) (xy 89.714435 -264.939376) (xy 89.749928 -264.973468)
			(xy 89.779493 -265.012812) (xy 89.802364 -265.056389) (xy 89.817948 -265.10307) (xy 89.825843 -265.151647)
			(xy 89.826338 -265.176254) (xy 90.15528 -265.176254) (xy 90.15924 -265.1272) (xy 90.171017 -265.079416)
			(xy 90.190308 -265.03414) (xy 90.216611 -264.992544) (xy 90.249246 -264.955707) (xy 90.287367 -264.924582)
			(xy 90.329988 -264.899975) (xy 90.376004 -264.882523) (xy 90.424223 -264.872679) (xy 90.473398 -264.870698)
			(xy 90.522253 -264.87663) (xy 90.569524 -264.890322) (xy 90.613986 -264.91142) (xy 90.654489 -264.939376)
			(xy 90.689982 -264.973468) (xy 90.719547 -265.012812) (xy 90.742418 -265.056389) (xy 90.758002 -265.10307)
			(xy 90.765897 -265.151647) (xy 90.766392 -265.176254) (xy 91.084903 -265.176254) (xy 91.088998 -265.125526)
			(xy 91.101177 -265.076112) (xy 91.121125 -265.029292) (xy 91.148326 -264.986278) (xy 91.182074 -264.948184)
			(xy 91.221496 -264.915997) (xy 91.26557 -264.890551) (xy 91.313156 -264.872504) (xy 91.36302 -264.862324)
			(xy 91.413872 -264.860275) (xy 91.464393 -264.866409) (xy 91.513277 -264.880569) (xy 91.559256 -264.902386)
			(xy 91.60114 -264.931296) (xy 91.637844 -264.966551) (xy 91.668417 -265.007237) (xy 91.692068 -265.0523)
			(xy 91.708184 -265.100574) (xy 91.716348 -265.150808) (xy 91.71686 -265.176254) (xy 92.035134 -265.176254)
			(xy 92.039094 -265.1272) (xy 92.050871 -265.079416) (xy 92.070162 -265.03414) (xy 92.096465 -264.992544)
			(xy 92.1291 -264.955707) (xy 92.167221 -264.924582) (xy 92.209842 -264.899975) (xy 92.255858 -264.882523)
			(xy 92.304077 -264.872679) (xy 92.353252 -264.870698) (xy 92.402107 -264.87663) (xy 92.449378 -264.890322)
			(xy 92.49384 -264.91142) (xy 92.534343 -264.939376) (xy 92.569836 -264.973468) (xy 92.599401 -265.012812)
			(xy 92.622272 -265.056389) (xy 92.637856 -265.10307) (xy 92.645751 -265.151647) (xy 92.646246 -265.176254)
			(xy 92.975188 -265.176254) (xy 92.979148 -265.1272) (xy 92.990925 -265.079416) (xy 93.010216 -265.03414)
			(xy 93.036519 -264.992544) (xy 93.069154 -264.955707) (xy 93.107275 -264.924582) (xy 93.149896 -264.899975)
			(xy 93.195912 -264.882523) (xy 93.244131 -264.872679) (xy 93.293306 -264.870698) (xy 93.342161 -264.87663)
			(xy 93.389432 -264.890322) (xy 93.433894 -264.91142) (xy 93.474397 -264.939376) (xy 93.50989 -264.973468)
			(xy 93.539455 -265.012812) (xy 93.562326 -265.056389) (xy 93.57791 -265.10307) (xy 93.585805 -265.151647)
			(xy 93.5863 -265.176254) (xy 93.904811 -265.176254) (xy 93.908906 -265.125526) (xy 93.921085 -265.076112)
			(xy 93.941033 -265.029292) (xy 93.968234 -264.986278) (xy 94.001982 -264.948184) (xy 94.041404 -264.915997)
			(xy 94.085478 -264.890551) (xy 94.133064 -264.872504) (xy 94.182928 -264.862324) (xy 94.23378 -264.860275)
			(xy 94.284301 -264.866409) (xy 94.333185 -264.880569) (xy 94.379164 -264.902386) (xy 94.421048 -264.931296)
			(xy 94.457752 -264.966551) (xy 94.488325 -265.007237) (xy 94.511976 -265.0523) (xy 94.528092 -265.100574)
			(xy 94.536256 -265.150808) (xy 94.536768 -265.176254) (xy 94.855296 -265.176254) (xy 94.859256 -265.1272)
			(xy 94.871033 -265.079416) (xy 94.890324 -265.03414) (xy 94.916627 -264.992544) (xy 94.949262 -264.955707)
			(xy 94.987383 -264.924582) (xy 95.030004 -264.899975) (xy 95.07602 -264.882523) (xy 95.124239 -264.872679)
			(xy 95.173414 -264.870698) (xy 95.222269 -264.87663) (xy 95.26954 -264.890322) (xy 95.314002 -264.91142)
			(xy 95.354505 -264.939376) (xy 95.389998 -264.973468) (xy 95.419563 -265.012812) (xy 95.442434 -265.056389)
			(xy 95.458018 -265.10307) (xy 95.465913 -265.151647) (xy 95.466408 -265.176254) (xy 95.79535 -265.176254)
			(xy 95.79931 -265.1272) (xy 95.811087 -265.079416) (xy 95.830378 -265.03414) (xy 95.856681 -264.992544)
			(xy 95.889316 -264.955707) (xy 95.927437 -264.924582) (xy 95.970058 -264.899975) (xy 96.016074 -264.882523)
			(xy 96.064293 -264.872679) (xy 96.113468 -264.870698) (xy 96.162323 -264.87663) (xy 96.209594 -264.890322)
			(xy 96.254056 -264.91142) (xy 96.294559 -264.939376) (xy 96.330052 -264.973468) (xy 96.359617 -265.012812)
			(xy 96.382488 -265.056389) (xy 96.398072 -265.10307) (xy 96.405967 -265.151647) (xy 96.406462 -265.176254)
			(xy 97.675204 -265.176254) (xy 97.679164 -265.1272) (xy 97.690941 -265.079416) (xy 97.710232 -265.03414)
			(xy 97.736535 -264.992544) (xy 97.76917 -264.955707) (xy 97.807291 -264.924582) (xy 97.849912 -264.899975)
			(xy 97.895928 -264.882523) (xy 97.944147 -264.872679) (xy 97.993322 -264.870698) (xy 98.042177 -264.87663)
			(xy 98.089448 -264.890322) (xy 98.13391 -264.91142) (xy 98.174413 -264.939376) (xy 98.209906 -264.973468)
			(xy 98.239471 -265.012812) (xy 98.262342 -265.056389) (xy 98.277926 -265.10307) (xy 98.285821 -265.151647)
			(xy 98.286316 -265.176254) (xy 99.555312 -265.176254) (xy 99.559272 -265.1272) (xy 99.571049 -265.079416)
			(xy 99.59034 -265.03414) (xy 99.616643 -264.992544) (xy 99.649278 -264.955707) (xy 99.687399 -264.924582)
			(xy 99.73002 -264.899975) (xy 99.776036 -264.882523) (xy 99.824255 -264.872679) (xy 99.87343 -264.870698)
			(xy 99.922285 -264.87663) (xy 99.969556 -264.890322) (xy 100.014018 -264.91142) (xy 100.054521 -264.939376)
			(xy 100.090014 -264.973468) (xy 100.119579 -265.012812) (xy 100.14245 -265.056389) (xy 100.158034 -265.10307)
			(xy 100.165929 -265.151647) (xy 100.166424 -265.176254) (xy 100.165929 -265.200861) (xy 100.158034 -265.249438)
			(xy 100.14245 -265.296119) (xy 100.119579 -265.339696) (xy 100.090014 -265.37904) (xy 100.054521 -265.413132)
			(xy 100.014018 -265.441088) (xy 99.969556 -265.462186) (xy 99.922285 -265.475878) (xy 99.87343 -265.48181)
			(xy 99.824255 -265.479829) (xy 99.776036 -265.469985) (xy 99.73002 -265.452533) (xy 99.687399 -265.427926)
			(xy 99.649278 -265.396801) (xy 99.616643 -265.359964) (xy 99.59034 -265.318368) (xy 99.571049 -265.273092)
			(xy 99.559272 -265.225308) (xy 99.555312 -265.176254) (xy 98.286316 -265.176254) (xy 98.285821 -265.200861)
			(xy 98.277926 -265.249438) (xy 98.262342 -265.296119) (xy 98.239471 -265.339696) (xy 98.209906 -265.37904)
			(xy 98.174413 -265.413132) (xy 98.13391 -265.441088) (xy 98.089448 -265.462186) (xy 98.042177 -265.475878)
			(xy 97.993322 -265.48181) (xy 97.944147 -265.479829) (xy 97.895928 -265.469985) (xy 97.849912 -265.452533)
			(xy 97.807291 -265.427926) (xy 97.76917 -265.396801) (xy 97.736535 -265.359964) (xy 97.710232 -265.318368)
			(xy 97.690941 -265.273092) (xy 97.679164 -265.225308) (xy 97.675204 -265.176254) (xy 96.406462 -265.176254)
			(xy 96.405967 -265.200861) (xy 96.398072 -265.249438) (xy 96.382488 -265.296119) (xy 96.359617 -265.339696)
			(xy 96.330052 -265.37904) (xy 96.294559 -265.413132) (xy 96.254056 -265.441088) (xy 96.209594 -265.462186)
			(xy 96.162323 -265.475878) (xy 96.113468 -265.48181) (xy 96.064293 -265.479829) (xy 96.016074 -265.469985)
			(xy 95.970058 -265.452533) (xy 95.927437 -265.427926) (xy 95.889316 -265.396801) (xy 95.856681 -265.359964)
			(xy 95.830378 -265.318368) (xy 95.811087 -265.273092) (xy 95.79931 -265.225308) (xy 95.79535 -265.176254)
			(xy 95.466408 -265.176254) (xy 95.465913 -265.200861) (xy 95.458018 -265.249438) (xy 95.442434 -265.296119)
			(xy 95.419563 -265.339696) (xy 95.389998 -265.37904) (xy 95.354505 -265.413132) (xy 95.314002 -265.441088)
			(xy 95.26954 -265.462186) (xy 95.222269 -265.475878) (xy 95.173414 -265.48181) (xy 95.124239 -265.479829)
			(xy 95.07602 -265.469985) (xy 95.030004 -265.452533) (xy 94.987383 -265.427926) (xy 94.949262 -265.396801)
			(xy 94.916627 -265.359964) (xy 94.890324 -265.318368) (xy 94.871033 -265.273092) (xy 94.859256 -265.225308)
			(xy 94.855296 -265.176254) (xy 94.536768 -265.176254) (xy 94.536256 -265.2017) (xy 94.528092 -265.251934)
			(xy 94.511976 -265.300208) (xy 94.488325 -265.345271) (xy 94.457752 -265.385957) (xy 94.421048 -265.421212)
			(xy 94.379164 -265.450122) (xy 94.333185 -265.471939) (xy 94.284301 -265.486099) (xy 94.23378 -265.492233)
			(xy 94.182928 -265.490184) (xy 94.133064 -265.480004) (xy 94.085478 -265.461957) (xy 94.041404 -265.436511)
			(xy 94.001982 -265.404324) (xy 93.968234 -265.36623) (xy 93.941033 -265.323216) (xy 93.921085 -265.276396)
			(xy 93.908906 -265.226982) (xy 93.904811 -265.176254) (xy 93.5863 -265.176254) (xy 93.585805 -265.200861)
			(xy 93.57791 -265.249438) (xy 93.562326 -265.296119) (xy 93.539455 -265.339696) (xy 93.50989 -265.37904)
			(xy 93.474397 -265.413132) (xy 93.433894 -265.441088) (xy 93.389432 -265.462186) (xy 93.342161 -265.475878)
			(xy 93.293306 -265.48181) (xy 93.244131 -265.479829) (xy 93.195912 -265.469985) (xy 93.149896 -265.452533)
			(xy 93.107275 -265.427926) (xy 93.069154 -265.396801) (xy 93.036519 -265.359964) (xy 93.010216 -265.318368)
			(xy 92.990925 -265.273092) (xy 92.979148 -265.225308) (xy 92.975188 -265.176254) (xy 92.646246 -265.176254)
			(xy 92.645751 -265.200861) (xy 92.637856 -265.249438) (xy 92.622272 -265.296119) (xy 92.599401 -265.339696)
			(xy 92.569836 -265.37904) (xy 92.534343 -265.413132) (xy 92.49384 -265.441088) (xy 92.449378 -265.462186)
			(xy 92.402107 -265.475878) (xy 92.353252 -265.48181) (xy 92.304077 -265.479829) (xy 92.255858 -265.469985)
			(xy 92.209842 -265.452533) (xy 92.167221 -265.427926) (xy 92.1291 -265.396801) (xy 92.096465 -265.359964)
			(xy 92.070162 -265.318368) (xy 92.050871 -265.273092) (xy 92.039094 -265.225308) (xy 92.035134 -265.176254)
			(xy 91.71686 -265.176254) (xy 91.716348 -265.2017) (xy 91.708184 -265.251934) (xy 91.692068 -265.300208)
			(xy 91.668417 -265.345271) (xy 91.637844 -265.385957) (xy 91.60114 -265.421212) (xy 91.559256 -265.450122)
			(xy 91.513277 -265.471939) (xy 91.464393 -265.486099) (xy 91.413872 -265.492233) (xy 91.36302 -265.490184)
			(xy 91.313156 -265.480004) (xy 91.26557 -265.461957) (xy 91.221496 -265.436511) (xy 91.182074 -265.404324)
			(xy 91.148326 -265.36623) (xy 91.121125 -265.323216) (xy 91.101177 -265.276396) (xy 91.088998 -265.226982)
			(xy 91.084903 -265.176254) (xy 90.766392 -265.176254) (xy 90.765897 -265.200861) (xy 90.758002 -265.249438)
			(xy 90.742418 -265.296119) (xy 90.719547 -265.339696) (xy 90.689982 -265.37904) (xy 90.654489 -265.413132)
			(xy 90.613986 -265.441088) (xy 90.569524 -265.462186) (xy 90.522253 -265.475878) (xy 90.473398 -265.48181)
			(xy 90.424223 -265.479829) (xy 90.376004 -265.469985) (xy 90.329988 -265.452533) (xy 90.287367 -265.427926)
			(xy 90.249246 -265.396801) (xy 90.216611 -265.359964) (xy 90.190308 -265.318368) (xy 90.171017 -265.273092)
			(xy 90.15924 -265.225308) (xy 90.15528 -265.176254) (xy 89.826338 -265.176254) (xy 89.825843 -265.200861)
			(xy 89.817948 -265.249438) (xy 89.802364 -265.296119) (xy 89.779493 -265.339696) (xy 89.749928 -265.37904)
			(xy 89.714435 -265.413132) (xy 89.673932 -265.441088) (xy 89.62947 -265.462186) (xy 89.582199 -265.475878)
			(xy 89.533344 -265.48181) (xy 89.484169 -265.479829) (xy 89.43595 -265.469985) (xy 89.389934 -265.452533)
			(xy 89.347313 -265.427926) (xy 89.309192 -265.396801) (xy 89.276557 -265.359964) (xy 89.250254 -265.318368)
			(xy 89.230963 -265.273092) (xy 89.219186 -265.225308) (xy 89.215226 -265.176254) (xy 88.886284 -265.176254)
			(xy 88.885789 -265.200861) (xy 88.877894 -265.249438) (xy 88.86231 -265.296119) (xy 88.839439 -265.339696)
			(xy 88.809874 -265.37904) (xy 88.774381 -265.413132) (xy 88.733878 -265.441088) (xy 88.689416 -265.462186)
			(xy 88.642145 -265.475878) (xy 88.59329 -265.48181) (xy 88.544115 -265.479829) (xy 88.495896 -265.469985)
			(xy 88.44988 -265.452533) (xy 88.407259 -265.427926) (xy 88.369138 -265.396801) (xy 88.336503 -265.359964)
			(xy 88.3102 -265.318368) (xy 88.290909 -265.273092) (xy 88.279132 -265.225308) (xy 88.275172 -265.176254)
			(xy 87.956644 -265.176254) (xy 87.956132 -265.2017) (xy 87.947968 -265.251934) (xy 87.931852 -265.300208)
			(xy 87.908201 -265.345271) (xy 87.877628 -265.385957) (xy 87.840924 -265.421212) (xy 87.79904 -265.450122)
			(xy 87.753061 -265.471939) (xy 87.704177 -265.486099) (xy 87.653656 -265.492233) (xy 87.602804 -265.490184)
			(xy 87.55294 -265.480004) (xy 87.505354 -265.461957) (xy 87.46128 -265.436511) (xy 87.421858 -265.404324)
			(xy 87.38811 -265.36623) (xy 87.360909 -265.323216) (xy 87.340961 -265.276396) (xy 87.328782 -265.226982)
			(xy 87.324687 -265.176254) (xy 87.00643 -265.176254) (xy 87.005935 -265.200861) (xy 86.99804 -265.249438)
			(xy 86.982456 -265.296119) (xy 86.959585 -265.339696) (xy 86.93002 -265.37904) (xy 86.894527 -265.413132)
			(xy 86.854024 -265.441088) (xy 86.809562 -265.462186) (xy 86.762291 -265.475878) (xy 86.713436 -265.48181)
			(xy 86.664261 -265.479829) (xy 86.616042 -265.469985) (xy 86.570026 -265.452533) (xy 86.527405 -265.427926)
			(xy 86.489284 -265.396801) (xy 86.456649 -265.359964) (xy 86.430346 -265.318368) (xy 86.411055 -265.273092)
			(xy 86.399278 -265.225308) (xy 86.395318 -265.176254) (xy 86.066376 -265.176254) (xy 86.065881 -265.200861)
			(xy 86.057986 -265.249438) (xy 86.042402 -265.296119) (xy 86.019531 -265.339696) (xy 85.989966 -265.37904)
			(xy 85.954473 -265.413132) (xy 85.91397 -265.441088) (xy 85.869508 -265.462186) (xy 85.822237 -265.475878)
			(xy 85.773382 -265.48181) (xy 85.724207 -265.479829) (xy 85.675988 -265.469985) (xy 85.629972 -265.452533)
			(xy 85.587351 -265.427926) (xy 85.54923 -265.396801) (xy 85.516595 -265.359964) (xy 85.490292 -265.318368)
			(xy 85.471001 -265.273092) (xy 85.459224 -265.225308) (xy 85.455264 -265.176254) (xy 85.136736 -265.176254)
			(xy 85.136224 -265.2017) (xy 85.12806 -265.251934) (xy 85.111944 -265.300208) (xy 85.088293 -265.345271)
			(xy 85.05772 -265.385957) (xy 85.021016 -265.421212) (xy 84.979132 -265.450122) (xy 84.933153 -265.471939)
			(xy 84.884269 -265.486099) (xy 84.833748 -265.492233) (xy 84.782896 -265.490184) (xy 84.733032 -265.480004)
			(xy 84.685446 -265.461957) (xy 84.641372 -265.436511) (xy 84.60195 -265.404324) (xy 84.568202 -265.36623)
			(xy 84.541001 -265.323216) (xy 84.521053 -265.276396) (xy 84.508874 -265.226982) (xy 84.504779 -265.176254)
			(xy 84.186268 -265.176254) (xy 84.185773 -265.200861) (xy 84.177878 -265.249438) (xy 84.162294 -265.296119)
			(xy 84.139423 -265.339696) (xy 84.109858 -265.37904) (xy 84.074365 -265.413132) (xy 84.033862 -265.441088)
			(xy 83.9894 -265.462186) (xy 83.942129 -265.475878) (xy 83.893274 -265.48181) (xy 83.844099 -265.479829)
			(xy 83.79588 -265.469985) (xy 83.749864 -265.452533) (xy 83.707243 -265.427926) (xy 83.669122 -265.396801)
			(xy 83.636487 -265.359964) (xy 83.610184 -265.318368) (xy 83.590893 -265.273092) (xy 83.579116 -265.225308)
			(xy 83.575156 -265.176254) (xy 83.246468 -265.176254) (xy 83.245973 -265.200861) (xy 83.238078 -265.249438)
			(xy 83.222494 -265.296119) (xy 83.199623 -265.339696) (xy 83.170058 -265.37904) (xy 83.134565 -265.413132)
			(xy 83.094062 -265.441088) (xy 83.0496 -265.462186) (xy 83.002329 -265.475878) (xy 82.953474 -265.48181)
			(xy 82.904299 -265.479829) (xy 82.85608 -265.469985) (xy 82.810064 -265.452533) (xy 82.767443 -265.427926)
			(xy 82.729322 -265.396801) (xy 82.696687 -265.359964) (xy 82.670384 -265.318368) (xy 82.651093 -265.273092)
			(xy 82.639316 -265.225308) (xy 82.635356 -265.176254) (xy 82.306414 -265.176254) (xy 82.305919 -265.200861)
			(xy 82.298024 -265.249438) (xy 82.28244 -265.296119) (xy 82.259569 -265.339696) (xy 82.230004 -265.37904)
			(xy 82.194511 -265.413132) (xy 82.154008 -265.441088) (xy 82.109546 -265.462186) (xy 82.062275 -265.475878)
			(xy 82.01342 -265.48181) (xy 81.964245 -265.479829) (xy 81.916026 -265.469985) (xy 81.87001 -265.452533)
			(xy 81.827389 -265.427926) (xy 81.789268 -265.396801) (xy 81.756633 -265.359964) (xy 81.73033 -265.318368)
			(xy 81.711039 -265.273092) (xy 81.699262 -265.225308) (xy 81.695302 -265.176254) (xy 81.376774 -265.176254)
			(xy 81.376262 -265.2017) (xy 81.368098 -265.251934) (xy 81.351982 -265.300208) (xy 81.328331 -265.345271)
			(xy 81.297758 -265.385957) (xy 81.261054 -265.421212) (xy 81.21917 -265.450122) (xy 81.173191 -265.471939)
			(xy 81.124307 -265.486099) (xy 81.073786 -265.492233) (xy 81.022934 -265.490184) (xy 80.97307 -265.480004)
			(xy 80.925484 -265.461957) (xy 80.88141 -265.436511) (xy 80.841988 -265.404324) (xy 80.80824 -265.36623)
			(xy 80.781039 -265.323216) (xy 80.761091 -265.276396) (xy 80.748912 -265.226982) (xy 80.744817 -265.176254)
			(xy 80.426306 -265.176254) (xy 80.425811 -265.200861) (xy 80.417916 -265.249438) (xy 80.402332 -265.296119)
			(xy 80.379461 -265.339696) (xy 80.349896 -265.37904) (xy 80.314403 -265.413132) (xy 80.2739 -265.441088)
			(xy 80.229438 -265.462186) (xy 80.182167 -265.475878) (xy 80.133312 -265.48181) (xy 80.084137 -265.479829)
			(xy 80.035918 -265.469985) (xy 79.989902 -265.452533) (xy 79.947281 -265.427926) (xy 79.90916 -265.396801)
			(xy 79.876525 -265.359964) (xy 79.850222 -265.318368) (xy 79.830931 -265.273092) (xy 79.819154 -265.225308)
			(xy 79.815194 -265.176254) (xy 77.263451 -265.176254) (xy 77.221316 -265.196248) (xy 77.174045 -265.20994)
			(xy 77.12519 -265.215872) (xy 77.076015 -265.213891) (xy 77.027796 -265.204047) (xy 76.98178 -265.186595)
			(xy 76.939159 -265.161988) (xy 76.901038 -265.130863) (xy 76.868403 -265.094026) (xy 76.8421 -265.05243)
			(xy 76.822809 -265.007154) (xy 76.811032 -264.95937) (xy 76.807072 -264.910316) (xy 73.375774 -264.910316)
			(xy 73.375774 -265.455146) (xy 73.376205 -265.465213) (xy 73.383928 -265.483808) (xy 73.39076 -265.491214)
			(xy 74.049382 -266.149836) (xy 74.056782 -266.156676) (xy 74.075381 -266.164391) (xy 74.08545 -266.164822)
		)
		(stroke
			(width 0)
			(type solid)
		)
		(fill yes)
		(layer "In15.Cu")
		(net "PVDDIO_P1")
	)
	(gr_poly
		(pts
			(xy 13.955522 -197.858126) (xy 13.966968 -197.85761) (xy 13.987603 -197.8477) (xy 13.995146 -197.839076)
			(xy 14.012672 -197.81774) (xy 14.012672 -197.817232) (xy 14.044676 -197.777354) (xy 14.048163 -197.77276)
			(xy 14.053171 -197.762372) (xy 14.054582 -197.75678) (xy 14.057122 -197.745858) (xy 14.054582 -197.734428)
			(xy 14.044624 -197.686725) (xy 14.033936 -197.58986) (xy 14.033246 -197.541134) (xy 14.033246 -197.540372)
			(xy 14.033684 -197.501813) (xy 14.040409 -197.424988) (xy 14.053753 -197.349033) (xy 14.073616 -197.274517)
			(xy 14.086332 -197.238112) (xy 14.088384 -197.230629) (xy 14.088376 -197.215118) (xy 14.086332 -197.207632)
			(xy 14.073593 -197.171234) (xy 14.053721 -197.096718) (xy 14.040381 -197.02076) (xy 14.033675 -196.943932)
			(xy 14.033246 -196.905372) (xy 14.033706 -196.864269) (xy 14.041291 -196.782413) (xy 14.056396 -196.701607)
			(xy 14.078893 -196.622538) (xy 14.108589 -196.545883) (xy 14.145232 -196.472295) (xy 14.188508 -196.402402)
			(xy 14.238048 -196.3368) (xy 14.29343 -196.276049) (xy 14.354182 -196.220667) (xy 14.419784 -196.171127)
			(xy 14.489677 -196.127851) (xy 14.563265 -196.091208) (xy 14.63992 -196.061512) (xy 14.718989 -196.039016)
			(xy 14.799795 -196.023911) (xy 14.881651 -196.016326) (xy 14.922754 -196.015864) (xy 14.961314 -196.016299)
			(xy 15.03814 -196.023017) (xy 15.114097 -196.036356) (xy 15.188616 -196.056214) (xy 15.225014 -196.06895)
			(xy 15.232498 -196.071006) (xy 15.24801 -196.071006) (xy 15.255494 -196.06895) (xy 15.291892 -196.056213)
			(xy 15.366408 -196.036345) (xy 15.442366 -196.023009) (xy 15.519194 -196.016305) (xy 15.557754 -196.015864)
			(xy 15.598859 -196.016322) (xy 15.680719 -196.023903) (xy 15.76153 -196.039005) (xy 15.840602 -196.061499)
			(xy 15.917262 -196.091193) (xy 15.990855 -196.127834) (xy 16.060754 -196.171109) (xy 16.126361 -196.220649)
			(xy 16.187117 -196.276031) (xy 16.242504 -196.336782) (xy 16.292049 -196.402385) (xy 16.33533 -196.47228)
			(xy 16.371977 -196.54587) (xy 16.401677 -196.622527) (xy 16.424178 -196.701598) (xy 16.439286 -196.782408)
			(xy 16.446875 -196.864267) (xy 16.447262 -196.905372) (xy 16.446826 -196.943931) (xy 16.440107 -197.020757)
			(xy 16.426767 -197.096714) (xy 16.406908 -197.171233) (xy 16.394176 -197.207632) (xy 16.392115 -197.215116)
			(xy 16.392107 -197.230631) (xy 16.394176 -197.238112) (xy 16.406917 -197.274509) (xy 16.426794 -197.349025)
			(xy 16.440138 -197.424983) (xy 16.44685 -197.501812) (xy 16.447262 -197.540372) (xy 16.447262 -197.541134)
			(xy 16.446592 -197.589861) (xy 16.435901 -197.686728) (xy 16.425926 -197.734428) (xy 16.423386 -197.745858)
			(xy 16.425926 -197.75678) (xy 16.427348 -197.762369) (xy 16.432355 -197.772753) (xy 16.435832 -197.777354)
			(xy 16.467836 -197.817232) (xy 16.467836 -197.81774) (xy 16.485362 -197.839076) (xy 16.492993 -197.847592)
			(xy 16.51357 -197.857493) (xy 16.524986 -197.858126) (xy 17.202658 -197.858126) (xy 17.207819 -197.858032)
			(xy 17.217934 -197.855985) (xy 17.222724 -197.854062) (xy 17.249648 -197.842378) (xy 17.253458 -197.838568)
			(xy 17.273872 -197.818387) (xy 17.318563 -197.78236) (xy 17.342612 -197.766686) (xy 17.34312 -197.766178)
			(xy 17.343628 -197.765924) (xy 17.348167 -197.762763) (xy 17.355848 -197.75481) (xy 17.358868 -197.750176)
			(xy 17.361916 -197.74535) (xy 17.365726 -197.734174) (xy 17.3736 -197.64756) (xy 17.373961 -197.641672)
			(xy 17.372292 -197.629998) (xy 17.370298 -197.624446) (xy 17.366234 -197.614286) (xy 17.357598 -197.606158)
			(xy 17.35709 -197.60565) (xy 17.338846 -197.588137) (xy 17.306841 -197.548981) (xy 17.280486 -197.505819)
			(xy 17.260275 -197.459462) (xy 17.246587 -197.410778) (xy 17.239678 -197.36068) (xy 17.239234 -197.335394)
			(xy 17.23975 -197.307794) (xy 17.247977 -197.253211) (xy 17.264247 -197.200464) (xy 17.288197 -197.150732)
			(xy 17.319292 -197.105124) (xy 17.356837 -197.06466) (xy 17.399994 -197.030243) (xy 17.447798 -197.002644)
			(xy 17.499182 -196.982477) (xy 17.552997 -196.970194) (xy 17.608042 -196.966069) (xy 17.663087 -196.970194)
			(xy 17.716902 -196.982477) (xy 17.768286 -197.002644) (xy 17.81609 -197.030243) (xy 17.859247 -197.06466)
			(xy 17.896792 -197.105124) (xy 17.927887 -197.150732) (xy 17.951837 -197.200464) (xy 17.968107 -197.253211)
			(xy 17.976334 -197.307794) (xy 17.97685 -197.335394) (xy 17.97685 -197.335648) (xy 17.976454 -197.36014)
			(xy 17.969961 -197.40869) (xy 17.963896 -197.432422) (xy 17.956726 -197.457087) (xy 17.936499 -197.504301)
			(xy 17.909922 -197.548254) (xy 17.877507 -197.588099) (xy 17.858994 -197.605904) (xy 17.85874 -197.605904)
			(xy 17.858232 -197.606412) (xy 17.854243 -197.610395) (xy 17.847966 -197.619755) (xy 17.845786 -197.624954)
			(xy 17.841468 -197.635622) (xy 17.84985 -197.728332) (xy 17.850543 -197.734177) (xy 17.854255 -197.745343)
			(xy 17.857216 -197.75043) (xy 17.863058 -197.759828) (xy 17.872964 -197.766178) (xy 17.873472 -197.766686)
			(xy 17.897535 -197.78234) (xy 17.942228 -197.818369) (xy 17.962626 -197.838568) (xy 17.966436 -197.842378)
			(xy 17.99336 -197.854062) (xy 17.998159 -197.855956) (xy 18.008268 -197.858012) (xy 18.013426 -197.858126)
			(xy 21.284438 -197.858126) (xy 21.290534 -197.857872) (xy 21.302664 -197.855664) (xy 21.322944 -197.841713)
			(xy 21.329396 -197.831202) (xy 21.331428 -197.826884) (xy 21.367496 -197.740016) (xy 21.370097 -197.733019)
			(xy 21.371526 -197.718167) (xy 21.37029 -197.710806) (xy 21.36902 -197.70344) (xy 21.362162 -197.69074)
			(xy 21.356574 -197.684898) (xy 21.332854 -197.660242) (xy 21.291723 -197.60557) (xy 21.258492 -197.545766)
			(xy 21.233791 -197.481964) (xy 21.218088 -197.415374) (xy 21.214334 -197.381368) (xy 21.21281 -197.36435)
			(xy 21.212048 -197.335394) (xy 21.21252 -197.304162) (xy 21.22036 -197.242192) (xy 21.235914 -197.181695)
			(xy 21.258938 -197.123629) (xy 21.289066 -197.068911) (xy 21.325823 -197.018406) (xy 21.368628 -196.972914)
			(xy 21.416803 -196.933153) (xy 21.442934 -196.91604) (xy 21.443696 -196.915532) (xy 21.448363 -196.912398)
			(xy 21.456309 -196.90445) (xy 21.459444 -196.899784) (xy 21.465286 -196.890386) (xy 21.470874 -196.828664)
			(xy 21.470874 -196.828156) (xy 21.473922 -196.79793) (xy 21.474279 -196.792043) (xy 21.472602 -196.780372)
			(xy 21.47062 -196.774816) (xy 21.466556 -196.764148) (xy 21.457666 -196.75602) (xy 21.439341 -196.738501)
			(xy 21.407184 -196.699305) (xy 21.380701 -196.656074) (xy 21.36039 -196.609622) (xy 21.346635 -196.560826)
			(xy 21.339696 -196.510605) (xy 21.339302 -196.485256) (xy 21.339818 -196.457656) (xy 21.348045 -196.403073)
			(xy 21.364315 -196.350326) (xy 21.388265 -196.300594) (xy 21.41936 -196.254986) (xy 21.456905 -196.214522)
			(xy 21.500062 -196.180105) (xy 21.547866 -196.152506) (xy 21.59925 -196.132339) (xy 21.653065 -196.120056)
			(xy 21.70811 -196.115931) (xy 21.763155 -196.120056) (xy 21.81697 -196.132339) (xy 21.868354 -196.152506)
			(xy 21.916158 -196.180105) (xy 21.959315 -196.214522) (xy 21.99686 -196.254986) (xy 22.027955 -196.300594)
			(xy 22.051905 -196.350326) (xy 22.068175 -196.403073) (xy 22.076402 -196.457656) (xy 22.076918 -196.485256)
			(xy 22.076494 -196.510602) (xy 22.069546 -196.560817) (xy 22.055787 -196.609607) (xy 22.035479 -196.656053)
			(xy 22.009002 -196.699282) (xy 21.976855 -196.738478) (xy 21.958554 -196.75602) (xy 21.954308 -196.760128)
			(xy 21.947642 -196.76988) (xy 21.945346 -196.775324) (xy 21.941282 -196.785992) (xy 21.945346 -196.828156)
			(xy 21.945346 -196.828664) (xy 21.949918 -196.878194) (xy 21.950567 -196.884169) (xy 21.95428 -196.895596)
			(xy 21.957284 -196.9008) (xy 21.962872 -196.909436) (xy 21.973286 -196.91604) (xy 21.999421 -196.933144)
			(xy 22.047587 -196.972912) (xy 22.090383 -197.018409) (xy 22.127132 -197.068916) (xy 22.157254 -197.123635)
			(xy 22.180272 -197.1817) (xy 22.195823 -197.242195) (xy 22.20366 -197.304163) (xy 22.204172 -197.335394)
			(xy 22.20341 -197.36435) (xy 22.201886 -197.381368) (xy 22.198132 -197.415339) (xy 22.182473 -197.481866)
			(xy 22.157821 -197.54561) (xy 22.124642 -197.605361) (xy 22.083567 -197.659986) (xy 22.0599 -197.684644)
			(xy 22.059392 -197.685152) (xy 22.054319 -197.690619) (xy 22.047341 -197.703791) (xy 22.045676 -197.71106)
			(xy 22.044406 -197.718426) (xy 22.045676 -197.732904) (xy 22.084792 -197.826884) (xy 22.086824 -197.831202)
			(xy 22.093243 -197.841734) (xy 22.11355 -197.855666) (xy 22.125686 -197.857872) (xy 22.131782 -197.858126)
			(xy 24.746712 -197.858126) (xy 24.751874 -197.858037) (xy 24.761993 -197.855999) (xy 24.766778 -197.854062)
			(xy 24.793702 -197.842378) (xy 24.797512 -197.838568) (xy 24.817925 -197.818386) (xy 24.862614 -197.782355)
			(xy 24.886666 -197.766686) (xy 24.887174 -197.766178) (xy 24.887682 -197.765924) (xy 24.892224 -197.762766)
			(xy 24.899912 -197.754817) (xy 24.902922 -197.750176) (xy 24.90597 -197.74535) (xy 24.90978 -197.734174)
			(xy 24.917654 -197.64756) (xy 24.918015 -197.641672) (xy 24.916345 -197.629998) (xy 24.914352 -197.624446)
			(xy 24.910288 -197.614286) (xy 24.901652 -197.606158) (xy 24.901144 -197.60565) (xy 24.882898 -197.588138)
			(xy 24.850888 -197.548984) (xy 24.824529 -197.505823) (xy 24.804315 -197.459465) (xy 24.790625 -197.41078)
			(xy 24.783715 -197.360681) (xy 24.783288 -197.335394) (xy 24.783804 -197.307794) (xy 24.792031 -197.253211)
			(xy 24.808301 -197.200464) (xy 24.832251 -197.150732) (xy 24.863346 -197.105124) (xy 24.900891 -197.06466)
			(xy 24.944048 -197.030243) (xy 24.991852 -197.002644) (xy 25.043236 -196.982477) (xy 25.097051 -196.970194)
			(xy 25.152096 -196.966069) (xy 25.207141 -196.970194) (xy 25.260956 -196.982477) (xy 25.31234 -197.002644)
			(xy 25.360144 -197.030243) (xy 25.403301 -197.06466) (xy 25.440846 -197.105124) (xy 25.471941 -197.150732)
			(xy 25.495891 -197.200464) (xy 25.512161 -197.253211) (xy 25.520388 -197.307794) (xy 25.520904 -197.335394)
			(xy 25.520904 -197.335648) (xy 25.520508 -197.36014) (xy 25.514016 -197.40869) (xy 25.50795 -197.432422)
			(xy 25.500779 -197.457086) (xy 25.48055 -197.504298) (xy 25.45397 -197.54825) (xy 25.421554 -197.588091)
			(xy 25.403048 -197.605904) (xy 25.402794 -197.605904) (xy 25.402286 -197.606412) (xy 25.398299 -197.610396)
			(xy 25.392028 -197.619759) (xy 25.38984 -197.624954) (xy 25.385522 -197.635622) (xy 25.393904 -197.728332)
			(xy 25.394596 -197.734177) (xy 25.398306 -197.745345) (xy 25.40127 -197.75043) (xy 25.407112 -197.759828)
			(xy 25.417018 -197.766178) (xy 25.417526 -197.766686) (xy 25.441587 -197.782342) (xy 25.486277 -197.818375)
			(xy 25.50668 -197.838568) (xy 25.51049 -197.842378) (xy 25.537414 -197.854062) (xy 25.542214 -197.855951)
			(xy 25.552323 -197.857996) (xy 25.55748 -197.858126) (xy 28.828492 -197.858126) (xy 28.834588 -197.857872)
			(xy 28.846724 -197.855673) (xy 28.867021 -197.84173) (xy 28.87345 -197.831202) (xy 28.875482 -197.826884)
			(xy 28.91155 -197.740016) (xy 28.914149 -197.733018) (xy 28.915576 -197.718168) (xy 28.914344 -197.710806)
			(xy 28.913074 -197.70344) (xy 28.906216 -197.69074) (xy 28.900628 -197.684898) (xy 28.87691 -197.660241)
			(xy 28.835783 -197.605568) (xy 28.802554 -197.545763) (xy 28.777856 -197.481962) (xy 28.762155 -197.415372)
			(xy 28.758388 -197.381368) (xy 28.756864 -197.36435) (xy 28.756102 -197.335394) (xy 28.756574 -197.304162)
			(xy 28.764414 -197.242193) (xy 28.77997 -197.181698) (xy 28.802995 -197.123634) (xy 28.833126 -197.068918)
			(xy 28.869885 -197.018416) (xy 28.912692 -196.972928) (xy 28.960869 -196.933171) (xy 28.986988 -196.91604)
			(xy 28.98775 -196.915532) (xy 28.99242 -196.912401) (xy 29.000372 -196.904456) (xy 29.003498 -196.899784)
			(xy 29.00934 -196.890386) (xy 29.014928 -196.828664) (xy 29.014928 -196.828156) (xy 29.017976 -196.79793)
			(xy 29.018333 -196.792043) (xy 29.016657 -196.780371) (xy 29.014674 -196.774816) (xy 29.01061 -196.764148)
			(xy 29.00172 -196.75602) (xy 28.983397 -196.7385) (xy 28.951244 -196.699303) (xy 28.924764 -196.656071)
			(xy 28.904456 -196.60962) (xy 28.890703 -196.560824) (xy 28.883764 -196.510604) (xy 28.883356 -196.485256)
			(xy 28.883872 -196.457656) (xy 28.892099 -196.403073) (xy 28.908369 -196.350326) (xy 28.932319 -196.300594)
			(xy 28.963414 -196.254986) (xy 29.000959 -196.214522) (xy 29.044116 -196.180105) (xy 29.09192 -196.152506)
			(xy 29.143304 -196.132339) (xy 29.197119 -196.120056) (xy 29.252164 -196.115931) (xy 29.307209 -196.120056)
			(xy 29.361024 -196.132339) (xy 29.412408 -196.152506) (xy 29.460212 -196.180105) (xy 29.503369 -196.214522)
			(xy 29.540914 -196.254986) (xy 29.572009 -196.300594) (xy 29.595959 -196.350326) (xy 29.612229 -196.403073)
			(xy 29.620456 -196.457656) (xy 29.620972 -196.485256) (xy 29.620548 -196.510603) (xy 29.6136 -196.560818)
			(xy 29.599844 -196.609609) (xy 29.579537 -196.656058) (xy 29.553063 -196.699289) (xy 29.520919 -196.738489)
			(xy 29.502608 -196.75602) (xy 29.498358 -196.760126) (xy 29.491686 -196.769875) (xy 29.4894 -196.775324)
			(xy 29.485336 -196.785992) (xy 29.4894 -196.828156) (xy 29.4894 -196.828664) (xy 29.493972 -196.878194)
			(xy 29.494622 -196.884168) (xy 29.498338 -196.895593) (xy 29.501338 -196.9008) (xy 29.506926 -196.909436)
			(xy 29.51734 -196.91604) (xy 29.543477 -196.933142) (xy 29.591647 -196.972908) (xy 29.634447 -197.018404)
			(xy 29.6712 -197.068911) (xy 29.701324 -197.12363) (xy 29.724345 -197.181696) (xy 29.739897 -197.242193)
			(xy 29.747736 -197.304162) (xy 29.748226 -197.335394) (xy 29.747464 -197.36435) (xy 29.74594 -197.381368)
			(xy 29.742186 -197.415339) (xy 29.726529 -197.481867) (xy 29.701878 -197.545613) (xy 29.668702 -197.605367)
			(xy 29.62763 -197.659995) (xy 29.603954 -197.684644) (xy 29.603446 -197.685152) (xy 29.598377 -197.690621)
			(xy 29.591405 -197.703794) (xy 29.58973 -197.71106) (xy 29.58846 -197.718426) (xy 29.58973 -197.732904)
			(xy 29.628846 -197.826884) (xy 29.630878 -197.831202) (xy 29.637294 -197.841741) (xy 29.657598 -197.855691)
			(xy 29.66974 -197.857872) (xy 29.675836 -197.858126) (xy 32.290512 -197.858126) (xy 32.295674 -197.858037)
			(xy 32.305793 -197.855999) (xy 32.310578 -197.854062) (xy 32.337502 -197.842378) (xy 32.341312 -197.838568)
			(xy 32.361725 -197.818386) (xy 32.406414 -197.782355) (xy 32.430466 -197.766686) (xy 32.430974 -197.766178)
			(xy 32.431482 -197.765924) (xy 32.436024 -197.762766) (xy 32.443712 -197.754817) (xy 32.446722 -197.750176)
			(xy 32.44977 -197.74535) (xy 32.45358 -197.734174) (xy 32.461454 -197.64756) (xy 32.461815 -197.641672)
			(xy 32.460145 -197.629998) (xy 32.458152 -197.624446) (xy 32.454088 -197.614286) (xy 32.445452 -197.606158)
			(xy 32.444944 -197.60565) (xy 32.426698 -197.588138) (xy 32.394688 -197.548984) (xy 32.368329 -197.505823)
			(xy 32.348115 -197.459465) (xy 32.334425 -197.41078) (xy 32.327515 -197.360681) (xy 32.327088 -197.335394)
			(xy 32.327604 -197.307794) (xy 32.335831 -197.253211) (xy 32.352101 -197.200464) (xy 32.376051 -197.150732)
			(xy 32.407146 -197.105124) (xy 32.444691 -197.06466) (xy 32.487848 -197.030243) (xy 32.535652 -197.002644)
			(xy 32.587036 -196.982477) (xy 32.640851 -196.970194) (xy 32.695896 -196.966069) (xy 32.750941 -196.970194)
			(xy 32.804756 -196.982477) (xy 32.85614 -197.002644) (xy 32.903944 -197.030243) (xy 32.947101 -197.06466)
			(xy 32.984646 -197.105124) (xy 33.015741 -197.150732) (xy 33.039691 -197.200464) (xy 33.055961 -197.253211)
			(xy 33.064188 -197.307794) (xy 33.064704 -197.335394) (xy 33.064704 -197.335648) (xy 33.064308 -197.36014)
			(xy 33.057816 -197.40869) (xy 33.05175 -197.432422) (xy 33.044579 -197.457086) (xy 33.02435 -197.504298)
			(xy 32.99777 -197.54825) (xy 32.965354 -197.588091) (xy 32.946848 -197.605904) (xy 32.946594 -197.605904)
			(xy 32.946086 -197.606412) (xy 32.942099 -197.610396) (xy 32.935828 -197.619759) (xy 32.93364 -197.624954)
			(xy 32.929322 -197.635622) (xy 32.937704 -197.728332) (xy 32.938396 -197.734177) (xy 32.942106 -197.745345)
			(xy 32.94507 -197.75043) (xy 32.950912 -197.759828) (xy 32.960818 -197.766178) (xy 32.961326 -197.766686)
			(xy 32.985387 -197.782342) (xy 33.030077 -197.818375) (xy 33.05048 -197.838568) (xy 33.05429 -197.842378)
			(xy 33.081214 -197.854062) (xy 33.086014 -197.855951) (xy 33.096123 -197.857996) (xy 33.10128 -197.858126)
			(xy 36.372292 -197.858126) (xy 36.378388 -197.857872) (xy 36.390524 -197.855673) (xy 36.410821 -197.84173)
			(xy 36.41725 -197.831202) (xy 36.419282 -197.826884) (xy 36.45535 -197.740016) (xy 36.457949 -197.733018)
			(xy 36.459376 -197.718168) (xy 36.458144 -197.710806) (xy 36.456874 -197.70344) (xy 36.450016 -197.69074)
			(xy 36.444428 -197.684898) (xy 36.42071 -197.660241) (xy 36.379583 -197.605568) (xy 36.346354 -197.545763)
			(xy 36.321656 -197.481962) (xy 36.305955 -197.415372) (xy 36.302188 -197.381368) (xy 36.300664 -197.36435)
			(xy 36.299902 -197.335394) (xy 36.300374 -197.304162) (xy 36.308214 -197.242193) (xy 36.32377 -197.181698)
			(xy 36.346795 -197.123634) (xy 36.376926 -197.068918) (xy 36.413685 -197.018416) (xy 36.456492 -196.972928)
			(xy 36.504669 -196.933171) (xy 36.530788 -196.91604) (xy 36.53155 -196.915532) (xy 36.53622 -196.912401)
			(xy 36.544172 -196.904456) (xy 36.547298 -196.899784) (xy 36.55314 -196.890386) (xy 36.558728 -196.828664)
			(xy 36.558728 -196.828156) (xy 36.561776 -196.79793) (xy 36.562133 -196.792043) (xy 36.560457 -196.780371)
			(xy 36.558474 -196.774816) (xy 36.55441 -196.764148) (xy 36.54552 -196.75602) (xy 36.527197 -196.7385)
			(xy 36.495044 -196.699303) (xy 36.468564 -196.656071) (xy 36.448256 -196.60962) (xy 36.434503 -196.560824)
			(xy 36.427564 -196.510604) (xy 36.427156 -196.485256) (xy 36.427672 -196.457656) (xy 36.435899 -196.403073)
			(xy 36.452169 -196.350326) (xy 36.476119 -196.300594) (xy 36.507214 -196.254986) (xy 36.544759 -196.214522)
			(xy 36.587916 -196.180105) (xy 36.63572 -196.152506) (xy 36.687104 -196.132339) (xy 36.740919 -196.120056)
			(xy 36.795964 -196.115931) (xy 36.851009 -196.120056) (xy 36.904824 -196.132339) (xy 36.956208 -196.152506)
			(xy 37.004012 -196.180105) (xy 37.047169 -196.214522) (xy 37.084714 -196.254986) (xy 37.115809 -196.300594)
			(xy 37.139759 -196.350326) (xy 37.156029 -196.403073) (xy 37.164256 -196.457656) (xy 37.164772 -196.485256)
			(xy 37.164348 -196.510603) (xy 37.1574 -196.560818) (xy 37.143644 -196.609609) (xy 37.123337 -196.656058)
			(xy 37.096863 -196.699289) (xy 37.064719 -196.738489) (xy 37.046408 -196.75602) (xy 37.042158 -196.760126)
			(xy 37.035486 -196.769875) (xy 37.0332 -196.775324) (xy 37.029136 -196.785992) (xy 37.0332 -196.828156)
			(xy 37.0332 -196.828664) (xy 37.037772 -196.878194) (xy 37.038422 -196.884168) (xy 37.042138 -196.895593)
			(xy 37.045138 -196.9008) (xy 37.050726 -196.909436) (xy 37.06114 -196.91604) (xy 37.087277 -196.933142)
			(xy 37.135447 -196.972908) (xy 37.178247 -197.018404) (xy 37.215 -197.068911) (xy 37.245124 -197.12363)
			(xy 37.268145 -197.181696) (xy 37.283697 -197.242193) (xy 37.291536 -197.304162) (xy 37.292026 -197.335394)
			(xy 37.291264 -197.36435) (xy 37.28974 -197.381368) (xy 37.285986 -197.415339) (xy 37.270329 -197.481867)
			(xy 37.245678 -197.545613) (xy 37.212502 -197.605367) (xy 37.17143 -197.659995) (xy 37.147754 -197.684644)
			(xy 37.147246 -197.685152) (xy 37.142177 -197.690621) (xy 37.135205 -197.703794) (xy 37.13353 -197.71106)
			(xy 37.13226 -197.718426) (xy 37.13353 -197.732904) (xy 37.172646 -197.826884) (xy 37.174678 -197.831202)
			(xy 37.181094 -197.841741) (xy 37.201398 -197.855691) (xy 37.21354 -197.857872) (xy 37.219636 -197.858126)
			(xy 39.834566 -197.858126) (xy 39.839727 -197.858031) (xy 39.849841 -197.855983) (xy 39.854632 -197.854062)
			(xy 39.881556 -197.842378) (xy 39.885366 -197.838568) (xy 39.90578 -197.818388) (xy 39.950472 -197.78236)
			(xy 39.97452 -197.766686) (xy 39.975028 -197.766178) (xy 39.975536 -197.765924) (xy 39.980074 -197.762763)
			(xy 39.987755 -197.754809) (xy 39.990776 -197.750176) (xy 39.993824 -197.74535) (xy 39.997634 -197.734174)
			(xy 40.005508 -197.64756) (xy 40.005869 -197.641672) (xy 40.0042 -197.629998) (xy 40.002206 -197.624446)
			(xy 39.998142 -197.614286) (xy 39.989506 -197.606158) (xy 39.988998 -197.60565) (xy 39.970754 -197.588137)
			(xy 39.938748 -197.548981) (xy 39.912392 -197.50582) (xy 39.892181 -197.459462) (xy 39.878492 -197.410778)
			(xy 39.871584 -197.36068) (xy 39.871142 -197.335394) (xy 39.871658 -197.307794) (xy 39.879885 -197.253211)
			(xy 39.896155 -197.200464) (xy 39.920105 -197.150732) (xy 39.9512 -197.105124) (xy 39.988745 -197.06466)
			(xy 40.031902 -197.030243) (xy 40.079706 -197.002644) (xy 40.13109 -196.982477) (xy 40.184905 -196.970194)
			(xy 40.23995 -196.966069) (xy 40.294995 -196.970194) (xy 40.34881 -196.982477) (xy 40.400194 -197.002644)
			(xy 40.447998 -197.030243) (xy 40.491155 -197.06466) (xy 40.5287 -197.105124) (xy 40.559795 -197.150732)
			(xy 40.583745 -197.200464) (xy 40.600015 -197.253211) (xy 40.608242 -197.307794) (xy 40.608758 -197.335394)
			(xy 40.608758 -197.335648) (xy 40.608362 -197.36014) (xy 40.601869 -197.40869) (xy 40.595804 -197.432422)
			(xy 40.588634 -197.457087) (xy 40.568407 -197.504301) (xy 40.54183 -197.548255) (xy 40.509417 -197.5881)
			(xy 40.490902 -197.605904) (xy 40.490648 -197.605904) (xy 40.49014 -197.606412) (xy 40.48615 -197.610395)
			(xy 40.479873 -197.619755) (xy 40.477694 -197.624954) (xy 40.473376 -197.635622) (xy 40.481758 -197.728332)
			(xy 40.482451 -197.734177) (xy 40.486165 -197.745343) (xy 40.489124 -197.75043) (xy 40.494966 -197.759828)
			(xy 40.504872 -197.766178) (xy 40.50538 -197.766686) (xy 40.529443 -197.78234) (xy 40.574135 -197.81837)
			(xy 40.594534 -197.838568) (xy 40.598344 -197.842378) (xy 40.625268 -197.854062) (xy 40.630067 -197.855955)
			(xy 40.640176 -197.858009) (xy 40.645334 -197.858126) (xy 43.916346 -197.858126) (xy 43.922442 -197.857872)
			(xy 43.934585 -197.855682) (xy 43.954898 -197.841747) (xy 43.961304 -197.831202) (xy 43.963336 -197.826884)
			(xy 43.999404 -197.740016) (xy 44.002004 -197.733019) (xy 44.003433 -197.718167) (xy 44.002198 -197.710806)
			(xy 44.000928 -197.70344) (xy 43.99407 -197.69074) (xy 43.988482 -197.684898) (xy 43.964762 -197.660242)
			(xy 43.92363 -197.60557) (xy 43.890398 -197.545767) (xy 43.865697 -197.481965) (xy 43.849994 -197.415374)
			(xy 43.846242 -197.381368) (xy 43.844718 -197.36435) (xy 43.843956 -197.335394) (xy 43.844428 -197.304162)
			(xy 43.852268 -197.242192) (xy 43.867823 -197.181695) (xy 43.890846 -197.123629) (xy 43.920975 -197.068912)
			(xy 43.957732 -197.018408) (xy 44.000537 -196.972916) (xy 44.048713 -196.933155) (xy 44.074842 -196.91604)
			(xy 44.075604 -196.915532) (xy 44.080271 -196.912398) (xy 44.088215 -196.904449) (xy 44.091352 -196.899784)
			(xy 44.097194 -196.890386) (xy 44.102782 -196.828664) (xy 44.102782 -196.828156) (xy 44.10583 -196.79793)
			(xy 44.106187 -196.792043) (xy 44.10451 -196.780372) (xy 44.102528 -196.774816) (xy 44.098464 -196.764148)
			(xy 44.089574 -196.75602) (xy 44.071248 -196.738501) (xy 44.039091 -196.699306) (xy 44.012607 -196.656075)
			(xy 43.992296 -196.609623) (xy 43.978541 -196.560826) (xy 43.971601 -196.510605) (xy 43.97121 -196.485256)
			(xy 43.971726 -196.457656) (xy 43.979953 -196.403073) (xy 43.996223 -196.350326) (xy 44.020173 -196.300594)
			(xy 44.051268 -196.254986) (xy 44.088813 -196.214522) (xy 44.13197 -196.180105) (xy 44.179774 -196.152506)
			(xy 44.231158 -196.132339) (xy 44.284973 -196.120056) (xy 44.340018 -196.115931) (xy 44.395063 -196.120056)
			(xy 44.448878 -196.132339) (xy 44.500262 -196.152506) (xy 44.548066 -196.180105) (xy 44.591223 -196.214522)
			(xy 44.628768 -196.254986) (xy 44.659863 -196.300594) (xy 44.683813 -196.350326) (xy 44.700083 -196.403073)
			(xy 44.70831 -196.457656) (xy 44.708826 -196.485256) (xy 44.708402 -196.510602) (xy 44.701454 -196.560817)
			(xy 44.687696 -196.609607) (xy 44.667387 -196.656054) (xy 44.640911 -196.699283) (xy 44.608765 -196.73848)
			(xy 44.590462 -196.75602) (xy 44.586215 -196.760128) (xy 44.579549 -196.769879) (xy 44.577254 -196.775324)
			(xy 44.57319 -196.785992) (xy 44.577254 -196.828156) (xy 44.577254 -196.828664) (xy 44.581826 -196.878194)
			(xy 44.582475 -196.884169) (xy 44.586188 -196.895595) (xy 44.589192 -196.9008) (xy 44.59478 -196.909436)
			(xy 44.605194 -196.91604) (xy 44.631329 -196.933144) (xy 44.679494 -196.972912) (xy 44.722289 -197.01841)
			(xy 44.759038 -197.068917) (xy 44.789159 -197.123635) (xy 44.812176 -197.181701) (xy 44.827727 -197.242196)
			(xy 44.835565 -197.304163) (xy 44.83608 -197.335394) (xy 44.835318 -197.36435) (xy 44.833794 -197.381368)
			(xy 44.83004 -197.415339) (xy 44.814381 -197.481866) (xy 44.789729 -197.54561) (xy 44.756551 -197.605362)
			(xy 44.715476 -197.659987) (xy 44.691808 -197.684644) (xy 44.6913 -197.685152) (xy 44.686227 -197.690619)
			(xy 44.679247 -197.70379) (xy 44.677584 -197.71106) (xy 44.676314 -197.718426) (xy 44.677584 -197.732904)
			(xy 44.7167 -197.826884) (xy 44.718732 -197.831202) (xy 44.725152 -197.841733) (xy 44.745459 -197.855662)
			(xy 44.757594 -197.857872) (xy 44.76369 -197.858126) (xy 47.37862 -197.858126) (xy 47.383782 -197.858036)
			(xy 47.3939 -197.855996) (xy 47.398686 -197.854062) (xy 47.42561 -197.842378) (xy 47.42942 -197.838568)
			(xy 47.449833 -197.818386) (xy 47.494523 -197.782355) (xy 47.518574 -197.766686) (xy 47.519082 -197.766178)
			(xy 47.51959 -197.765924) (xy 47.524131 -197.762766) (xy 47.531818 -197.754816) (xy 47.53483 -197.750176)
			(xy 47.537878 -197.74535) (xy 47.541688 -197.734174) (xy 47.549562 -197.64756) (xy 47.549923 -197.641672)
			(xy 47.548253 -197.629998) (xy 47.54626 -197.624446) (xy 47.542196 -197.614286) (xy 47.53356 -197.606158)
			(xy 47.533052 -197.60565) (xy 47.514805 -197.588138) (xy 47.482795 -197.548984) (xy 47.456436 -197.505823)
			(xy 47.436221 -197.459465) (xy 47.42253 -197.41078) (xy 47.415621 -197.360681) (xy 47.415196 -197.335394)
			(xy 47.415712 -197.307794) (xy 47.423939 -197.253211) (xy 47.440209 -197.200464) (xy 47.464159 -197.150732)
			(xy 47.495254 -197.105124) (xy 47.532799 -197.06466) (xy 47.575956 -197.030243) (xy 47.62376 -197.002644)
			(xy 47.675144 -196.982477) (xy 47.728959 -196.970194) (xy 47.784004 -196.966069) (xy 47.839049 -196.970194)
			(xy 47.892864 -196.982477) (xy 47.944248 -197.002644) (xy 47.992052 -197.030243) (xy 48.035209 -197.06466)
			(xy 48.072754 -197.105124) (xy 48.103849 -197.150732) (xy 48.127799 -197.200464) (xy 48.144069 -197.253211)
			(xy 48.152296 -197.307794) (xy 48.152812 -197.335394) (xy 48.152812 -197.335648) (xy 48.152416 -197.36014)
			(xy 48.145922 -197.40869) (xy 48.139858 -197.432422) (xy 48.132687 -197.457086) (xy 48.112459 -197.504299)
			(xy 48.085879 -197.548251) (xy 48.053463 -197.588093) (xy 48.034956 -197.605904) (xy 48.034702 -197.605904)
			(xy 48.034194 -197.606412) (xy 48.030207 -197.610396) (xy 48.023935 -197.619758) (xy 48.021748 -197.624954)
			(xy 48.01743 -197.635622) (xy 48.025812 -197.728332) (xy 48.026504 -197.734177) (xy 48.030214 -197.745345)
			(xy 48.033178 -197.75043) (xy 48.03902 -197.759828) (xy 48.048926 -197.766178) (xy 48.049434 -197.766686)
			(xy 48.073495 -197.782342) (xy 48.118184 -197.818376) (xy 48.138588 -197.838568) (xy 48.142398 -197.842378)
			(xy 48.169322 -197.854062) (xy 48.174122 -197.85595) (xy 48.184231 -197.857994) (xy 48.189388 -197.858126)
			(xy 51.4604 -197.858126) (xy 51.466496 -197.857872) (xy 51.478631 -197.855671) (xy 51.498925 -197.841727)
			(xy 51.505358 -197.831202) (xy 51.50739 -197.826884) (xy 51.543458 -197.740016) (xy 51.546056 -197.733018)
			(xy 51.547484 -197.718168) (xy 51.546252 -197.710806) (xy 51.544982 -197.70344) (xy 51.538124 -197.69074)
			(xy 51.532536 -197.684898) (xy 51.508818 -197.660241) (xy 51.46769 -197.605568) (xy 51.434461 -197.545764)
			(xy 51.409762 -197.481962) (xy 51.39406 -197.415373) (xy 51.390296 -197.381368) (xy 51.388772 -197.36435)
			(xy 51.38801 -197.335394) (xy 51.388482 -197.304163) (xy 51.396323 -197.242194) (xy 51.411878 -197.181699)
			(xy 51.434904 -197.123634) (xy 51.465034 -197.068919) (xy 51.501794 -197.018418) (xy 51.544601 -196.97293)
			(xy 51.592779 -196.933174) (xy 51.618896 -196.91604) (xy 51.619658 -196.915532) (xy 51.624327 -196.9124)
			(xy 51.632278 -196.904455) (xy 51.635406 -196.899784) (xy 51.641248 -196.890386) (xy 51.646836 -196.828664)
			(xy 51.646836 -196.828156) (xy 51.649884 -196.79793) (xy 51.650241 -196.792043) (xy 51.648566 -196.780371)
			(xy 51.646582 -196.774816) (xy 51.642518 -196.764148) (xy 51.633628 -196.75602) (xy 51.615304 -196.7385)
			(xy 51.583151 -196.699303) (xy 51.556671 -196.656072) (xy 51.536362 -196.60962) (xy 51.522609 -196.560824)
			(xy 51.51567 -196.510605) (xy 51.515264 -196.485256) (xy 51.51578 -196.457656) (xy 51.524007 -196.403073)
			(xy 51.540277 -196.350326) (xy 51.564227 -196.300594) (xy 51.595322 -196.254986) (xy 51.632867 -196.214522)
			(xy 51.676024 -196.180105) (xy 51.723828 -196.152506) (xy 51.775212 -196.132339) (xy 51.829027 -196.120056)
			(xy 51.884072 -196.115931) (xy 51.939117 -196.120056) (xy 51.992932 -196.132339) (xy 52.044316 -196.152506)
			(xy 52.09212 -196.180105) (xy 52.135277 -196.214522) (xy 52.172822 -196.254986) (xy 52.203917 -196.300594)
			(xy 52.227867 -196.350326) (xy 52.244137 -196.403073) (xy 52.252364 -196.457656) (xy 52.25288 -196.485256)
			(xy 59.058825 -196.485256) (xy 59.06276 -196.431485) (xy 59.074483 -196.378861) (xy 59.093743 -196.328504)
			(xy 59.120129 -196.281487) (xy 59.153081 -196.238814) (xy 59.191894 -196.201393) (xy 59.235742 -196.170023)
			(xy 59.28369 -196.145371) (xy 59.334717 -196.127963) (xy 59.387735 -196.11817) (xy 59.441614 -196.116201)
			(xy 59.495205 -196.122098) (xy 59.547366 -196.135734) (xy 59.596986 -196.156821) (xy 59.643007 -196.184907)
			(xy 59.684449 -196.219395) (xy 59.720427 -196.259549) (xy 59.750175 -196.304513) (xy 59.77306 -196.35333)
			(xy 59.788592 -196.404959) (xy 59.796442 -196.458299) (xy 59.796934 -196.485256) (xy 59.796442 -196.512213)
			(xy 59.788592 -196.565553) (xy 59.77306 -196.617182) (xy 59.750175 -196.665999) (xy 59.720427 -196.710963)
			(xy 59.684449 -196.751117) (xy 59.643007 -196.785605) (xy 59.596986 -196.813691) (xy 59.547366 -196.834778)
			(xy 59.495205 -196.848414) (xy 59.441614 -196.854311) (xy 59.387735 -196.852342) (xy 59.334717 -196.842549)
			(xy 59.28369 -196.825141) (xy 59.235742 -196.800489) (xy 59.191894 -196.769119) (xy 59.153081 -196.731698)
			(xy 59.120129 -196.689025) (xy 59.093743 -196.642008) (xy 59.074483 -196.591651) (xy 59.06276 -196.539027)
			(xy 59.058825 -196.485256) (xy 52.25288 -196.485256) (xy 52.252456 -196.510603) (xy 52.245509 -196.560818)
			(xy 52.231752 -196.60961) (xy 52.211446 -196.656058) (xy 52.184972 -196.69929) (xy 52.152829 -196.738491)
			(xy 52.134516 -196.75602) (xy 52.130266 -196.760126) (xy 52.123592 -196.769874) (xy 52.121308 -196.775324)
			(xy 52.117244 -196.785992) (xy 52.121308 -196.828156) (xy 52.121308 -196.828664) (xy 52.12588 -196.878194)
			(xy 52.12653 -196.884168) (xy 52.130247 -196.895593) (xy 52.133246 -196.9008) (xy 52.138834 -196.909436)
			(xy 52.149248 -196.91604) (xy 52.175385 -196.933142) (xy 52.223554 -196.972909) (xy 52.266353 -197.018405)
			(xy 52.303105 -197.068911) (xy 52.333229 -197.123631) (xy 52.356249 -197.181697) (xy 52.371801 -197.242193)
			(xy 52.37964 -197.304162) (xy 52.380134 -197.335394) (xy 54.958757 -197.335394) (xy 54.962692 -197.281623)
			(xy 54.974415 -197.228999) (xy 54.993675 -197.178642) (xy 55.020061 -197.131625) (xy 55.053013 -197.088952)
			(xy 55.091826 -197.051531) (xy 55.135674 -197.020161) (xy 55.183622 -196.995509) (xy 55.234649 -196.978101)
			(xy 55.287667 -196.968308) (xy 55.341546 -196.966339) (xy 55.395137 -196.972236) (xy 55.447298 -196.985872)
			(xy 55.496918 -197.006959) (xy 55.542939 -197.035045) (xy 55.584381 -197.069533) (xy 55.620359 -197.109687)
			(xy 55.650107 -197.154651) (xy 55.672992 -197.203468) (xy 55.688524 -197.255097) (xy 55.696374 -197.308437)
			(xy 55.696866 -197.335394) (xy 55.696374 -197.362351) (xy 55.688524 -197.415691) (xy 55.672992 -197.46732)
			(xy 55.650107 -197.516137) (xy 55.620359 -197.561101) (xy 55.584381 -197.601255) (xy 55.542939 -197.635743)
			(xy 55.496918 -197.663829) (xy 55.447298 -197.684916) (xy 55.395137 -197.698552) (xy 55.341546 -197.704449)
			(xy 55.287667 -197.70248) (xy 55.234649 -197.692687) (xy 55.183622 -197.675279) (xy 55.135674 -197.650627)
			(xy 55.091826 -197.619257) (xy 55.053013 -197.581836) (xy 55.020061 -197.539163) (xy 54.993675 -197.492146)
			(xy 54.974415 -197.441789) (xy 54.962692 -197.389165) (xy 54.958757 -197.335394) (xy 52.380134 -197.335394)
			(xy 52.379372 -197.36435) (xy 52.377848 -197.381368) (xy 52.374094 -197.415339) (xy 52.358437 -197.481867)
			(xy 52.333787 -197.545613) (xy 52.300611 -197.605368) (xy 52.25954 -197.659996) (xy 52.235862 -197.684644)
			(xy 52.235354 -197.685152) (xy 52.230285 -197.690621) (xy 52.223312 -197.703793) (xy 52.221638 -197.71106)
			(xy 52.220368 -197.718426) (xy 52.221638 -197.732904) (xy 52.260754 -197.826884) (xy 52.262786 -197.831202)
			(xy 52.269202 -197.84174) (xy 52.289507 -197.855686) (xy 52.301648 -197.857872) (xy 52.307744 -197.858126)
			(xy 59.251596 -197.858126) (xy 59.262518 -197.855586) (xy 59.267852 -197.853046) (xy 59.292984 -197.841522)
			(xy 59.345815 -197.82523) (xy 59.400483 -197.816987) (xy 59.428126 -197.81647) (xy 59.455774 -197.81694)
			(xy 59.510453 -197.825161) (xy 59.563286 -197.841474) (xy 59.5884 -197.853046) (xy 59.593734 -197.855586)
			(xy 59.604656 -197.858126) (xy 61.682884 -197.858126) (xy 61.692536 -197.85711) (xy 61.699782 -197.855486)
			(xy 61.712958 -197.848651) (xy 61.718444 -197.843648) (xy 62.10808 -197.454012) (xy 62.114768 -197.446604)
			(xy 62.122358 -197.428168) (xy 62.122812 -197.418198) (xy 62.122812 -189.590934) (xy 62.122326 -189.580972)
			(xy 62.11474 -189.562546) (xy 62.10808 -189.55512) (xy 59.374278 -186.821318) (xy 59.370722 -186.818016)
			(xy 59.368436 -186.816238) (xy 59.359379 -186.810318) (xy 59.3382 -186.805988) (xy 59.327542 -186.807856)
			(xy 59.240928 -186.829954) (xy 59.234645 -186.831751) (xy 59.223204 -186.838056) (xy 59.218322 -186.8424)
			(xy 59.21375 -186.846718) (xy 59.207146 -186.858148) (xy 59.205114 -186.864752) (xy 59.191804 -186.908253)
			(xy 59.158279 -186.992828) (xy 59.117142 -187.073973) (xy 59.068739 -187.151006) (xy 59.013478 -187.223277)
			(xy 58.951825 -187.290178) (xy 58.884299 -187.351145) (xy 58.811468 -187.405665) (xy 58.733945 -187.45328)
			(xy 58.652384 -187.493587) (xy 58.567472 -187.526247) (xy 58.479923 -187.550986) (xy 58.390475 -187.567596)
			(xy 58.299881 -187.575935) (xy 58.254392 -187.57646) (xy 56.486044 -187.57646) (xy 56.440723 -187.575219)
			(xy 56.350576 -187.565479) (xy 56.261696 -187.547549) (xy 56.174824 -187.521579) (xy 56.090686 -187.487785)
			(xy 56.009985 -187.446451) (xy 55.933395 -187.39792) (xy 55.861556 -187.3426) (xy 55.795068 -187.280951)
			(xy 55.734487 -187.213489) (xy 55.680318 -187.140777) (xy 55.633015 -187.063423) (xy 55.592971 -186.982074)
			(xy 55.560523 -186.897408) (xy 55.535941 -186.810132) (xy 55.51943 -186.720977) (xy 55.511129 -186.630687)
			(xy 55.510684 -186.585352) (xy 55.511215 -186.539556) (xy 55.51967 -186.448355) (xy 55.536504 -186.358323)
			(xy 55.561572 -186.270229) (xy 55.594662 -186.184823) (xy 55.635491 -186.102835) (xy 55.68371 -186.024963)
			(xy 55.738908 -185.951873) (xy 55.800615 -185.884187) (xy 55.868303 -185.822483) (xy 55.941396 -185.767287)
			(xy 56.01927 -185.719071) (xy 56.10126 -185.678246) (xy 56.186667 -185.64516) (xy 56.274762 -185.620094)
			(xy 56.364795 -185.603264) (xy 56.455996 -185.594813) (xy 56.501792 -185.594244) (xy 58.02503 -185.594244)
			(xy 58.034128 -185.593829) (xy 58.051154 -185.587396) (xy 58.06486 -185.575421) (xy 58.06948 -185.567574)
			(xy 58.071512 -185.562494) (xy 58.074235 -185.555462) (xy 58.075793 -185.540469) (xy 58.07456 -185.53303)
			(xy 58.07329 -185.526426) (xy 58.066178 -185.513218) (xy 55.933086 -183.380126) (xy 55.926242 -183.372728)
			(xy 55.918521 -183.354128) (xy 55.9181 -183.344058) (xy 55.9181 -180.618638) (xy 55.917614 -180.608675)
			(xy 55.910028 -180.59025) (xy 55.903368 -180.582824) (xy 55.540656 -180.219858) (xy 55.534461 -180.214115)
			(xy 55.519278 -180.206731) (xy 55.510938 -180.20538) (xy 55.504588 -180.204872) (xy 45.828966 -180.204872)
			(xy 45.818899 -180.204442) (xy 45.800306 -180.196716) (xy 45.792898 -180.189886) (xy 44.962826 -179.359814)
			(xy 44.95599 -179.352412) (xy 44.948283 -179.333814) (xy 44.94784 -179.323746) (xy 44.94784 -154.017726)
			(xy 44.948278 -154.007663) (xy 44.956016 -153.989082) (xy 44.962826 -153.981658) (xy 59.735212 -139.209272)
			(xy 59.742608 -139.20242) (xy 59.761207 -139.194678) (xy 59.77128 -139.194286) (xy 72.567038 -139.194286)
			(xy 72.593708 -139.174982) (xy 72.598788 -139.159488) (xy 72.609232 -139.129401) (xy 72.636579 -139.071883)
			(xy 72.670896 -139.01823) (xy 72.711644 -138.969284) (xy 72.758187 -138.92581) (xy 72.809795 -138.888489)
			(xy 72.865659 -138.857906) (xy 72.924907 -138.834539) (xy 72.986608 -138.818755) (xy 73.049798 -138.810801)
			(xy 73.113486 -138.810801) (xy 73.176676 -138.818755) (xy 73.238377 -138.834539) (xy 73.297625 -138.857906)
			(xy 73.353489 -138.888489) (xy 73.405097 -138.92581) (xy 73.45164 -138.969284) (xy 73.492388 -139.01823)
			(xy 73.526705 -139.071883) (xy 73.554052 -139.129401) (xy 73.564496 -139.159488) (xy 73.569576 -139.174982)
			(xy 73.596246 -139.194286) (xy 79.578708 -139.194286) (xy 79.580994 -139.194286) (xy 79.591002 -139.193424)
			(xy 79.609179 -139.184912) (xy 79.622688 -139.170067) (xy 79.62646 -139.160758) (xy 79.626714 -139.159996)
			(xy 79.657956 -139.069064) (xy 79.660283 -139.061515) (xy 79.660669 -139.045731) (xy 79.658718 -139.038076)
			(xy 79.656432 -139.03071) (xy 79.647796 -139.017756) (xy 79.641192 -139.012676) (xy 79.615508 -138.991963)
			(xy 79.569184 -138.944978) (xy 79.529325 -138.892396) (xy 79.496601 -138.8351) (xy 79.471563 -138.774054)
			(xy 79.454631 -138.710281) (xy 79.446089 -138.644855) (xy 79.445612 -138.611864) (xy 79.446114 -138.579903)
			(xy 79.454125 -138.516485) (xy 79.470022 -138.454571) (xy 79.493554 -138.395138) (xy 79.524348 -138.339123)
			(xy 79.561921 -138.287408) (xy 79.605678 -138.240811) (xy 79.654931 -138.200066) (xy 79.708902 -138.165815)
			(xy 79.766741 -138.138598) (xy 79.827534 -138.118845) (xy 79.890324 -138.106867) (xy 79.95412 -138.102854)
			(xy 80.017916 -138.106867) (xy 80.080706 -138.118845) (xy 80.141499 -138.138598) (xy 80.199338 -138.165815)
			(xy 80.253309 -138.200066) (xy 80.302562 -138.240811) (xy 80.346319 -138.287408) (xy 80.383892 -138.339123)
			(xy 80.414686 -138.395138) (xy 80.438218 -138.454571) (xy 80.454115 -138.516485) (xy 80.462126 -138.579903)
			(xy 80.462628 -138.611864) (xy 80.462106 -138.644855) (xy 80.453576 -138.710282) (xy 80.436657 -138.774057)
			(xy 80.41163 -138.835108) (xy 80.378918 -138.892409) (xy 80.339069 -138.944998) (xy 80.292753 -138.991992)
			(xy 80.267048 -139.012676) (xy 80.266794 -139.01293) (xy 80.260838 -139.017999) (xy 80.252046 -139.030927)
			(xy 80.249522 -139.03833) (xy 80.247236 -139.045696) (xy 80.24749 -139.06119) (xy 80.281526 -139.159996)
			(xy 80.28178 -139.160758) (xy 80.285647 -139.170009) (xy 80.299141 -139.184811) (xy 80.317265 -139.193341)
			(xy 80.327246 -139.194286) (xy 83.128866 -139.194286) (xy 83.138056 -139.193891) (xy 83.155237 -139.187366)
			(xy 83.162394 -139.181586) (xy 83.169252 -139.17549) (xy 83.177888 -139.159488) (xy 83.179158 -139.15009)
			(xy 83.183204 -139.122898) (xy 83.198094 -139.069978) (xy 83.220427 -139.019744) (xy 83.24974 -138.973237)
			(xy 83.285426 -138.931419) (xy 83.326746 -138.895158) (xy 83.372843 -138.865204) (xy 83.422763 -138.842179)
			(xy 83.475472 -138.826558) (xy 83.529877 -138.818666) (xy 83.584851 -138.818666) (xy 83.639256 -138.826558)
			(xy 83.691965 -138.842179) (xy 83.741885 -138.865204) (xy 83.787982 -138.895158) (xy 83.829302 -138.931419)
			(xy 83.864988 -138.973237) (xy 83.894301 -139.019744) (xy 83.916634 -139.069978) (xy 83.931524 -139.122898)
			(xy 83.93557 -139.15009) (xy 83.93557 -139.150344) (xy 83.937203 -139.159378) (xy 83.945934 -139.175513)
			(xy 83.952588 -139.18184) (xy 83.959446 -139.187936) (xy 83.976464 -139.194286) (xy 89.408 -139.194286)
			(xy 89.417695 -139.193848) (xy 89.435701 -139.186654) (xy 89.443052 -139.180316) (xy 89.444068 -139.1793)
			(xy 89.443814 -139.164822) (xy 89.444329 -139.135672) (xy 89.45287 -139.078001) (xy 89.46977 -139.022204)
			(xy 89.494665 -138.969486) (xy 89.527017 -138.920986) (xy 89.566127 -138.87775) (xy 89.611152 -138.840713)
			(xy 89.661118 -138.810674) (xy 89.714946 -138.788283) (xy 89.771475 -138.774021) (xy 89.80043 -138.770614)
			(xy 89.8017 -138.769344) (xy 89.822274 -138.707114) (xy 89.833958 -138.671554) (xy 89.835861 -138.665055)
			(xy 89.83651 -138.651533) (xy 89.835228 -138.644884) (xy 89.833958 -138.63828) (xy 89.827608 -138.626342)
			(xy 89.822782 -138.621262) (xy 89.801559 -138.597685) (xy 89.764516 -138.546188) (xy 89.734162 -138.490485)
			(xy 89.710968 -138.431442) (xy 89.695293 -138.369973) (xy 89.687381 -138.307032) (xy 89.686892 -138.275314)
			(xy 89.686892 -138.27506) (xy 89.687394 -138.243099) (xy 89.695405 -138.179681) (xy 89.711302 -138.117767)
			(xy 89.734834 -138.058334) (xy 89.765628 -138.002319) (xy 89.803201 -137.950604) (xy 89.846958 -137.904007)
			(xy 89.896211 -137.863262) (xy 89.950182 -137.829011) (xy 90.008021 -137.801794) (xy 90.068814 -137.782041)
			(xy 90.131604 -137.770063) (xy 90.1954 -137.76605) (xy 90.259196 -137.770063) (xy 90.321986 -137.782041)
			(xy 90.382779 -137.801794) (xy 90.440618 -137.829011) (xy 90.494589 -137.863262) (xy 90.543842 -137.904007)
			(xy 90.587599 -137.950604) (xy 90.625172 -138.002319) (xy 90.655966 -138.058334) (xy 90.679498 -138.117767)
			(xy 90.695395 -138.179681) (xy 90.703406 -138.243099) (xy 90.703908 -138.27506) (xy 90.703428 -138.30705)
			(xy 90.695405 -138.370526) (xy 90.679482 -138.432494) (xy 90.65591 -138.491974) (xy 90.625061 -138.548026)
			(xy 90.587423 -138.599765) (xy 90.543592 -138.646373) (xy 90.494258 -138.687113) (xy 90.440203 -138.721342)
			(xy 90.382281 -138.748517) (xy 90.321407 -138.768211) (xy 90.258543 -138.780112) (xy 90.226642 -138.782552)
			(xy 90.212672 -138.783568) (xy 90.201496 -138.790934) (xy 90.19588 -138.794939) (xy 90.186868 -138.805373)
			(xy 90.183716 -138.811508) (xy 90.139774 -138.904218) (xy 90.140028 -138.906504) (xy 90.14941 -138.917685)
			(xy 90.1667 -138.941203) (xy 90.174572 -138.953494) (xy 90.178293 -138.959009) (xy 90.188072 -138.968023)
			(xy 90.193876 -138.971274) (xy 90.197686 -138.973306) (xy 90.269314 -138.973306) (xy 90.275532 -138.97316)
			(xy 90.287609 -138.970209) (xy 90.29319 -138.967464) (xy 90.32367 -138.951208) (xy 90.325702 -138.94816)
			(xy 90.341046 -138.926707) (xy 90.376694 -138.887835) (xy 90.417356 -138.854242) (xy 90.462256 -138.826569)
			(xy 90.510539 -138.805343) (xy 90.561286 -138.790968) (xy 90.613528 -138.783718) (xy 90.6399 -138.783314)
			(xy 90.666293 -138.783762) (xy 90.718575 -138.791041) (xy 90.769353 -138.805461) (xy 90.817658 -138.826746)
			(xy 90.862565 -138.854489) (xy 90.903218 -138.88816) (xy 90.938839 -138.927116) (xy 90.968747 -138.970611)
			(xy 90.992371 -139.017816) (xy 91.009259 -139.067827) (xy 91.019089 -139.11969) (xy 91.0209 -139.146026)
			(xy 91.021408 -139.155932) (xy 91.029536 -139.173458) (xy 91.036648 -139.180316) (xy 91.043969 -139.186698)
			(xy 91.061996 -139.193879) (xy 91.0717 -139.194286) (xy 96.675194 -139.194286) (xy 96.684004 -139.193869)
			(xy 96.700562 -139.187829) (xy 96.714112 -139.176558) (xy 96.718882 -139.16914) (xy 96.763332 -139.093448)
			(xy 96.766522 -139.087648) (xy 96.770117 -139.074914) (xy 96.770444 -139.068302) (xy 96.770444 -139.055094)
			(xy 96.763586 -139.043156) (xy 96.745182 -139.008818) (xy 96.717877 -138.935855) (xy 96.70923 -138.897868)
			(xy 96.70669 -138.885422) (xy 96.699324 -138.876278) (xy 96.695303 -138.871693) (xy 96.685546 -138.864381)
			(xy 96.68002 -138.8618) (xy 96.64192 -138.845036) (xy 96.603312 -138.828272) (xy 96.597736 -138.826075)
			(xy 96.585934 -138.824021) (xy 96.579944 -138.824208) (xy 96.568514 -138.82497) (xy 96.557592 -138.831574)
			(xy 96.557084 -138.831574) (xy 96.527285 -138.848857) (xy 96.464019 -138.876109) (xy 96.397651 -138.894567)
			(xy 96.329399 -138.903891) (xy 96.294956 -138.904472) (xy 96.262999 -138.903968) (xy 96.19959 -138.895952)
			(xy 96.137685 -138.880053) (xy 96.078261 -138.85652) (xy 96.022254 -138.825726) (xy 95.970548 -138.788156)
			(xy 95.923959 -138.744402) (xy 95.883221 -138.695153) (xy 95.848975 -138.641188) (xy 95.821764 -138.583356)
			(xy 95.802014 -138.52257) (xy 95.790038 -138.459788) (xy 95.786025 -138.396) (xy 95.790038 -138.332212)
			(xy 95.802014 -138.26943) (xy 95.821764 -138.208644) (xy 95.848975 -138.150812) (xy 95.883221 -138.096847)
			(xy 95.923959 -138.047598) (xy 95.970548 -138.003844) (xy 96.022254 -137.966274) (xy 96.078261 -137.93548)
			(xy 96.137685 -137.911947) (xy 96.19959 -137.896048) (xy 96.262999 -137.888032) (xy 96.294956 -137.887456)
			(xy 96.307678 -137.887536) (xy 96.33309 -137.888808) (xy 96.345756 -137.889996) (xy 96.377721 -137.893705)
			(xy 96.440428 -137.908163) (xy 96.50081 -137.930416) (xy 96.557903 -137.960107) (xy 96.610795 -137.996762)
			(xy 96.658641 -138.039796) (xy 96.700678 -138.088521) (xy 96.736232 -138.142159) (xy 96.764738 -138.199853)
			(xy 96.785738 -138.260682) (xy 96.792796 -138.292078) (xy 96.795336 -138.304524) (xy 96.802448 -138.313414)
			(xy 96.806446 -138.318074) (xy 96.816201 -138.325523) (xy 96.821752 -138.328146) (xy 96.898714 -138.361674)
			(xy 96.90429 -138.363866) (xy 96.916093 -138.365913) (xy 96.922082 -138.365738) (xy 96.933512 -138.364976)
			(xy 96.944434 -138.358372) (xy 96.944942 -138.358372) (xy 96.974741 -138.341089) (xy 97.038007 -138.313838)
			(xy 97.104375 -138.295382) (xy 97.172627 -138.28606) (xy 97.20707 -138.285474) (xy 97.240107 -138.286006)
			(xy 97.305625 -138.294573) (xy 97.36948 -138.311554) (xy 97.430599 -138.336663) (xy 97.487951 -138.369476)
			(xy 97.506048 -138.383221) (xy 104.750102 -138.383221) (xy 104.750102 -138.319299) (xy 104.758113 -138.255881)
			(xy 104.77401 -138.193967) (xy 104.797542 -138.134534) (xy 104.828336 -138.078519) (xy 104.865909 -138.026804)
			(xy 104.909666 -137.980207) (xy 104.958919 -137.939462) (xy 105.01289 -137.905211) (xy 105.070729 -137.877994)
			(xy 105.131522 -137.858241) (xy 105.194312 -137.846263) (xy 105.258108 -137.84225) (xy 105.321904 -137.846263)
			(xy 105.384694 -137.858241) (xy 105.445487 -137.877994) (xy 105.503326 -137.905211) (xy 105.557297 -137.939462)
			(xy 105.60655 -137.980207) (xy 105.650307 -138.026804) (xy 105.68788 -138.078519) (xy 105.718674 -138.134534)
			(xy 105.742206 -138.193967) (xy 105.758103 -138.255881) (xy 105.766114 -138.319299) (xy 105.766616 -138.35126)
			(xy 105.766114 -138.383221) (xy 105.758103 -138.446639) (xy 105.742206 -138.508553) (xy 105.718674 -138.567986)
			(xy 105.68788 -138.624001) (xy 105.650307 -138.675716) (xy 105.60655 -138.722313) (xy 105.557297 -138.763058)
			(xy 105.503326 -138.797309) (xy 105.445487 -138.824526) (xy 105.384694 -138.844279) (xy 105.321904 -138.856257)
			(xy 105.258108 -138.860271) (xy 105.194312 -138.856257) (xy 105.131522 -138.844279) (xy 105.070729 -138.824526)
			(xy 105.01289 -138.797309) (xy 104.958919 -138.763058) (xy 104.909666 -138.722313) (xy 104.865909 -138.675716)
			(xy 104.828336 -138.624001) (xy 104.797542 -138.567986) (xy 104.77401 -138.508553) (xy 104.758113 -138.446639)
			(xy 104.750102 -138.383221) (xy 97.506048 -138.383221) (xy 97.540569 -138.409441) (xy 97.587568 -138.455885)
			(xy 97.628155 -138.508025) (xy 97.661648 -138.564982) (xy 97.687481 -138.625798) (xy 97.705219 -138.689447)
			(xy 97.714565 -138.754858) (xy 97.715578 -138.787886) (xy 97.715578 -138.79322) (xy 97.715102 -138.825839)
			(xy 97.706859 -138.890552) (xy 97.690421 -138.953684) (xy 97.666058 -139.0142) (xy 97.650554 -139.042902)
			(xy 97.646998 -139.048998) (xy 97.643696 -139.061698) (xy 97.643696 -139.068302) (xy 97.644002 -139.074917)
			(xy 97.647597 -139.087657) (xy 97.650808 -139.093448) (xy 97.671382 -139.1285) (xy 97.695258 -139.16914)
			(xy 97.700019 -139.176574) (xy 97.71355 -139.187888) (xy 97.730127 -139.193915) (xy 97.738946 -139.194286)
			(xy 98.019108 -139.194286) (xy 98.031663 -139.193642) (xy 98.053794 -139.181784) (xy 98.061272 -139.17168)
			(xy 98.081592 -139.1412) (xy 98.108516 -139.100814) (xy 98.111738 -139.095593) (xy 98.115852 -139.084038)
			(xy 98.116644 -139.077954) (xy 98.117914 -139.065762) (xy 98.112834 -139.05357) (xy 98.103508 -139.030186)
			(xy 98.090387 -138.981582) (xy 98.083769 -138.931676) (xy 98.08337 -138.906504) (xy 98.083856 -138.879253)
			(xy 98.091612 -138.825305) (xy 98.106967 -138.77301) (xy 98.129609 -138.723433) (xy 98.159075 -138.677583)
			(xy 98.194766 -138.636392) (xy 98.235957 -138.600701) (xy 98.281807 -138.571235) (xy 98.331384 -138.548593)
			(xy 98.383679 -138.533238) (xy 98.437627 -138.525482) (xy 98.492129 -138.525482) (xy 98.546077 -138.533238)
			(xy 98.598372 -138.548593) (xy 98.647949 -138.571235) (xy 98.693799 -138.600701) (xy 98.73499 -138.636392)
			(xy 98.770681 -138.677583) (xy 98.800147 -138.723433) (xy 98.822789 -138.77301) (xy 98.838144 -138.825305)
			(xy 98.8459 -138.879253) (xy 98.846386 -138.906504) (xy 98.845983 -138.931676) (xy 98.839366 -138.981582)
			(xy 98.826247 -139.030186) (xy 98.816922 -139.05357) (xy 98.816922 -139.053824) (xy 98.814623 -139.059766)
			(xy 98.812699 -139.072358) (xy 98.813112 -139.078716) (xy 98.814382 -139.0904) (xy 98.848164 -139.1412)
			(xy 98.868484 -139.17168) (xy 98.876002 -139.181739) (xy 98.898109 -139.193593) (xy 98.910648 -139.194286)
			(xy 99.041966 -139.194286) (xy 99.04603 -139.194032) (xy 99.05664 -139.192612) (xy 99.075407 -139.182367)
			(xy 99.082352 -139.17422) (xy 99.084638 -139.170918) (xy 99.130866 -139.098782) (xy 99.134125 -139.093318)
			(xy 99.138103 -139.081237) (xy 99.13874 -139.074906) (xy 99.139502 -139.062206) (xy 99.134168 -139.050522)
			(xy 99.134168 -139.050014) (xy 99.123194 -139.025003) (xy 99.107716 -138.972624) (xy 99.099878 -138.918572)
			(xy 99.09937 -138.891264) (xy 99.099856 -138.864013) (xy 99.107612 -138.810065) (xy 99.122967 -138.75777)
			(xy 99.145609 -138.708193) (xy 99.175075 -138.662343) (xy 99.210766 -138.621152) (xy 99.251957 -138.585461)
			(xy 99.297807 -138.555995) (xy 99.347384 -138.533353) (xy 99.399679 -138.517998) (xy 99.453627 -138.510242)
			(xy 99.508129 -138.510242) (xy 99.562077 -138.517998) (xy 99.614372 -138.533353) (xy 99.663949 -138.555995)
			(xy 99.709799 -138.585461) (xy 99.75099 -138.621152) (xy 99.786681 -138.662343) (xy 99.816147 -138.708193)
			(xy 99.838789 -138.75777) (xy 99.854144 -138.810065) (xy 99.8619 -138.864013) (xy 99.862386 -138.891264)
			(xy 99.861881 -138.918572) (xy 99.854027 -138.972621) (xy 99.838558 -139.025002) (xy 99.827588 -139.050014)
			(xy 99.827588 -139.050522) (xy 99.827334 -139.050522) (xy 99.824937 -139.056311) (xy 99.82275 -139.068646)
			(xy 99.823016 -139.074906) (xy 99.824032 -139.08786) (xy 99.877118 -139.170918) (xy 99.879404 -139.17422)
			(xy 99.88627 -139.182458) (xy 99.905083 -139.192714) (xy 99.915726 -139.194032) (xy 99.91979 -139.194286)
			(xy 100.04933 -139.194286) (xy 100.061772 -139.193595) (xy 100.083735 -139.181881) (xy 100.09124 -139.171934)
			(xy 100.10394 -139.153138) (xy 100.138484 -139.10183) (xy 100.141817 -139.096507) (xy 100.146062 -139.08469)
			(xy 100.146866 -139.078462) (xy 100.148136 -139.06627) (xy 100.148136 -139.066016) (xy 100.14331 -139.054586)
			(xy 100.134538 -139.031905) (xy 100.122157 -138.984878) (xy 100.115842 -138.93666) (xy 100.11537 -138.912346)
			(xy 100.11537 -138.911838) (xy 100.11537 -138.906504) (xy 100.116167 -138.879469) (xy 100.124451 -138.826022)
			(xy 100.140202 -138.774281) (xy 100.163102 -138.725284) (xy 100.192694 -138.680013) (xy 100.228384 -138.639375)
			(xy 100.269456 -138.604186) (xy 100.315087 -138.575151) (xy 100.364361 -138.552852) (xy 100.416291 -138.537737)
			(xy 100.469835 -138.530108) (xy 100.496878 -138.529568) (xy 100.524614 -138.530071) (xy 100.579499 -138.538113)
			(xy 100.632642 -138.554017) (xy 100.682923 -138.577447) (xy 100.729282 -138.607909) (xy 100.770742 -138.644763)
			(xy 100.80643 -138.68723) (xy 100.835593 -138.734417) (xy 100.857618 -138.785329) (xy 100.872039 -138.838893)
			(xy 100.875846 -138.866372) (xy 100.87737 -138.880596) (xy 100.87864 -138.911076) (xy 100.87855 -138.91641)
			(xy 101.13086 -138.91641) (xy 101.134931 -138.860788) (xy 101.147057 -138.806351) (xy 101.16698 -138.75426)
			(xy 101.194276 -138.705625) (xy 101.228362 -138.661482) (xy 101.268511 -138.622773) (xy 101.313869 -138.590322)
			(xy 101.363469 -138.564821) (xy 101.416253 -138.546814) (xy 101.471096 -138.536684) (xy 101.52683 -138.534647)
			(xy 101.582267 -138.540747) (xy 101.636224 -138.554853) (xy 101.687553 -138.576665) (xy 101.735159 -138.605719)
			(xy 101.778027 -138.641394) (xy 101.815244 -138.682931) (xy 101.846017 -138.729444) (xy 101.869689 -138.779941)
			(xy 101.885757 -138.833348) (xy 101.893877 -138.888524) (xy 101.894386 -138.91641) (xy 101.893877 -138.944296)
			(xy 101.885757 -138.999472) (xy 101.869689 -139.052879) (xy 101.846017 -139.103376) (xy 101.815244 -139.149889)
			(xy 101.778027 -139.191426) (xy 101.735159 -139.227101) (xy 101.687553 -139.256155) (xy 101.636224 -139.277967)
			(xy 101.582267 -139.292073) (xy 101.52683 -139.298173) (xy 101.471096 -139.296136) (xy 101.416253 -139.286006)
			(xy 101.363469 -139.267999) (xy 101.313869 -139.242498) (xy 101.268511 -139.210047) (xy 101.228362 -139.171338)
			(xy 101.194276 -139.127195) (xy 101.16698 -139.07856) (xy 101.147057 -139.026469) (xy 101.134931 -138.972032)
			(xy 101.13086 -138.91641) (xy 100.87855 -138.91641) (xy 100.878178 -138.93834) (xy 100.870419 -138.992312)
			(xy 100.855056 -139.04463) (xy 100.832401 -139.094228) (xy 100.802916 -139.140096) (xy 100.785422 -139.161012)
			(xy 100.778818 -139.168632) (xy 100.776024 -139.176506) (xy 100.774452 -139.181104) (xy 100.772922 -139.190697)
			(xy 100.772976 -139.195556) (xy 100.77577 -139.267184) (xy 100.776823 -139.276003) (xy 100.784254 -139.292124)
			(xy 100.790248 -139.29868) (xy 101.165406 -139.673838) (xy 101.172784 -139.680429) (xy 101.191083 -139.687899)
			(xy 101.200966 -139.688316) (xy 109.510322 -139.688316) (xy 109.519974 -139.6873) (xy 109.527217 -139.685671)
			(xy 109.540385 -139.678828) (xy 109.545882 -139.673838) (xy 111.943134 -137.276586) (xy 111.95053 -137.269735)
			(xy 111.969129 -137.262) (xy 111.979202 -137.2616) (xy 114.07775 -137.2616) (xy 114.087402 -137.260584)
			(xy 114.094643 -137.258951) (xy 114.107804 -137.252101) (xy 114.11331 -137.247122) (xy 117.807486 -133.552946)
			(xy 117.812244 -133.547801) (xy 117.81907 -133.535568) (xy 117.820948 -133.528816) (xy 117.822472 -133.522212)
			(xy 117.822218 -133.508496) (xy 117.819932 -133.501638) (xy 117.808776 -133.464139) (xy 117.796781 -133.386831)
			(xy 117.796056 -133.347714) (xy 117.796519 -133.316982) (xy 117.803926 -133.255965) (xy 117.818633 -133.196286)
			(xy 117.840427 -133.138814) (xy 117.868988 -133.084389) (xy 117.903902 -133.033803) (xy 117.944659 -132.987794)
			(xy 117.990664 -132.947033) (xy 118.041246 -132.912114) (xy 118.095669 -132.883547) (xy 118.153138 -132.861748)
			(xy 118.212816 -132.847035) (xy 118.273832 -132.839622) (xy 118.304564 -132.839206) (xy 118.343681 -132.839925)
			(xy 118.42099 -132.851921) (xy 118.458488 -132.863082) (xy 118.458742 -132.863082) (xy 118.465374 -132.86499)
			(xy 118.479161 -132.865497) (xy 118.48592 -132.864098) (xy 118.492778 -132.862574) (xy 118.504716 -132.855716)
			(xy 122.34291 -129.017522) (xy 122.347902 -129.012025) (xy 122.354757 -128.998861) (xy 122.356372 -128.991614)
			(xy 122.357388 -128.981962) (xy 122.357388 -118.608602) (xy 122.357215 -118.602594) (xy 122.354381 -118.590917)
			(xy 122.3518 -118.585488) (xy 122.349961 -118.582014) (xy 122.345368 -118.575634) (xy 122.342656 -118.572788)
			(xy 120.60682 -116.836952) (xy 120.60397 -116.834244) (xy 120.597594 -116.829648) (xy 120.59412 -116.827808)
			(xy 120.588692 -116.825228) (xy 120.577013 -116.822413) (xy 120.571006 -116.82222) (xy 84.021422 -116.82222)
			(xy 84.011358 -116.821783) (xy 83.992772 -116.814051) (xy 83.985354 -116.807234) (xy 81.693766 -114.515646)
			(xy 81.686921 -114.508248) (xy 81.679196 -114.489649) (xy 81.67878 -114.479578) (xy 81.67878 -82.626962)
			(xy 81.679209 -82.616894) (xy 81.686931 -82.598298) (xy 81.693766 -82.590894) (xy 86.911434 -77.373226)
			(xy 86.918833 -77.366382) (xy 86.937431 -77.358656) (xy 86.947502 -77.35824) (xy 90.303096 -77.35824)
			(xy 90.313346 -77.357783) (xy 90.332228 -77.349804) (xy 90.339672 -77.342746) (xy 90.397584 -77.283056)
			(xy 90.40495 -77.263752) (xy 90.404696 -77.253338) (xy 90.404442 -77.236828) (xy 90.404944 -77.204867)
			(xy 90.412955 -77.141449) (xy 90.428852 -77.079535) (xy 90.452384 -77.020102) (xy 90.483178 -76.964087)
			(xy 90.520751 -76.912372) (xy 90.564508 -76.865775) (xy 90.613761 -76.82503) (xy 90.667732 -76.790779)
			(xy 90.725571 -76.763562) (xy 90.786364 -76.743809) (xy 90.849154 -76.731831) (xy 90.91295 -76.727818)
			(xy 90.976746 -76.731831) (xy 91.039536 -76.743809) (xy 91.100329 -76.763562) (xy 91.158168 -76.790779)
			(xy 91.212139 -76.82503) (xy 91.261392 -76.865775) (xy 91.305149 -76.912372) (xy 91.342722 -76.964087)
			(xy 91.373516 -77.020102) (xy 91.397048 -77.079535) (xy 91.412945 -77.141449) (xy 91.420956 -77.204867)
			(xy 91.421458 -77.236828) (xy 91.421204 -77.253338) (xy 91.42095 -77.263752) (xy 91.428316 -77.283056)
			(xy 91.486228 -77.342746) (xy 91.493679 -77.3498) (xy 91.512553 -77.357801) (xy 91.522804 -77.35824)
			(xy 92.974668 -77.35824) (xy 92.986086 -77.357781) (xy 93.00671 -77.347994) (xy 93.014292 -77.339444)
			(xy 93.071442 -77.268832) (xy 93.076522 -77.24648) (xy 93.074236 -77.235304) (xy 93.070212 -77.215482)
			(xy 93.065884 -77.175264) (xy 93.0656 -77.15504) (xy 93.066086 -77.127789) (xy 93.073842 -77.073841)
			(xy 93.089197 -77.021546) (xy 93.111839 -76.971969) (xy 93.141305 -76.926119) (xy 93.176996 -76.884928)
			(xy 93.218187 -76.849237) (xy 93.264037 -76.819771) (xy 93.313614 -76.797129) (xy 93.365909 -76.781774)
			(xy 93.419857 -76.774018) (xy 93.474359 -76.774018) (xy 93.528307 -76.781774) (xy 93.580602 -76.797129)
			(xy 93.630179 -76.819771) (xy 93.676029 -76.849237) (xy 93.71722 -76.884928) (xy 93.752911 -76.926119)
			(xy 93.782377 -76.971969) (xy 93.805019 -77.021546) (xy 93.820374 -77.073841) (xy 93.82813 -77.127789)
			(xy 93.828616 -77.15504) (xy 93.828324 -77.175264) (xy 93.824001 -77.215481) (xy 93.81998 -77.235304)
			(xy 93.817694 -77.24648) (xy 93.822774 -77.268832) (xy 93.879924 -77.339444) (xy 93.88759 -77.347884)
			(xy 93.908162 -77.357646) (xy 93.919548 -77.35824) (xy 97.149158 -77.35824) (xy 97.15881 -77.357224)
			(xy 97.166056 -77.3556) (xy 97.179229 -77.348762) (xy 97.184718 -77.343762) (xy 108.461302 -66.067178)
			(xy 108.46629 -66.061679) (xy 108.473134 -66.048513) (xy 108.474764 -66.04127) (xy 108.47578 -66.031618)
			(xy 108.47578 -56.736742) (xy 108.475612 -56.730733) (xy 108.472785 -56.719052) (xy 108.470192 -56.713628)
			(xy 108.468355 -56.710152) (xy 108.463765 -56.70377) (xy 108.461048 -56.700928) (xy 107.808522 -56.048402)
			(xy 107.805671 -56.045696) (xy 107.799292 -56.041104) (xy 107.795822 -56.039258) (xy 107.790395 -56.036676)
			(xy 107.778715 -56.033857) (xy 107.772708 -56.03367) (xy 105.001314 -56.03367) (xy 104.993583 -56.033937)
			(xy 104.978842 -56.038595) (xy 104.972358 -56.042814) (xy 104.966008 -56.046878) (xy 104.956864 -56.058816)
			(xy 104.953816 -56.066436) (xy 104.943732 -56.091594) (xy 104.917479 -56.139009) (xy 104.884781 -56.182232)
			(xy 104.846296 -56.220394) (xy 104.802798 -56.252726) (xy 104.755163 -56.278578) (xy 104.704349 -56.29743)
			(xy 104.651379 -56.308901) (xy 104.597319 -56.312762) (xy 104.543256 -56.308935) (xy 104.490279 -56.297496)
			(xy 104.439453 -56.278676) (xy 104.391802 -56.252854) (xy 104.348284 -56.220549) (xy 104.309775 -56.182411)
			(xy 104.27705 -56.139208) (xy 104.250768 -56.091809) (xy 104.240584 -56.06669) (xy 104.240584 -56.066182)
			(xy 104.24033 -56.065928) (xy 104.237369 -56.058983) (xy 104.228075 -56.047097) (xy 104.222042 -56.04256)
			(xy 104.215438 -56.038242) (xy 104.201214 -56.03367) (xy 102.144322 -56.03367) (xy 102.13572 -56.034008)
			(xy 102.119496 -56.03973) (xy 102.112572 -56.044846) (xy 102.105968 -56.049926) (xy 102.097078 -56.06415)
			(xy 102.095046 -56.072786) (xy 102.087109 -56.104257) (xy 102.064314 -56.165027) (xy 102.033972 -56.222402)
			(xy 101.996578 -56.275452) (xy 101.952738 -56.323313) (xy 101.903165 -56.365207) (xy 101.848665 -56.400454)
			(xy 101.790124 -56.42848) (xy 101.728492 -56.448831) (xy 101.664772 -56.461175) (xy 101.6 -56.465313)
			(xy 101.535228 -56.461175) (xy 101.471508 -56.448831) (xy 101.409876 -56.42848) (xy 101.351335 -56.400454)
			(xy 101.296835 -56.365207) (xy 101.247262 -56.323313) (xy 101.203422 -56.275452) (xy 101.166028 -56.222402)
			(xy 101.135686 -56.165027) (xy 101.112891 -56.104257) (xy 101.104954 -56.072786) (xy 101.104954 -56.072532)
			(xy 101.102629 -56.064402) (xy 101.093549 -56.050149) (xy 101.087174 -56.044592) (xy 101.080316 -56.039258)
			(xy 101.064568 -56.03367) (xy 98.127058 -56.03367) (xy 98.123248 -56.033924) (xy 98.112552 -56.035234)
			(xy 98.093627 -56.045503) (xy 98.086672 -56.053736) (xy 98.084386 -56.057038) (xy 98.038158 -56.129174)
			(xy 98.034893 -56.134636) (xy 98.030902 -56.146716) (xy 98.030284 -56.15305) (xy 98.029522 -56.16575)
			(xy 98.034856 -56.177434) (xy 98.034856 -56.177942) (xy 98.045899 -56.203025) (xy 98.061485 -56.255567)
			(xy 98.069389 -56.309798) (xy 98.069908 -56.3372) (xy 98.069422 -56.364451) (xy 98.061666 -56.418399)
			(xy 98.046311 -56.470694) (xy 98.023669 -56.520271) (xy 97.994203 -56.566121) (xy 97.958512 -56.607312)
			(xy 97.917321 -56.643003) (xy 97.871471 -56.672469) (xy 97.821894 -56.695111) (xy 97.769599 -56.710466)
			(xy 97.715651 -56.718222) (xy 97.661149 -56.718222) (xy 97.607201 -56.710466) (xy 97.554906 -56.695111)
			(xy 97.505329 -56.672469) (xy 97.459479 -56.643003) (xy 97.418288 -56.607312) (xy 97.382597 -56.566121)
			(xy 97.353131 -56.520271) (xy 97.330489 -56.470694) (xy 97.315134 -56.418399) (xy 97.307378 -56.364451)
			(xy 97.306892 -56.3372) (xy 97.307401 -56.309798) (xy 97.31531 -56.255566) (xy 97.330894 -56.203023)
			(xy 97.341944 -56.177942) (xy 97.341944 -56.177434) (xy 97.342198 -56.177434) (xy 97.344589 -56.171644)
			(xy 97.346763 -56.15931) (xy 97.346516 -56.15305) (xy 97.3455 -56.140096) (xy 97.292414 -56.057038)
			(xy 97.290128 -56.053736) (xy 97.283213 -56.045459) (xy 97.264262 -56.035204) (xy 97.253552 -56.033924)
			(xy 97.249742 -56.03367) (xy 96.312736 -56.03367) (xy 96.305878 -56.034178) (xy 96.295039 -56.036206)
			(xy 96.276477 -56.048066) (xy 96.270064 -56.057038) (xy 96.235012 -56.118506) (xy 96.225106 -56.136032)
			(xy 96.221965 -56.141968) (xy 96.218626 -56.154971) (xy 96.218502 -56.161686) (xy 96.218502 -56.175148)
			(xy 96.225614 -56.187086) (xy 96.242408 -56.216605) (xy 96.268885 -56.279145) (xy 96.286815 -56.344649)
			(xy 96.29588 -56.411955) (xy 96.29648 -56.445912) (xy 96.29648 -56.452516) (xy 96.295371 -56.489284)
			(xy 96.283856 -56.561934) (xy 96.261982 -56.632164) (xy 96.246696 -56.665622) (xy 96.246442 -56.665876)
			(xy 96.244065 -56.671349) (xy 96.241618 -56.683024) (xy 96.241616 -56.68899) (xy 96.24187 -56.700674)
			(xy 96.26727 -56.747664) (xy 96.286574 -56.783732) (xy 96.289587 -56.78903) (xy 96.297669 -56.798151)
			(xy 96.301828 -56.801215) (xy 106.917738 -56.801215) (xy 106.917738 -56.737293) (xy 106.925749 -56.673875)
			(xy 106.941646 -56.611961) (xy 106.965178 -56.552528) (xy 106.995972 -56.496513) (xy 107.033545 -56.444798)
			(xy 107.077302 -56.398201) (xy 107.126555 -56.357456) (xy 107.180526 -56.323205) (xy 107.238365 -56.295988)
			(xy 107.299158 -56.276235) (xy 107.361948 -56.264257) (xy 107.425744 -56.260244) (xy 107.48954 -56.264257)
			(xy 107.55233 -56.276235) (xy 107.613123 -56.295988) (xy 107.670962 -56.323205) (xy 107.724933 -56.357456)
			(xy 107.774186 -56.398201) (xy 107.817943 -56.444798) (xy 107.855516 -56.496513) (xy 107.88631 -56.552528)
			(xy 107.909842 -56.611961) (xy 107.925739 -56.673875) (xy 107.93375 -56.737293) (xy 107.934252 -56.769254)
			(xy 107.93375 -56.801215) (xy 107.925739 -56.864633) (xy 107.909842 -56.926547) (xy 107.88631 -56.98598)
			(xy 107.855516 -57.041995) (xy 107.817943 -57.09371) (xy 107.774186 -57.140307) (xy 107.724933 -57.181052)
			(xy 107.670962 -57.215303) (xy 107.613123 -57.24252) (xy 107.55233 -57.262273) (xy 107.48954 -57.274251)
			(xy 107.425744 -57.278265) (xy 107.361948 -57.274251) (xy 107.299158 -57.262273) (xy 107.238365 -57.24252)
			(xy 107.180526 -57.215303) (xy 107.126555 -57.181052) (xy 107.077302 -57.140307) (xy 107.033545 -57.09371)
			(xy 106.995972 -57.041995) (xy 106.965178 -56.98598) (xy 106.941646 -56.926547) (xy 106.925749 -56.864633)
			(xy 106.917738 -56.801215) (xy 96.301828 -56.801215) (xy 96.302576 -56.801766) (xy 96.311974 -56.808116)
			(xy 96.322134 -56.80964) (xy 96.32442 -56.809894) (xy 96.351439 -56.814125) (xy 96.403976 -56.829313)
			(xy 96.453805 -56.851849) (xy 96.499905 -56.881271) (xy 96.541331 -56.916975) (xy 96.577232 -56.958228)
			(xy 96.606875 -57.004187) (xy 96.629649 -57.053907) (xy 96.64509 -57.106371) (xy 96.652879 -57.160502)
			(xy 96.65335 -57.187846) (xy 96.652861 -57.215096) (xy 96.6451 -57.269041) (xy 96.629741 -57.321333)
			(xy 96.607098 -57.370907) (xy 96.577631 -57.416755) (xy 96.54194 -57.457943) (xy 96.500751 -57.493633)
			(xy 96.454903 -57.5231) (xy 96.405329 -57.545742) (xy 96.353037 -57.5611) (xy 96.299092 -57.568861)
			(xy 96.271842 -57.569354) (xy 96.244105 -57.568852) (xy 96.189216 -57.560813) (xy 96.13607 -57.544911)
			(xy 96.085785 -57.521483) (xy 96.039422 -57.491021) (xy 95.997958 -57.454169) (xy 95.962266 -57.411701)
			(xy 95.933098 -57.364514) (xy 95.911069 -57.313601) (xy 95.896644 -57.260035) (xy 95.892874 -57.23255)
			(xy 95.89135 -57.218326) (xy 95.89008 -57.187846) (xy 95.89008 -57.187338) (xy 95.890539 -57.161021)
			(xy 95.897806 -57.108892) (xy 95.904558 -57.083452) (xy 95.906336 -57.07761) (xy 95.906844 -57.065164)
			(xy 95.903542 -57.0484) (xy 95.90024 -57.044336) (xy 95.845376 -56.973978) (xy 95.841625 -56.969377)
			(xy 95.832383 -56.96193) (xy 95.827088 -56.959246) (xy 95.81642 -56.954166) (xy 95.803974 -56.95442)
			(xy 95.787972 -56.954674) (xy 95.754942 -56.954145) (xy 95.689439 -56.945588) (xy 95.625596 -56.928622)
			(xy 95.564486 -56.903532) (xy 95.50714 -56.870741) (xy 95.454522 -56.830801) (xy 95.407518 -56.784384)
			(xy 95.36692 -56.732272) (xy 95.333411 -56.675342) (xy 95.307556 -56.614552) (xy 95.289789 -56.550927)
			(xy 95.28041 -56.485536) (xy 95.279464 -56.452516) (xy 95.279464 -56.445912) (xy 95.279999 -56.41195)
			(xy 95.289042 -56.344632) (xy 95.306981 -56.27912) (xy 95.333495 -56.216586) (xy 95.35033 -56.187086)
			(xy 95.35033 -56.186832) (xy 95.353635 -56.181) (xy 95.357357 -56.168127) (xy 95.357696 -56.161432)
			(xy 95.357696 -56.14797) (xy 95.340932 -56.118506) (xy 95.30588 -56.057038) (xy 95.299466 -56.048071)
			(xy 95.280899 -56.036226) (xy 95.270066 -56.034178) (xy 95.263208 -56.03367) (xy 93.466666 -56.03367)
			(xy 93.465904 -56.03367) (xy 93.453917 -56.034569) (xy 93.432714 -56.045827) (xy 93.425264 -56.05526)
			(xy 93.424756 -56.055768) (xy 93.377258 -56.12511) (xy 93.373893 -56.130294) (xy 93.36954 -56.141857)
			(xy 93.368622 -56.14797) (xy 93.367352 -56.159908) (xy 93.371924 -56.171846) (xy 93.382776 -56.201189)
			(xy 93.39804 -56.261863) (xy 93.405734 -56.323952) (xy 93.406214 -56.355234) (xy 93.405712 -56.387195)
			(xy 93.397701 -56.450613) (xy 93.381804 -56.512527) (xy 93.358272 -56.57196) (xy 93.327478 -56.627975)
			(xy 93.289905 -56.67969) (xy 93.246148 -56.726287) (xy 93.196895 -56.767032) (xy 93.142924 -56.801283)
			(xy 93.085085 -56.8285) (xy 93.024292 -56.848253) (xy 92.961502 -56.860231) (xy 92.897706 -56.864245)
			(xy 92.83391 -56.860231) (xy 92.77112 -56.848253) (xy 92.710327 -56.8285) (xy 92.652488 -56.801283)
			(xy 92.598517 -56.767032) (xy 92.549264 -56.726287) (xy 92.505507 -56.67969) (xy 92.467934 -56.627975)
			(xy 92.43714 -56.57196) (xy 92.413608 -56.512527) (xy 92.397711 -56.450613) (xy 92.3897 -56.387195)
			(xy 92.389198 -56.355234) (xy 92.389697 -56.323954) (xy 92.397405 -56.261869) (xy 92.412659 -56.201196)
			(xy 92.423488 -56.171846) (xy 92.423742 -56.171592) (xy 92.425724 -56.165778) (xy 92.427128 -56.153577)
			(xy 92.426536 -56.147462) (xy 92.425266 -56.135524) (xy 92.370656 -56.055768) (xy 92.370148 -56.05526)
			(xy 92.362722 -56.045794) (xy 92.341509 -56.034516) (xy 92.329508 -56.03367) (xy 91.531948 -56.03367)
			(xy 91.522688 -56.034019) (xy 91.505355 -56.040525) (xy 91.498166 -56.04637) (xy 91.491308 -56.052466)
			(xy 91.482672 -56.068976) (xy 91.48191 -56.075834) (xy 91.481656 -56.078882) (xy 91.478002 -56.106471)
			(xy 91.463734 -56.16026) (xy 91.441808 -56.211409) (xy 91.412689 -56.258833) (xy 91.376995 -56.301527)
			(xy 91.33548 -56.338587) (xy 91.289026 -56.369228) (xy 91.238615 -56.392801) (xy 91.185316 -56.408806)
			(xy 91.130259 -56.416904) (xy 91.102434 -56.417464) (xy 91.073313 -56.416911) (xy 91.015748 -56.408056)
			(xy 90.960194 -56.390563) (xy 90.907942 -56.364837) (xy 90.88374 -56.34863) (xy 90.883486 -56.34863)
			(xy 90.876059 -56.343846) (xy 90.859039 -56.339155) (xy 90.850212 -56.339486) (xy 90.841576 -56.340248)
			(xy 90.825574 -56.347614) (xy 90.753946 -56.419242) (xy 90.747137 -56.426587) (xy 90.739413 -56.44505)
			(xy 90.73896 -56.455056) (xy 90.73896 -56.45531) (xy 90.739214 -56.45785) (xy 90.739929 -56.465849)
			(xy 90.745614 -56.480858) (xy 90.75039 -56.487314) (xy 90.7751 -56.511429) (xy 90.818441 -56.565176)
			(xy 90.854112 -56.624293) (xy 90.881457 -56.687692) (xy 90.899975 -56.754207) (xy 90.909324 -56.822616)
			(xy 90.909902 -56.857138) (xy 90.909436 -56.887884) (xy 90.90202 -56.948926) (xy 90.887301 -57.00863)
			(xy 90.865494 -57.066125) (xy 90.836915 -57.120572) (xy 90.801983 -57.171179) (xy 90.761207 -57.217205)
			(xy 90.71518 -57.257982) (xy 90.664574 -57.292914) (xy 90.610127 -57.321493) (xy 90.552632 -57.3433)
			(xy 90.492928 -57.35802) (xy 90.431886 -57.365436) (xy 90.40114 -57.3659) (xy 90.366617 -57.365325)
			(xy 90.298205 -57.355985) (xy 90.231686 -57.337473) (xy 90.168285 -57.310128) (xy 90.109168 -57.274454)
			(xy 90.055423 -57.231107) (xy 90.031316 -57.206388) (xy 90.023769 -57.200849) (xy 90.005971 -57.195103)
			(xy 89.987293 -57.196087) (xy 89.970197 -57.203674) (xy 89.963244 -57.209944) (xy 89.90457 -57.268618)
			(xy 89.901863 -57.271469) (xy 89.89727 -57.277847) (xy 89.895426 -57.281318) (xy 89.892124 -57.287668)
			(xy 89.8906 -57.29605) (xy 89.885852 -57.321959) (xy 89.870165 -57.372242) (xy 89.84771 -57.41989)
			(xy 89.818914 -57.463995) (xy 89.784325 -57.50372) (xy 89.744601 -57.53831) (xy 89.700496 -57.567107)
			(xy 89.652849 -57.589563) (xy 89.602566 -57.605251) (xy 89.576656 -57.609994) (xy 89.568274 -57.611518)
			(xy 89.561924 -57.61482) (xy 89.558449 -57.616658) (xy 89.552067 -57.621249) (xy 89.549224 -57.623964)
			(xy 89.268046 -57.905142) (xy 89.261243 -57.912465) (xy 89.253524 -57.930886) (xy 89.253473 -57.950859)
			(xy 89.25687 -57.96026) (xy 89.30005 -58.049668) (xy 89.303637 -58.056575) (xy 89.314242 -58.067954)
			(xy 89.320878 -58.07202) (xy 89.32799 -58.07583) (xy 89.34323 -58.078878) (xy 89.351104 -58.078116)
			(xy 89.365279 -58.076589) (xy 89.393744 -58.074937) (xy 89.408 -58.074814) (xy 89.43996 -58.075316)
			(xy 89.503375 -58.083327) (xy 89.565286 -58.099223) (xy 89.624717 -58.122753) (xy 89.68073 -58.153547)
			(xy 89.732441 -58.191118) (xy 89.779037 -58.234873) (xy 89.81978 -58.284124) (xy 89.85403 -58.338093)
			(xy 89.881246 -58.395929) (xy 89.900998 -58.45672) (xy 89.912975 -58.519507) (xy 89.916989 -58.5833)
			(xy 89.912975 -58.647093) (xy 89.900998 -58.70988) (xy 89.881246 -58.770671) (xy 89.85403 -58.828507)
			(xy 89.829737 -58.866786) (xy 93.453204 -58.866786) (xy 93.453805 -58.837133) (xy 93.462996 -58.778542)
			(xy 93.48114 -58.722078) (xy 93.507799 -58.669101) (xy 93.542332 -58.620884) (xy 93.583908 -58.57859)
			(xy 93.607382 -58.560462) (xy 93.614785 -58.554451) (xy 93.624842 -58.538268) (xy 93.62694 -58.528966)
			(xy 93.639894 -58.461148) (xy 93.641139 -58.451725) (xy 93.637482 -58.433089) (xy 93.632782 -58.424826)
			(xy 93.632782 -58.424572) (xy 93.614259 -58.393995) (xy 93.585007 -58.328765) (xy 93.565178 -58.260082)
			(xy 93.55516 -58.189298) (xy 93.55455 -58.153554) (xy 93.555052 -58.121593) (xy 93.563063 -58.058175)
			(xy 93.57896 -57.996261) (xy 93.602492 -57.936828) (xy 93.633286 -57.880813) (xy 93.670859 -57.829098)
			(xy 93.714616 -57.782501) (xy 93.763869 -57.741756) (xy 93.81784 -57.707505) (xy 93.875679 -57.680288)
			(xy 93.936472 -57.660535) (xy 93.999262 -57.648557) (xy 94.063058 -57.644544) (xy 94.126854 -57.648557)
			(xy 94.189644 -57.660535) (xy 94.250437 -57.680288) (xy 94.308276 -57.707505) (xy 94.362247 -57.741756)
			(xy 94.4115 -57.782501) (xy 94.455257 -57.829098) (xy 94.49283 -57.880813) (xy 94.523624 -57.936828)
			(xy 94.547156 -57.996261) (xy 94.563053 -58.058175) (xy 94.565412 -58.076846) (xy 95.889824 -58.076846)
			(xy 95.893895 -58.021224) (xy 95.906021 -57.966787) (xy 95.925944 -57.914696) (xy 95.95324 -57.866061)
			(xy 95.987326 -57.821918) (xy 96.027475 -57.783209) (xy 96.072833 -57.750758) (xy 96.122433 -57.725257)
			(xy 96.175217 -57.70725) (xy 96.23006 -57.69712) (xy 96.285794 -57.695083) (xy 96.341231 -57.701183)
			(xy 96.395188 -57.715289) (xy 96.446517 -57.737101) (xy 96.494123 -57.766155) (xy 96.536991 -57.80183)
			(xy 96.574208 -57.843367) (xy 96.604981 -57.88988) (xy 96.614973 -57.911195) (xy 98.884734 -57.911195)
			(xy 98.884734 -57.847273) (xy 98.892745 -57.783855) (xy 98.908642 -57.721941) (xy 98.932174 -57.662508)
			(xy 98.962968 -57.606493) (xy 99.000541 -57.554778) (xy 99.044298 -57.508181) (xy 99.093551 -57.467436)
			(xy 99.147522 -57.433185) (xy 99.205361 -57.405968) (xy 99.266154 -57.386215) (xy 99.328944 -57.374237)
			(xy 99.39274 -57.370224) (xy 99.456536 -57.374237) (xy 99.519326 -57.386215) (xy 99.580119 -57.405968)
			(xy 99.637958 -57.433185) (xy 99.691929 -57.467436) (xy 99.741182 -57.508181) (xy 99.784939 -57.554778)
			(xy 99.822512 -57.606493) (xy 99.853306 -57.662508) (xy 99.876838 -57.721941) (xy 99.892735 -57.783855)
			(xy 99.900746 -57.847273) (xy 99.901248 -57.879234) (xy 99.900746 -57.911195) (xy 99.892735 -57.974613)
			(xy 99.876838 -58.036527) (xy 99.853306 -58.09596) (xy 99.822512 -58.151975) (xy 99.784939 -58.20369)
			(xy 99.741182 -58.250287) (xy 99.691929 -58.291032) (xy 99.637958 -58.325283) (xy 99.580119 -58.3525)
			(xy 99.519326 -58.372253) (xy 99.456536 -58.384231) (xy 99.39274 -58.388245) (xy 99.328944 -58.384231)
			(xy 99.266154 -58.372253) (xy 99.205361 -58.3525) (xy 99.147522 -58.325283) (xy 99.093551 -58.291032)
			(xy 99.044298 -58.250287) (xy 99.000541 -58.20369) (xy 98.962968 -58.151975) (xy 98.932174 -58.09596)
			(xy 98.908642 -58.036527) (xy 98.892745 -57.974613) (xy 98.884734 -57.911195) (xy 96.614973 -57.911195)
			(xy 96.628653 -57.940377) (xy 96.644721 -57.993784) (xy 96.652841 -58.04896) (xy 96.65335 -58.076846)
			(xy 96.652841 -58.104732) (xy 96.644721 -58.159908) (xy 96.628653 -58.213315) (xy 96.604981 -58.263812)
			(xy 96.574208 -58.310325) (xy 96.536991 -58.351862) (xy 96.494123 -58.387537) (xy 96.446517 -58.416591)
			(xy 96.395188 -58.438403) (xy 96.341231 -58.452509) (xy 96.285794 -58.458609) (xy 96.23006 -58.456572)
			(xy 96.175217 -58.446442) (xy 96.122433 -58.428435) (xy 96.072833 -58.402934) (xy 96.027475 -58.370483)
			(xy 95.987326 -58.331774) (xy 95.95324 -58.287631) (xy 95.925944 -58.238996) (xy 95.906021 -58.186905)
			(xy 95.893895 -58.132468) (xy 95.889824 -58.076846) (xy 94.565412 -58.076846) (xy 94.571064 -58.121593)
			(xy 94.571566 -58.153554) (xy 94.571566 -58.153808) (xy 94.570919 -58.190429) (xy 94.560385 -58.262909)
			(xy 94.539578 -58.333134) (xy 94.52483 -58.36666) (xy 94.521544 -58.37454) (xy 94.519927 -58.391529)
			(xy 94.524004 -58.408099) (xy 94.528386 -58.415428) (xy 94.574868 -58.487564) (xy 94.579802 -58.494541)
			(xy 94.589453 -58.502) (xy 106.20021 -58.502) (xy 106.204224 -58.438206) (xy 106.216202 -58.375418)
			(xy 106.235954 -58.314626) (xy 106.263171 -58.25679) (xy 106.297421 -58.20282) (xy 106.338166 -58.153569)
			(xy 106.384762 -58.109813) (xy 106.436475 -58.072243) (xy 106.492489 -58.041449) (xy 106.551921 -58.01792)
			(xy 106.613834 -58.002024) (xy 106.67725 -57.994014) (xy 106.70921 -57.993534) (xy 106.742505 -57.994075)
			(xy 106.80852 -58.00281) (xy 106.872827 -58.020103) (xy 106.903774 -58.032396) (xy 106.904028 -58.032396)
			(xy 106.91568 -58.036593) (xy 106.940317 -58.034316) (xy 106.951018 -58.028078) (xy 107.03179 -57.975246)
			(xy 107.043982 -57.953148) (xy 107.044236 -57.940702) (xy 107.045308 -57.913859) (xy 107.054065 -57.860856)
			(xy 107.070169 -57.809604) (xy 107.0933 -57.761118) (xy 107.123001 -57.716353) (xy 107.158687 -57.676197)
			(xy 107.19965 -57.641441) (xy 107.245083 -57.612772) (xy 107.294087 -57.590758) (xy 107.345694 -57.575833)
			(xy 107.398883 -57.568292) (xy 107.425744 -57.56783) (xy 107.452996 -57.568243) (xy 107.506944 -57.576005)
			(xy 107.559239 -57.591366) (xy 107.608816 -57.614012) (xy 107.654665 -57.643482) (xy 107.695854 -57.679177)
			(xy 107.731544 -57.72037) (xy 107.761009 -57.766223) (xy 107.78365 -57.815802) (xy 107.799004 -57.868099)
			(xy 107.80676 -57.922048) (xy 107.80676 -57.976552) (xy 107.799004 -58.030501) (xy 107.78365 -58.082798)
			(xy 107.761009 -58.132377) (xy 107.731544 -58.17823) (xy 107.695854 -58.219423) (xy 107.654665 -58.255118)
			(xy 107.608816 -58.284588) (xy 107.559239 -58.307234) (xy 107.506944 -58.322595) (xy 107.452996 -58.330357)
			(xy 107.425744 -58.330846) (xy 107.403435 -58.330538) (xy 107.359123 -58.325312) (xy 107.337352 -58.320432)
			(xy 107.337098 -58.320432) (xy 107.32493 -58.318297) (xy 107.301034 -58.324409) (xy 107.291378 -58.332116)
			(xy 107.21975 -58.39714) (xy 107.211114 -58.420508) (xy 107.212892 -58.432954) (xy 107.215138 -58.450138)
			(xy 107.21755 -58.484713) (xy 107.217718 -58.502042) (xy 107.217127 -58.536121) (xy 107.207956 -58.603661)
			(xy 107.19943 -58.636662) (xy 107.19943 -58.636916) (xy 107.197404 -58.645572) (xy 107.198895 -58.663277)
			(xy 107.206358 -58.679401) (xy 107.212384 -58.685938) (xy 107.284774 -58.758328) (xy 107.31119 -58.765186)
			(xy 107.324398 -58.76163) (xy 107.349244 -58.755224) (xy 107.400089 -58.748335) (xy 107.425744 -58.747914)
			(xy 107.452995 -58.748359) (xy 107.506941 -58.756121) (xy 107.559233 -58.771481) (xy 107.608808 -58.794126)
			(xy 107.654655 -58.823595) (xy 107.695843 -58.859288) (xy 107.731532 -58.90048) (xy 107.760995 -58.946331)
			(xy 107.783635 -58.995908) (xy 107.798988 -59.048202) (xy 107.806744 -59.102149) (xy 107.806744 -59.156651)
			(xy 107.798988 -59.210598) (xy 107.783635 -59.262892) (xy 107.760995 -59.312469) (xy 107.731532 -59.35832)
			(xy 107.695843 -59.399512) (xy 107.654655 -59.435205) (xy 107.608808 -59.464674) (xy 107.559233 -59.487319)
			(xy 107.506941 -59.502679) (xy 107.452995 -59.510441) (xy 107.425744 -59.51093) (xy 107.396772 -59.51037)
			(xy 107.339501 -59.50157) (xy 107.311698 -59.493404) (xy 107.302542 -59.490897) (xy 107.283613 -59.492183)
			(xy 107.266442 -59.500254) (xy 107.259628 -59.506866) (xy 107.19689 -59.57316) (xy 107.190624 -59.580269)
			(xy 107.183415 -59.597783) (xy 107.183058 -59.616719) (xy 107.185968 -59.625738) (xy 107.196029 -59.654068)
			(xy 107.210149 -59.712508) (xy 107.217267 -59.772207) (xy 107.217718 -59.802268) (xy 107.217266 -59.833812)
			(xy 107.209467 -59.896415) (xy 107.193983 -59.957572) (xy 107.171054 -60.016345) (xy 107.141031 -60.07183)
			(xy 107.104375 -60.123175) (xy 107.061649 -60.169592) (xy 107.013511 -60.210368) (xy 106.960698 -60.244876)
			(xy 106.904022 -60.272586) (xy 106.844354 -60.293073) (xy 106.78261 -60.306021) (xy 106.719739 -60.311233)
			(xy 106.656705 -60.308629) (xy 106.594478 -60.298247) (xy 106.534013 -60.280248) (xy 106.476239 -60.254907)
			(xy 106.422043 -60.222615) (xy 106.372257 -60.183868) (xy 106.327647 -60.139259) (xy 106.288897 -60.089475)
			(xy 106.256603 -60.035281) (xy 106.23126 -59.977508) (xy 106.213258 -59.917043) (xy 106.202874 -59.854817)
			(xy 106.200266 -59.791783) (xy 106.205475 -59.728912) (xy 106.218422 -59.667167) (xy 106.238906 -59.607498)
			(xy 106.266614 -59.550821) (xy 106.301119 -59.498007) (xy 106.341892 -59.449866) (xy 106.388307 -59.407139)
			(xy 106.439651 -59.370481) (xy 106.495135 -59.340455) (xy 106.553907 -59.317524) (xy 106.615064 -59.302037)
			(xy 106.677666 -59.294235) (xy 106.70921 -59.29376) (xy 106.744618 -59.294389) (xy 106.814749 -59.304208)
			(xy 106.882841 -59.323656) (xy 106.915458 -59.337448) (xy 106.924258 -59.340946) (xy 106.943165 -59.341772)
			(xy 106.961072 -59.335647) (xy 106.968544 -59.329828) (xy 107.049824 -59.26201) (xy 107.058714 -59.234578)
			(xy 107.055158 -59.220354) (xy 107.050067 -59.198095) (xy 107.044588 -59.152761) (xy 107.044236 -59.12993)
			(xy 107.044236 -59.129422) (xy 107.044341 -59.116426) (xy 107.046123 -59.090495) (xy 107.047792 -59.077606)
			(xy 107.04957 -59.06389) (xy 107.03941 -59.038744) (xy 106.947208 -58.968386) (xy 106.920284 -58.96483)
			(xy 106.907584 -58.970418) (xy 106.876184 -58.983057) (xy 106.810893 -59.000904) (xy 106.743814 -59.009952)
			(xy 106.709972 -59.01055) (xy 106.70921 -59.01055) (xy 106.67725 -59.009986) (xy 106.613834 -59.001976)
			(xy 106.551921 -58.98608) (xy 106.492489 -58.962551) (xy 106.436475 -58.931757) (xy 106.384762 -58.894187)
			(xy 106.338166 -58.850431) (xy 106.297421 -58.80118) (xy 106.263171 -58.74721) (xy 106.235954 -58.689374)
			(xy 106.216202 -58.628582) (xy 106.204224 -58.565794) (xy 106.20021 -58.502) (xy 94.589453 -58.502)
			(xy 94.593317 -58.504986) (xy 94.609505 -58.510434) (xy 94.618048 -58.510678) (xy 94.622112 -58.510678)
			(xy 94.649362 -58.511193) (xy 94.703306 -58.518951) (xy 94.755597 -58.534306) (xy 94.805171 -58.556947)
			(xy 94.851018 -58.586413) (xy 94.892206 -58.622103) (xy 94.927894 -58.663291) (xy 94.957359 -58.709139)
			(xy 94.979998 -58.758714) (xy 94.995352 -58.811006) (xy 95.003108 -58.86495) (xy 95.003108 -58.91945)
			(xy 94.995352 -58.973394) (xy 94.979998 -59.025686) (xy 94.959768 -59.069986) (xy 95.891094 -59.069986)
			(xy 95.895165 -59.014364) (xy 95.907291 -58.959927) (xy 95.927214 -58.907836) (xy 95.95451 -58.859201)
			(xy 95.988596 -58.815058) (xy 96.028745 -58.776349) (xy 96.074103 -58.743898) (xy 96.123703 -58.718397)
			(xy 96.176487 -58.70039) (xy 96.23133 -58.69026) (xy 96.287064 -58.688223) (xy 96.342501 -58.694323)
			(xy 96.396458 -58.708429) (xy 96.447787 -58.730241) (xy 96.495393 -58.759295) (xy 96.538261 -58.79497)
			(xy 96.575478 -58.836507) (xy 96.606251 -58.88302) (xy 96.629923 -58.933517) (xy 96.645991 -58.986924)
			(xy 96.654111 -59.0421) (xy 96.65462 -59.069986) (xy 96.654111 -59.097872) (xy 96.645991 -59.153048)
			(xy 96.629923 -59.206455) (xy 96.606251 -59.256952) (xy 96.575478 -59.303465) (xy 96.538261 -59.345002)
			(xy 96.495393 -59.380677) (xy 96.447787 -59.409731) (xy 96.396458 -59.431543) (xy 96.342501 -59.445649)
			(xy 96.287064 -59.451749) (xy 96.23133 -59.449712) (xy 96.176487 -59.439582) (xy 96.123703 -59.421575)
			(xy 96.074103 -59.396074) (xy 96.028745 -59.363623) (xy 95.988596 -59.324914) (xy 95.95451 -59.280771)
			(xy 95.927214 -59.232136) (xy 95.907291 -59.180045) (xy 95.895165 -59.125608) (xy 95.891094 -59.069986)
			(xy 94.959768 -59.069986) (xy 94.957359 -59.075261) (xy 94.927894 -59.121109) (xy 94.892206 -59.162297)
			(xy 94.851018 -59.197987) (xy 94.805171 -59.227453) (xy 94.755597 -59.250094) (xy 94.703306 -59.265449)
			(xy 94.649362 -59.273207) (xy 94.622112 -59.273694) (xy 94.595246 -59.273234) (xy 94.542044 -59.265708)
			(xy 94.490424 -59.250789) (xy 94.44141 -59.228773) (xy 94.395971 -59.200095) (xy 94.355007 -59.165323)
			(xy 94.31933 -59.125146) (xy 94.304104 -59.103006) (xy 94.296826 -59.093252) (xy 94.27559 -59.081442)
			(xy 94.263464 -59.0804) (xy 94.168214 -59.077098) (xy 94.145862 -59.087766) (xy 94.138496 -59.097672)
			(xy 94.131074 -59.107251) (xy 94.115186 -59.125552) (xy 94.106746 -59.134248) (xy 94.10059 -59.141063)
			(xy 94.093183 -59.157854) (xy 94.09217 -59.176179) (xy 94.094554 -59.185048) (xy 94.12605 -59.284362)
			(xy 94.146878 -59.302904) (xy 94.160848 -59.305444) (xy 94.192376 -59.311695) (xy 94.25365 -59.331113)
			(xy 94.311986 -59.3581) (xy 94.366455 -59.392227) (xy 94.416187 -59.432948) (xy 94.460389 -59.479614)
			(xy 94.498354 -59.531479) (xy 94.529479 -59.587718) (xy 94.553265 -59.647431) (xy 94.569334 -59.709667)
			(xy 94.577428 -59.773432) (xy 94.577916 -59.80557) (xy 94.577414 -59.837531) (xy 94.569403 -59.900949)
			(xy 94.553506 -59.962863) (xy 94.529974 -60.022296) (xy 94.49918 -60.078311) (xy 94.472382 -60.115196)
			(xy 96.183956 -60.115196) (xy 96.188027 -60.059574) (xy 96.200153 -60.005137) (xy 96.220076 -59.953046)
			(xy 96.247372 -59.904411) (xy 96.281458 -59.860268) (xy 96.321607 -59.821559) (xy 96.366965 -59.789108)
			(xy 96.416565 -59.763607) (xy 96.469349 -59.7456) (xy 96.524192 -59.73547) (xy 96.579926 -59.733433)
			(xy 96.635363 -59.739533) (xy 96.68932 -59.753639) (xy 96.740649 -59.775451) (xy 96.788255 -59.804505)
			(xy 96.831123 -59.84018) (xy 96.86834 -59.881717) (xy 96.899113 -59.92823) (xy 96.922785 -59.978727)
			(xy 96.938853 -60.032134) (xy 96.946973 -60.08731) (xy 96.947482 -60.115196) (xy 96.946973 -60.143082)
			(xy 96.938853 -60.198258) (xy 96.922785 -60.251665) (xy 96.899113 -60.302162) (xy 96.86834 -60.348675)
			(xy 96.831123 -60.390212) (xy 96.788255 -60.425887) (xy 96.740649 -60.454941) (xy 96.68932 -60.476753)
			(xy 96.635363 -60.490859) (xy 96.579926 -60.496959) (xy 96.524192 -60.494922) (xy 96.469349 -60.484792)
			(xy 96.416565 -60.466785) (xy 96.366965 -60.441284) (xy 96.321607 -60.408833) (xy 96.281458 -60.370124)
			(xy 96.247372 -60.325981) (xy 96.220076 -60.277346) (xy 96.200153 -60.225255) (xy 96.188027 -60.170818)
			(xy 96.183956 -60.115196) (xy 94.472382 -60.115196) (xy 94.461607 -60.130026) (xy 94.41785 -60.176623)
			(xy 94.368597 -60.217368) (xy 94.314626 -60.251619) (xy 94.256787 -60.278836) (xy 94.195994 -60.298589)
			(xy 94.133204 -60.310567) (xy 94.069408 -60.314581) (xy 94.005612 -60.310567) (xy 93.942822 -60.298589)
			(xy 93.882029 -60.278836) (xy 93.82419 -60.251619) (xy 93.770219 -60.217368) (xy 93.720966 -60.176623)
			(xy 93.677209 -60.130026) (xy 93.639636 -60.078311) (xy 93.608842 -60.022296) (xy 93.58531 -59.962863)
			(xy 93.569413 -59.900949) (xy 93.561402 -59.837531) (xy 93.5609 -59.80557) (xy 93.561409 -59.772876)
			(xy 93.569772 -59.708024) (xy 93.586384 -59.644781) (xy 93.610968 -59.58419) (xy 93.64312 -59.527253)
			(xy 93.682308 -59.474908) (xy 93.727886 -59.428022) (xy 93.753178 -59.407298) (xy 93.760194 -59.401249)
			(xy 93.769754 -59.385403) (xy 93.773034 -59.36719) (xy 93.77172 -59.358022) (xy 93.75521 -59.269884)
			(xy 93.753094 -59.260933) (xy 93.743524 -59.245241) (xy 93.729058 -59.233904) (xy 93.720412 -59.230768)
			(xy 93.694925 -59.222291) (xy 93.646443 -59.199171) (xy 93.601684 -59.169479) (xy 93.561532 -59.133802)
			(xy 93.526781 -59.092846) (xy 93.498118 -59.04742) (xy 93.476111 -58.998423) (xy 93.461193 -58.946824)
			(xy 93.453661 -58.893642) (xy 93.453204 -58.866786) (xy 89.829737 -58.866786) (xy 89.81978 -58.882476)
			(xy 89.779037 -58.931727) (xy 89.732441 -58.975482) (xy 89.68073 -59.013053) (xy 89.624717 -59.043847)
			(xy 89.565286 -59.067377) (xy 89.503375 -59.083273) (xy 89.43996 -59.091284) (xy 89.408 -59.09183)
			(xy 89.376286 -59.091349) (xy 89.313349 -59.083471) (xy 89.251882 -59.067823) (xy 89.192839 -59.04465)
			(xy 89.137137 -59.014311) (xy 89.085643 -58.977278) (xy 89.039156 -58.934126) (xy 88.998399 -58.885526)
			(xy 88.964005 -58.832233) (xy 88.936509 -58.775074) (xy 88.916337 -58.71494) (xy 88.903804 -58.652762)
			(xy 88.901016 -58.621168) (xy 88.9 -58.608214) (xy 88.892634 -58.597038) (xy 88.888949 -58.59178)
			(xy 88.879435 -58.583165) (xy 88.873838 -58.58002) (xy 88.797638 -58.539888) (xy 88.791797 -58.537135)
			(xy 88.779203 -58.534299) (xy 88.772746 -58.5343) (xy 88.759792 -58.534554) (xy 88.748362 -58.541158)
			(xy 88.72516 -58.554181) (xy 88.675936 -58.574379) (xy 88.624383 -58.587536) (xy 88.597994 -58.590942)
			(xy 88.589358 -58.591958) (xy 88.581738 -58.595514) (xy 88.577904 -58.597472) (xy 88.570877 -58.602443)
			(xy 88.567768 -58.60542) (xy 87.287905 -59.885283) (xy 88.899994 -59.885283) (xy 88.899994 -59.821361)
			(xy 88.908005 -59.757943) (xy 88.923902 -59.696029) (xy 88.947434 -59.636596) (xy 88.978228 -59.580581)
			(xy 89.015801 -59.528866) (xy 89.059558 -59.482269) (xy 89.108811 -59.441524) (xy 89.162782 -59.407273)
			(xy 89.220621 -59.380056) (xy 89.281414 -59.360303) (xy 89.344204 -59.348325) (xy 89.408 -59.344312)
			(xy 89.471796 -59.348325) (xy 89.534586 -59.360303) (xy 89.595379 -59.380056) (xy 89.653218 -59.407273)
			(xy 89.707189 -59.441524) (xy 89.756442 -59.482269) (xy 89.800199 -59.528866) (xy 89.837772 -59.580581)
			(xy 89.868566 -59.636596) (xy 89.892098 -59.696029) (xy 89.907995 -59.757943) (xy 89.916006 -59.821361)
			(xy 89.916508 -59.853322) (xy 89.916006 -59.885283) (xy 89.907995 -59.948701) (xy 89.892098 -60.010615)
			(xy 89.868566 -60.070048) (xy 89.837772 -60.126063) (xy 89.800199 -60.177778) (xy 89.756442 -60.224375)
			(xy 89.707189 -60.26512) (xy 89.653218 -60.299371) (xy 89.595379 -60.326588) (xy 89.534586 -60.346341)
			(xy 89.471796 -60.358319) (xy 89.408 -60.362333) (xy 89.344204 -60.358319) (xy 89.281414 -60.346341)
			(xy 89.220621 -60.326588) (xy 89.162782 -60.299371) (xy 89.108811 -60.26512) (xy 89.059558 -60.224375)
			(xy 89.015801 -60.177778) (xy 88.978228 -60.126063) (xy 88.947434 -60.070048) (xy 88.923902 -60.010615)
			(xy 88.908005 -59.948701) (xy 88.899994 -59.885283) (xy 87.287905 -59.885283) (xy 87.28456 -59.888628)
			(xy 87.281854 -59.891479) (xy 87.277262 -59.897858) (xy 87.275416 -59.901328) (xy 87.272831 -59.906754)
			(xy 87.270002 -59.918434) (xy 87.269828 -59.924442) (xy 87.269828 -60.711545) (xy 92.34398 -60.711545)
			(xy 92.34398 -60.647623) (xy 92.351991 -60.584205) (xy 92.367888 -60.522291) (xy 92.39142 -60.462858)
			(xy 92.422214 -60.406843) (xy 92.459787 -60.355128) (xy 92.503544 -60.308531) (xy 92.552797 -60.267786)
			(xy 92.606768 -60.233535) (xy 92.664607 -60.206318) (xy 92.7254 -60.186565) (xy 92.78819 -60.174587)
			(xy 92.851986 -60.170574) (xy 92.915782 -60.174587) (xy 92.978572 -60.186565) (xy 93.039365 -60.206318)
			(xy 93.097204 -60.233535) (xy 93.151175 -60.267786) (xy 93.200428 -60.308531) (xy 93.244185 -60.355128)
			(xy 93.281758 -60.406843) (xy 93.312552 -60.462858) (xy 93.336084 -60.522291) (xy 93.351981 -60.584205)
			(xy 93.359992 -60.647623) (xy 93.360494 -60.679584) (xy 93.359992 -60.711545) (xy 93.351981 -60.774963)
			(xy 93.336084 -60.836877) (xy 93.312552 -60.89631) (xy 93.281758 -60.952325) (xy 93.244185 -61.00404)
			(xy 93.200428 -61.050637) (xy 93.151175 -61.091382) (xy 93.107317 -61.119215) (xy 104.124754 -61.119215)
			(xy 104.124754 -61.055293) (xy 104.132765 -60.991875) (xy 104.148662 -60.929961) (xy 104.172194 -60.870528)
			(xy 104.202988 -60.814513) (xy 104.240561 -60.762798) (xy 104.284318 -60.716201) (xy 104.333571 -60.675456)
			(xy 104.387542 -60.641205) (xy 104.445381 -60.613988) (xy 104.506174 -60.594235) (xy 104.568964 -60.582257)
			(xy 104.63276 -60.578244) (xy 104.696556 -60.582257) (xy 104.759346 -60.594235) (xy 104.820139 -60.613988)
			(xy 104.877978 -60.641205) (xy 104.931949 -60.675456) (xy 104.981202 -60.716201) (xy 105.024959 -60.762798)
			(xy 105.062532 -60.814513) (xy 105.093326 -60.870528) (xy 105.116858 -60.929961) (xy 105.132755 -60.991875)
			(xy 105.140766 -61.055293) (xy 105.141268 -61.087254) (xy 106.200702 -61.087254) (xy 106.201204 -61.055293)
			(xy 106.209215 -60.991875) (xy 106.225112 -60.929961) (xy 106.248644 -60.870528) (xy 106.279438 -60.814513)
			(xy 106.317011 -60.762798) (xy 106.360768 -60.716201) (xy 106.410021 -60.675456) (xy 106.463992 -60.641205)
			(xy 106.521831 -60.613988) (xy 106.582624 -60.594235) (xy 106.645414 -60.582257) (xy 106.70921 -60.578244)
			(xy 106.773006 -60.582257) (xy 106.835796 -60.594235) (xy 106.896589 -60.613988) (xy 106.954428 -60.641205)
			(xy 107.008399 -60.675456) (xy 107.057652 -60.716201) (xy 107.101409 -60.762798) (xy 107.138982 -60.814513)
			(xy 107.169776 -60.870528) (xy 107.193308 -60.929961) (xy 107.209205 -60.991875) (xy 107.217216 -61.055293)
			(xy 107.217718 -61.087254) (xy 107.217167 -61.120586) (xy 107.208462 -61.186679) (xy 107.191194 -61.251068)
			(xy 107.165661 -61.312648) (xy 107.1323 -61.370363) (xy 107.091683 -61.423224) (xy 107.044506 -61.470325)
			(xy 106.991579 -61.510856) (xy 106.962956 -61.527944) (xy 106.950288 -61.5358) (xy 106.929859 -61.557488)
			(xy 106.916561 -61.584152) (xy 106.911528 -61.613519) (xy 106.915186 -61.643089) (xy 106.927226 -61.670343)
			(xy 106.946622 -61.692961) (xy 106.958892 -61.701426) (xy 106.98162 -61.716553) (xy 107.022925 -61.752254)
			(xy 107.058721 -61.793477) (xy 107.088278 -61.83938) (xy 107.110993 -61.889025) (xy 107.126401 -61.941401)
			(xy 107.13419 -61.995438) (xy 107.13466 -62.022736) (xy 107.134174 -62.049987) (xy 107.126418 -62.103935)
			(xy 107.111063 -62.15623) (xy 107.088421 -62.205807) (xy 107.058955 -62.251657) (xy 107.023264 -62.292848)
			(xy 106.982073 -62.328539) (xy 106.936223 -62.358005) (xy 106.886646 -62.380647) (xy 106.834351 -62.396002)
			(xy 106.780403 -62.403758) (xy 106.725901 -62.403758) (xy 106.671953 -62.396002) (xy 106.619658 -62.380647)
			(xy 106.570081 -62.358005) (xy 106.524231 -62.328539) (xy 106.48304 -62.292848) (xy 106.447349 -62.251657)
			(xy 106.417883 -62.205807) (xy 106.395241 -62.15623) (xy 106.379886 -62.103935) (xy 106.37213 -62.049987)
			(xy 106.371644 -62.022736) (xy 106.372141 -61.99388) (xy 106.380836 -61.936825) (xy 106.398032 -61.881734)
			(xy 106.423336 -61.829864) (xy 106.456171 -61.782402) (xy 106.495785 -61.740432) (xy 106.518202 -61.722254)
			(xy 106.52967 -61.712705) (xy 106.546893 -61.68835) (xy 106.556343 -61.660056) (xy 106.557213 -61.630239)
			(xy 106.54943 -61.601443) (xy 106.533656 -61.576124) (xy 106.51124 -61.556444) (xy 106.497882 -61.549788)
			(xy 106.468737 -61.535903) (xy 106.413888 -61.501852) (xy 106.363789 -61.461135) (xy 106.319246 -61.414404)
			(xy 106.280975 -61.362413) (xy 106.24959 -61.305996) (xy 106.225598 -61.246061) (xy 106.209383 -61.183572)
			(xy 106.201206 -61.119533) (xy 106.200702 -61.087254) (xy 105.141268 -61.087254) (xy 105.140766 -61.119215)
			(xy 105.132755 -61.182633) (xy 105.116858 -61.244547) (xy 105.093326 -61.30398) (xy 105.062532 -61.359995)
			(xy 105.024959 -61.41171) (xy 104.981202 -61.458307) (xy 104.931949 -61.499052) (xy 104.877978 -61.533303)
			(xy 104.820139 -61.56052) (xy 104.759346 -61.580273) (xy 104.696556 -61.592251) (xy 104.63276 -61.596265)
			(xy 104.568964 -61.592251) (xy 104.506174 -61.580273) (xy 104.445381 -61.56052) (xy 104.387542 -61.533303)
			(xy 104.333571 -61.499052) (xy 104.284318 -61.458307) (xy 104.240561 -61.41171) (xy 104.202988 -61.359995)
			(xy 104.172194 -61.30398) (xy 104.148662 -61.244547) (xy 104.132765 -61.182633) (xy 104.124754 -61.119215)
			(xy 93.107317 -61.119215) (xy 93.097204 -61.125633) (xy 93.039365 -61.15285) (xy 92.978572 -61.172603)
			(xy 92.915782 -61.184581) (xy 92.851986 -61.188595) (xy 92.78819 -61.184581) (xy 92.7254 -61.172603)
			(xy 92.664607 -61.15285) (xy 92.606768 -61.125633) (xy 92.552797 -61.091382) (xy 92.503544 -61.050637)
			(xy 92.459787 -61.00404) (xy 92.422214 -60.952325) (xy 92.39142 -60.89631) (xy 92.367888 -60.836877)
			(xy 92.351991 -60.774963) (xy 92.34398 -60.711545) (xy 87.269828 -60.711545) (xy 87.269828 -61.87821)
			(xy 96.14103 -61.87821) (xy 96.145101 -61.822588) (xy 96.157227 -61.768151) (xy 96.17715 -61.71606)
			(xy 96.204446 -61.667425) (xy 96.238532 -61.623282) (xy 96.278681 -61.584573) (xy 96.324039 -61.552122)
			(xy 96.373639 -61.526621) (xy 96.426423 -61.508614) (xy 96.481266 -61.498484) (xy 96.537 -61.496447)
			(xy 96.592437 -61.502547) (xy 96.646394 -61.516653) (xy 96.697723 -61.538465) (xy 96.745329 -61.567519)
			(xy 96.788197 -61.603194) (xy 96.825414 -61.644731) (xy 96.856187 -61.691244) (xy 96.879859 -61.741741)
			(xy 96.895927 -61.795148) (xy 96.904047 -61.850324) (xy 96.904556 -61.87821) (xy 96.904047 -61.906096)
			(xy 96.895927 -61.961272) (xy 96.879859 -62.014679) (xy 96.856187 -62.065176) (xy 96.825414 -62.111689)
			(xy 96.788197 -62.153226) (xy 96.745329 -62.188901) (xy 96.697723 -62.217955) (xy 96.646394 -62.239767)
			(xy 96.592437 -62.253873) (xy 96.537 -62.259973) (xy 96.481266 -62.257936) (xy 96.426423 -62.247806)
			(xy 96.373639 -62.229799) (xy 96.324039 -62.204298) (xy 96.278681 -62.171847) (xy 96.238532 -62.133138)
			(xy 96.204446 -62.088995) (xy 96.17715 -62.04036) (xy 96.157227 -61.988269) (xy 96.145101 -61.933832)
			(xy 96.14103 -61.87821) (xy 87.269828 -61.87821) (xy 87.269828 -62.204346) (xy 87.269397 -62.214413)
			(xy 87.261674 -62.233008) (xy 87.254842 -62.240414) (xy 86.104476 -63.39078) (xy 107.245402 -63.39078)
			(xy 107.249473 -63.335158) (xy 107.261599 -63.280721) (xy 107.281522 -63.22863) (xy 107.308818 -63.179995)
			(xy 107.342904 -63.135852) (xy 107.383053 -63.097143) (xy 107.428411 -63.064692) (xy 107.478011 -63.039191)
			(xy 107.530795 -63.021184) (xy 107.585638 -63.011054) (xy 107.641372 -63.009017) (xy 107.696809 -63.015117)
			(xy 107.750766 -63.029223) (xy 107.802095 -63.051035) (xy 107.849701 -63.080089) (xy 107.892569 -63.115764)
			(xy 107.929786 -63.157301) (xy 107.960559 -63.203814) (xy 107.984231 -63.254311) (xy 108.000299 -63.307718)
			(xy 108.008419 -63.362894) (xy 108.008928 -63.39078) (xy 108.008419 -63.418666) (xy 108.000299 -63.473842)
			(xy 107.984231 -63.527249) (xy 107.960559 -63.577746) (xy 107.929786 -63.624259) (xy 107.892569 -63.665796)
			(xy 107.849701 -63.701471) (xy 107.802095 -63.730525) (xy 107.750766 -63.752337) (xy 107.696809 -63.766443)
			(xy 107.641372 -63.772543) (xy 107.585638 -63.770506) (xy 107.530795 -63.760376) (xy 107.478011 -63.742369)
			(xy 107.428411 -63.716868) (xy 107.383053 -63.684417) (xy 107.342904 -63.645708) (xy 107.308818 -63.601565)
			(xy 107.281522 -63.55293) (xy 107.261599 -63.500839) (xy 107.249473 -63.446402) (xy 107.245402 -63.39078)
			(xy 86.104476 -63.39078) (xy 84.937346 -64.55791) (xy 104.447592 -64.55791) (xy 104.451663 -64.502288)
			(xy 104.463789 -64.447851) (xy 104.483712 -64.39576) (xy 104.511008 -64.347125) (xy 104.545094 -64.302982)
			(xy 104.585243 -64.264273) (xy 104.630601 -64.231822) (xy 104.680201 -64.206321) (xy 104.732985 -64.188314)
			(xy 104.787828 -64.178184) (xy 104.843562 -64.176147) (xy 104.898999 -64.182247) (xy 104.952956 -64.196353)
			(xy 105.004285 -64.218165) (xy 105.051891 -64.247219) (xy 105.094759 -64.282894) (xy 105.131976 -64.324431)
			(xy 105.162749 -64.370944) (xy 105.186421 -64.421441) (xy 105.202489 -64.474848) (xy 105.210609 -64.530024)
			(xy 105.211118 -64.55791) (xy 105.210609 -64.585796) (xy 105.202489 -64.640972) (xy 105.186421 -64.694379)
			(xy 105.162749 -64.744876) (xy 105.131976 -64.791389) (xy 105.094759 -64.832926) (xy 105.051891 -64.868601)
			(xy 105.004285 -64.897655) (xy 104.952956 -64.919467) (xy 104.898999 -64.933573) (xy 104.843562 -64.939673)
			(xy 104.787828 -64.937636) (xy 104.732985 -64.927506) (xy 104.680201 -64.909499) (xy 104.630601 -64.883998)
			(xy 104.585243 -64.851547) (xy 104.545094 -64.812838) (xy 104.511008 -64.768695) (xy 104.483712 -64.72006)
			(xy 104.463789 -64.667969) (xy 104.451663 -64.613532) (xy 104.447592 -64.55791) (xy 84.937346 -64.55791)
			(xy 82.905346 -66.58991) (xy 104.447592 -66.58991) (xy 104.451663 -66.534288) (xy 104.463789 -66.479851)
			(xy 104.483712 -66.42776) (xy 104.511008 -66.379125) (xy 104.545094 -66.334982) (xy 104.585243 -66.296273)
			(xy 104.630601 -66.263822) (xy 104.680201 -66.238321) (xy 104.732985 -66.220314) (xy 104.787828 -66.210184)
			(xy 104.843562 -66.208147) (xy 104.898999 -66.214247) (xy 104.952956 -66.228353) (xy 105.004285 -66.250165)
			(xy 105.051891 -66.279219) (xy 105.094759 -66.314894) (xy 105.131976 -66.356431) (xy 105.162749 -66.402944)
			(xy 105.186421 -66.453441) (xy 105.202489 -66.506848) (xy 105.210609 -66.562024) (xy 105.211118 -66.58991)
			(xy 105.210609 -66.617796) (xy 105.202489 -66.672972) (xy 105.186421 -66.726379) (xy 105.162749 -66.776876)
			(xy 105.131976 -66.823389) (xy 105.094759 -66.864926) (xy 105.051891 -66.900601) (xy 105.004285 -66.929655)
			(xy 104.952956 -66.951467) (xy 104.898999 -66.965573) (xy 104.843562 -66.971673) (xy 104.787828 -66.969636)
			(xy 104.732985 -66.959506) (xy 104.680201 -66.941499) (xy 104.630601 -66.915998) (xy 104.585243 -66.883547)
			(xy 104.545094 -66.844838) (xy 104.511008 -66.800695) (xy 104.483712 -66.75206) (xy 104.463789 -66.699969)
			(xy 104.451663 -66.645532) (xy 104.447592 -66.58991) (xy 82.905346 -66.58991) (xy 82.296762 -67.198494)
			(xy 82.289362 -67.205335) (xy 82.270764 -67.213057) (xy 82.260694 -67.21348) (xy 72.755506 -67.21348)
			(xy 72.749498 -67.213652) (xy 72.73782 -67.216484) (xy 72.732392 -67.219068) (xy 72.728917 -67.220906)
			(xy 72.722535 -67.225497) (xy 72.719692 -67.228212) (xy 71.301864 -68.64604) (xy 83.691982 -68.64604)
			(xy 83.696053 -68.590418) (xy 83.708179 -68.535981) (xy 83.728102 -68.48389) (xy 83.755398 -68.435255)
			(xy 83.789484 -68.391112) (xy 83.829633 -68.352403) (xy 83.874991 -68.319952) (xy 83.924591 -68.294451)
			(xy 83.977375 -68.276444) (xy 84.032218 -68.266314) (xy 84.087952 -68.264277) (xy 84.143389 -68.270377)
			(xy 84.197346 -68.284483) (xy 84.248675 -68.306295) (xy 84.296281 -68.335349) (xy 84.339149 -68.371024)
			(xy 84.376366 -68.412561) (xy 84.407139 -68.459074) (xy 84.430811 -68.509571) (xy 84.446879 -68.562978)
			(xy 84.454999 -68.618154) (xy 84.455508 -68.64604) (xy 84.454999 -68.673926) (xy 84.446879 -68.729102)
			(xy 84.438703 -68.756276) (xy 98.795586 -68.756276) (xy 98.796126 -68.72736) (xy 98.804846 -68.670188)
			(xy 98.822098 -68.614988) (xy 98.847485 -68.563026) (xy 98.880426 -68.515491) (xy 98.920167 -68.473475)
			(xy 98.942652 -68.455286) (xy 98.951464 -68.447684) (xy 98.961643 -68.426779) (xy 98.96221 -68.415154)
			(xy 98.96221 -68.335398) (xy 98.961654 -68.323768) (xy 98.951477 -68.302859) (xy 98.942652 -68.295266)
			(xy 98.920142 -68.277106) (xy 98.880411 -68.235079) (xy 98.847476 -68.187537) (xy 98.822093 -68.13557)
			(xy 98.804842 -68.080367) (xy 98.796118 -68.023194) (xy 98.795586 -67.994276) (xy 98.796072 -67.967025)
			(xy 98.803828 -67.913077) (xy 98.819183 -67.860782) (xy 98.841825 -67.811205) (xy 98.871291 -67.765355)
			(xy 98.906982 -67.724164) (xy 98.948173 -67.688473) (xy 98.994023 -67.659007) (xy 99.0436 -67.636365)
			(xy 99.095895 -67.62101) (xy 99.149843 -67.613254) (xy 99.204345 -67.613254) (xy 99.258293 -67.62101)
			(xy 99.310588 -67.636365) (xy 99.360165 -67.659007) (xy 99.406015 -67.688473) (xy 99.447206 -67.724164)
			(xy 99.482897 -67.765355) (xy 99.512363 -67.811205) (xy 99.535005 -67.860782) (xy 99.55036 -67.913077)
			(xy 99.558116 -67.967025) (xy 99.558602 -67.994276) (xy 99.558066 -68.023192) (xy 99.54934 -68.080363)
			(xy 99.532086 -68.135561) (xy 99.506698 -68.187523) (xy 99.473757 -68.235057) (xy 99.43402 -68.277075)
			(xy 99.411536 -68.295266) (xy 99.402743 -68.302887) (xy 99.392554 -68.323778) (xy 99.391978 -68.335398)
			(xy 99.391978 -68.415154) (xy 99.392508 -68.426787) (xy 99.402704 -68.447695) (xy 99.411536 -68.455286)
			(xy 99.43402 -68.473476) (xy 99.473754 -68.515497) (xy 99.506692 -68.563032) (xy 99.53208 -68.614994)
			(xy 99.534242 -68.62191) (xy 104.447592 -68.62191) (xy 104.451663 -68.566288) (xy 104.463789 -68.511851)
			(xy 104.483712 -68.45976) (xy 104.511008 -68.411125) (xy 104.545094 -68.366982) (xy 104.585243 -68.328273)
			(xy 104.630601 -68.295822) (xy 104.680201 -68.270321) (xy 104.732985 -68.252314) (xy 104.787828 -68.242184)
			(xy 104.843562 -68.240147) (xy 104.898999 -68.246247) (xy 104.952956 -68.260353) (xy 105.004285 -68.282165)
			(xy 105.051891 -68.311219) (xy 105.094759 -68.346894) (xy 105.131976 -68.388431) (xy 105.162749 -68.434944)
			(xy 105.186421 -68.485441) (xy 105.202489 -68.538848) (xy 105.210609 -68.594024) (xy 105.211118 -68.62191)
			(xy 105.210609 -68.649796) (xy 105.202489 -68.704972) (xy 105.186421 -68.758379) (xy 105.162749 -68.808876)
			(xy 105.131976 -68.855389) (xy 105.094759 -68.896926) (xy 105.051891 -68.932601) (xy 105.004285 -68.961655)
			(xy 104.952956 -68.983467) (xy 104.898999 -68.997573) (xy 104.843562 -69.003673) (xy 104.787828 -69.001636)
			(xy 104.732985 -68.991506) (xy 104.680201 -68.973499) (xy 104.630601 -68.947998) (xy 104.585243 -68.915547)
			(xy 104.545094 -68.876838) (xy 104.511008 -68.832695) (xy 104.483712 -68.78406) (xy 104.463789 -68.731969)
			(xy 104.451663 -68.677532) (xy 104.447592 -68.62191) (xy 99.534242 -68.62191) (xy 99.549336 -68.670191)
			(xy 99.558066 -68.72736) (xy 99.558602 -68.756276) (xy 99.558116 -68.783527) (xy 99.55036 -68.837475)
			(xy 99.535005 -68.88977) (xy 99.512363 -68.939347) (xy 99.482897 -68.985197) (xy 99.447206 -69.026388)
			(xy 99.406015 -69.062079) (xy 99.360165 -69.091545) (xy 99.310588 -69.114187) (xy 99.258293 -69.129542)
			(xy 99.204345 -69.137298) (xy 99.149843 -69.137298) (xy 99.095895 -69.129542) (xy 99.0436 -69.114187)
			(xy 98.994023 -69.091545) (xy 98.948173 -69.062079) (xy 98.906982 -69.026388) (xy 98.871291 -68.985197)
			(xy 98.841825 -68.939347) (xy 98.819183 -68.88977) (xy 98.803828 -68.837475) (xy 98.796072 -68.783527)
			(xy 98.795586 -68.756276) (xy 84.438703 -68.756276) (xy 84.430811 -68.782509) (xy 84.407139 -68.833006)
			(xy 84.376366 -68.879519) (xy 84.339149 -68.921056) (xy 84.296281 -68.956731) (xy 84.248675 -68.985785)
			(xy 84.197346 -69.007597) (xy 84.143389 -69.021703) (xy 84.087952 -69.027803) (xy 84.032218 -69.025766)
			(xy 83.977375 -69.015636) (xy 83.924591 -68.997629) (xy 83.874991 -68.972128) (xy 83.829633 -68.939677)
			(xy 83.789484 -68.900968) (xy 83.755398 -68.856825) (xy 83.728102 -68.80819) (xy 83.708179 -68.756099)
			(xy 83.696053 -68.701662) (xy 83.691982 -68.64604) (xy 71.301864 -68.64604) (xy 70.082918 -69.864986)
			(xy 89.974164 -69.864986) (xy 89.978235 -69.809364) (xy 89.990361 -69.754927) (xy 90.010284 -69.702836)
			(xy 90.03758 -69.654201) (xy 90.071666 -69.610058) (xy 90.111815 -69.571349) (xy 90.157173 -69.538898)
			(xy 90.206773 -69.513397) (xy 90.259557 -69.49539) (xy 90.3144 -69.48526) (xy 90.370134 -69.483223)
			(xy 90.425571 -69.489323) (xy 90.479528 -69.503429) (xy 90.530857 -69.525241) (xy 90.578463 -69.554295)
			(xy 90.621331 -69.58997) (xy 90.658548 -69.631507) (xy 90.689321 -69.67802) (xy 90.712993 -69.728517)
			(xy 90.729061 -69.781924) (xy 90.737181 -69.8371) (xy 90.73769 -69.864986) (xy 90.737181 -69.892872)
			(xy 90.736239 -69.899276) (xy 98.795076 -69.899276) (xy 98.799147 -69.843654) (xy 98.811273 -69.789217)
			(xy 98.831196 -69.737126) (xy 98.858492 -69.688491) (xy 98.892578 -69.644348) (xy 98.932727 -69.605639)
			(xy 98.978085 -69.573188) (xy 99.027685 -69.547687) (xy 99.080469 -69.52968) (xy 99.135312 -69.51955)
			(xy 99.191046 -69.517513) (xy 99.246483 -69.523613) (xy 99.30044 -69.537719) (xy 99.351769 -69.559531)
			(xy 99.399375 -69.588585) (xy 99.442243 -69.62426) (xy 99.47946 -69.665797) (xy 99.510233 -69.71231)
			(xy 99.533905 -69.762807) (xy 99.549973 -69.816214) (xy 99.558093 -69.87139) (xy 99.558602 -69.899276)
			(xy 99.558093 -69.927162) (xy 99.549973 -69.982338) (xy 99.533905 -70.035745) (xy 99.510233 -70.086242)
			(xy 99.47946 -70.132755) (xy 99.442243 -70.174292) (xy 99.399375 -70.209967) (xy 99.351769 -70.239021)
			(xy 99.30044 -70.260833) (xy 99.246483 -70.274939) (xy 99.191046 -70.281039) (xy 99.135312 -70.279002)
			(xy 99.080469 -70.268872) (xy 99.027685 -70.250865) (xy 98.978085 -70.225364) (xy 98.932727 -70.192913)
			(xy 98.892578 -70.154204) (xy 98.858492 -70.110061) (xy 98.831196 -70.061426) (xy 98.811273 -70.009335)
			(xy 98.799147 -69.954898) (xy 98.795076 -69.899276) (xy 90.736239 -69.899276) (xy 90.729061 -69.948048)
			(xy 90.712993 -70.001455) (xy 90.689321 -70.051952) (xy 90.658548 -70.098465) (xy 90.621331 -70.140002)
			(xy 90.578463 -70.175677) (xy 90.530857 -70.204731) (xy 90.479528 -70.226543) (xy 90.425571 -70.240649)
			(xy 90.370134 -70.246749) (xy 90.3144 -70.244712) (xy 90.259557 -70.234582) (xy 90.206773 -70.216575)
			(xy 90.157173 -70.191074) (xy 90.111815 -70.158623) (xy 90.071666 -70.119914) (xy 90.03758 -70.075771)
			(xy 90.010284 -70.027136) (xy 89.990361 -69.975045) (xy 89.978235 -69.920608) (xy 89.974164 -69.864986)
			(xy 70.082918 -69.864986) (xy 69.664072 -70.283832) (xy 88.435686 -70.283832) (xy 88.439757 -70.22821)
			(xy 88.451883 -70.173773) (xy 88.471806 -70.121682) (xy 88.499102 -70.073047) (xy 88.533188 -70.028904)
			(xy 88.573337 -69.990195) (xy 88.618695 -69.957744) (xy 88.668295 -69.932243) (xy 88.721079 -69.914236)
			(xy 88.775922 -69.904106) (xy 88.831656 -69.902069) (xy 88.887093 -69.908169) (xy 88.94105 -69.922275)
			(xy 88.992379 -69.944087) (xy 89.039985 -69.973141) (xy 89.082853 -70.008816) (xy 89.12007 -70.050353)
			(xy 89.150843 -70.096866) (xy 89.174515 -70.147363) (xy 89.190583 -70.20077) (xy 89.198703 -70.255946)
			(xy 89.199212 -70.283832) (xy 89.198703 -70.311718) (xy 89.190583 -70.366894) (xy 89.174515 -70.420301)
			(xy 89.150843 -70.470798) (xy 89.12007 -70.517311) (xy 89.082853 -70.558848) (xy 89.039985 -70.594523)
			(xy 88.992379 -70.623577) (xy 88.94105 -70.645389) (xy 88.887093 -70.659495) (xy 88.831656 -70.665595)
			(xy 88.775922 -70.663558) (xy 88.721079 -70.653428) (xy 88.668295 -70.635421) (xy 88.618695 -70.60992)
			(xy 88.573337 -70.577469) (xy 88.533188 -70.53876) (xy 88.499102 -70.494617) (xy 88.471806 -70.445982)
			(xy 88.451883 -70.393891) (xy 88.439757 -70.339454) (xy 88.435686 -70.283832) (xy 69.664072 -70.283832)
			(xy 68.70665 -71.241254) (xy 97.805935 -71.241254) (xy 97.805935 -71.186746) (xy 97.813692 -71.132792)
			(xy 97.829049 -71.080491) (xy 97.851693 -71.030908) (xy 97.881163 -70.985052) (xy 97.916859 -70.943857)
			(xy 97.958054 -70.908162) (xy 98.00391 -70.878692) (xy 98.053493 -70.856049) (xy 98.105794 -70.840692)
			(xy 98.159748 -70.832935) (xy 98.187002 -70.832472) (xy 98.216944 -70.833054) (xy 98.27609 -70.842423)
			(xy 98.333048 -70.860915) (xy 98.386418 -70.888077) (xy 98.43489 -70.92324) (xy 98.456496 -70.943978)
			(xy 98.464624 -70.952106) (xy 98.48596 -70.959726) (xy 98.587306 -70.949312) (xy 98.60661 -70.937628)
			(xy 98.61296 -70.927976) (xy 98.630602 -70.901964) (xy 98.671377 -70.854129) (xy 98.717737 -70.811685)
			(xy 98.768975 -70.775279) (xy 98.82431 -70.745465) (xy 98.882897 -70.7227) (xy 98.943844 -70.707329)
			(xy 99.00622 -70.699588) (xy 99.037648 -70.699122) (xy 99.068381 -70.699511) (xy 99.129399 -70.706925)
			(xy 99.189078 -70.72164) (xy 99.246548 -70.743442) (xy 99.300972 -70.772011) (xy 99.351555 -70.806932)
			(xy 99.39756 -70.847695) (xy 99.438316 -70.893707) (xy 99.473229 -70.944295) (xy 99.50179 -70.998723)
			(xy 99.523583 -71.056197) (xy 99.538289 -71.115878) (xy 99.545694 -71.176897) (xy 99.546156 -71.20763)
			(xy 99.545714 -71.237729) (xy 99.538609 -71.297506) (xy 99.524492 -71.356025) (xy 99.503559 -71.412467)
			(xy 99.476105 -71.466039) (xy 99.442513 -71.515993) (xy 99.42322 -71.5391) (xy 99.415807 -71.548813)
			(xy 99.410239 -71.572567) (xy 99.412552 -71.584566) (xy 99.436428 -71.67753) (xy 99.45243 -71.695564)
			(xy 99.464368 -71.700136) (xy 99.492925 -71.711473) (xy 99.547309 -71.740068) (xy 99.597853 -71.775006)
			(xy 99.64382 -71.815778) (xy 99.684541 -71.86179) (xy 99.719423 -71.912372) (xy 99.747958 -71.966788)
			(xy 99.76973 -72.024245) (xy 99.784422 -72.083906) (xy 99.791821 -72.144902) (xy 99.792282 -72.175624)
			(xy 99.79178 -72.207585) (xy 99.783769 -72.271003) (xy 99.767872 -72.332917) (xy 99.74434 -72.39235)
			(xy 99.713546 -72.448365) (xy 99.675973 -72.50008) (xy 99.632216 -72.546677) (xy 99.582963 -72.587422)
			(xy 99.528992 -72.621673) (xy 99.471153 -72.64889) (xy 99.41036 -72.668643) (xy 99.34757 -72.680621)
			(xy 99.283774 -72.684635) (xy 99.219978 -72.680621) (xy 99.157188 -72.668643) (xy 99.096395 -72.64889)
			(xy 99.038556 -72.621673) (xy 98.984585 -72.587422) (xy 98.935332 -72.546677) (xy 98.891575 -72.50008)
			(xy 98.854002 -72.448365) (xy 98.823208 -72.39235) (xy 98.799676 -72.332917) (xy 98.783779 -72.271003)
			(xy 98.775768 -72.207585) (xy 98.775266 -72.175624) (xy 98.775735 -72.145526) (xy 98.782833 -72.085749)
			(xy 98.796945 -72.027231) (xy 98.817873 -71.970789) (xy 98.845323 -71.917216) (xy 98.878911 -71.867262)
			(xy 98.898202 -71.844154) (xy 98.905585 -71.834422) (xy 98.91117 -71.810683) (xy 98.90887 -71.798688)
			(xy 98.888296 -71.71817) (xy 98.884607 -71.706449) (xy 98.86827 -71.68814) (xy 98.857054 -71.683118)
			(xy 98.828193 -71.671654) (xy 98.773268 -71.64267) (xy 98.722284 -71.607209) (xy 98.676001 -71.5658)
			(xy 98.635109 -71.51906) (xy 98.617278 -71.493634) (xy 98.617024 -71.49338) (xy 98.610207 -71.484563)
			(xy 98.590974 -71.473358) (xy 98.57994 -71.47179) (xy 98.490024 -71.463662) (xy 98.468434 -71.47179)
			(xy 98.46056 -71.479918) (xy 98.442539 -71.497863) (xy 98.402554 -71.529291) (xy 98.358749 -71.55513)
			(xy 98.3119 -71.57492) (xy 98.262838 -71.588312) (xy 98.212431 -71.595068) (xy 98.187002 -71.595488)
			(xy 98.159748 -71.595065) (xy 98.105794 -71.587308) (xy 98.053493 -71.571951) (xy 98.00391 -71.549308)
			(xy 97.958054 -71.519838) (xy 97.916859 -71.484143) (xy 97.881163 -71.442948) (xy 97.851693 -71.397092)
			(xy 97.829049 -71.347509) (xy 97.813692 -71.295208) (xy 97.805935 -71.241254) (xy 68.70665 -71.241254)
			(xy 66.814954 -73.13295) (xy 86.505032 -73.13295) (xy 86.509103 -73.077328) (xy 86.521229 -73.022891)
			(xy 86.541152 -72.9708) (xy 86.568448 -72.922165) (xy 86.602534 -72.878022) (xy 86.642683 -72.839313)
			(xy 86.688041 -72.806862) (xy 86.737641 -72.781361) (xy 86.790425 -72.763354) (xy 86.845268 -72.753224)
			(xy 86.901002 -72.751187) (xy 86.956439 -72.757287) (xy 87.010396 -72.771393) (xy 87.061725 -72.793205)
			(xy 87.109331 -72.822259) (xy 87.112442 -72.824848) (xy 88.440512 -72.824848) (xy 88.444583 -72.769226)
			(xy 88.456709 -72.714789) (xy 88.476632 -72.662698) (xy 88.503928 -72.614063) (xy 88.538014 -72.56992)
			(xy 88.578163 -72.531211) (xy 88.623521 -72.49876) (xy 88.673121 -72.473259) (xy 88.725905 -72.455252)
			(xy 88.780748 -72.445122) (xy 88.836482 -72.443085) (xy 88.891919 -72.449185) (xy 88.945876 -72.463291)
			(xy 88.997205 -72.485103) (xy 89.044811 -72.514157) (xy 89.087679 -72.549832) (xy 89.124896 -72.591369)
			(xy 89.155669 -72.637882) (xy 89.179341 -72.688379) (xy 89.195409 -72.741786) (xy 89.203529 -72.796962)
			(xy 89.204038 -72.824848) (xy 89.203529 -72.852734) (xy 89.195409 -72.90791) (xy 89.179341 -72.961317)
			(xy 89.155669 -73.011814) (xy 89.124896 -73.058327) (xy 89.087679 -73.099864) (xy 89.044811 -73.135539)
			(xy 88.997205 -73.164593) (xy 88.945876 -73.186405) (xy 88.891919 -73.200511) (xy 88.836482 -73.206611)
			(xy 88.780748 -73.204574) (xy 88.725905 -73.194444) (xy 88.673121 -73.176437) (xy 88.623521 -73.150936)
			(xy 88.578163 -73.118485) (xy 88.538014 -73.079776) (xy 88.503928 -73.035633) (xy 88.476632 -72.986998)
			(xy 88.456709 -72.934907) (xy 88.444583 -72.88047) (xy 88.440512 -72.824848) (xy 87.112442 -72.824848)
			(xy 87.152199 -72.857934) (xy 87.189416 -72.899471) (xy 87.220189 -72.945984) (xy 87.243861 -72.996481)
			(xy 87.259929 -73.049888) (xy 87.268049 -73.105064) (xy 87.268558 -73.13295) (xy 87.268049 -73.160836)
			(xy 87.259929 -73.216012) (xy 87.243861 -73.269419) (xy 87.220189 -73.319916) (xy 87.202223 -73.347072)
			(xy 90.990418 -73.347072) (xy 90.994489 -73.29145) (xy 91.006615 -73.237013) (xy 91.026538 -73.184922)
			(xy 91.053834 -73.136287) (xy 91.08792 -73.092144) (xy 91.128069 -73.053435) (xy 91.173427 -73.020984)
			(xy 91.223027 -72.995483) (xy 91.275811 -72.977476) (xy 91.330654 -72.967346) (xy 91.386388 -72.965309)
			(xy 91.441825 -72.971409) (xy 91.495782 -72.985515) (xy 91.547111 -73.007327) (xy 91.594717 -73.036381)
			(xy 91.637585 -73.072056) (xy 91.674802 -73.113593) (xy 91.705575 -73.160106) (xy 91.729247 -73.210603)
			(xy 91.745315 -73.26401) (xy 91.753435 -73.319186) (xy 91.753944 -73.347072) (xy 91.753435 -73.374958)
			(xy 91.745315 -73.430134) (xy 91.729247 -73.483541) (xy 91.705575 -73.534038) (xy 91.674802 -73.580551)
			(xy 91.637585 -73.622088) (xy 91.594717 -73.657763) (xy 91.547111 -73.686817) (xy 91.495782 -73.708629)
			(xy 91.441825 -73.722735) (xy 91.386388 -73.728835) (xy 91.330654 -73.726798) (xy 91.275811 -73.716668)
			(xy 91.223027 -73.698661) (xy 91.173427 -73.67316) (xy 91.128069 -73.640709) (xy 91.08792 -73.602)
			(xy 91.053834 -73.557857) (xy 91.026538 -73.509222) (xy 91.006615 -73.457131) (xy 90.994489 -73.402694)
			(xy 90.990418 -73.347072) (xy 87.202223 -73.347072) (xy 87.189416 -73.366429) (xy 87.152199 -73.407966)
			(xy 87.109331 -73.443641) (xy 87.061725 -73.472695) (xy 87.010396 -73.494507) (xy 86.956439 -73.508613)
			(xy 86.901002 -73.514713) (xy 86.845268 -73.512676) (xy 86.790425 -73.502546) (xy 86.737641 -73.484539)
			(xy 86.688041 -73.459038) (xy 86.642683 -73.426587) (xy 86.602534 -73.387878) (xy 86.568448 -73.343735)
			(xy 86.541152 -73.2951) (xy 86.521229 -73.243009) (xy 86.509103 -73.188572) (xy 86.505032 -73.13295)
			(xy 66.814954 -73.13295) (xy 65.264284 -74.68362) (xy 91.167964 -74.68362) (xy 91.172035 -74.627998)
			(xy 91.184161 -74.573561) (xy 91.204084 -74.52147) (xy 91.23138 -74.472835) (xy 91.265466 -74.428692)
			(xy 91.305615 -74.389983) (xy 91.350973 -74.357532) (xy 91.400573 -74.332031) (xy 91.453357 -74.314024)
			(xy 91.5082 -74.303894) (xy 91.563934 -74.301857) (xy 91.619371 -74.307957) (xy 91.673328 -74.322063)
			(xy 91.724657 -74.343875) (xy 91.772263 -74.372929) (xy 91.815131 -74.408604) (xy 91.852348 -74.450141)
			(xy 91.883121 -74.496654) (xy 91.906793 -74.547151) (xy 91.922861 -74.600558) (xy 91.930981 -74.655734)
			(xy 91.93149 -74.68362) (xy 91.930981 -74.711506) (xy 91.922861 -74.766682) (xy 91.906793 -74.820089)
			(xy 91.883121 -74.870586) (xy 91.852348 -74.917099) (xy 91.815131 -74.958636) (xy 91.772263 -74.994311)
			(xy 91.724657 -75.023365) (xy 91.673328 -75.045177) (xy 91.619371 -75.059283) (xy 91.563934 -75.065383)
			(xy 91.5082 -75.063346) (xy 91.453357 -75.053216) (xy 91.400573 -75.035209) (xy 91.350973 -75.009708)
			(xy 91.305615 -74.977257) (xy 91.265466 -74.938548) (xy 91.23138 -74.894405) (xy 91.204084 -74.84577)
			(xy 91.184161 -74.793679) (xy 91.172035 -74.739242) (xy 91.167964 -74.68362) (xy 65.264284 -74.68362)
			(xy 64.292734 -75.65517) (xy 89.99931 -75.65517) (xy 90.003381 -75.599548) (xy 90.015507 -75.545111)
			(xy 90.03543 -75.49302) (xy 90.062726 -75.444385) (xy 90.096812 -75.400242) (xy 90.136961 -75.361533)
			(xy 90.182319 -75.329082) (xy 90.231919 -75.303581) (xy 90.284703 -75.285574) (xy 90.339546 -75.275444)
			(xy 90.39528 -75.273407) (xy 90.450717 -75.279507) (xy 90.504674 -75.293613) (xy 90.556003 -75.315425)
			(xy 90.603609 -75.344479) (xy 90.646477 -75.380154) (xy 90.683694 -75.421691) (xy 90.714467 -75.468204)
			(xy 90.738139 -75.518701) (xy 90.754207 -75.572108) (xy 90.762327 -75.627284) (xy 90.762836 -75.65517)
			(xy 90.762327 -75.683056) (xy 90.754207 -75.738232) (xy 90.738139 -75.791639) (xy 90.714467 -75.842136)
			(xy 90.684065 -75.888088) (xy 95.934782 -75.888088) (xy 95.938853 -75.832466) (xy 95.950979 -75.778029)
			(xy 95.970902 -75.725938) (xy 95.998198 -75.677303) (xy 96.032284 -75.63316) (xy 96.072433 -75.594451)
			(xy 96.117791 -75.562) (xy 96.167391 -75.536499) (xy 96.220175 -75.518492) (xy 96.275018 -75.508362)
			(xy 96.330752 -75.506325) (xy 96.386189 -75.512425) (xy 96.440146 -75.526531) (xy 96.491475 -75.548343)
			(xy 96.539081 -75.577397) (xy 96.581949 -75.613072) (xy 96.619166 -75.654609) (xy 96.649939 -75.701122)
			(xy 96.673611 -75.751619) (xy 96.689679 -75.805026) (xy 96.697799 -75.860202) (xy 96.698308 -75.888088)
			(xy 96.697799 -75.915974) (xy 96.689679 -75.97115) (xy 96.673611 -76.024557) (xy 96.649939 -76.075054)
			(xy 96.619166 -76.121567) (xy 96.581949 -76.163104) (xy 96.539081 -76.198779) (xy 96.491475 -76.227833)
			(xy 96.440146 -76.249645) (xy 96.386189 -76.263751) (xy 96.330752 -76.269851) (xy 96.275018 -76.267814)
			(xy 96.220175 -76.257684) (xy 96.167391 -76.239677) (xy 96.117791 -76.214176) (xy 96.072433 -76.181725)
			(xy 96.032284 -76.143016) (xy 95.998198 -76.098873) (xy 95.970902 -76.050238) (xy 95.950979 -75.998147)
			(xy 95.938853 -75.94371) (xy 95.934782 -75.888088) (xy 90.684065 -75.888088) (xy 90.683694 -75.888649)
			(xy 90.646477 -75.930186) (xy 90.603609 -75.965861) (xy 90.556003 -75.994915) (xy 90.504674 -76.016727)
			(xy 90.450717 -76.030833) (xy 90.39528 -76.036933) (xy 90.339546 -76.034896) (xy 90.284703 -76.024766)
			(xy 90.231919 -76.006759) (xy 90.182319 -75.981258) (xy 90.136961 -75.948807) (xy 90.096812 -75.910098)
			(xy 90.062726 -75.865955) (xy 90.03543 -75.81732) (xy 90.015507 -75.765229) (xy 90.003381 -75.710792)
			(xy 89.99931 -75.65517) (xy 64.292734 -75.65517) (xy 48.287704 -91.6602) (xy 58.777886 -91.6602)
			(xy 58.7819 -91.596404) (xy 58.793878 -91.533613) (xy 58.813631 -91.472819) (xy 58.840848 -91.41498)
			(xy 58.8751 -91.361009) (xy 58.915846 -91.311756) (xy 58.962443 -91.267998) (xy 59.014158 -91.230425)
			(xy 59.070174 -91.19963) (xy 59.129608 -91.176099) (xy 59.191522 -91.160202) (xy 59.254941 -91.152191)
			(xy 59.286902 -91.15171) (xy 59.317623 -91.152179) (xy 59.378616 -91.159578) (xy 59.438275 -91.17427)
			(xy 59.49573 -91.196039) (xy 59.550146 -91.224569) (xy 59.5757 -91.241626) (xy 59.584385 -91.247019)
			(xy 59.604402 -91.25108) (xy 59.624419 -91.247019) (xy 59.633104 -91.241626) (xy 59.658662 -91.224574)
			(xy 59.713075 -91.196039) (xy 59.770529 -91.174267) (xy 59.830188 -91.159573) (xy 59.891181 -91.152173)
			(xy 59.921902 -91.15171) (xy 59.953864 -91.152176) (xy 60.017284 -91.160188) (xy 60.0792 -91.176086)
			(xy 60.138635 -91.199618) (xy 60.194652 -91.230414) (xy 60.246368 -91.267988) (xy 60.292966 -91.311747)
			(xy 60.333713 -91.361001) (xy 60.367965 -91.414974) (xy 60.395183 -91.472815) (xy 60.414937 -91.53361)
			(xy 60.426915 -91.596402) (xy 60.430929 -91.6602) (xy 60.428917 -91.692179) (xy 60.556896 -91.692179)
			(xy 60.556896 -91.628257) (xy 60.564907 -91.564839) (xy 60.580804 -91.502925) (xy 60.604336 -91.443492)
			(xy 60.63513 -91.387477) (xy 60.672703 -91.335762) (xy 60.71646 -91.289165) (xy 60.765713 -91.24842)
			(xy 60.819684 -91.214169) (xy 60.877523 -91.186952) (xy 60.938316 -91.167199) (xy 61.001106 -91.155221)
			(xy 61.064902 -91.151208) (xy 61.128698 -91.155221) (xy 61.191488 -91.167199) (xy 61.252281 -91.186952)
			(xy 61.31012 -91.214169) (xy 61.364091 -91.24842) (xy 61.413344 -91.289165) (xy 61.457101 -91.335762)
			(xy 61.494674 -91.387477) (xy 61.525468 -91.443492) (xy 61.549 -91.502925) (xy 61.564897 -91.564839)
			(xy 61.572908 -91.628257) (xy 61.57341 -91.660218) (xy 61.572908 -91.692179) (xy 61.564897 -91.755597)
			(xy 61.549 -91.817511) (xy 61.525468 -91.876944) (xy 61.494674 -91.932959) (xy 61.457101 -91.984674)
			(xy 61.413344 -92.031271) (xy 61.364091 -92.072016) (xy 61.31012 -92.106267) (xy 61.252281 -92.133484)
			(xy 61.191488 -92.153237) (xy 61.128698 -92.165215) (xy 61.064902 -92.169229) (xy 61.001106 -92.165215)
			(xy 60.938316 -92.153237) (xy 60.877523 -92.133484) (xy 60.819684 -92.106267) (xy 60.765713 -92.072016)
			(xy 60.71646 -92.031271) (xy 60.672703 -91.984674) (xy 60.63513 -91.932959) (xy 60.604336 -91.876944)
			(xy 60.580804 -91.817511) (xy 60.564907 -91.755597) (xy 60.556896 -91.692179) (xy 60.428917 -91.692179)
			(xy 60.426915 -91.723998) (xy 60.414937 -91.78679) (xy 60.395183 -91.847585) (xy 60.367965 -91.905426)
			(xy 60.333713 -91.959399) (xy 60.292966 -92.008653) (xy 60.246368 -92.052412) (xy 60.194652 -92.089986)
			(xy 60.138635 -92.120782) (xy 60.0792 -92.144314) (xy 60.017284 -92.160212) (xy 59.953864 -92.168224)
			(xy 59.921902 -92.168726) (xy 59.891182 -92.168249) (xy 59.830189 -92.16085) (xy 59.77053 -92.14616)
			(xy 59.713075 -92.124393) (xy 59.658659 -92.095866) (xy 59.633104 -92.07881) (xy 59.624419 -92.073417)
			(xy 59.604402 -92.069356) (xy 59.584385 -92.073417) (xy 59.5757 -92.07881) (xy 59.550144 -92.095865)
			(xy 59.49573 -92.124398) (xy 59.438275 -92.14617) (xy 59.378617 -92.160863) (xy 59.317623 -92.168263)
			(xy 59.286902 -92.168726) (xy 59.254941 -92.168209) (xy 59.191522 -92.160198) (xy 59.129608 -92.144301)
			(xy 59.070174 -92.12077) (xy 59.014158 -92.089975) (xy 58.962443 -92.052402) (xy 58.915846 -92.008644)
			(xy 58.8751 -91.959391) (xy 58.840848 -91.90542) (xy 58.813631 -91.847581) (xy 58.793878 -91.786787)
			(xy 58.7819 -91.723996) (xy 58.777886 -91.6602) (xy 48.287704 -91.6602) (xy 41.307836 -98.640068)
			(xy 45.819056 -98.640068) (xy 45.819056 -98.555372) (xy 45.827107 -98.471058) (xy 45.843136 -98.387892)
			(xy 45.866997 -98.306625) (xy 45.898476 -98.227995) (xy 45.937287 -98.152714) (xy 45.983077 -98.081462)
			(xy 46.035433 -98.014886) (xy 46.093881 -97.953588) (xy 46.157891 -97.898123) (xy 46.226883 -97.848994)
			(xy 46.300233 -97.806645) (xy 46.377276 -97.771461) (xy 46.457315 -97.743759) (xy 46.539624 -97.723791)
			(xy 46.623459 -97.711738) (xy 46.70806 -97.707708) (xy 46.792661 -97.711738) (xy 46.876496 -97.723791)
			(xy 46.958805 -97.743759) (xy 47.038844 -97.771461) (xy 47.115887 -97.806645) (xy 47.189237 -97.848994)
			(xy 47.258229 -97.898123) (xy 47.322239 -97.953588) (xy 47.380687 -98.014886) (xy 47.433043 -98.081462)
			(xy 47.478833 -98.152714) (xy 47.517644 -98.227995) (xy 47.549123 -98.306625) (xy 47.572984 -98.387892)
			(xy 47.589013 -98.471058) (xy 47.597064 -98.555372) (xy 47.597568 -98.59772) (xy 47.728122 -98.59772)
			(xy 47.732193 -98.542098) (xy 47.744319 -98.487661) (xy 47.764242 -98.43557) (xy 47.791538 -98.386935)
			(xy 47.825624 -98.342792) (xy 47.865773 -98.304083) (xy 47.911131 -98.271632) (xy 47.960731 -98.246131)
			(xy 48.013515 -98.228124) (xy 48.068358 -98.217994) (xy 48.124092 -98.215957) (xy 48.179529 -98.222057)
			(xy 48.233486 -98.236163) (xy 48.284815 -98.257975) (xy 48.332421 -98.287029) (xy 48.375289 -98.322704)
			(xy 48.412506 -98.364241) (xy 48.443279 -98.410754) (xy 48.466951 -98.461251) (xy 48.483019 -98.514658)
			(xy 48.491139 -98.569834) (xy 48.491648 -98.59772) (xy 48.491139 -98.625606) (xy 48.483019 -98.680782)
			(xy 48.466951 -98.734189) (xy 48.443279 -98.784686) (xy 48.412506 -98.831199) (xy 48.375289 -98.872736)
			(xy 48.332421 -98.908411) (xy 48.284815 -98.937465) (xy 48.233486 -98.959277) (xy 48.179529 -98.973383)
			(xy 48.124092 -98.979483) (xy 48.068358 -98.977446) (xy 48.013515 -98.967316) (xy 47.960731 -98.949309)
			(xy 47.911131 -98.923808) (xy 47.865773 -98.891357) (xy 47.825624 -98.852648) (xy 47.791538 -98.808505)
			(xy 47.764242 -98.75987) (xy 47.744319 -98.707779) (xy 47.732193 -98.653342) (xy 47.728122 -98.59772)
			(xy 47.597568 -98.59772) (xy 47.597064 -98.640068) (xy 47.589013 -98.724382) (xy 47.572984 -98.807548)
			(xy 47.549123 -98.888815) (xy 47.517644 -98.967445) (xy 47.478833 -99.042726) (xy 47.433043 -99.113978)
			(xy 47.380687 -99.180554) (xy 47.322239 -99.241852) (xy 47.258229 -99.297317) (xy 47.189237 -99.346446)
			(xy 47.115887 -99.388795) (xy 47.038844 -99.423979) (xy 46.958805 -99.451681) (xy 46.876496 -99.471649)
			(xy 46.792661 -99.483702) (xy 46.70806 -99.487733) (xy 46.623459 -99.483702) (xy 46.539624 -99.471649)
			(xy 46.457315 -99.451681) (xy 46.377276 -99.423979) (xy 46.300233 -99.388795) (xy 46.226883 -99.346446)
			(xy 46.157891 -99.297317) (xy 46.093881 -99.241852) (xy 46.035433 -99.180554) (xy 45.983077 -99.113978)
			(xy 45.937287 -99.042726) (xy 45.898476 -98.967445) (xy 45.866997 -98.888815) (xy 45.843136 -98.807548)
			(xy 45.827107 -98.724382) (xy 45.819056 -98.640068) (xy 41.307836 -98.640068) (xy 39.095723 -100.852181)
			(xy 40.850814 -100.852181) (xy 40.850814 -100.788259) (xy 40.858825 -100.724841) (xy 40.874722 -100.662927)
			(xy 40.898254 -100.603494) (xy 40.929048 -100.547479) (xy 40.966621 -100.495764) (xy 41.010378 -100.449167)
			(xy 41.059631 -100.408422) (xy 41.113602 -100.374171) (xy 41.171441 -100.346954) (xy 41.232234 -100.327201)
			(xy 41.295024 -100.315223) (xy 41.35882 -100.31121) (xy 41.422616 -100.315223) (xy 41.485406 -100.327201)
			(xy 41.546199 -100.346954) (xy 41.604038 -100.374171) (xy 41.617175 -100.382508) (xy 43.388276 -100.382508)
			(xy 43.388276 -100.297812) (xy 43.396327 -100.213498) (xy 43.412356 -100.130332) (xy 43.436217 -100.049065)
			(xy 43.467696 -99.970435) (xy 43.506507 -99.895154) (xy 43.552297 -99.823902) (xy 43.604653 -99.757326)
			(xy 43.663101 -99.696028) (xy 43.727111 -99.640563) (xy 43.796103 -99.591434) (xy 43.869453 -99.549085)
			(xy 43.946496 -99.513901) (xy 44.026535 -99.486199) (xy 44.108844 -99.466231) (xy 44.192679 -99.454178)
			(xy 44.27728 -99.450148) (xy 44.361881 -99.454178) (xy 44.445716 -99.466231) (xy 44.528025 -99.486199)
			(xy 44.608064 -99.513901) (xy 44.685107 -99.549085) (xy 44.758457 -99.591434) (xy 44.827449 -99.640563)
			(xy 44.891459 -99.696028) (xy 44.949907 -99.757326) (xy 45.002263 -99.823902) (xy 45.048053 -99.895154)
			(xy 45.086864 -99.970435) (xy 45.118343 -100.049065) (xy 45.142204 -100.130332) (xy 45.158233 -100.213498)
			(xy 45.166284 -100.297812) (xy 45.166788 -100.34016) (xy 45.166284 -100.382508) (xy 45.158233 -100.466822)
			(xy 45.142204 -100.549988) (xy 45.118343 -100.631255) (xy 45.086864 -100.709885) (xy 45.048053 -100.785166)
			(xy 45.037632 -100.801381) (xy 47.571654 -100.801381) (xy 47.571654 -100.737459) (xy 47.579665 -100.674041)
			(xy 47.595562 -100.612127) (xy 47.619094 -100.552694) (xy 47.649888 -100.496679) (xy 47.687461 -100.444964)
			(xy 47.731218 -100.398367) (xy 47.780471 -100.357622) (xy 47.834442 -100.323371) (xy 47.892281 -100.296154)
			(xy 47.953074 -100.276401) (xy 48.015864 -100.264423) (xy 48.07966 -100.26041) (xy 48.143456 -100.264423)
			(xy 48.206246 -100.276401) (xy 48.267039 -100.296154) (xy 48.324878 -100.323371) (xy 48.378849 -100.357622)
			(xy 48.428102 -100.398367) (xy 48.471859 -100.444964) (xy 48.509432 -100.496679) (xy 48.540226 -100.552694)
			(xy 48.563758 -100.612127) (xy 48.579655 -100.674041) (xy 48.587666 -100.737459) (xy 48.588168 -100.76942)
			(xy 48.587666 -100.801381) (xy 48.579655 -100.864799) (xy 48.563758 -100.926713) (xy 48.540226 -100.986146)
			(xy 48.509432 -101.042161) (xy 48.471859 -101.093876) (xy 48.428102 -101.140473) (xy 48.378849 -101.181218)
			(xy 48.324878 -101.215469) (xy 48.267039 -101.242686) (xy 48.206246 -101.262439) (xy 48.143456 -101.274417)
			(xy 48.07966 -101.278431) (xy 48.015864 -101.274417) (xy 47.953074 -101.262439) (xy 47.892281 -101.242686)
			(xy 47.834442 -101.215469) (xy 47.780471 -101.181218) (xy 47.731218 -101.140473) (xy 47.687461 -101.093876)
			(xy 47.649888 -101.042161) (xy 47.619094 -100.986146) (xy 47.595562 -100.926713) (xy 47.579665 -100.864799)
			(xy 47.571654 -100.801381) (xy 45.037632 -100.801381) (xy 45.002263 -100.856418) (xy 44.949907 -100.922994)
			(xy 44.891459 -100.984292) (xy 44.827449 -101.039757) (xy 44.758457 -101.088886) (xy 44.685107 -101.131235)
			(xy 44.608064 -101.166419) (xy 44.528025 -101.194121) (xy 44.445716 -101.214089) (xy 44.361881 -101.226142)
			(xy 44.27728 -101.230173) (xy 44.192679 -101.226142) (xy 44.108844 -101.214089) (xy 44.026535 -101.194121)
			(xy 43.946496 -101.166419) (xy 43.869453 -101.131235) (xy 43.796103 -101.088886) (xy 43.727111 -101.039757)
			(xy 43.663101 -100.984292) (xy 43.604653 -100.922994) (xy 43.552297 -100.856418) (xy 43.506507 -100.785166)
			(xy 43.467696 -100.709885) (xy 43.436217 -100.631255) (xy 43.412356 -100.549988) (xy 43.396327 -100.466822)
			(xy 43.388276 -100.382508) (xy 41.617175 -100.382508) (xy 41.658009 -100.408422) (xy 41.707262 -100.449167)
			(xy 41.751019 -100.495764) (xy 41.788592 -100.547479) (xy 41.819386 -100.603494) (xy 41.842918 -100.662927)
			(xy 41.858815 -100.724841) (xy 41.866826 -100.788259) (xy 41.867328 -100.82022) (xy 41.866826 -100.852181)
			(xy 41.858815 -100.915599) (xy 41.842918 -100.977513) (xy 41.819386 -101.036946) (xy 41.788592 -101.092961)
			(xy 41.751019 -101.144676) (xy 41.707262 -101.191273) (xy 41.658009 -101.232018) (xy 41.604038 -101.266269)
			(xy 41.546199 -101.293486) (xy 41.485406 -101.313239) (xy 41.422616 -101.325217) (xy 41.35882 -101.329231)
			(xy 41.295024 -101.325217) (xy 41.232234 -101.313239) (xy 41.171441 -101.293486) (xy 41.113602 -101.266269)
			(xy 41.059631 -101.232018) (xy 41.010378 -101.191273) (xy 40.966621 -101.144676) (xy 40.929048 -101.092961)
			(xy 40.898254 -101.036946) (xy 40.874722 -100.977513) (xy 40.858825 -100.915599) (xy 40.850814 -100.852181)
			(xy 39.095723 -100.852181) (xy 38.205664 -101.74224) (xy 43.803822 -101.74224) (xy 43.807893 -101.686618)
			(xy 43.820019 -101.632181) (xy 43.839942 -101.58009) (xy 43.867238 -101.531455) (xy 43.901324 -101.487312)
			(xy 43.941473 -101.448603) (xy 43.986831 -101.416152) (xy 44.036431 -101.390651) (xy 44.089215 -101.372644)
			(xy 44.144058 -101.362514) (xy 44.199792 -101.360477) (xy 44.255229 -101.366577) (xy 44.309186 -101.380683)
			(xy 44.360515 -101.402495) (xy 44.408121 -101.431549) (xy 44.450989 -101.467224) (xy 44.488206 -101.508761)
			(xy 44.518979 -101.555274) (xy 44.542651 -101.605771) (xy 44.558719 -101.659178) (xy 44.566839 -101.714354)
			(xy 44.567348 -101.74224) (xy 44.566839 -101.770126) (xy 44.558719 -101.825302) (xy 44.542651 -101.878709)
			(xy 44.518979 -101.929206) (xy 44.488206 -101.975719) (xy 44.450989 -102.017256) (xy 44.408121 -102.052931)
			(xy 44.360515 -102.081985) (xy 44.309186 -102.103797) (xy 44.255229 -102.117903) (xy 44.199792 -102.124003)
			(xy 44.144058 -102.121966) (xy 44.089215 -102.111836) (xy 44.036431 -102.093829) (xy 43.986831 -102.068328)
			(xy 43.941473 -102.035877) (xy 43.901324 -101.997168) (xy 43.867238 -101.953025) (xy 43.839942 -101.90439)
			(xy 43.820019 -101.852299) (xy 43.807893 -101.797862) (xy 43.803822 -101.74224) (xy 38.205664 -101.74224)
			(xy 34.301684 -105.64622) (xy 42.521632 -105.64622) (xy 42.522172 -105.617167) (xy 42.530968 -105.55973)
			(xy 42.548376 -105.504292) (xy 42.573993 -105.452137) (xy 42.607225 -105.404471) (xy 42.647303 -105.362399)
			(xy 42.669968 -105.344214) (xy 42.678796 -105.336762) (xy 42.689122 -105.316124) (xy 42.68978 -105.30459)
			(xy 42.69105 -105.21315) (xy 42.681398 -105.192322) (xy 42.672254 -105.184956) (xy 42.650727 -105.166724)
			(xy 42.612717 -105.125041) (xy 42.581264 -105.078213) (xy 42.557052 -105.027262) (xy 42.540612 -104.973301)
			(xy 42.532301 -104.917505) (xy 42.531792 -104.8893) (xy 42.532278 -104.862049) (xy 42.540034 -104.808101)
			(xy 42.555389 -104.755806) (xy 42.578031 -104.706229) (xy 42.607497 -104.660379) (xy 42.643188 -104.619188)
			(xy 42.684379 -104.583497) (xy 42.730229 -104.554031) (xy 42.779806 -104.531389) (xy 42.832101 -104.516034)
			(xy 42.886049 -104.508278) (xy 42.940551 -104.508278) (xy 42.994499 -104.516034) (xy 43.046794 -104.531389)
			(xy 43.096371 -104.554031) (xy 43.142221 -104.583497) (xy 43.183412 -104.619188) (xy 43.219103 -104.660379)
			(xy 43.248569 -104.706229) (xy 43.271211 -104.755806) (xy 43.286566 -104.808101) (xy 43.294322 -104.862049)
			(xy 43.294808 -104.8893) (xy 43.294267 -104.918353) (xy 43.285468 -104.975789) (xy 43.26806 -105.031226)
			(xy 43.242443 -105.083381) (xy 43.209212 -105.131047) (xy 43.169136 -105.17312) (xy 43.146472 -105.191306)
			(xy 43.137624 -105.198738) (xy 43.127312 -105.219392) (xy 43.12666 -105.23093) (xy 43.12539 -105.32237)
			(xy 43.135042 -105.343198) (xy 43.144186 -105.350564) (xy 43.164665 -105.367794) (xy 43.201033 -105.407057)
			(xy 43.231542 -105.451028) (xy 43.255593 -105.498838) (xy 43.264582 -105.524046) (xy 43.264582 -105.5243)
			(xy 43.267757 -105.532533) (xy 43.2788 -105.546281) (xy 43.293861 -105.555454) (xy 43.302428 -105.557574)
			(xy 43.388026 -105.575608) (xy 43.39676 -105.57702) (xy 43.414257 -105.574515) (xy 43.429846 -105.566183)
			(xy 43.436032 -105.55986) (xy 43.454171 -105.540522) (xy 43.494921 -105.5066) (xy 43.539975 -105.478646)
			(xy 43.588465 -105.457199) (xy 43.639457 -105.44267) (xy 43.691969 -105.435341) (xy 43.71848 -105.434892)
			(xy 43.745734 -105.435354) (xy 43.799687 -105.443109) (xy 43.851987 -105.458463) (xy 43.90157 -105.481104)
			(xy 43.945072 -105.50906) (xy 49.323752 -105.50906) (xy 49.324313 -105.480007) (xy 49.333104 -105.422571)
			(xy 49.350507 -105.367134) (xy 49.37612 -105.314978) (xy 49.409348 -105.267312) (xy 49.449424 -105.225239)
			(xy 49.472088 -105.207054) (xy 49.480901 -105.199587) (xy 49.491234 -105.17896) (xy 49.4919 -105.16743)
			(xy 49.49317 -105.07599) (xy 49.483518 -105.055162) (xy 49.474374 -105.047796) (xy 49.452822 -105.029592)
			(xy 49.414813 -104.987904) (xy 49.383362 -104.94107) (xy 49.359155 -104.890114) (xy 49.34272 -104.836147)
			(xy 49.334416 -104.780347) (xy 49.333912 -104.75214) (xy 49.334398 -104.724889) (xy 49.342154 -104.670941)
			(xy 49.357509 -104.618646) (xy 49.380151 -104.569069) (xy 49.409617 -104.523219) (xy 49.445308 -104.482028)
			(xy 49.486499 -104.446337) (xy 49.532349 -104.416871) (xy 49.581926 -104.394229) (xy 49.634221 -104.378874)
			(xy 49.688169 -104.371118) (xy 49.742671 -104.371118) (xy 49.796619 -104.378874) (xy 49.848914 -104.394229)
			(xy 49.898491 -104.416871) (xy 49.944341 -104.446337) (xy 49.985532 -104.482028) (xy 50.021223 -104.523219)
			(xy 50.050689 -104.569069) (xy 50.073331 -104.618646) (xy 50.088686 -104.670941) (xy 50.096442 -104.724889)
			(xy 50.096928 -104.75214) (xy 50.096375 -104.781193) (xy 50.087583 -104.83863) (xy 50.070179 -104.894068)
			(xy 50.044565 -104.946224) (xy 50.011335 -104.993889) (xy 49.971257 -105.035962) (xy 49.948592 -105.054146)
			(xy 49.939775 -105.061609) (xy 49.929445 -105.082239) (xy 49.92878 -105.09377) (xy 49.92751 -105.18521)
			(xy 49.937162 -105.206038) (xy 49.946306 -105.213404) (xy 49.967854 -105.231613) (xy 50.005864 -105.273299)
			(xy 50.037316 -105.320132) (xy 50.061524 -105.371087) (xy 50.07796 -105.425054) (xy 50.086264 -105.480853)
			(xy 50.086768 -105.50906) (xy 50.086282 -105.536311) (xy 50.078526 -105.590259) (xy 50.063171 -105.642554)
			(xy 50.040529 -105.692131) (xy 50.011063 -105.737981) (xy 49.975372 -105.779172) (xy 49.934181 -105.814863)
			(xy 49.888331 -105.844329) (xy 49.838754 -105.866971) (xy 49.786459 -105.882326) (xy 49.732511 -105.890082)
			(xy 49.678009 -105.890082) (xy 49.624061 -105.882326) (xy 49.571766 -105.866971) (xy 49.522189 -105.844329)
			(xy 49.476339 -105.814863) (xy 49.435148 -105.779172) (xy 49.399457 -105.737981) (xy 49.369991 -105.692131)
			(xy 49.347349 -105.642554) (xy 49.331994 -105.590259) (xy 49.324238 -105.536311) (xy 49.323752 -105.50906)
			(xy 43.945072 -105.50906) (xy 43.947425 -105.510572) (xy 43.98862 -105.546265) (xy 44.024316 -105.587459)
			(xy 44.053786 -105.633313) (xy 44.07643 -105.682894) (xy 44.091787 -105.735194) (xy 44.099545 -105.789146)
			(xy 44.099545 -105.843654) (xy 44.091787 -105.897606) (xy 44.07643 -105.949906) (xy 44.053786 -105.999487)
			(xy 44.024316 -106.045341) (xy 43.98862 -106.086535) (xy 43.947425 -106.122228) (xy 43.90157 -106.151696)
			(xy 43.851987 -106.174337) (xy 43.799687 -106.189691) (xy 43.745734 -106.197446) (xy 43.71848 -106.197908)
			(xy 43.692085 -106.197414) (xy 43.639798 -106.190146) (xy 43.589013 -106.175737) (xy 43.5407 -106.154464)
			(xy 43.495782 -106.126731) (xy 43.455117 -106.09307) (xy 43.419482 -106.054123) (xy 43.389558 -106.010634)
			(xy 43.365916 -105.963435) (xy 43.357038 -105.938574) (xy 43.357038 -105.93832) (xy 43.353842 -105.930097)
			(xy 43.342808 -105.916347) (xy 43.327755 -105.90717) (xy 43.319192 -105.905046) (xy 43.233594 -105.887012)
			(xy 43.224859 -105.88561) (xy 43.207362 -105.888109) (xy 43.191774 -105.896438) (xy 43.185588 -105.90276)
			(xy 43.167443 -105.922092) (xy 43.126694 -105.956014) (xy 43.081641 -105.983968) (xy 43.033152 -106.005416)
			(xy 42.982162 -106.019946) (xy 42.92965 -106.027277) (xy 42.90314 -106.027728) (xy 42.875889 -106.027208)
			(xy 42.821941 -106.019457) (xy 42.769646 -106.004107) (xy 42.720067 -105.98147) (xy 42.674215 -105.952008)
			(xy 42.633022 -105.91632) (xy 42.597328 -105.875133) (xy 42.567859 -105.829286) (xy 42.545214 -105.779711)
			(xy 42.529856 -105.727418) (xy 42.522097 -105.673471) (xy 42.521632 -105.64622) (xy 34.301684 -105.64622)
			(xy 33.296903 -106.651001) (xy 39.720514 -106.651001) (xy 39.720514 -106.587079) (xy 39.728525 -106.523661)
			(xy 39.744422 -106.461747) (xy 39.767954 -106.402314) (xy 39.798748 -106.346299) (xy 39.836321 -106.294584)
			(xy 39.880078 -106.247987) (xy 39.929331 -106.207242) (xy 39.983302 -106.172991) (xy 40.041141 -106.145774)
			(xy 40.101934 -106.126021) (xy 40.164724 -106.114043) (xy 40.22852 -106.11003) (xy 40.292316 -106.114043)
			(xy 40.355106 -106.126021) (xy 40.415899 -106.145774) (xy 40.473738 -106.172991) (xy 40.527709 -106.207242)
			(xy 40.576962 -106.247987) (xy 40.620719 -106.294584) (xy 40.658292 -106.346299) (xy 40.689086 -106.402314)
			(xy 40.712618 -106.461747) (xy 40.728515 -106.523661) (xy 40.728558 -106.524001) (xy 44.621444 -106.524001)
			(xy 44.621444 -106.460079) (xy 44.629455 -106.396661) (xy 44.645352 -106.334747) (xy 44.668884 -106.275314)
			(xy 44.699678 -106.219299) (xy 44.737251 -106.167584) (xy 44.781008 -106.120987) (xy 44.830261 -106.080242)
			(xy 44.884232 -106.045991) (xy 44.942071 -106.018774) (xy 45.002864 -105.999021) (xy 45.065654 -105.987043)
			(xy 45.12945 -105.98303) (xy 45.193246 -105.987043) (xy 45.256036 -105.999021) (xy 45.316829 -106.018774)
			(xy 45.374668 -106.045991) (xy 45.428639 -106.080242) (xy 45.477892 -106.120987) (xy 45.521649 -106.167584)
			(xy 45.559222 -106.219299) (xy 45.590016 -106.275314) (xy 45.613548 -106.334747) (xy 45.629445 -106.396661)
			(xy 45.637456 -106.460079) (xy 45.637958 -106.49204) (xy 45.637616 -106.513841) (xy 46.522634 -106.513841)
			(xy 46.522634 -106.449919) (xy 46.530645 -106.386501) (xy 46.546542 -106.324587) (xy 46.570074 -106.265154)
			(xy 46.600868 -106.209139) (xy 46.638441 -106.157424) (xy 46.682198 -106.110827) (xy 46.731451 -106.070082)
			(xy 46.785422 -106.035831) (xy 46.843261 -106.008614) (xy 46.904054 -105.988861) (xy 46.966844 -105.976883)
			(xy 47.03064 -105.97287) (xy 47.094436 -105.976883) (xy 47.157226 -105.988861) (xy 47.218019 -106.008614)
			(xy 47.275858 -106.035831) (xy 47.329829 -106.070082) (xy 47.379082 -106.110827) (xy 47.422839 -106.157424)
			(xy 47.460412 -106.209139) (xy 47.491206 -106.265154) (xy 47.514738 -106.324587) (xy 47.530635 -106.386501)
			(xy 47.538646 -106.449919) (xy 47.539148 -106.48188) (xy 47.538646 -106.513841) (xy 47.530635 -106.577259)
			(xy 47.514738 -106.639173) (xy 47.491206 -106.698606) (xy 47.460412 -106.754621) (xy 47.422839 -106.806336)
			(xy 47.379082 -106.852933) (xy 47.329829 -106.893678) (xy 47.275858 -106.927929) (xy 47.218019 -106.955146)
			(xy 47.157226 -106.974899) (xy 47.094436 -106.986877) (xy 47.03064 -106.990891) (xy 46.966844 -106.986877)
			(xy 46.904054 -106.974899) (xy 46.843261 -106.955146) (xy 46.785422 -106.927929) (xy 46.731451 -106.893678)
			(xy 46.682198 -106.852933) (xy 46.638441 -106.806336) (xy 46.600868 -106.754621) (xy 46.570074 -106.698606)
			(xy 46.546542 -106.639173) (xy 46.530645 -106.577259) (xy 46.522634 -106.513841) (xy 45.637616 -106.513841)
			(xy 45.637456 -106.524001) (xy 45.629445 -106.587419) (xy 45.613548 -106.649333) (xy 45.590016 -106.708766)
			(xy 45.559222 -106.764781) (xy 45.521649 -106.816496) (xy 45.477892 -106.863093) (xy 45.428639 -106.903838)
			(xy 45.374668 -106.938089) (xy 45.316829 -106.965306) (xy 45.256036 -106.985059) (xy 45.193246 -106.997037)
			(xy 45.12945 -107.001051) (xy 45.065654 -106.997037) (xy 45.002864 -106.985059) (xy 44.942071 -106.965306)
			(xy 44.884232 -106.938089) (xy 44.830261 -106.903838) (xy 44.781008 -106.863093) (xy 44.737251 -106.816496)
			(xy 44.699678 -106.764781) (xy 44.668884 -106.708766) (xy 44.645352 -106.649333) (xy 44.629455 -106.587419)
			(xy 44.621444 -106.524001) (xy 40.728558 -106.524001) (xy 40.736526 -106.587079) (xy 40.737028 -106.61904)
			(xy 40.736526 -106.651001) (xy 40.728515 -106.714419) (xy 40.712618 -106.776333) (xy 40.689086 -106.835766)
			(xy 40.658292 -106.891781) (xy 40.620719 -106.943496) (xy 40.576962 -106.990093) (xy 40.527709 -107.030838)
			(xy 40.473738 -107.065089) (xy 40.415899 -107.092306) (xy 40.355106 -107.112059) (xy 40.292316 -107.124037)
			(xy 40.22852 -107.128051) (xy 40.164724 -107.124037) (xy 40.101934 -107.112059) (xy 40.041141 -107.092306)
			(xy 39.983302 -107.065089) (xy 39.929331 -107.030838) (xy 39.880078 -106.990093) (xy 39.836321 -106.943496)
			(xy 39.798748 -106.891781) (xy 39.767954 -106.835766) (xy 39.744422 -106.776333) (xy 39.728525 -106.714419)
			(xy 39.720514 -106.651001) (xy 33.296903 -106.651001) (xy 32.255503 -107.692401) (xy 36.944294 -107.692401)
			(xy 36.944294 -107.628479) (xy 36.952305 -107.565061) (xy 36.968202 -107.503147) (xy 36.991734 -107.443714)
			(xy 37.022528 -107.387699) (xy 37.060101 -107.335984) (xy 37.103858 -107.289387) (xy 37.153111 -107.248642)
			(xy 37.207082 -107.214391) (xy 37.264921 -107.187174) (xy 37.325714 -107.167421) (xy 37.388504 -107.155443)
			(xy 37.4523 -107.15143) (xy 37.516096 -107.155443) (xy 37.578886 -107.167421) (xy 37.639679 -107.187174)
			(xy 37.697518 -107.214391) (xy 37.751489 -107.248642) (xy 37.800742 -107.289387) (xy 37.844499 -107.335984)
			(xy 37.882072 -107.387699) (xy 37.912866 -107.443714) (xy 37.936398 -107.503147) (xy 37.952295 -107.565061)
			(xy 37.960306 -107.628479) (xy 37.960808 -107.66044) (xy 37.960306 -107.692401) (xy 37.952295 -107.755819)
			(xy 37.936398 -107.817733) (xy 37.912866 -107.877166) (xy 37.882072 -107.933181) (xy 37.844499 -107.984896)
			(xy 37.800742 -108.031493) (xy 37.751489 -108.072238) (xy 37.697518 -108.106489) (xy 37.639679 -108.133706)
			(xy 37.578886 -108.153459) (xy 37.516096 -108.165437) (xy 37.4523 -108.169451) (xy 37.388504 -108.165437)
			(xy 37.325714 -108.153459) (xy 37.264921 -108.133706) (xy 37.207082 -108.106489) (xy 37.153111 -108.072238)
			(xy 37.103858 -108.031493) (xy 37.060101 -107.984896) (xy 37.022528 -107.933181) (xy 36.991734 -107.877166)
			(xy 36.968202 -107.817733) (xy 36.952305 -107.755819) (xy 36.944294 -107.692401) (xy 32.255503 -107.692401)
			(xy 30.687264 -109.26064) (xy 34.761428 -109.26064) (xy 34.765458 -109.176039) (xy 34.777511 -109.092204)
			(xy 34.797479 -109.009895) (xy 34.825181 -108.929856) (xy 34.860365 -108.852813) (xy 34.902714 -108.779463)
			(xy 34.951843 -108.710471) (xy 35.007308 -108.646461) (xy 35.068606 -108.588013) (xy 35.135182 -108.535657)
			(xy 35.206434 -108.489867) (xy 35.281715 -108.451056) (xy 35.360345 -108.419577) (xy 35.441612 -108.395716)
			(xy 35.524778 -108.379687) (xy 35.609092 -108.371636) (xy 35.65144 -108.371132) (xy 35.694663 -108.371665)
			(xy 35.7807 -108.380045) (xy 35.865519 -108.396734) (xy 35.948319 -108.421572) (xy 36.028318 -108.454326)
			(xy 36.104763 -108.494687) (xy 36.176931 -108.542274) (xy 36.244141 -108.596638) (xy 36.305761 -108.657266)
			(xy 36.361208 -108.723586) (xy 36.386008 -108.75899) (xy 36.391922 -108.766819) (xy 36.408246 -108.77767)
			(xy 36.417758 -108.780072) (xy 36.497006 -108.796328) (xy 36.51631 -108.792518) (xy 36.524692 -108.787184)
			(xy 36.547842 -108.772864) (xy 36.597358 -108.750255) (xy 36.649588 -108.734926) (xy 36.703469 -108.727189)
			(xy 36.730686 -108.726732) (xy 36.73094 -108.726732) (xy 36.758192 -108.727141) (xy 36.812141 -108.734903)
			(xy 36.864437 -108.750263) (xy 36.914014 -108.772909) (xy 36.959864 -108.802379) (xy 37.001054 -108.838074)
			(xy 37.036745 -108.879268) (xy 37.066211 -108.925121) (xy 37.088851 -108.974701) (xy 37.104206 -109.026998)
			(xy 37.111962 -109.080948) (xy 37.111962 -109.135452) (xy 37.104206 -109.189402) (xy 37.088851 -109.241699)
			(xy 37.066211 -109.291279) (xy 37.036745 -109.337132) (xy 37.001054 -109.378326) (xy 36.959864 -109.414021)
			(xy 36.914014 -109.443491) (xy 36.864437 -109.466137) (xy 36.812141 -109.481497) (xy 36.758192 -109.489259)
			(xy 36.73094 -109.489748) (xy 36.703234 -109.489239) (xy 36.648408 -109.481203) (xy 36.62172 -109.473746)
			(xy 36.621466 -109.473746) (xy 36.611967 -109.471402) (xy 36.592507 -109.473213) (xy 36.58362 -109.477302)
			(xy 36.511992 -109.514894) (xy 36.499292 -109.52988) (xy 36.496244 -109.539278) (xy 36.482328 -109.579808)
			(xy 36.447772 -109.658231) (xy 36.405836 -109.732968) (xy 36.356907 -109.803325) (xy 36.301439 -109.868652)
			(xy 36.239946 -109.928342) (xy 36.172998 -109.981842) (xy 36.101216 -110.028657) (xy 36.025265 -110.068351)
			(xy 35.945849 -110.100559) (xy 35.863703 -110.12498) (xy 35.77959 -110.141389) (xy 35.694289 -110.149634)
			(xy 35.65144 -110.150148) (xy 35.609092 -110.149644) (xy 35.524778 -110.141593) (xy 35.441612 -110.125564)
			(xy 35.360345 -110.101703) (xy 35.281715 -110.070224) (xy 35.206434 -110.031413) (xy 35.135182 -109.985623)
			(xy 35.068606 -109.933267) (xy 35.007308 -109.874819) (xy 34.951843 -109.810809) (xy 34.902714 -109.741817)
			(xy 34.860365 -109.668467) (xy 34.825181 -109.591424) (xy 34.797479 -109.511385) (xy 34.777511 -109.429076)
			(xy 34.765458 -109.345241) (xy 34.761428 -109.26064) (xy 30.687264 -109.26064) (xy 27.705304 -112.2426)
			(xy 34.693352 -112.2426) (xy 34.693879 -112.215225) (xy 34.701706 -112.161038) (xy 34.717198 -112.108527)
			(xy 34.740038 -112.058769) (xy 34.769757 -112.012788) (xy 34.805743 -111.971527) (xy 34.847258 -111.935834)
			(xy 34.893449 -111.906443) (xy 34.943367 -111.883956) (xy 34.995988 -111.868837) (xy 35.023044 -111.864648)
			(xy 35.031411 -111.863206) (xy 35.046526 -111.855482) (xy 35.058301 -111.843257) (xy 35.06216 -111.835692)
			(xy 35.103816 -111.746538) (xy 35.102038 -111.72063) (xy 35.09518 -111.709708) (xy 35.081212 -111.686745)
			(xy 35.059184 -111.63772) (xy 35.044251 -111.586089) (xy 35.036711 -111.532874) (xy 35.036252 -111.506)
			(xy 35.036778 -111.478751) (xy 35.044533 -111.424806) (xy 35.059886 -111.372515) (xy 35.082524 -111.32294)
			(xy 35.111987 -111.277092) (xy 35.147674 -111.235903) (xy 35.18886 -111.200211) (xy 35.234705 -111.170744)
			(xy 35.284277 -111.1481) (xy 35.336567 -111.132742) (xy 35.390511 -111.124981) (xy 35.41776 -111.124492)
			(xy 35.444691 -111.124981) (xy 35.498019 -111.132539) (xy 35.549753 -111.147526) (xy 35.598864 -111.169642)
			(xy 35.644374 -111.198448) (xy 35.685379 -111.233371) (xy 35.721063 -111.273715) (xy 35.736276 -111.295942)
			(xy 35.741302 -111.302935) (xy 35.754984 -111.313373) (xy 35.771354 -111.318678) (xy 35.779964 -111.318802)
			(xy 35.879024 -111.316516) (xy 35.901376 -111.303562) (xy 35.908234 -111.29264) (xy 35.908234 -111.292386)
			(xy 35.923081 -111.268488) (xy 35.95874 -111.22497) (xy 36.000404 -111.187161) (xy 36.047169 -111.155882)
			(xy 36.098021 -111.13181) (xy 36.151857 -111.115469) (xy 36.207509 -111.107211) (xy 36.23564 -111.106712)
			(xy 36.263244 -111.107164) (xy 36.317879 -111.115103) (xy 36.370798 -111.130837) (xy 36.420894 -111.15404)
			(xy 36.467121 -111.184224) (xy 36.508511 -111.220759) (xy 36.5442 -111.262881) (xy 36.559236 -111.286036)
			(xy 36.566348 -111.297466) (xy 36.590478 -111.31042) (xy 36.692332 -111.306356) (xy 36.70125 -111.305679)
			(xy 36.717801 -111.29893) (xy 36.731043 -111.286925) (xy 36.735512 -111.279178) (xy 36.747856 -111.256264)
			(xy 36.777918 -111.213774) (xy 36.813481 -111.175769) (xy 36.853883 -111.142954) (xy 36.898373 -111.115941)
			(xy 36.946125 -111.09523) (xy 36.996249 -111.081206) (xy 37.047815 -111.074132) (xy 37.07384 -111.073692)
			(xy 37.100481 -111.074126) (xy 37.153242 -111.081557) (xy 37.204457 -111.096255) (xy 37.253129 -111.117934)
			(xy 37.298313 -111.146172) (xy 37.339129 -111.180421) (xy 37.374785 -111.220015) (xy 37.39007 -111.24184)
			(xy 37.397436 -111.252762) (xy 37.421312 -111.2647) (xy 37.53485 -111.259112) (xy 37.557202 -111.244888)
			(xy 37.563552 -111.233204) (xy 37.577947 -111.207642) (xy 37.613421 -111.160919) (xy 37.655625 -111.120174)
			(xy 37.703566 -111.086364) (xy 37.756114 -111.060286) (xy 37.812034 -111.042554) (xy 37.870008 -111.033586)
			(xy 37.89934 -111.033052) (xy 37.92659 -111.03354) (xy 37.980536 -111.041301) (xy 38.032828 -111.05666)
			(xy 38.082403 -111.079302) (xy 38.128251 -111.108769) (xy 38.16944 -111.14446) (xy 38.205131 -111.185649)
			(xy 38.234598 -111.231497) (xy 38.25724 -111.281072) (xy 38.272599 -111.333364) (xy 38.28036 -111.38731)
			(xy 38.280848 -111.41456) (xy 38.280352 -111.442663) (xy 38.272111 -111.49826) (xy 38.2558 -111.552046)
			(xy 38.231773 -111.602857) (xy 38.20055 -111.649591) (xy 38.162807 -111.691238) (xy 38.141402 -111.709454)
			(xy 38.141148 -111.709708) (xy 38.134383 -111.71573) (xy 38.125338 -111.731412) (xy 38.122303 -111.749259)
			(xy 38.123622 -111.758222) (xy 38.142672 -111.859568) (xy 38.161214 -111.880396) (xy 38.174422 -111.884714)
			(xy 38.199659 -111.893334) (xy 38.247604 -111.91669) (xy 38.291831 -111.946493) (xy 38.331477 -111.982163)
			(xy 38.365771 -112.023006) (xy 38.394044 -112.068225) (xy 38.415746 -112.116941) (xy 38.430455 -112.168203)
			(xy 38.437883 -112.221015) (xy 38.438328 -112.24768) (xy 38.438153 -112.256781) (xy 38.803574 -112.256781)
			(xy 38.803574 -112.192859) (xy 38.811585 -112.129441) (xy 38.827482 -112.067527) (xy 38.851014 -112.008094)
			(xy 38.881808 -111.952079) (xy 38.919381 -111.900364) (xy 38.963138 -111.853767) (xy 39.012391 -111.813022)
			(xy 39.066362 -111.778771) (xy 39.124201 -111.751554) (xy 39.184994 -111.731801) (xy 39.247784 -111.719823)
			(xy 39.31158 -111.71581) (xy 39.375376 -111.719823) (xy 39.438166 -111.731801) (xy 39.498959 -111.751554)
			(xy 39.556798 -111.778771) (xy 39.610769 -111.813022) (xy 39.660022 -111.853767) (xy 39.703779 -111.900364)
			(xy 39.741352 -111.952079) (xy 39.772146 -112.008094) (xy 39.795678 -112.067527) (xy 39.805413 -112.10544)
			(xy 41.495472 -112.10544) (xy 41.495926 -112.078063) (xy 41.503762 -112.023872) (xy 41.519263 -111.971358)
			(xy 41.542112 -111.921599) (xy 41.571838 -111.875617) (xy 41.607833 -111.834356) (xy 41.649355 -111.798665)
			(xy 41.695554 -111.769275) (xy 41.745479 -111.746791) (xy 41.798105 -111.731675) (xy 41.825164 -111.727488)
			(xy 41.833515 -111.725977) (xy 41.84863 -111.718284) (xy 41.860414 -111.706086) (xy 41.86428 -111.698532)
			(xy 41.905936 -111.609378) (xy 41.904158 -111.58347) (xy 41.8973 -111.572548) (xy 41.883351 -111.549575)
			(xy 41.861317 -111.500553) (xy 41.84638 -111.448926) (xy 41.838833 -111.395713) (xy 41.838372 -111.36884)
			(xy 41.838892 -111.341589) (xy 41.846643 -111.287641) (xy 41.861993 -111.235346) (xy 41.88463 -111.185767)
			(xy 41.914092 -111.139915) (xy 41.94978 -111.098722) (xy 41.990967 -111.063028) (xy 42.036814 -111.033559)
			(xy 42.086389 -111.010914) (xy 42.138682 -110.995556) (xy 42.192629 -110.987797) (xy 42.21988 -110.987332)
			(xy 42.246812 -110.987787) (xy 42.300142 -110.99535) (xy 42.351878 -111.010341) (xy 42.400989 -111.032462)
			(xy 42.4465 -111.061273) (xy 42.487503 -111.096202) (xy 42.523184 -111.136553) (xy 42.538396 -111.158782)
			(xy 42.5434 -111.165793) (xy 42.557093 -111.176224) (xy 42.573471 -111.181522) (xy 42.582084 -111.181642)
			(xy 42.681144 -111.179356) (xy 42.703496 -111.166402) (xy 42.710354 -111.15548) (xy 42.710354 -111.155226)
			(xy 42.72527 -111.131373) (xy 42.760916 -111.087853) (xy 42.802568 -111.05004) (xy 42.849321 -111.018755)
			(xy 42.900162 -110.994676) (xy 42.953988 -110.978325) (xy 43.009633 -110.970057) (xy 43.03776 -110.969552)
			(xy 43.065364 -110.970016) (xy 43.119997 -110.977956) (xy 43.172914 -110.993691) (xy 43.223009 -111.016892)
			(xy 43.269236 -111.047073) (xy 43.310627 -111.083605) (xy 43.346319 -111.125723) (xy 43.361356 -111.148876)
			(xy 43.368468 -111.160306) (xy 43.392598 -111.17326) (xy 43.494452 -111.169196) (xy 43.503376 -111.168563)
			(xy 43.519932 -111.161799) (xy 43.53317 -111.149774) (xy 43.537632 -111.142018) (xy 43.550052 -111.119147)
			(xy 43.580103 -111.076657) (xy 43.615654 -111.038649) (xy 43.656044 -111.005831) (xy 43.700524 -110.978811)
			(xy 43.748265 -110.958093) (xy 43.79838 -110.944062) (xy 43.849939 -110.936977) (xy 43.87596 -110.936532)
			(xy 43.9026 -110.937009) (xy 43.95536 -110.94443) (xy 44.006574 -110.959119) (xy 44.055247 -110.98079)
			(xy 44.100432 -111.009023) (xy 44.141249 -111.043267) (xy 44.176905 -111.082857) (xy 44.19219 -111.10468)
			(xy 44.199556 -111.115602) (xy 44.223432 -111.12754) (xy 44.33697 -111.121952) (xy 44.359322 -111.107728)
			(xy 44.365672 -111.096044) (xy 44.380068 -111.070483) (xy 44.41554 -111.023758) (xy 44.457743 -110.98301)
			(xy 44.505684 -110.9492) (xy 44.558233 -110.923122) (xy 44.614153 -110.905391) (xy 44.672128 -110.896424)
			(xy 44.70146 -110.895892) (xy 44.728712 -110.896393) (xy 44.782661 -110.904144) (xy 44.834959 -110.919495)
			(xy 44.884539 -110.942133) (xy 44.930392 -110.971597) (xy 44.971585 -111.007287) (xy 45.007279 -111.048476)
			(xy 45.036748 -111.094326) (xy 45.059391 -111.143904) (xy 45.074747 -111.196199) (xy 45.082505 -111.250148)
			(xy 45.082968 -111.2774) (xy 45.082493 -111.305503) (xy 45.074246 -111.361101) (xy 45.057931 -111.414887)
			(xy 45.0339 -111.465698) (xy 45.002674 -111.512432) (xy 44.964928 -111.554079) (xy 44.943522 -111.572294)
			(xy 44.943268 -111.572548) (xy 44.936542 -111.578609) (xy 44.927486 -111.594271) (xy 44.924434 -111.612104)
			(xy 44.925742 -111.621062) (xy 44.944792 -111.722408) (xy 44.963334 -111.743236) (xy 44.976542 -111.747554)
			(xy 45.001796 -111.756128) (xy 45.049743 -111.779489) (xy 45.093969 -111.809298) (xy 45.133615 -111.844974)
			(xy 45.167908 -111.885823) (xy 45.196179 -111.931048) (xy 45.217878 -111.979769) (xy 45.232582 -112.031037)
			(xy 45.240005 -112.083853) (xy 45.240448 -112.11052) (xy 45.240279 -112.119621) (xy 45.605694 -112.119621)
			(xy 45.605694 -112.055699) (xy 45.613705 -111.992281) (xy 45.629602 -111.930367) (xy 45.653134 -111.870934)
			(xy 45.683928 -111.814919) (xy 45.721501 -111.763204) (xy 45.765258 -111.716607) (xy 45.814511 -111.675862)
			(xy 45.868482 -111.641611) (xy 45.926321 -111.614394) (xy 45.987114 -111.594641) (xy 46.049904 -111.582663)
			(xy 46.1137 -111.57865) (xy 46.177496 -111.582663) (xy 46.240286 -111.594641) (xy 46.301079 -111.614394)
			(xy 46.358918 -111.641611) (xy 46.412889 -111.675862) (xy 46.462142 -111.716607) (xy 46.505899 -111.763204)
			(xy 46.543472 -111.814919) (xy 46.574266 -111.870934) (xy 46.597798 -111.930367) (xy 46.613695 -111.992281)
			(xy 46.617941 -112.025895) (xy 78.67624 -112.025895) (xy 78.67624 -111.961973) (xy 78.684251 -111.898555)
			(xy 78.700148 -111.836641) (xy 78.72368 -111.777208) (xy 78.754474 -111.721193) (xy 78.792047 -111.669478)
			(xy 78.835804 -111.622881) (xy 78.885057 -111.582136) (xy 78.939028 -111.547885) (xy 78.996867 -111.520668)
			(xy 79.05766 -111.500915) (xy 79.12045 -111.488937) (xy 79.184246 -111.484924) (xy 79.248042 -111.488937)
			(xy 79.310832 -111.500915) (xy 79.371625 -111.520668) (xy 79.429464 -111.547885) (xy 79.483435 -111.582136)
			(xy 79.532688 -111.622881) (xy 79.576445 -111.669478) (xy 79.614018 -111.721193) (xy 79.644812 -111.777208)
			(xy 79.668344 -111.836641) (xy 79.684241 -111.898555) (xy 79.692252 -111.961973) (xy 79.692754 -111.993934)
			(xy 79.692252 -112.025895) (xy 79.684241 -112.089313) (xy 79.668344 -112.151227) (xy 79.644812 -112.21066)
			(xy 79.614018 -112.266675) (xy 79.576445 -112.31839) (xy 79.532688 -112.364987) (xy 79.483435 -112.405732)
			(xy 79.429464 -112.439983) (xy 79.371625 -112.4672) (xy 79.310832 -112.486953) (xy 79.248042 -112.498931)
			(xy 79.184246 -112.502945) (xy 79.12045 -112.498931) (xy 79.05766 -112.486953) (xy 78.996867 -112.4672)
			(xy 78.939028 -112.439983) (xy 78.885057 -112.405732) (xy 78.835804 -112.364987) (xy 78.792047 -112.31839)
			(xy 78.754474 -112.266675) (xy 78.72368 -112.21066) (xy 78.700148 -112.151227) (xy 78.684251 -112.089313)
			(xy 78.67624 -112.025895) (xy 46.617941 -112.025895) (xy 46.621706 -112.055699) (xy 46.622208 -112.08766)
			(xy 46.621706 -112.119621) (xy 46.613695 -112.183039) (xy 46.597798 -112.244953) (xy 46.574266 -112.304386)
			(xy 46.543472 -112.360401) (xy 46.505899 -112.412116) (xy 46.462142 -112.458713) (xy 46.412889 -112.499458)
			(xy 46.358918 -112.533709) (xy 46.301079 -112.560926) (xy 46.240286 -112.580679) (xy 46.177496 -112.592657)
			(xy 46.1137 -112.596671) (xy 46.049904 -112.592657) (xy 45.987114 -112.580679) (xy 45.926321 -112.560926)
			(xy 45.868482 -112.533709) (xy 45.814511 -112.499458) (xy 45.765258 -112.458713) (xy 45.721501 -112.412116)
			(xy 45.683928 -112.360401) (xy 45.653134 -112.304386) (xy 45.629602 -112.244953) (xy 45.613705 -112.183039)
			(xy 45.605694 -112.119621) (xy 45.240279 -112.119621) (xy 45.239941 -112.13777) (xy 45.232183 -112.191715)
			(xy 45.216827 -112.244007) (xy 45.194187 -112.293581) (xy 45.164722 -112.33943) (xy 45.129033 -112.380619)
			(xy 45.087846 -112.41631) (xy 45.041999 -112.445777) (xy 44.992425 -112.46842) (xy 44.940134 -112.483778)
			(xy 44.88619 -112.49154) (xy 44.85894 -112.492028) (xy 44.830806 -112.491539) (xy 44.775145 -112.48329)
			(xy 44.7213 -112.466952) (xy 44.670442 -112.442879) (xy 44.623672 -112.411593) (xy 44.582008 -112.373774)
			(xy 44.563792 -112.352328) (xy 44.556352 -112.344014) (xy 44.536317 -112.334263) (xy 44.525184 -112.333532)
			(xy 44.436538 -112.332262) (xy 44.416218 -112.341152) (xy 44.408852 -112.349534) (xy 44.390648 -112.369517)
			(xy 44.3496 -112.404687) (xy 44.304001 -112.433715) (xy 44.254765 -112.456023) (xy 44.202874 -112.471164)
			(xy 44.149367 -112.478835) (xy 44.12234 -112.479328) (xy 44.095702 -112.478825) (xy 44.042944 -112.471405)
			(xy 43.991731 -112.456719) (xy 43.943059 -112.435051) (xy 43.897874 -112.406823) (xy 43.857056 -112.372584)
			(xy 43.821397 -112.333) (xy 43.80611 -112.31118) (xy 43.798744 -112.300258) (xy 43.775884 -112.288574)
			(xy 43.663616 -112.291622) (xy 43.641264 -112.30483) (xy 43.63466 -112.316006) (xy 43.619762 -112.339917)
			(xy 43.584131 -112.383553) (xy 43.542468 -112.421471) (xy 43.49568 -112.452846) (xy 43.444784 -112.476996)
			(xy 43.390889 -112.493393) (xy 43.335167 -112.501682) (xy 43.307 -112.502188) (xy 43.278731 -112.50168)
			(xy 43.222812 -112.493348) (xy 43.168735 -112.476852) (xy 43.117686 -112.452554) (xy 43.070783 -112.420986)
			(xy 43.029054 -112.382839) (xy 43.010836 -112.361218) (xy 43.003327 -112.352885) (xy 42.983168 -112.34312)
			(xy 42.971974 -112.342422) (xy 42.88282 -112.341152) (xy 42.862246 -112.350296) (xy 42.85488 -112.358932)
			(xy 42.836662 -112.379416) (xy 42.795381 -112.415485) (xy 42.749363 -112.445275) (xy 42.699555 -112.468172)
			(xy 42.646983 -112.483704) (xy 42.592729 -112.491553) (xy 42.56532 -112.492028) (xy 42.53986 -112.491633)
			(xy 42.489393 -112.484861) (xy 42.440275 -112.471435) (xy 42.39338 -112.451594) (xy 42.349541 -112.42569)
			(xy 42.309539 -112.394184) (xy 42.291508 -112.376204) (xy 42.284396 -112.368838) (xy 42.265854 -112.360964)
			(xy 42.172636 -112.360202) (xy 42.154094 -112.367822) (xy 42.146728 -112.375188) (xy 42.125135 -112.395994)
			(xy 42.076632 -112.431249) (xy 42.02321 -112.458478) (xy 41.966184 -112.477011) (xy 41.906961 -112.486392)
			(xy 41.87698 -112.486948) (xy 41.84973 -112.486441) (xy 41.795785 -112.478683) (xy 41.743493 -112.463327)
			(xy 41.693919 -112.440687) (xy 41.64807 -112.411222) (xy 41.606881 -112.375533) (xy 41.57119 -112.334346)
			(xy 41.541723 -112.288499) (xy 41.51908 -112.238925) (xy 41.503722 -112.186634) (xy 41.49596 -112.13269)
			(xy 41.495472 -112.10544) (xy 39.805413 -112.10544) (xy 39.811575 -112.129441) (xy 39.819586 -112.192859)
			(xy 39.820088 -112.22482) (xy 39.819586 -112.256781) (xy 39.811575 -112.320199) (xy 39.795678 -112.382113)
			(xy 39.772146 -112.441546) (xy 39.741352 -112.497561) (xy 39.703779 -112.549276) (xy 39.660022 -112.595873)
			(xy 39.610769 -112.636618) (xy 39.556798 -112.670869) (xy 39.498959 -112.698086) (xy 39.438166 -112.717839)
			(xy 39.375376 -112.729817) (xy 39.31158 -112.733831) (xy 39.247784 -112.729817) (xy 39.184994 -112.717839)
			(xy 39.124201 -112.698086) (xy 39.066362 -112.670869) (xy 39.012391 -112.636618) (xy 38.963138 -112.595873)
			(xy 38.919381 -112.549276) (xy 38.881808 -112.497561) (xy 38.851014 -112.441546) (xy 38.827482 -112.382113)
			(xy 38.811585 -112.320199) (xy 38.803574 -112.256781) (xy 38.438153 -112.256781) (xy 38.437803 -112.27493)
			(xy 38.43005 -112.328875) (xy 38.414698 -112.381168) (xy 38.392061 -112.430744) (xy 38.362599 -112.476593)
			(xy 38.326911 -112.517783) (xy 38.285725 -112.553475) (xy 38.239879 -112.582942) (xy 38.190305 -112.605584)
			(xy 38.138014 -112.620941) (xy 38.08407 -112.6287) (xy 38.05682 -112.629188) (xy 38.028684 -112.628727)
			(xy 37.973022 -112.620475) (xy 37.919176 -112.604132) (xy 37.868317 -112.580054) (xy 37.821549 -112.548762)
			(xy 37.779887 -112.510937) (xy 37.761672 -112.489488) (xy 37.754231 -112.481176) (xy 37.734197 -112.471421)
			(xy 37.723064 -112.470692) (xy 37.634418 -112.469422) (xy 37.614098 -112.478312) (xy 37.606732 -112.486694)
			(xy 37.588551 -112.506699) (xy 37.547496 -112.541864) (xy 37.501893 -112.570888) (xy 37.452652 -112.593192)
			(xy 37.400758 -112.608329) (xy 37.347248 -112.615996) (xy 37.32022 -112.616488) (xy 37.29358 -112.616018)
			(xy 37.24082 -112.608594) (xy 37.189606 -112.593904) (xy 37.140933 -112.572231) (xy 37.095749 -112.543998)
			(xy 37.054932 -112.509753) (xy 37.019276 -112.470163) (xy 37.00399 -112.44834) (xy 36.996624 -112.437418)
			(xy 36.973764 -112.425734) (xy 36.861496 -112.428782) (xy 36.839144 -112.44199) (xy 36.83254 -112.453166)
			(xy 36.817677 -112.4771) (xy 36.782039 -112.520733) (xy 36.740369 -112.558647) (xy 36.693574 -112.590019)
			(xy 36.642673 -112.614164) (xy 36.588774 -112.630558) (xy 36.533049 -112.638844) (xy 36.50488 -112.639348)
			(xy 36.47661 -112.638868) (xy 36.420689 -112.630533) (xy 36.36661 -112.614032) (xy 36.315561 -112.589729)
			(xy 36.268659 -112.558155) (xy 36.226933 -112.520002) (xy 36.208716 -112.498378) (xy 36.201206 -112.490045)
			(xy 36.181048 -112.480278) (xy 36.169854 -112.479582) (xy 36.0807 -112.478312) (xy 36.060126 -112.487456)
			(xy 36.05276 -112.496092) (xy 36.034566 -112.516598) (xy 35.993278 -112.552663) (xy 35.947255 -112.582448)
			(xy 35.897442 -112.60534) (xy 35.844867 -112.620869) (xy 35.79061 -112.628714) (xy 35.7632 -112.629188)
			(xy 35.737741 -112.628753) (xy 35.687275 -112.621991) (xy 35.638157 -112.608574) (xy 35.591262 -112.58874)
			(xy 35.547423 -112.562842) (xy 35.507419 -112.531341) (xy 35.489388 -112.513364) (xy 35.482276 -112.505998)
			(xy 35.463734 -112.498124) (xy 35.370516 -112.497362) (xy 35.351974 -112.504982) (xy 35.344608 -112.512348)
			(xy 35.323017 -112.533157) (xy 35.274514 -112.568412) (xy 35.221091 -112.595641) (xy 35.164065 -112.614174)
			(xy 35.104841 -112.623553) (xy 35.07486 -112.624108) (xy 35.047608 -112.623659) (xy 34.993659 -112.615897)
			(xy 34.941363 -112.600537) (xy 34.891786 -112.577891) (xy 34.845936 -112.548421) (xy 34.804746 -112.512726)
			(xy 34.769055 -112.471532) (xy 34.739589 -112.425679) (xy 34.716949 -112.376099) (xy 34.701594 -112.323802)
			(xy 34.693838 -112.269852) (xy 34.693352 -112.2426) (xy 27.705304 -112.2426) (xy 22.003512 -117.944392)
			(xy 22.000807 -117.947243) (xy 21.996215 -117.953622) (xy 21.994368 -117.957092) (xy 21.991792 -117.96252)
			(xy 21.988981 -117.9742) (xy 21.98878 -117.980206) (xy 21.98878 -118.485115) (xy 96.56673 -118.485115)
			(xy 96.56673 -118.421193) (xy 96.574741 -118.357775) (xy 96.590638 -118.295861) (xy 96.61417 -118.236428)
			(xy 96.644964 -118.180413) (xy 96.682537 -118.128698) (xy 96.726294 -118.082101) (xy 96.775547 -118.041356)
			(xy 96.829518 -118.007105) (xy 96.887357 -117.979888) (xy 96.94815 -117.960135) (xy 97.01094 -117.948157)
			(xy 97.074736 -117.944144) (xy 97.138532 -117.948157) (xy 97.201322 -117.960135) (xy 97.262115 -117.979888)
			(xy 97.319954 -118.007105) (xy 97.373925 -118.041356) (xy 97.423178 -118.082101) (xy 97.466935 -118.128698)
			(xy 97.504508 -118.180413) (xy 97.535302 -118.236428) (xy 97.558834 -118.295861) (xy 97.574731 -118.357775)
			(xy 97.582742 -118.421193) (xy 97.583244 -118.453154) (xy 97.582742 -118.485115) (xy 97.574731 -118.548533)
			(xy 97.558834 -118.610447) (xy 97.535302 -118.66988) (xy 97.504508 -118.725895) (xy 97.466935 -118.77761)
			(xy 97.423178 -118.824207) (xy 97.373925 -118.864952) (xy 97.319954 -118.899203) (xy 97.262115 -118.92642)
			(xy 97.201322 -118.946173) (xy 97.138532 -118.958151) (xy 97.074736 -118.962165) (xy 97.01094 -118.958151)
			(xy 96.94815 -118.946173) (xy 96.887357 -118.92642) (xy 96.829518 -118.899203) (xy 96.775547 -118.864952)
			(xy 96.726294 -118.824207) (xy 96.682537 -118.77761) (xy 96.644964 -118.725895) (xy 96.61417 -118.66988)
			(xy 96.590638 -118.610447) (xy 96.574741 -118.548533) (xy 96.56673 -118.485115) (xy 21.98878 -118.485115)
			(xy 21.98878 -119.89645) (xy 97.324682 -119.89645) (xy 97.324682 -119.84195) (xy 97.332437 -119.788006)
			(xy 97.347791 -119.735714) (xy 97.37043 -119.686139) (xy 97.399893 -119.64029) (xy 97.435581 -119.599101)
			(xy 97.476768 -119.56341) (xy 97.522614 -119.533943) (xy 97.572187 -119.511301) (xy 97.624478 -119.495943)
			(xy 97.678422 -119.488184) (xy 97.705672 -119.487696) (xy 97.738872 -119.488407) (xy 97.804267 -119.499905)
			(xy 97.83572 -119.510556) (xy 97.846134 -119.514366) (xy 97.868232 -119.512334) (xy 97.945194 -119.468646)
			(xy 97.954501 -119.462788) (xy 97.967414 -119.445022) (xy 97.970086 -119.434356) (xy 97.970086 -119.433848)
			(xy 97.975453 -119.408037) (xy 97.992419 -119.358122) (xy 98.016096 -119.311019) (xy 98.046034 -119.267625)
			(xy 98.081662 -119.228766) (xy 98.122301 -119.195184) (xy 98.167178 -119.167518) (xy 98.215437 -119.146295)
			(xy 98.266158 -119.131919) (xy 98.318376 -119.124664) (xy 98.344736 -119.124222) (xy 98.371988 -119.12465)
			(xy 98.425936 -119.132412) (xy 98.47823 -119.147771) (xy 98.487749 -119.152119) (xy 107.748826 -119.152119)
			(xy 107.748826 -119.088197) (xy 107.756837 -119.024779) (xy 107.772734 -118.962865) (xy 107.796266 -118.903432)
			(xy 107.82706 -118.847417) (xy 107.864633 -118.795702) (xy 107.90839 -118.749105) (xy 107.957643 -118.70836)
			(xy 108.011614 -118.674109) (xy 108.069453 -118.646892) (xy 108.130246 -118.627139) (xy 108.193036 -118.615161)
			(xy 108.256832 -118.611148) (xy 108.320628 -118.615161) (xy 108.383418 -118.627139) (xy 108.444211 -118.646892)
			(xy 108.50205 -118.674109) (xy 108.556021 -118.70836) (xy 108.605274 -118.749105) (xy 108.649031 -118.795702)
			(xy 108.686604 -118.847417) (xy 108.717398 -118.903432) (xy 108.74093 -118.962865) (xy 108.756827 -119.024779)
			(xy 108.764838 -119.088197) (xy 108.76534 -119.120158) (xy 108.764838 -119.152119) (xy 108.756827 -119.215537)
			(xy 108.74093 -119.277451) (xy 108.717398 -119.336884) (xy 108.686604 -119.392899) (xy 108.649031 -119.444614)
			(xy 108.605274 -119.491211) (xy 108.556021 -119.531956) (xy 108.50205 -119.566207) (xy 108.444211 -119.593424)
			(xy 108.383418 -119.613177) (xy 108.320628 -119.625155) (xy 108.256832 -119.629169) (xy 108.193036 -119.625155)
			(xy 108.130246 -119.613177) (xy 108.069453 -119.593424) (xy 108.011614 -119.566207) (xy 107.957643 -119.531956)
			(xy 107.90839 -119.491211) (xy 107.864633 -119.444614) (xy 107.82706 -119.392899) (xy 107.796266 -119.336884)
			(xy 107.772734 -119.277451) (xy 107.756837 -119.215537) (xy 107.748826 -119.152119) (xy 98.487749 -119.152119)
			(xy 98.527807 -119.170416) (xy 98.573656 -119.199886) (xy 98.614846 -119.23558) (xy 98.650536 -119.276772)
			(xy 98.680001 -119.322625) (xy 98.702642 -119.372203) (xy 98.717996 -119.424499) (xy 98.725752 -119.478448)
			(xy 98.725752 -119.532952) (xy 98.717996 -119.586901) (xy 98.702642 -119.639197) (xy 98.680001 -119.688775)
			(xy 98.650536 -119.734628) (xy 98.614846 -119.77582) (xy 98.573656 -119.811514) (xy 98.527807 -119.840984)
			(xy 98.47823 -119.863629) (xy 98.425936 -119.878988) (xy 98.371988 -119.88675) (xy 98.344736 -119.887238)
			(xy 98.311536 -119.886529) (xy 98.24614 -119.87503) (xy 98.214688 -119.864378) (xy 98.204274 -119.860568)
			(xy 98.182176 -119.8626) (xy 98.105214 -119.906288) (xy 98.095897 -119.912133) (xy 98.095746 -119.912341)
			(xy 109.544352 -119.912341) (xy 109.544352 -119.848419) (xy 109.552363 -119.785001) (xy 109.56826 -119.723087)
			(xy 109.591792 -119.663654) (xy 109.622586 -119.607639) (xy 109.660159 -119.555924) (xy 109.703916 -119.509327)
			(xy 109.753169 -119.468582) (xy 109.80714 -119.434331) (xy 109.864979 -119.407114) (xy 109.925772 -119.387361)
			(xy 109.988562 -119.375383) (xy 110.052358 -119.37137) (xy 110.116154 -119.375383) (xy 110.178944 -119.387361)
			(xy 110.239737 -119.407114) (xy 110.297576 -119.434331) (xy 110.351547 -119.468582) (xy 110.4008 -119.509327)
			(xy 110.444557 -119.555924) (xy 110.48213 -119.607639) (xy 110.512924 -119.663654) (xy 110.536456 -119.723087)
			(xy 110.552353 -119.785001) (xy 110.560364 -119.848419) (xy 110.560866 -119.88038) (xy 110.560364 -119.912341)
			(xy 110.552353 -119.975759) (xy 110.536456 -120.037673) (xy 110.512924 -120.097106) (xy 110.48213 -120.153121)
			(xy 110.444557 -120.204836) (xy 110.4008 -120.251433) (xy 110.351547 -120.292178) (xy 110.297576 -120.326429)
			(xy 110.239737 -120.353646) (xy 110.178944 -120.373399) (xy 110.116154 -120.385377) (xy 110.052358 -120.389391)
			(xy 109.988562 -120.385377) (xy 109.925772 -120.373399) (xy 109.864979 -120.353646) (xy 109.80714 -120.326429)
			(xy 109.753169 -120.292178) (xy 109.703916 -120.251433) (xy 109.660159 -120.204836) (xy 109.622586 -120.153121)
			(xy 109.591792 -120.097106) (xy 109.56826 -120.037673) (xy 109.552363 -119.975759) (xy 109.544352 -119.912341)
			(xy 98.095746 -119.912341) (xy 98.082989 -119.929909) (xy 98.080322 -119.940578) (xy 98.080322 -119.941086)
			(xy 98.074899 -119.966884) (xy 98.057942 -120.016799) (xy 98.034273 -120.063903) (xy 98.004343 -120.107298)
			(xy 97.968721 -120.146158) (xy 97.928088 -120.179742) (xy 97.883216 -120.20741) (xy 97.834962 -120.228635)
			(xy 97.784244 -120.243013) (xy 97.73203 -120.250269) (xy 97.705672 -120.250712) (xy 97.678422 -120.250216)
			(xy 97.624478 -120.242457) (xy 97.572187 -120.227099) (xy 97.522614 -120.204457) (xy 97.476768 -120.17499)
			(xy 97.435581 -120.139299) (xy 97.399893 -120.09811) (xy 97.37043 -120.052261) (xy 97.347791 -120.002686)
			(xy 97.332437 -119.950394) (xy 97.324682 -119.89645) (xy 21.98878 -119.89645) (xy 21.98878 -120.862301)
			(xy 37.035734 -120.862301) (xy 37.035734 -120.798379) (xy 37.043745 -120.734961) (xy 37.059642 -120.673047)
			(xy 37.083174 -120.613614) (xy 37.113968 -120.557599) (xy 37.151541 -120.505884) (xy 37.195298 -120.459287)
			(xy 37.244551 -120.418542) (xy 37.298522 -120.384291) (xy 37.356361 -120.357074) (xy 37.417154 -120.337321)
			(xy 37.479944 -120.325343) (xy 37.54374 -120.32133) (xy 37.607536 -120.325343) (xy 37.670326 -120.337321)
			(xy 37.731119 -120.357074) (xy 37.788958 -120.384291) (xy 37.842929 -120.418542) (xy 37.892182 -120.459287)
			(xy 37.935939 -120.505884) (xy 37.973512 -120.557599) (xy 38.004306 -120.613614) (xy 38.021311 -120.656561)
			(xy 43.182534 -120.656561) (xy 43.182534 -120.592639) (xy 43.190545 -120.529221) (xy 43.206442 -120.467307)
			(xy 43.229974 -120.407874) (xy 43.260768 -120.351859) (xy 43.298341 -120.300144) (xy 43.342098 -120.253547)
			(xy 43.391351 -120.212802) (xy 43.445322 -120.178551) (xy 43.503161 -120.151334) (xy 43.563954 -120.131581)
			(xy 43.626744 -120.119603) (xy 43.69054 -120.11559) (xy 43.754336 -120.119603) (xy 43.817126 -120.131581)
			(xy 43.877919 -120.151334) (xy 43.935758 -120.178551) (xy 43.989729 -120.212802) (xy 44.038982 -120.253547)
			(xy 44.082739 -120.300144) (xy 44.120312 -120.351859) (xy 44.151106 -120.407874) (xy 44.174638 -120.467307)
			(xy 44.190535 -120.529221) (xy 44.198546 -120.592639) (xy 44.199048 -120.6246) (xy 44.198546 -120.656561)
			(xy 44.190535 -120.719979) (xy 44.174638 -120.781893) (xy 44.151106 -120.841326) (xy 44.120312 -120.897341)
			(xy 44.082739 -120.949056) (xy 44.07834 -120.953741) (xy 98.49713 -120.953741) (xy 98.49713 -120.889819)
			(xy 98.505141 -120.826401) (xy 98.521038 -120.764487) (xy 98.54457 -120.705054) (xy 98.575364 -120.649039)
			(xy 98.612937 -120.597324) (xy 98.656694 -120.550727) (xy 98.705947 -120.509982) (xy 98.759918 -120.475731)
			(xy 98.817757 -120.448514) (xy 98.87855 -120.428761) (xy 98.94134 -120.416783) (xy 99.005136 -120.41277)
			(xy 99.068932 -120.416783) (xy 99.131722 -120.428761) (xy 99.192515 -120.448514) (xy 99.250354 -120.475731)
			(xy 99.304325 -120.509982) (xy 99.353578 -120.550727) (xy 99.397335 -120.597324) (xy 99.434908 -120.649039)
			(xy 99.465702 -120.705054) (xy 99.489234 -120.764487) (xy 99.502349 -120.815565) (xy 110.293398 -120.815565)
			(xy 110.293398 -120.751643) (xy 110.301409 -120.688225) (xy 110.317306 -120.626311) (xy 110.340838 -120.566878)
			(xy 110.371632 -120.510863) (xy 110.409205 -120.459148) (xy 110.452962 -120.412551) (xy 110.502215 -120.371806)
			(xy 110.556186 -120.337555) (xy 110.614025 -120.310338) (xy 110.674818 -120.290585) (xy 110.737608 -120.278607)
			(xy 110.801404 -120.274594) (xy 110.8652 -120.278607) (xy 110.92799 -120.290585) (xy 110.988783 -120.310338)
			(xy 111.046622 -120.337555) (xy 111.100593 -120.371806) (xy 111.149846 -120.412551) (xy 111.193603 -120.459148)
			(xy 111.231176 -120.510863) (xy 111.24732 -120.540229) (xy 111.835432 -120.540229) (xy 111.835432 -120.476307)
			(xy 111.843443 -120.412889) (xy 111.85934 -120.350975) (xy 111.882872 -120.291542) (xy 111.913666 -120.235527)
			(xy 111.951239 -120.183812) (xy 111.994996 -120.137215) (xy 112.044249 -120.09647) (xy 112.09822 -120.062219)
			(xy 112.156059 -120.035002) (xy 112.216852 -120.015249) (xy 112.279642 -120.003271) (xy 112.343438 -119.999258)
			(xy 112.407234 -120.003271) (xy 112.470024 -120.015249) (xy 112.530817 -120.035002) (xy 112.588656 -120.062219)
			(xy 112.642627 -120.09647) (xy 112.69188 -120.137215) (xy 112.735637 -120.183812) (xy 112.77321 -120.235527)
			(xy 112.804004 -120.291542) (xy 112.827536 -120.350975) (xy 112.843433 -120.412889) (xy 112.845626 -120.430247)
			(xy 113.663978 -120.430247) (xy 113.663978 -120.366325) (xy 113.671989 -120.302907) (xy 113.687886 -120.240993)
			(xy 113.711418 -120.18156) (xy 113.742212 -120.125545) (xy 113.779785 -120.07383) (xy 113.823542 -120.027233)
			(xy 113.872795 -119.986488) (xy 113.926766 -119.952237) (xy 113.984605 -119.92502) (xy 114.045398 -119.905267)
			(xy 114.108188 -119.893289) (xy 114.171984 -119.889276) (xy 114.23578 -119.893289) (xy 114.29857 -119.905267)
			(xy 114.359363 -119.92502) (xy 114.417202 -119.952237) (xy 114.471173 -119.986488) (xy 114.520426 -120.027233)
			(xy 114.564183 -120.07383) (xy 114.601756 -120.125545) (xy 114.63255 -120.18156) (xy 114.656082 -120.240993)
			(xy 114.671979 -120.302907) (xy 114.67999 -120.366325) (xy 114.680492 -120.398286) (xy 114.67999 -120.430247)
			(xy 114.671979 -120.493665) (xy 114.656082 -120.555579) (xy 114.63255 -120.615012) (xy 114.601756 -120.671027)
			(xy 114.564183 -120.722742) (xy 114.520426 -120.769339) (xy 114.471173 -120.810084) (xy 114.417202 -120.844335)
			(xy 114.359363 -120.871552) (xy 114.29857 -120.891305) (xy 114.23578 -120.903283) (xy 114.171984 -120.907297)
			(xy 114.108188 -120.903283) (xy 114.045398 -120.891305) (xy 113.984605 -120.871552) (xy 113.926766 -120.844335)
			(xy 113.872795 -120.810084) (xy 113.823542 -120.769339) (xy 113.779785 -120.722742) (xy 113.742212 -120.671027)
			(xy 113.711418 -120.615012) (xy 113.687886 -120.555579) (xy 113.671989 -120.493665) (xy 113.663978 -120.430247)
			(xy 112.845626 -120.430247) (xy 112.851444 -120.476307) (xy 112.851946 -120.508268) (xy 112.851444 -120.540229)
			(xy 112.843433 -120.603647) (xy 112.827536 -120.665561) (xy 112.804004 -120.724994) (xy 112.77321 -120.781009)
			(xy 112.735637 -120.832724) (xy 112.69188 -120.879321) (xy 112.642627 -120.920066) (xy 112.588656 -120.954317)
			(xy 112.530817 -120.981534) (xy 112.470024 -121.001287) (xy 112.407234 -121.013265) (xy 112.343438 -121.017279)
			(xy 112.279642 -121.013265) (xy 112.216852 -121.001287) (xy 112.156059 -120.981534) (xy 112.09822 -120.954317)
			(xy 112.044249 -120.920066) (xy 111.994996 -120.879321) (xy 111.951239 -120.832724) (xy 111.913666 -120.781009)
			(xy 111.882872 -120.724994) (xy 111.85934 -120.665561) (xy 111.843443 -120.603647) (xy 111.835432 -120.540229)
			(xy 111.24732 -120.540229) (xy 111.26197 -120.566878) (xy 111.285502 -120.626311) (xy 111.301399 -120.688225)
			(xy 111.30941 -120.751643) (xy 111.309912 -120.783604) (xy 111.30941 -120.815565) (xy 111.301399 -120.878983)
			(xy 111.285502 -120.940897) (xy 111.26197 -121.00033) (xy 111.231176 -121.056345) (xy 111.193603 -121.10806)
			(xy 111.149846 -121.154657) (xy 111.100593 -121.195402) (xy 111.046622 -121.229653) (xy 110.988783 -121.25687)
			(xy 110.92799 -121.276623) (xy 110.8652 -121.288601) (xy 110.801404 -121.292615) (xy 110.737608 -121.288601)
			(xy 110.674818 -121.276623) (xy 110.614025 -121.25687) (xy 110.556186 -121.229653) (xy 110.502215 -121.195402)
			(xy 110.452962 -121.154657) (xy 110.409205 -121.10806) (xy 110.371632 -121.056345) (xy 110.340838 -121.00033)
			(xy 110.317306 -120.940897) (xy 110.301409 -120.878983) (xy 110.293398 -120.815565) (xy 99.502349 -120.815565)
			(xy 99.505131 -120.826401) (xy 99.513142 -120.889819) (xy 99.513644 -120.92178) (xy 99.513142 -120.953741)
			(xy 99.505131 -121.017159) (xy 99.489234 -121.079073) (xy 99.465702 -121.138506) (xy 99.434908 -121.194521)
			(xy 99.397335 -121.246236) (xy 99.353578 -121.292833) (xy 99.304325 -121.333578) (xy 99.250354 -121.367829)
			(xy 99.192515 -121.395046) (xy 99.131722 -121.414799) (xy 99.068932 -121.426777) (xy 99.005136 -121.430791)
			(xy 98.94134 -121.426777) (xy 98.87855 -121.414799) (xy 98.817757 -121.395046) (xy 98.759918 -121.367829)
			(xy 98.705947 -121.333578) (xy 98.656694 -121.292833) (xy 98.612937 -121.246236) (xy 98.575364 -121.194521)
			(xy 98.54457 -121.138506) (xy 98.521038 -121.079073) (xy 98.505141 -121.017159) (xy 98.49713 -120.953741)
			(xy 44.07834 -120.953741) (xy 44.038982 -120.995653) (xy 43.989729 -121.036398) (xy 43.935758 -121.070649)
			(xy 43.877919 -121.097866) (xy 43.817126 -121.117619) (xy 43.754336 -121.129597) (xy 43.69054 -121.133611)
			(xy 43.626744 -121.129597) (xy 43.563954 -121.117619) (xy 43.503161 -121.097866) (xy 43.445322 -121.070649)
			(xy 43.391351 -121.036398) (xy 43.342098 -120.995653) (xy 43.298341 -120.949056) (xy 43.260768 -120.897341)
			(xy 43.229974 -120.841326) (xy 43.206442 -120.781893) (xy 43.190545 -120.719979) (xy 43.182534 -120.656561)
			(xy 38.021311 -120.656561) (xy 38.027838 -120.673047) (xy 38.043735 -120.734961) (xy 38.051746 -120.798379)
			(xy 38.052248 -120.83034) (xy 38.051746 -120.862301) (xy 38.043735 -120.925719) (xy 38.027838 -120.987633)
			(xy 38.004306 -121.047066) (xy 37.973512 -121.103081) (xy 37.935939 -121.154796) (xy 37.892182 -121.201393)
			(xy 37.842929 -121.242138) (xy 37.788958 -121.276389) (xy 37.731119 -121.303606) (xy 37.670326 -121.323359)
			(xy 37.607536 -121.335337) (xy 37.54374 -121.339351) (xy 37.479944 -121.335337) (xy 37.417154 -121.323359)
			(xy 37.356361 -121.303606) (xy 37.298522 -121.276389) (xy 37.244551 -121.242138) (xy 37.195298 -121.201393)
			(xy 37.151541 -121.154796) (xy 37.113968 -121.103081) (xy 37.083174 -121.047066) (xy 37.059642 -120.987633)
			(xy 37.043745 -120.925719) (xy 37.035734 -120.862301) (xy 21.98878 -120.862301) (xy 21.98878 -121.755365)
			(xy 95.751898 -121.755365) (xy 95.751898 -121.691443) (xy 95.759909 -121.628025) (xy 95.775806 -121.566111)
			(xy 95.799338 -121.506678) (xy 95.830132 -121.450663) (xy 95.867705 -121.398948) (xy 95.911462 -121.352351)
			(xy 95.960715 -121.311606) (xy 96.014686 -121.277355) (xy 96.072525 -121.250138) (xy 96.133318 -121.230385)
			(xy 96.196108 -121.218407) (xy 96.259904 -121.214394) (xy 96.3237 -121.218407) (xy 96.38649 -121.230385)
			(xy 96.447283 -121.250138) (xy 96.505122 -121.277355) (xy 96.559093 -121.311606) (xy 96.608346 -121.352351)
			(xy 96.652103 -121.398948) (xy 96.689676 -121.450663) (xy 96.72047 -121.506678) (xy 96.744002 -121.566111)
			(xy 96.759899 -121.628025) (xy 96.76791 -121.691443) (xy 96.767985 -121.696226) (xy 101.122732 -121.696226)
			(xy 101.126803 -121.640604) (xy 101.138929 -121.586167) (xy 101.158852 -121.534076) (xy 101.186148 -121.485441)
			(xy 101.220234 -121.441298) (xy 101.260383 -121.402589) (xy 101.305741 -121.370138) (xy 101.355341 -121.344637)
			(xy 101.408125 -121.32663) (xy 101.462968 -121.3165) (xy 101.518702 -121.314463) (xy 101.574139 -121.320563)
			(xy 101.628096 -121.334669) (xy 101.679425 -121.356481) (xy 101.727031 -121.385535) (xy 101.769899 -121.42121)
			(xy 101.807116 -121.462747) (xy 101.837889 -121.50926) (xy 101.861561 -121.559757) (xy 101.877629 -121.613164)
			(xy 101.885749 -121.66834) (xy 101.885901 -121.676668) (xy 104.627932 -121.676668) (xy 104.632003 -121.621046)
			(xy 104.644129 -121.566609) (xy 104.664052 -121.514518) (xy 104.691348 -121.465883) (xy 104.725434 -121.42174)
			(xy 104.765583 -121.383031) (xy 104.810941 -121.35058) (xy 104.860541 -121.325079) (xy 104.913325 -121.307072)
			(xy 104.968168 -121.296942) (xy 105.023902 -121.294905) (xy 105.079339 -121.301005) (xy 105.133296 -121.315111)
			(xy 105.184625 -121.336923) (xy 105.232231 -121.365977) (xy 105.275099 -121.401652) (xy 105.312316 -121.443189)
			(xy 105.343089 -121.489702) (xy 105.366761 -121.540199) (xy 105.382829 -121.593606) (xy 105.390949 -121.648782)
			(xy 105.391101 -121.65711) (xy 108.133132 -121.65711) (xy 108.137203 -121.601488) (xy 108.149329 -121.547051)
			(xy 108.169252 -121.49496) (xy 108.196548 -121.446325) (xy 108.230634 -121.402182) (xy 108.270783 -121.363473)
			(xy 108.316141 -121.331022) (xy 108.365741 -121.305521) (xy 108.418525 -121.287514) (xy 108.473368 -121.277384)
			(xy 108.529102 -121.275347) (xy 108.584539 -121.281447) (xy 108.638496 -121.295553) (xy 108.689825 -121.317365)
			(xy 108.737431 -121.346419) (xy 108.780299 -121.382094) (xy 108.817516 -121.423631) (xy 108.848289 -121.470144)
			(xy 108.871961 -121.520641) (xy 108.888029 -121.574048) (xy 108.896149 -121.629224) (xy 108.896658 -121.65711)
			(xy 108.896149 -121.684996) (xy 108.888029 -121.740172) (xy 108.871961 -121.793579) (xy 108.848289 -121.844076)
			(xy 108.817516 -121.890589) (xy 108.780299 -121.932126) (xy 108.737431 -121.967801) (xy 108.712194 -121.983203)
			(xy 112.914932 -121.983203) (xy 112.914932 -121.919281) (xy 112.922943 -121.855863) (xy 112.93884 -121.793949)
			(xy 112.962372 -121.734516) (xy 112.993166 -121.678501) (xy 113.030739 -121.626786) (xy 113.074496 -121.580189)
			(xy 113.123749 -121.539444) (xy 113.17772 -121.505193) (xy 113.235559 -121.477976) (xy 113.296352 -121.458223)
			(xy 113.359142 -121.446245) (xy 113.422938 -121.442232) (xy 113.486734 -121.446245) (xy 113.549524 -121.458223)
			(xy 113.610317 -121.477976) (xy 113.668156 -121.505193) (xy 113.722127 -121.539444) (xy 113.725837 -121.542513)
			(xy 114.62232 -121.542513) (xy 114.62232 -121.478591) (xy 114.630331 -121.415173) (xy 114.646228 -121.353259)
			(xy 114.66976 -121.293826) (xy 114.700554 -121.237811) (xy 114.738127 -121.186096) (xy 114.781884 -121.139499)
			(xy 114.831137 -121.098754) (xy 114.885108 -121.064503) (xy 114.942947 -121.037286) (xy 115.00374 -121.017533)
			(xy 115.06653 -121.005555) (xy 115.130326 -121.001542) (xy 115.194122 -121.005555) (xy 115.256912 -121.017533)
			(xy 115.317705 -121.037286) (xy 115.375544 -121.064503) (xy 115.429515 -121.098754) (xy 115.478768 -121.139499)
			(xy 115.522525 -121.186096) (xy 115.560098 -121.237811) (xy 115.590892 -121.293826) (xy 115.614424 -121.353259)
			(xy 115.630321 -121.415173) (xy 115.638332 -121.478591) (xy 115.638834 -121.510552) (xy 115.638332 -121.542513)
			(xy 115.630321 -121.605931) (xy 115.614424 -121.667845) (xy 115.590892 -121.727278) (xy 115.560098 -121.783293)
			(xy 115.522525 -121.835008) (xy 115.478768 -121.881605) (xy 115.429515 -121.92235) (xy 115.375544 -121.956601)
			(xy 115.317705 -121.983818) (xy 115.256912 -122.003571) (xy 115.194122 -122.015549) (xy 115.130326 -122.019563)
			(xy 115.06653 -122.015549) (xy 115.00374 -122.003571) (xy 114.942947 -121.983818) (xy 114.885108 -121.956601)
			(xy 114.831137 -121.92235) (xy 114.781884 -121.881605) (xy 114.738127 -121.835008) (xy 114.700554 -121.783293)
			(xy 114.66976 -121.727278) (xy 114.646228 -121.667845) (xy 114.630331 -121.605931) (xy 114.62232 -121.542513)
			(xy 113.725837 -121.542513) (xy 113.77138 -121.580189) (xy 113.815137 -121.626786) (xy 113.85271 -121.678501)
			(xy 113.883504 -121.734516) (xy 113.907036 -121.793949) (xy 113.922933 -121.855863) (xy 113.930944 -121.919281)
			(xy 113.931446 -121.951242) (xy 113.930944 -121.983203) (xy 113.922933 -122.046621) (xy 113.907036 -122.108535)
			(xy 113.883504 -122.167968) (xy 113.85271 -122.223983) (xy 113.815137 -122.275698) (xy 113.77138 -122.322295)
			(xy 113.722127 -122.36304) (xy 113.668156 -122.397291) (xy 113.610317 -122.424508) (xy 113.549524 -122.444261)
			(xy 113.486734 -122.456239) (xy 113.422938 -122.460253) (xy 113.359142 -122.456239) (xy 113.296352 -122.444261)
			(xy 113.235559 -122.424508) (xy 113.17772 -122.397291) (xy 113.123749 -122.36304) (xy 113.074496 -122.322295)
			(xy 113.030739 -122.275698) (xy 112.993166 -122.223983) (xy 112.962372 -122.167968) (xy 112.93884 -122.108535)
			(xy 112.922943 -122.046621) (xy 112.914932 -121.983203) (xy 108.712194 -121.983203) (xy 108.689825 -121.996855)
			(xy 108.638496 -122.018667) (xy 108.584539 -122.032773) (xy 108.529102 -122.038873) (xy 108.473368 -122.036836)
			(xy 108.418525 -122.026706) (xy 108.365741 -122.008699) (xy 108.316141 -121.983198) (xy 108.270783 -121.950747)
			(xy 108.230634 -121.912038) (xy 108.196548 -121.867895) (xy 108.169252 -121.81926) (xy 108.149329 -121.767169)
			(xy 108.137203 -121.712732) (xy 108.133132 -121.65711) (xy 105.391101 -121.65711) (xy 105.391458 -121.676668)
			(xy 105.390949 -121.704554) (xy 105.382829 -121.75973) (xy 105.366761 -121.813137) (xy 105.343089 -121.863634)
			(xy 105.312316 -121.910147) (xy 105.275099 -121.951684) (xy 105.232231 -121.987359) (xy 105.184625 -122.016413)
			(xy 105.133296 -122.038225) (xy 105.079339 -122.052331) (xy 105.023902 -122.058431) (xy 104.968168 -122.056394)
			(xy 104.913325 -122.046264) (xy 104.860541 -122.028257) (xy 104.810941 -122.002756) (xy 104.765583 -121.970305)
			(xy 104.725434 -121.931596) (xy 104.691348 -121.887453) (xy 104.664052 -121.838818) (xy 104.644129 -121.786727)
			(xy 104.632003 -121.73229) (xy 104.627932 -121.676668) (xy 101.885901 -121.676668) (xy 101.886258 -121.696226)
			(xy 101.885749 -121.724112) (xy 101.877629 -121.779288) (xy 101.861561 -121.832695) (xy 101.837889 -121.883192)
			(xy 101.807116 -121.929705) (xy 101.769899 -121.971242) (xy 101.727031 -122.006917) (xy 101.679425 -122.035971)
			(xy 101.628096 -122.057783) (xy 101.574139 -122.071889) (xy 101.518702 -122.077989) (xy 101.462968 -122.075952)
			(xy 101.408125 -122.065822) (xy 101.355341 -122.047815) (xy 101.305741 -122.022314) (xy 101.260383 -121.989863)
			(xy 101.220234 -121.951154) (xy 101.186148 -121.907011) (xy 101.158852 -121.858376) (xy 101.138929 -121.806285)
			(xy 101.126803 -121.751848) (xy 101.122732 -121.696226) (xy 96.767985 -121.696226) (xy 96.768412 -121.723404)
			(xy 96.76791 -121.755365) (xy 96.759899 -121.818783) (xy 96.744002 -121.880697) (xy 96.72047 -121.94013)
			(xy 96.689676 -121.996145) (xy 96.652103 -122.04786) (xy 96.608346 -122.094457) (xy 96.559093 -122.135202)
			(xy 96.505122 -122.169453) (xy 96.447283 -122.19667) (xy 96.38649 -122.216423) (xy 96.3237 -122.228401)
			(xy 96.259904 -122.232415) (xy 96.196108 -122.228401) (xy 96.133318 -122.216423) (xy 96.072525 -122.19667)
			(xy 96.014686 -122.169453) (xy 95.960715 -122.135202) (xy 95.911462 -122.094457) (xy 95.867705 -122.04786)
			(xy 95.830132 -121.996145) (xy 95.799338 -121.94013) (xy 95.775806 -121.880697) (xy 95.759909 -121.818783)
			(xy 95.751898 -121.755365) (xy 21.98878 -121.755365) (xy 21.98878 -122.936) (xy 111.250982 -122.936)
			(xy 111.255053 -122.880378) (xy 111.267179 -122.825941) (xy 111.287102 -122.77385) (xy 111.314398 -122.725215)
			(xy 111.348484 -122.681072) (xy 111.388633 -122.642363) (xy 111.433991 -122.609912) (xy 111.483591 -122.584411)
			(xy 111.536375 -122.566404) (xy 111.591218 -122.556274) (xy 111.646952 -122.554237) (xy 111.702389 -122.560337)
			(xy 111.756346 -122.574443) (xy 111.807675 -122.596255) (xy 111.855281 -122.625309) (xy 111.898149 -122.660984)
			(xy 111.935366 -122.702521) (xy 111.966139 -122.749034) (xy 111.989811 -122.799531) (xy 112.005879 -122.852938)
			(xy 112.013999 -122.908114) (xy 112.014508 -122.936) (xy 112.013999 -122.963886) (xy 112.005879 -123.019062)
			(xy 111.989811 -123.072469) (xy 111.966139 -123.122966) (xy 111.935366 -123.169479) (xy 111.898149 -123.211016)
			(xy 111.855281 -123.246691) (xy 111.807675 -123.275745) (xy 111.756346 -123.297557) (xy 111.702389 -123.311663)
			(xy 111.646952 -123.317763) (xy 111.591218 -123.315726) (xy 111.536375 -123.305596) (xy 111.483591 -123.287589)
			(xy 111.433991 -123.262088) (xy 111.388633 -123.229637) (xy 111.348484 -123.190928) (xy 111.314398 -123.146785)
			(xy 111.287102 -123.09815) (xy 111.267179 -123.046059) (xy 111.255053 -122.991622) (xy 111.250982 -122.936)
			(xy 21.98878 -122.936) (xy 21.98878 -125.513338) (xy 35.46856 -125.513338) (xy 35.469005 -125.482207)
			(xy 35.476614 -125.42041) (xy 35.49171 -125.360005) (xy 35.514068 -125.301895) (xy 35.543352 -125.246949)
			(xy 35.579126 -125.195988) (xy 35.620853 -125.149777) (xy 35.644074 -125.129036) (xy 35.650723 -125.122704)
			(xy 35.659458 -125.106574) (xy 35.661092 -125.09754) (xy 35.66541 -125.06706) (xy 35.666237 -125.05801)
			(xy 35.662216 -125.040304) (xy 35.657536 -125.032516) (xy 35.642895 -125.009164) (xy 35.619722 -124.959157)
			(xy 35.603998 -124.906333) (xy 35.59605 -124.851794) (xy 35.59556 -124.824236) (xy 35.596084 -124.795919)
			(xy 35.604473 -124.73991) (xy 35.621043 -124.685754) (xy 35.64543 -124.63464) (xy 35.660838 -124.610876)
			(xy 35.665663 -124.602993) (xy 35.669967 -124.585035) (xy 35.66922 -124.575824) (xy 35.664902 -124.54509)
			(xy 35.663369 -124.535868) (xy 35.654498 -124.519428) (xy 35.64763 -124.513086) (xy 35.623941 -124.492368)
			(xy 35.581398 -124.44599) (xy 35.544904 -124.394716) (xy 35.515018 -124.33933) (xy 35.492196 -124.280678)
			(xy 35.476787 -124.219659) (xy 35.469027 -124.157204) (xy 35.46856 -124.125736) (xy 35.469062 -124.093775)
			(xy 35.477073 -124.030357) (xy 35.49297 -123.968443) (xy 35.516502 -123.90901) (xy 35.547296 -123.852995)
			(xy 35.584869 -123.80128) (xy 35.628626 -123.754683) (xy 35.677879 -123.713938) (xy 35.73185 -123.679687)
			(xy 35.789689 -123.65247) (xy 35.850482 -123.632717) (xy 35.913272 -123.620739) (xy 35.977068 -123.616726)
			(xy 36.040864 -123.620739) (xy 36.103654 -123.632717) (xy 36.164447 -123.65247) (xy 36.222286 -123.679687)
			(xy 36.276257 -123.713938) (xy 36.32551 -123.754683) (xy 36.369267 -123.80128) (xy 36.40684 -123.852995)
			(xy 36.437634 -123.90901) (xy 36.461166 -123.968443) (xy 36.477063 -124.030357) (xy 36.485074 -124.093775)
			(xy 36.485576 -124.125736) (xy 36.485096 -124.157202) (xy 36.477327 -124.219652) (xy 36.461912 -124.280666)
			(xy 36.439087 -124.339312) (xy 36.4092 -124.394693) (xy 36.376277 -124.44095) (xy 117.962932 -124.44095)
			(xy 117.967003 -124.385328) (xy 117.979129 -124.330891) (xy 117.999052 -124.2788) (xy 118.026348 -124.230165)
			(xy 118.060434 -124.186022) (xy 118.100583 -124.147313) (xy 118.145941 -124.114862) (xy 118.195541 -124.089361)
			(xy 118.248325 -124.071354) (xy 118.303168 -124.061224) (xy 118.358902 -124.059187) (xy 118.414339 -124.065287)
			(xy 118.468296 -124.079393) (xy 118.519625 -124.101205) (xy 118.567231 -124.130259) (xy 118.610099 -124.165934)
			(xy 118.647316 -124.207471) (xy 118.678089 -124.253984) (xy 118.701761 -124.304481) (xy 118.717829 -124.357888)
			(xy 118.725949 -124.413064) (xy 118.726458 -124.44095) (xy 118.725949 -124.468836) (xy 118.717829 -124.524012)
			(xy 118.701761 -124.577419) (xy 118.678089 -124.627916) (xy 118.647316 -124.674429) (xy 118.610099 -124.715966)
			(xy 118.567231 -124.751641) (xy 118.519625 -124.780695) (xy 118.468296 -124.802507) (xy 118.414339 -124.816613)
			(xy 118.358902 -124.822713) (xy 118.303168 -124.820676) (xy 118.248325 -124.810546) (xy 118.195541 -124.792539)
			(xy 118.145941 -124.767038) (xy 118.100583 -124.734587) (xy 118.060434 -124.695878) (xy 118.026348 -124.651735)
			(xy 117.999052 -124.6031) (xy 117.979129 -124.551009) (xy 117.967003 -124.496572) (xy 117.962932 -124.44095)
			(xy 36.376277 -124.44095) (xy 36.372708 -124.445964) (xy 36.330169 -124.492341) (xy 36.306506 -124.513086)
			(xy 36.299729 -124.5195) (xy 36.290869 -124.535904) (xy 36.289234 -124.54509) (xy 36.284916 -124.575824)
			(xy 36.284103 -124.585042) (xy 36.288401 -124.603024) (xy 36.293298 -124.610876) (xy 36.308713 -124.634636)
			(xy 36.333115 -124.685746) (xy 36.349686 -124.739904) (xy 36.358061 -124.795918) (xy 36.358576 -124.824236)
			(xy 36.358088 -124.851794) (xy 36.350143 -124.906335) (xy 36.334423 -124.959162) (xy 36.311257 -125.009174)
			(xy 36.2966 -125.032516) (xy 36.291957 -125.040321) (xy 36.28792 -125.058015) (xy 36.288726 -125.06706)
			(xy 36.293044 -125.09754) (xy 36.294665 -125.106581) (xy 36.303386 -125.122729) (xy 36.310062 -125.129036)
			(xy 36.333298 -125.149759) (xy 36.375024 -125.195973) (xy 36.410793 -125.246937) (xy 36.440073 -125.301886)
			(xy 36.462423 -125.36) (xy 36.47751 -125.420408) (xy 36.485108 -125.482206) (xy 36.485274 -125.493229)
			(xy 95.918776 -125.493229) (xy 95.918776 -125.429307) (xy 95.926787 -125.365889) (xy 95.942684 -125.303975)
			(xy 95.966216 -125.244542) (xy 95.99701 -125.188527) (xy 96.034583 -125.136812) (xy 96.07834 -125.090215)
			(xy 96.127593 -125.04947) (xy 96.181564 -125.015219) (xy 96.239403 -124.988002) (xy 96.300196 -124.968249)
			(xy 96.362986 -124.956271) (xy 96.426782 -124.952258) (xy 96.490578 -124.956271) (xy 96.553368 -124.968249)
			(xy 96.614161 -124.988002) (xy 96.672 -125.015219) (xy 96.725971 -125.04947) (xy 96.775224 -125.090215)
			(xy 96.818981 -125.136812) (xy 96.856554 -125.188527) (xy 96.887348 -125.244542) (xy 96.91088 -125.303975)
			(xy 96.926777 -125.365889) (xy 96.934788 -125.429307) (xy 96.93529 -125.461268) (xy 96.934788 -125.493229)
			(xy 96.926777 -125.556647) (xy 96.922571 -125.573028) (xy 97.962718 -125.573028) (xy 97.966789 -125.517406)
			(xy 97.978915 -125.462969) (xy 97.998838 -125.410878) (xy 98.026134 -125.362243) (xy 98.06022 -125.3181)
			(xy 98.100369 -125.279391) (xy 98.145727 -125.24694) (xy 98.195327 -125.221439) (xy 98.248111 -125.203432)
			(xy 98.302954 -125.193302) (xy 98.358688 -125.191265) (xy 98.414125 -125.197365) (xy 98.468082 -125.211471)
			(xy 98.519411 -125.233283) (xy 98.567017 -125.262337) (xy 98.609885 -125.298012) (xy 98.647102 -125.339549)
			(xy 98.677875 -125.386062) (xy 98.701547 -125.436559) (xy 98.717615 -125.489966) (xy 98.725735 -125.545142)
			(xy 98.726244 -125.573028) (xy 98.725924 -125.590554) (xy 102.422704 -125.590554) (xy 102.426775 -125.534932)
			(xy 102.438901 -125.480495) (xy 102.458824 -125.428404) (xy 102.48612 -125.379769) (xy 102.520206 -125.335626)
			(xy 102.560355 -125.296917) (xy 102.605713 -125.264466) (xy 102.655313 -125.238965) (xy 102.708097 -125.220958)
			(xy 102.76294 -125.210828) (xy 102.818674 -125.208791) (xy 102.874111 -125.214891) (xy 102.928068 -125.228997)
			(xy 102.979397 -125.250809) (xy 103.027003 -125.279863) (xy 103.069871 -125.315538) (xy 103.107088 -125.357075)
			(xy 103.137861 -125.403588) (xy 103.161533 -125.454085) (xy 103.177601 -125.507492) (xy 103.185721 -125.562668)
			(xy 103.185873 -125.570996) (xy 105.927904 -125.570996) (xy 105.931975 -125.515374) (xy 105.944101 -125.460937)
			(xy 105.964024 -125.408846) (xy 105.99132 -125.360211) (xy 106.025406 -125.316068) (xy 106.065555 -125.277359)
			(xy 106.110913 -125.244908) (xy 106.160513 -125.219407) (xy 106.213297 -125.2014) (xy 106.26814 -125.19127)
			(xy 106.323874 -125.189233) (xy 106.379311 -125.195333) (xy 106.433268 -125.209439) (xy 106.484597 -125.231251)
			(xy 106.532203 -125.260305) (xy 106.575071 -125.29598) (xy 106.612288 -125.337517) (xy 106.643061 -125.38403)
			(xy 106.666733 -125.434527) (xy 106.682801 -125.487934) (xy 106.690921 -125.54311) (xy 106.691073 -125.551438)
			(xy 109.433104 -125.551438) (xy 109.437175 -125.495816) (xy 109.449301 -125.441379) (xy 109.469224 -125.389288)
			(xy 109.49652 -125.340653) (xy 109.530606 -125.29651) (xy 109.570755 -125.257801) (xy 109.616113 -125.22535)
			(xy 109.665713 -125.199849) (xy 109.718497 -125.181842) (xy 109.77334 -125.171712) (xy 109.829074 -125.169675)
			(xy 109.884511 -125.175775) (xy 109.938468 -125.189881) (xy 109.989797 -125.211693) (xy 110.037403 -125.240747)
			(xy 110.080271 -125.276422) (xy 110.117488 -125.317959) (xy 110.148261 -125.364472) (xy 110.171933 -125.414969)
			(xy 110.188001 -125.468376) (xy 110.196121 -125.523552) (xy 110.19663 -125.551438) (xy 110.196121 -125.579324)
			(xy 110.188001 -125.6345) (xy 110.171933 -125.687907) (xy 110.148261 -125.738404) (xy 110.117488 -125.784917)
			(xy 110.080271 -125.826454) (xy 110.037403 -125.862129) (xy 109.989797 -125.891183) (xy 109.938468 -125.912995)
			(xy 109.884511 -125.927101) (xy 109.829074 -125.933201) (xy 109.77334 -125.931164) (xy 109.718497 -125.921034)
			(xy 109.665713 -125.903027) (xy 109.616113 -125.877526) (xy 109.570755 -125.845075) (xy 109.530606 -125.806366)
			(xy 109.49652 -125.762223) (xy 109.469224 -125.713588) (xy 109.449301 -125.661497) (xy 109.437175 -125.60706)
			(xy 109.433104 -125.551438) (xy 106.691073 -125.551438) (xy 106.69143 -125.570996) (xy 106.690921 -125.598882)
			(xy 106.682801 -125.654058) (xy 106.666733 -125.707465) (xy 106.643061 -125.757962) (xy 106.612288 -125.804475)
			(xy 106.575071 -125.846012) (xy 106.532203 -125.881687) (xy 106.484597 -125.910741) (xy 106.433268 -125.932553)
			(xy 106.379311 -125.946659) (xy 106.323874 -125.952759) (xy 106.26814 -125.950722) (xy 106.213297 -125.940592)
			(xy 106.160513 -125.922585) (xy 106.110913 -125.897084) (xy 106.065555 -125.864633) (xy 106.025406 -125.825924)
			(xy 105.99132 -125.781781) (xy 105.964024 -125.733146) (xy 105.944101 -125.681055) (xy 105.931975 -125.626618)
			(xy 105.927904 -125.570996) (xy 103.185873 -125.570996) (xy 103.18623 -125.590554) (xy 103.185721 -125.61844)
			(xy 103.177601 -125.673616) (xy 103.161533 -125.727023) (xy 103.137861 -125.77752) (xy 103.107088 -125.824033)
			(xy 103.069871 -125.86557) (xy 103.027003 -125.901245) (xy 102.979397 -125.930299) (xy 102.928068 -125.952111)
			(xy 102.874111 -125.966217) (xy 102.818674 -125.972317) (xy 102.76294 -125.97028) (xy 102.708097 -125.96015)
			(xy 102.655313 -125.942143) (xy 102.605713 -125.916642) (xy 102.560355 -125.884191) (xy 102.520206 -125.845482)
			(xy 102.48612 -125.801339) (xy 102.458824 -125.752704) (xy 102.438901 -125.700613) (xy 102.426775 -125.646176)
			(xy 102.422704 -125.590554) (xy 98.725924 -125.590554) (xy 98.725735 -125.600914) (xy 98.717615 -125.65609)
			(xy 98.701547 -125.709497) (xy 98.677875 -125.759994) (xy 98.647102 -125.806507) (xy 98.609885 -125.848044)
			(xy 98.567017 -125.883719) (xy 98.519411 -125.912773) (xy 98.468082 -125.934585) (xy 98.414125 -125.948691)
			(xy 98.358688 -125.954791) (xy 98.302954 -125.952754) (xy 98.248111 -125.942624) (xy 98.195327 -125.924617)
			(xy 98.145727 -125.899116) (xy 98.100369 -125.866665) (xy 98.06022 -125.827956) (xy 98.026134 -125.783813)
			(xy 97.998838 -125.735178) (xy 97.978915 -125.683087) (xy 97.966789 -125.62865) (xy 97.962718 -125.573028)
			(xy 96.922571 -125.573028) (xy 96.91088 -125.618561) (xy 96.887348 -125.677994) (xy 96.856554 -125.734009)
			(xy 96.818981 -125.785724) (xy 96.775224 -125.832321) (xy 96.725971 -125.873066) (xy 96.672 -125.907317)
			(xy 96.614161 -125.934534) (xy 96.553368 -125.954287) (xy 96.490578 -125.966265) (xy 96.426782 -125.970279)
			(xy 96.362986 -125.966265) (xy 96.300196 -125.954287) (xy 96.239403 -125.934534) (xy 96.181564 -125.907317)
			(xy 96.127593 -125.873066) (xy 96.07834 -125.832321) (xy 96.034583 -125.785724) (xy 95.99701 -125.734009)
			(xy 95.966216 -125.677994) (xy 95.942684 -125.618561) (xy 95.926787 -125.556647) (xy 95.918776 -125.493229)
			(xy 36.485274 -125.493229) (xy 36.485576 -125.513338) (xy 36.485074 -125.545299) (xy 36.477063 -125.608717)
			(xy 36.461166 -125.670631) (xy 36.437634 -125.730064) (xy 36.40684 -125.786079) (xy 36.369267 -125.837794)
			(xy 36.32551 -125.884391) (xy 36.276257 -125.925136) (xy 36.222286 -125.959387) (xy 36.164447 -125.986604)
			(xy 36.103654 -126.006357) (xy 36.040864 -126.018335) (xy 35.977068 -126.022349) (xy 35.913272 -126.018335)
			(xy 35.850482 -126.006357) (xy 35.789689 -125.986604) (xy 35.73185 -125.959387) (xy 35.677879 -125.925136)
			(xy 35.628626 -125.884391) (xy 35.584869 -125.837794) (xy 35.547296 -125.786079) (xy 35.516502 -125.730064)
			(xy 35.49297 -125.670631) (xy 35.477073 -125.608717) (xy 35.469062 -125.545299) (xy 35.46856 -125.513338)
			(xy 21.98878 -125.513338) (xy 21.98878 -126.133309) (xy 85.937592 -126.133309) (xy 85.937592 -126.069387)
			(xy 85.945603 -126.005969) (xy 85.9615 -125.944055) (xy 85.985032 -125.884622) (xy 86.015826 -125.828607)
			(xy 86.053399 -125.776892) (xy 86.097156 -125.730295) (xy 86.146409 -125.68955) (xy 86.20038 -125.655299)
			(xy 86.258219 -125.628082) (xy 86.319012 -125.608329) (xy 86.381802 -125.596351) (xy 86.445598 -125.592338)
			(xy 86.509394 -125.596351) (xy 86.572184 -125.608329) (xy 86.632977 -125.628082) (xy 86.690816 -125.655299)
			(xy 86.744787 -125.68955) (xy 86.79404 -125.730295) (xy 86.837797 -125.776892) (xy 86.87537 -125.828607)
			(xy 86.906164 -125.884622) (xy 86.929696 -125.944055) (xy 86.945593 -126.005969) (xy 86.953604 -126.069387)
			(xy 86.954106 -126.101348) (xy 86.953604 -126.133309) (xy 86.947604 -126.180807) (xy 103.88193 -126.180807)
			(xy 103.88193 -126.116885) (xy 103.889941 -126.053467) (xy 103.905838 -125.991553) (xy 103.92937 -125.93212)
			(xy 103.960164 -125.876105) (xy 103.997737 -125.82439) (xy 104.041494 -125.777793) (xy 104.090747 -125.737048)
			(xy 104.144718 -125.702797) (xy 104.202557 -125.67558) (xy 104.26335 -125.655827) (xy 104.32614 -125.643849)
			(xy 104.389936 -125.639836) (xy 104.453732 -125.643849) (xy 104.516522 -125.655827) (xy 104.577315 -125.67558)
			(xy 104.635154 -125.702797) (xy 104.689125 -125.737048) (xy 104.738378 -125.777793) (xy 104.782135 -125.82439)
			(xy 104.819708 -125.876105) (xy 104.850502 -125.93212) (xy 104.874034 -125.991553) (xy 104.889931 -126.053467)
			(xy 104.897942 -126.116885) (xy 104.898444 -126.148846) (xy 104.898249 -126.161249) (xy 107.38713 -126.161249)
			(xy 107.38713 -126.097327) (xy 107.395141 -126.033909) (xy 107.411038 -125.971995) (xy 107.43457 -125.912562)
			(xy 107.465364 -125.856547) (xy 107.502937 -125.804832) (xy 107.546694 -125.758235) (xy 107.595947 -125.71749)
			(xy 107.649918 -125.683239) (xy 107.707757 -125.656022) (xy 107.76855 -125.636269) (xy 107.83134 -125.624291)
			(xy 107.895136 -125.620278) (xy 107.958932 -125.624291) (xy 108.021722 -125.636269) (xy 108.082515 -125.656022)
			(xy 108.140354 -125.683239) (xy 108.194325 -125.71749) (xy 108.243578 -125.758235) (xy 108.287335 -125.804832)
			(xy 108.324908 -125.856547) (xy 108.355702 -125.912562) (xy 108.379234 -125.971995) (xy 108.395131 -126.033909)
			(xy 108.403142 -126.097327) (xy 108.403644 -126.129288) (xy 108.403142 -126.161249) (xy 108.395131 -126.224667)
			(xy 108.379234 -126.286581) (xy 108.374333 -126.29896) (xy 113.857022 -126.29896) (xy 113.861093 -126.243338)
			(xy 113.873219 -126.188901) (xy 113.893142 -126.13681) (xy 113.920438 -126.088175) (xy 113.954524 -126.044032)
			(xy 113.994673 -126.005323) (xy 114.040031 -125.972872) (xy 114.089631 -125.947371) (xy 114.142415 -125.929364)
			(xy 114.197258 -125.919234) (xy 114.252992 -125.917197) (xy 114.308429 -125.923297) (xy 114.362386 -125.937403)
			(xy 114.413715 -125.959215) (xy 114.461321 -125.988269) (xy 114.504189 -126.023944) (xy 114.541406 -126.065481)
			(xy 114.572179 -126.111994) (xy 114.595851 -126.162491) (xy 114.611919 -126.215898) (xy 114.620039 -126.271074)
			(xy 114.620548 -126.29896) (xy 114.620039 -126.326846) (xy 114.611919 -126.382022) (xy 114.595851 -126.435429)
			(xy 114.572179 -126.485926) (xy 114.571865 -126.4864) (xy 115.676701 -126.4864) (xy 115.680715 -126.422606)
			(xy 115.692692 -126.359818) (xy 115.712445 -126.299026) (xy 115.739661 -126.241189) (xy 115.773911 -126.187219)
			(xy 115.814655 -126.137968) (xy 115.86125 -126.094211) (xy 115.912963 -126.05664) (xy 115.968976 -126.025846)
			(xy 116.028408 -126.002315) (xy 116.09032 -125.986418) (xy 116.153736 -125.978406) (xy 116.185696 -125.977904)
			(xy 116.217695 -125.978323) (xy 116.281187 -125.986364) (xy 116.343169 -126.002308) (xy 116.40266 -126.025903)
			(xy 116.45872 -126.056775) (xy 116.510465 -126.094437) (xy 116.557075 -126.138293) (xy 116.597815 -126.18765)
			(xy 116.63204 -126.241729) (xy 116.65921 -126.299675) (xy 116.678895 -126.360571) (xy 116.685314 -126.391924)
			(xy 116.685314 -126.392178) (xy 116.687857 -126.402442) (xy 116.699932 -126.419769) (xy 116.708682 -126.425706)
			(xy 116.772436 -126.465076) (xy 116.781699 -126.470099) (xy 116.802547 -126.472993) (xy 116.812822 -126.470664)
			(xy 116.813076 -126.470664) (xy 116.847036 -126.461645) (xy 116.916628 -126.451954) (xy 116.95176 -126.45136)
			(xy 116.952014 -126.45136) (xy 116.983972 -126.451927) (xy 117.047385 -126.459939) (xy 117.109294 -126.475836)
			(xy 117.168722 -126.499367) (xy 117.224732 -126.53016) (xy 117.276441 -126.56773) (xy 117.323034 -126.611485)
			(xy 117.363776 -126.660734) (xy 117.398023 -126.714702) (xy 117.425237 -126.772536) (xy 117.444989 -126.833324)
			(xy 117.456965 -126.896109) (xy 117.460979 -126.9599) (xy 117.456965 -127.023691) (xy 117.444989 -127.086476)
			(xy 117.425237 -127.147264) (xy 117.398023 -127.205098) (xy 117.363776 -127.259066) (xy 117.323034 -127.308315)
			(xy 117.276441 -127.35207) (xy 117.224732 -127.38964) (xy 117.168722 -127.420433) (xy 117.109294 -127.443964)
			(xy 117.047385 -127.459861) (xy 116.983972 -127.467873) (xy 116.952014 -127.468376) (xy 116.920017 -127.467883)
			(xy 116.856531 -127.459844) (xy 116.794555 -127.443904) (xy 116.735068 -127.420316) (xy 116.67901 -127.38945)
			(xy 116.627267 -127.351796) (xy 116.580656 -127.307949) (xy 116.539915 -127.2586) (xy 116.505687 -127.20453)
			(xy 116.478512 -127.146593) (xy 116.45882 -127.085705) (xy 116.452396 -127.054356) (xy 116.452396 -127.054102)
			(xy 116.449858 -127.043837) (xy 116.437779 -127.02651) (xy 116.429028 -127.020574) (xy 116.365274 -126.981204)
			(xy 116.356007 -126.976189) (xy 116.335162 -126.973287) (xy 116.324888 -126.975616) (xy 116.324634 -126.975616)
			(xy 116.290673 -126.984632) (xy 116.221082 -126.994326) (xy 116.18595 -126.99492) (xy 116.185696 -126.99492)
			(xy 116.153736 -126.994394) (xy 116.09032 -126.986382) (xy 116.028408 -126.970485) (xy 115.968976 -126.946954)
			(xy 115.912963 -126.91616) (xy 115.86125 -126.878589) (xy 115.814655 -126.834832) (xy 115.773911 -126.785581)
			(xy 115.739661 -126.731611) (xy 115.712445 -126.673774) (xy 115.692692 -126.612982) (xy 115.680715 -126.550194)
			(xy 115.676701 -126.4864) (xy 114.571865 -126.4864) (xy 114.541406 -126.532439) (xy 114.504189 -126.573976)
			(xy 114.461321 -126.609651) (xy 114.413715 -126.638705) (xy 114.362386 -126.660517) (xy 114.308429 -126.674623)
			(xy 114.252992 -126.680723) (xy 114.197258 -126.678686) (xy 114.142415 -126.668556) (xy 114.089631 -126.650549)
			(xy 114.040031 -126.625048) (xy 113.994673 -126.592597) (xy 113.954524 -126.553888) (xy 113.920438 -126.509745)
			(xy 113.893142 -126.46111) (xy 113.873219 -126.409019) (xy 113.861093 -126.354582) (xy 113.857022 -126.29896)
			(xy 108.374333 -126.29896) (xy 108.355702 -126.346014) (xy 108.324908 -126.402029) (xy 108.287335 -126.453744)
			(xy 108.243578 -126.500341) (xy 108.194325 -126.541086) (xy 108.140354 -126.575337) (xy 108.082515 -126.602554)
			(xy 108.021722 -126.622307) (xy 107.958932 -126.634285) (xy 107.895136 -126.638299) (xy 107.83134 -126.634285)
			(xy 107.76855 -126.622307) (xy 107.707757 -126.602554) (xy 107.649918 -126.575337) (xy 107.595947 -126.541086)
			(xy 107.546694 -126.500341) (xy 107.502937 -126.453744) (xy 107.465364 -126.402029) (xy 107.43457 -126.346014)
			(xy 107.411038 -126.286581) (xy 107.395141 -126.224667) (xy 107.38713 -126.161249) (xy 104.898249 -126.161249)
			(xy 104.897942 -126.180807) (xy 104.889931 -126.244225) (xy 104.874034 -126.306139) (xy 104.850502 -126.365572)
			(xy 104.819708 -126.421587) (xy 104.782135 -126.473302) (xy 104.738378 -126.519899) (xy 104.689125 -126.560644)
			(xy 104.635154 -126.594895) (xy 104.577315 -126.622112) (xy 104.516522 -126.641865) (xy 104.453732 -126.653843)
			(xy 104.389936 -126.657857) (xy 104.32614 -126.653843) (xy 104.26335 -126.641865) (xy 104.202557 -126.622112)
			(xy 104.144718 -126.594895) (xy 104.090747 -126.560644) (xy 104.041494 -126.519899) (xy 103.997737 -126.473302)
			(xy 103.960164 -126.421587) (xy 103.92937 -126.365572) (xy 103.905838 -126.306139) (xy 103.889941 -126.244225)
			(xy 103.88193 -126.180807) (xy 86.947604 -126.180807) (xy 86.945593 -126.196727) (xy 86.929696 -126.258641)
			(xy 86.906164 -126.318074) (xy 86.87537 -126.374089) (xy 86.837797 -126.425804) (xy 86.79404 -126.472401)
			(xy 86.744787 -126.513146) (xy 86.690816 -126.547397) (xy 86.632977 -126.574614) (xy 86.572184 -126.594367)
			(xy 86.509394 -126.606345) (xy 86.445598 -126.610359) (xy 86.381802 -126.606345) (xy 86.319012 -126.594367)
			(xy 86.258219 -126.574614) (xy 86.20038 -126.547397) (xy 86.146409 -126.513146) (xy 86.097156 -126.472401)
			(xy 86.053399 -126.425804) (xy 86.015826 -126.374089) (xy 85.985032 -126.318074) (xy 85.9615 -126.258641)
			(xy 85.945603 -126.196727) (xy 85.937592 -126.133309) (xy 21.98878 -126.133309) (xy 21.98878 -127.874014)
			(xy 34.642552 -127.874014) (xy 34.642552 -127.87376) (xy 34.643056 -127.831412) (xy 34.651107 -127.747098)
			(xy 34.667136 -127.663932) (xy 34.690997 -127.582665) (xy 34.722476 -127.504035) (xy 34.761287 -127.428754)
			(xy 34.807077 -127.357502) (xy 34.859433 -127.290926) (xy 34.917881 -127.229628) (xy 34.981891 -127.174163)
			(xy 35.050883 -127.125034) (xy 35.124233 -127.082685) (xy 35.201276 -127.047501) (xy 35.281315 -127.019799)
			(xy 35.363624 -126.999831) (xy 35.447459 -126.987778) (xy 35.53206 -126.983748) (xy 35.616661 -126.987778)
			(xy 35.700496 -126.999831) (xy 35.782805 -127.019799) (xy 35.862844 -127.047501) (xy 35.939887 -127.082685)
			(xy 36.013237 -127.125034) (xy 36.082229 -127.174163) (xy 36.146239 -127.229628) (xy 36.204687 -127.290926)
			(xy 36.257043 -127.357502) (xy 36.302833 -127.428754) (xy 36.341644 -127.504035) (xy 36.342299 -127.505671)
			(xy 110.51133 -127.505671) (xy 110.51133 -127.441749) (xy 110.519341 -127.378331) (xy 110.535238 -127.316417)
			(xy 110.55877 -127.256984) (xy 110.589564 -127.200969) (xy 110.627137 -127.149254) (xy 110.670894 -127.102657)
			(xy 110.720147 -127.061912) (xy 110.774118 -127.027661) (xy 110.831957 -127.000444) (xy 110.89275 -126.980691)
			(xy 110.95554 -126.968713) (xy 111.019336 -126.9647) (xy 111.083132 -126.968713) (xy 111.145922 -126.980691)
			(xy 111.206715 -127.000444) (xy 111.264554 -127.027661) (xy 111.318525 -127.061912) (xy 111.367778 -127.102657)
			(xy 111.411535 -127.149254) (xy 111.449108 -127.200969) (xy 111.479902 -127.256984) (xy 111.503434 -127.316417)
			(xy 111.519331 -127.378331) (xy 111.527342 -127.441749) (xy 111.527844 -127.47371) (xy 111.527342 -127.505671)
			(xy 111.519331 -127.569089) (xy 111.510114 -127.604985) (xy 112.187476 -127.604985) (xy 112.187476 -127.541063)
			(xy 112.195487 -127.477645) (xy 112.211384 -127.415731) (xy 112.234916 -127.356298) (xy 112.26571 -127.300283)
			(xy 112.303283 -127.248568) (xy 112.34704 -127.201971) (xy 112.396293 -127.161226) (xy 112.450264 -127.126975)
			(xy 112.508103 -127.099758) (xy 112.568896 -127.080005) (xy 112.631686 -127.068027) (xy 112.695482 -127.064014)
			(xy 112.759278 -127.068027) (xy 112.822068 -127.080005) (xy 112.882861 -127.099758) (xy 112.9407 -127.126975)
			(xy 112.994671 -127.161226) (xy 113.043924 -127.201971) (xy 113.087681 -127.248568) (xy 113.125254 -127.300283)
			(xy 113.156048 -127.356298) (xy 113.17958 -127.415731) (xy 113.195477 -127.477645) (xy 113.203488 -127.541063)
			(xy 113.20399 -127.573024) (xy 113.203488 -127.604985) (xy 113.195477 -127.668403) (xy 113.17958 -127.730317)
			(xy 113.156048 -127.78975) (xy 113.125254 -127.845765) (xy 113.087681 -127.89748) (xy 113.043924 -127.944077)
			(xy 112.994671 -127.984822) (xy 112.9407 -128.019073) (xy 112.882861 -128.04629) (xy 112.822068 -128.066043)
			(xy 112.759278 -128.078021) (xy 112.695482 -128.082035) (xy 112.631686 -128.078021) (xy 112.568896 -128.066043)
			(xy 112.508103 -128.04629) (xy 112.450264 -128.019073) (xy 112.396293 -127.984822) (xy 112.34704 -127.944077)
			(xy 112.303283 -127.89748) (xy 112.26571 -127.845765) (xy 112.234916 -127.78975) (xy 112.211384 -127.730317)
			(xy 112.195487 -127.668403) (xy 112.187476 -127.604985) (xy 111.510114 -127.604985) (xy 111.503434 -127.631003)
			(xy 111.479902 -127.690436) (xy 111.449108 -127.746451) (xy 111.411535 -127.798166) (xy 111.367778 -127.844763)
			(xy 111.318525 -127.885508) (xy 111.264554 -127.919759) (xy 111.206715 -127.946976) (xy 111.145922 -127.966729)
			(xy 111.083132 -127.978707) (xy 111.019336 -127.982721) (xy 110.95554 -127.978707) (xy 110.89275 -127.966729)
			(xy 110.831957 -127.946976) (xy 110.774118 -127.919759) (xy 110.720147 -127.885508) (xy 110.670894 -127.844763)
			(xy 110.627137 -127.798166) (xy 110.589564 -127.746451) (xy 110.55877 -127.690436) (xy 110.535238 -127.631003)
			(xy 110.519341 -127.569089) (xy 110.51133 -127.505671) (xy 36.342299 -127.505671) (xy 36.373123 -127.582665)
			(xy 36.396984 -127.663932) (xy 36.413013 -127.747098) (xy 36.421064 -127.831412) (xy 36.421568 -127.87376)
			(xy 36.421568 -127.874014) (xy 36.421101 -127.914407) (xy 36.413782 -127.99486) (xy 36.399196 -128.074318)
			(xy 36.377464 -128.152126) (xy 36.348765 -128.227641) (xy 36.313335 -128.300243) (xy 36.29279 -128.335024)
			(xy 36.288157 -128.343492) (xy 36.285002 -128.362521) (xy 36.289054 -128.38138) (xy 36.29406 -128.389634)
			(xy 36.31799 -128.426247) (xy 36.359289 -128.503358) (xy 36.392816 -128.584152) (xy 36.418246 -128.667848)
			(xy 36.435333 -128.753637) (xy 36.440267 -128.8037) (xy 96.565622 -128.8037) (xy 96.569637 -128.739893)
			(xy 96.581618 -128.677092) (xy 96.601375 -128.616288) (xy 96.628598 -128.55844) (xy 96.662856 -128.50446)
			(xy 96.70361 -128.4552) (xy 96.750217 -128.411436) (xy 96.801942 -128.373859) (xy 96.857969 -128.343062)
			(xy 96.917414 -128.31953) (xy 96.97934 -128.303634) (xy 97.042769 -128.295625) (xy 97.074736 -128.295146)
			(xy 97.106616 -128.295675) (xy 97.169873 -128.303666) (xy 97.231634 -128.319505) (xy 97.290929 -128.342943)
			(xy 97.346828 -128.373613) (xy 97.372932 -128.39192) (xy 97.382086 -128.397976) (xy 97.403586 -128.402292)
			(xy 97.424924 -128.397236) (xy 97.433892 -128.390904) (xy 97.460743 -128.370752) (xy 97.518713 -128.33689)
			(xy 97.580637 -128.310955) (xy 97.645436 -128.293398) (xy 97.711983 -128.284527) (xy 97.74555 -128.28397)
			(xy 97.746058 -128.28397) (xy 97.778021 -128.284492) (xy 97.841443 -128.2925) (xy 97.903361 -128.308393)
			(xy 97.962798 -128.331922) (xy 98.018818 -128.362715) (xy 98.070537 -128.400286) (xy 98.117138 -128.444044)
			(xy 98.157887 -128.493298) (xy 98.192142 -128.547271) (xy 98.219361 -128.605112) (xy 98.239116 -128.665908)
			(xy 98.251095 -128.728701) (xy 98.25511 -128.7925) (xy 98.252397 -128.835615) (xy 100.37673 -128.835615)
			(xy 100.37673 -128.771693) (xy 100.384741 -128.708275) (xy 100.400638 -128.646361) (xy 100.42417 -128.586928)
			(xy 100.454964 -128.530913) (xy 100.492537 -128.479198) (xy 100.536294 -128.432601) (xy 100.585547 -128.391856)
			(xy 100.639518 -128.357605) (xy 100.697357 -128.330388) (xy 100.75815 -128.310635) (xy 100.82094 -128.298657)
			(xy 100.884736 -128.294644) (xy 100.948532 -128.298657) (xy 101.011322 -128.310635) (xy 101.072115 -128.330388)
			(xy 101.129954 -128.357605) (xy 101.183925 -128.391856) (xy 101.233178 -128.432601) (xy 101.276935 -128.479198)
			(xy 101.314508 -128.530913) (xy 101.345302 -128.586928) (xy 101.368834 -128.646361) (xy 101.384731 -128.708275)
			(xy 101.392742 -128.771693) (xy 101.393244 -128.803654) (xy 101.392815 -128.830958) (xy 101.773609 -128.830958)
			(xy 101.773609 -128.776442) (xy 101.781368 -128.722482) (xy 101.796728 -128.670174) (xy 101.819376 -128.620586)
			(xy 101.84885 -128.574725) (xy 101.884552 -128.533527) (xy 101.925754 -128.497829) (xy 101.971618 -128.468358)
			(xy 102.021208 -128.445715) (xy 102.073517 -128.43036) (xy 102.127478 -128.422607) (xy 102.154736 -128.422146)
			(xy 102.182439 -128.422621) (xy 102.237263 -128.430635) (xy 102.290353 -128.446491) (xy 102.340593 -128.469854)
			(xy 102.364032 -128.48463) (xy 102.372108 -128.489467) (xy 102.390483 -128.493493) (xy 102.399846 -128.492504)
			(xy 102.430072 -128.487678) (xy 102.439655 -128.485756) (xy 102.456383 -128.475677) (xy 102.462584 -128.46812)
			(xy 102.487767 -128.435818) (xy 102.543148 -128.375465) (xy 102.603842 -128.320457) (xy 102.669333 -128.27126)
			(xy 102.739069 -128.228289) (xy 102.812458 -128.191909) (xy 102.88888 -128.162427) (xy 102.967688 -128.140093)
			(xy 103.048216 -128.125095) (xy 103.12978 -128.117562) (xy 103.170736 -128.117092) (xy 103.213083 -128.117597)
			(xy 103.297394 -128.125651) (xy 103.380558 -128.141683) (xy 103.461821 -128.165547) (xy 103.540448 -128.197027)
			(xy 103.615727 -128.235839) (xy 103.686976 -128.28163) (xy 103.753549 -128.333986) (xy 103.814844 -128.392434)
			(xy 103.870307 -128.456443) (xy 103.919433 -128.525434) (xy 103.96178 -128.598782) (xy 103.996962 -128.675824)
			(xy 104.024663 -128.755861) (xy 104.038125 -128.811355) (xy 105.278851 -128.811355) (xy 105.278851 -128.756845)
			(xy 105.286609 -128.702891) (xy 105.301967 -128.650589) (xy 105.324613 -128.601006) (xy 105.354084 -128.555151)
			(xy 105.389782 -128.513957) (xy 105.43098 -128.478263) (xy 105.476838 -128.448796) (xy 105.526423 -128.426155)
			(xy 105.578726 -128.410802) (xy 105.632681 -128.403049) (xy 105.659936 -128.402588) (xy 105.687982 -128.4031)
			(xy 105.74347 -128.41131) (xy 105.79716 -128.427549) (xy 105.847898 -128.451466) (xy 105.871518 -128.466596)
			(xy 105.879138 -128.471676) (xy 105.897172 -128.475994) (xy 105.982008 -128.46431) (xy 105.998264 -128.45542)
			(xy 106.00436 -128.448562) (xy 106.032492 -128.416988) (xy 106.093781 -128.358712) (xy 106.160323 -128.306513)
			(xy 106.231516 -128.260864) (xy 106.306719 -128.222174) (xy 106.385254 -128.190794) (xy 106.466412 -128.167006)
			(xy 106.54946 -128.151025) (xy 106.63365 -128.142995) (xy 106.675936 -128.142492) (xy 106.718283 -128.142997)
			(xy 106.802594 -128.151051) (xy 106.885758 -128.167083) (xy 106.967021 -128.190947) (xy 107.045648 -128.222427)
			(xy 107.120927 -128.261239) (xy 107.192176 -128.30703) (xy 107.258749 -128.359386) (xy 107.320044 -128.417834)
			(xy 107.375507 -128.481843) (xy 107.424633 -128.550834) (xy 107.46698 -128.624182) (xy 107.502162 -128.701224)
			(xy 107.529863 -128.781261) (xy 107.54983 -128.863568) (xy 107.561883 -128.947401) (xy 107.565913 -129.032)
			(xy 107.561883 -129.116599) (xy 107.54983 -129.200432) (xy 107.529863 -129.282739) (xy 107.502162 -129.362776)
			(xy 107.46698 -129.439818) (xy 107.424633 -129.513166) (xy 107.375507 -129.582157) (xy 107.320044 -129.646166)
			(xy 107.295057 -129.669992) (xy 108.07606 -129.669992) (xy 108.081268 -129.60712) (xy 108.094213 -129.545374)
			(xy 108.114697 -129.485704) (xy 108.142404 -129.429026) (xy 108.176909 -129.376211) (xy 108.217682 -129.328069)
			(xy 108.264096 -129.28534) (xy 108.31544 -129.248681) (xy 108.370924 -129.218654) (xy 108.429696 -129.195721)
			(xy 108.490853 -129.180233) (xy 108.553456 -129.17243) (xy 108.585 -129.171954) (xy 108.629704 -129.173986)
			(xy 108.643607 -129.174638) (xy 108.670935 -129.169452) (xy 108.695851 -129.157088) (xy 108.71651 -129.138462)
			(xy 108.731379 -129.114954) (xy 108.739356 -129.088307) (xy 108.739851 -129.060496) (xy 108.732827 -129.033582)
			(xy 108.726224 -129.021332) (xy 108.70971 -128.991995) (xy 108.683677 -128.929909) (xy 108.666063 -128.864932)
			(xy 108.657175 -128.798199) (xy 108.656628 -128.764538) (xy 108.657027 -128.732995) (xy 108.664826 -128.670392)
			(xy 108.680308 -128.609234) (xy 108.703237 -128.550461) (xy 108.733259 -128.494976) (xy 108.769913 -128.44363)
			(xy 108.812637 -128.397212) (xy 108.860775 -128.356436) (xy 108.913586 -128.321927) (xy 108.970261 -128.294215)
			(xy 109.029928 -128.273726) (xy 109.091671 -128.260775) (xy 109.154542 -128.255561) (xy 109.217575 -128.258163)
			(xy 109.279802 -128.268543) (xy 109.340268 -128.286539) (xy 109.398043 -128.311877) (xy 109.45224 -128.344166)
			(xy 109.502028 -128.382911) (xy 109.508709 -128.389591) (xy 113.29009 -128.389591) (xy 113.29009 -128.325669)
			(xy 113.298101 -128.262251) (xy 113.313998 -128.200337) (xy 113.33753 -128.140904) (xy 113.368324 -128.084889)
			(xy 113.405897 -128.033174) (xy 113.449654 -127.986577) (xy 113.498907 -127.945832) (xy 113.552878 -127.911581)
			(xy 113.610717 -127.884364) (xy 113.67151 -127.864611) (xy 113.7343 -127.852633) (xy 113.798096 -127.84862)
			(xy 113.861892 -127.852633) (xy 113.924682 -127.864611) (xy 113.985475 -127.884364) (xy 114.043314 -127.911581)
			(xy 114.097285 -127.945832) (xy 114.146538 -127.986577) (xy 114.190295 -128.033174) (xy 114.227868 -128.084889)
			(xy 114.258662 -128.140904) (xy 114.282194 -128.200337) (xy 114.298091 -128.262251) (xy 114.306102 -128.325669)
			(xy 114.306604 -128.35763) (xy 114.306102 -128.389591) (xy 114.298091 -128.453009) (xy 114.282194 -128.514923)
			(xy 114.258662 -128.574356) (xy 114.227868 -128.630371) (xy 114.190295 -128.682086) (xy 114.146538 -128.728683)
			(xy 114.097285 -128.769428) (xy 114.043314 -128.803679) (xy 113.985475 -128.830896) (xy 113.924682 -128.850649)
			(xy 113.861892 -128.862627) (xy 113.798096 -128.866641) (xy 113.7343 -128.862627) (xy 113.67151 -128.850649)
			(xy 113.610717 -128.830896) (xy 113.552878 -128.803679) (xy 113.498907 -128.769428) (xy 113.449654 -128.728683)
			(xy 113.405897 -128.682086) (xy 113.368324 -128.630371) (xy 113.33753 -128.574356) (xy 113.313998 -128.514923)
			(xy 113.298101 -128.453009) (xy 113.29009 -128.389591) (xy 109.508709 -128.389591) (xy 109.54664 -128.427517)
			(xy 109.585392 -128.477298) (xy 109.617689 -128.531491) (xy 109.643035 -128.589262) (xy 109.661041 -128.649725)
			(xy 109.671429 -128.711951) (xy 109.674041 -128.774984) (xy 109.668835 -128.837856) (xy 109.655893 -128.899601)
			(xy 109.635413 -128.959271) (xy 109.60771 -129.015949) (xy 109.573209 -129.068766) (xy 109.532439 -129.116909)
			(xy 109.486028 -129.15964) (xy 109.434687 -129.196302) (xy 109.379206 -129.226332) (xy 109.320436 -129.249269)
			(xy 109.259281 -129.26476) (xy 109.196679 -129.272568) (xy 109.165136 -129.273046) (xy 109.120432 -129.271014)
			(xy 109.106527 -129.270391) (xy 109.0792 -129.275569) (xy 109.054282 -129.287927) (xy 109.033622 -129.306549)
			(xy 109.018752 -129.330054) (xy 109.010774 -129.356699) (xy 109.01028 -129.384509) (xy 109.017307 -129.41142)
			(xy 109.023912 -129.423668) (xy 109.040429 -129.453004) (xy 109.066461 -129.51509) (xy 109.084074 -129.580067)
			(xy 109.092961 -129.646801) (xy 109.093508 -129.680462) (xy 109.093073 -129.712006) (xy 109.085274 -129.77461)
			(xy 109.069791 -129.835768) (xy 109.046862 -129.894542) (xy 109.016839 -129.950028) (xy 108.980184 -130.001374)
			(xy 108.938241 -130.046941) (xy 111.78133 -130.046941) (xy 111.78133 -129.983019) (xy 111.789341 -129.919601)
			(xy 111.805238 -129.857687) (xy 111.82877 -129.798254) (xy 111.859564 -129.742239) (xy 111.897137 -129.690524)
			(xy 111.940894 -129.643927) (xy 111.990147 -129.603182) (xy 112.044118 -129.568931) (xy 112.101957 -129.541714)
			(xy 112.16275 -129.521961) (xy 112.22554 -129.509983) (xy 112.289336 -129.50597) (xy 112.353132 -129.509983)
			(xy 112.415922 -129.521961) (xy 112.476715 -129.541714) (xy 112.534554 -129.568931) (xy 112.588525 -129.603182)
			(xy 112.637778 -129.643927) (xy 112.681535 -129.690524) (xy 112.719108 -129.742239) (xy 112.749902 -129.798254)
			(xy 112.773434 -129.857687) (xy 112.789331 -129.919601) (xy 112.797342 -129.983019) (xy 112.797844 -130.01498)
			(xy 112.797342 -130.046941) (xy 113.05133 -130.046941) (xy 113.05133 -129.983019) (xy 113.059341 -129.919601)
			(xy 113.075238 -129.857687) (xy 113.09877 -129.798254) (xy 113.129564 -129.742239) (xy 113.167137 -129.690524)
			(xy 113.210894 -129.643927) (xy 113.260147 -129.603182) (xy 113.314118 -129.568931) (xy 113.371957 -129.541714)
			(xy 113.43275 -129.521961) (xy 113.49554 -129.509983) (xy 113.559336 -129.50597) (xy 113.623132 -129.509983)
			(xy 113.685922 -129.521961) (xy 113.746715 -129.541714) (xy 113.804554 -129.568931) (xy 113.858525 -129.603182)
			(xy 113.907778 -129.643927) (xy 113.951535 -129.690524) (xy 113.989108 -129.742239) (xy 114.019902 -129.798254)
			(xy 114.043434 -129.857687) (xy 114.059331 -129.919601) (xy 114.067342 -129.983019) (xy 114.067844 -130.01498)
			(xy 114.067342 -130.046941) (xy 114.32133 -130.046941) (xy 114.32133 -129.983019) (xy 114.329341 -129.919601)
			(xy 114.345238 -129.857687) (xy 114.36877 -129.798254) (xy 114.399564 -129.742239) (xy 114.437137 -129.690524)
			(xy 114.480894 -129.643927) (xy 114.530147 -129.603182) (xy 114.584118 -129.568931) (xy 114.641957 -129.541714)
			(xy 114.70275 -129.521961) (xy 114.76554 -129.509983) (xy 114.829336 -129.50597) (xy 114.893132 -129.509983)
			(xy 114.955922 -129.521961) (xy 115.016715 -129.541714) (xy 115.074554 -129.568931) (xy 115.128525 -129.603182)
			(xy 115.177778 -129.643927) (xy 115.221535 -129.690524) (xy 115.259108 -129.742239) (xy 115.289902 -129.798254)
			(xy 115.313434 -129.857687) (xy 115.329331 -129.919601) (xy 115.337342 -129.983019) (xy 115.337844 -130.01498)
			(xy 115.337342 -130.046941) (xy 115.59133 -130.046941) (xy 115.59133 -129.983019) (xy 115.599341 -129.919601)
			(xy 115.615238 -129.857687) (xy 115.63877 -129.798254) (xy 115.669564 -129.742239) (xy 115.707137 -129.690524)
			(xy 115.750894 -129.643927) (xy 115.800147 -129.603182) (xy 115.854118 -129.568931) (xy 115.911957 -129.541714)
			(xy 115.97275 -129.521961) (xy 116.03554 -129.509983) (xy 116.099336 -129.50597) (xy 116.163132 -129.509983)
			(xy 116.225922 -129.521961) (xy 116.286715 -129.541714) (xy 116.344554 -129.568931) (xy 116.398525 -129.603182)
			(xy 116.447778 -129.643927) (xy 116.491535 -129.690524) (xy 116.529108 -129.742239) (xy 116.559902 -129.798254)
			(xy 116.583434 -129.857687) (xy 116.599331 -129.919601) (xy 116.607342 -129.983019) (xy 116.607844 -130.01498)
			(xy 116.607342 -130.046941) (xy 116.599331 -130.110359) (xy 116.583434 -130.172273) (xy 116.559902 -130.231706)
			(xy 116.529108 -130.287721) (xy 116.491535 -130.339436) (xy 116.447778 -130.386033) (xy 116.398525 -130.426778)
			(xy 116.344554 -130.461029) (xy 116.286715 -130.488246) (xy 116.225922 -130.507999) (xy 116.163132 -130.519977)
			(xy 116.099336 -130.523991) (xy 116.03554 -130.519977) (xy 115.97275 -130.507999) (xy 115.911957 -130.488246)
			(xy 115.854118 -130.461029) (xy 115.800147 -130.426778) (xy 115.750894 -130.386033) (xy 115.707137 -130.339436)
			(xy 115.669564 -130.287721) (xy 115.63877 -130.231706) (xy 115.615238 -130.172273) (xy 115.599341 -130.110359)
			(xy 115.59133 -130.046941) (xy 115.337342 -130.046941) (xy 115.329331 -130.110359) (xy 115.313434 -130.172273)
			(xy 115.289902 -130.231706) (xy 115.259108 -130.287721) (xy 115.221535 -130.339436) (xy 115.177778 -130.386033)
			(xy 115.128525 -130.426778) (xy 115.074554 -130.461029) (xy 115.016715 -130.488246) (xy 114.955922 -130.507999)
			(xy 114.893132 -130.519977) (xy 114.829336 -130.523991) (xy 114.76554 -130.519977) (xy 114.70275 -130.507999)
			(xy 114.641957 -130.488246) (xy 114.584118 -130.461029) (xy 114.530147 -130.426778) (xy 114.480894 -130.386033)
			(xy 114.437137 -130.339436) (xy 114.399564 -130.287721) (xy 114.36877 -130.231706) (xy 114.345238 -130.172273)
			(xy 114.329341 -130.110359) (xy 114.32133 -130.046941) (xy 114.067342 -130.046941) (xy 114.059331 -130.110359)
			(xy 114.043434 -130.172273) (xy 114.019902 -130.231706) (xy 113.989108 -130.287721) (xy 113.951535 -130.339436)
			(xy 113.907778 -130.386033) (xy 113.858525 -130.426778) (xy 113.804554 -130.461029) (xy 113.746715 -130.488246)
			(xy 113.685922 -130.507999) (xy 113.623132 -130.519977) (xy 113.559336 -130.523991) (xy 113.49554 -130.519977)
			(xy 113.43275 -130.507999) (xy 113.371957 -130.488246) (xy 113.314118 -130.461029) (xy 113.260147 -130.426778)
			(xy 113.210894 -130.386033) (xy 113.167137 -130.339436) (xy 113.129564 -130.287721) (xy 113.09877 -130.231706)
			(xy 113.075238 -130.172273) (xy 113.059341 -130.110359) (xy 113.05133 -130.046941) (xy 112.797342 -130.046941)
			(xy 112.789331 -130.110359) (xy 112.773434 -130.172273) (xy 112.749902 -130.231706) (xy 112.719108 -130.287721)
			(xy 112.681535 -130.339436) (xy 112.637778 -130.386033) (xy 112.588525 -130.426778) (xy 112.534554 -130.461029)
			(xy 112.476715 -130.488246) (xy 112.415922 -130.507999) (xy 112.353132 -130.519977) (xy 112.289336 -130.523991)
			(xy 112.22554 -130.519977) (xy 112.16275 -130.507999) (xy 112.101957 -130.488246) (xy 112.044118 -130.461029)
			(xy 111.990147 -130.426778) (xy 111.940894 -130.386033) (xy 111.897137 -130.339436) (xy 111.859564 -130.287721)
			(xy 111.82877 -130.231706) (xy 111.805238 -130.172273) (xy 111.789341 -130.110359) (xy 111.78133 -130.046941)
			(xy 108.938241 -130.046941) (xy 108.937458 -130.047792) (xy 108.88932 -130.088569) (xy 108.836507 -130.123077)
			(xy 108.779831 -130.150789) (xy 108.720162 -130.171276) (xy 108.658418 -130.184226) (xy 108.595546 -130.189439)
			(xy 108.532512 -130.186835) (xy 108.470284 -130.176454) (xy 108.409818 -130.158456) (xy 108.352043 -130.133116)
			(xy 108.297846 -130.100825) (xy 108.248059 -130.062077) (xy 108.203448 -130.017469) (xy 108.164697 -129.967686)
			(xy 108.132401 -129.913491) (xy 108.107057 -129.855717) (xy 108.089054 -129.795253) (xy 108.078669 -129.733026)
			(xy 108.07606 -129.669992) (xy 107.295057 -129.669992) (xy 107.258749 -129.704614) (xy 107.192176 -129.75697)
			(xy 107.120927 -129.802761) (xy 107.045648 -129.841573) (xy 106.967021 -129.873053) (xy 106.885758 -129.896917)
			(xy 106.802594 -129.912949) (xy 106.718283 -129.921003) (xy 106.675936 -129.921508) (xy 106.633544 -129.921005)
			(xy 106.549144 -129.912957) (xy 106.465893 -129.89691) (xy 106.384547 -129.873011) (xy 106.305846 -129.841477)
			(xy 106.230505 -129.802593) (xy 106.159207 -129.756715) (xy 106.092601 -129.704257) (xy 106.031291 -129.645697)
			(xy 105.975834 -129.581566) (xy 105.926733 -129.512447) (xy 105.884436 -129.438968) (xy 105.849326 -129.361797)
			(xy 105.821721 -129.281633) (xy 105.81132 -129.240534) (xy 105.808771 -129.231754) (xy 105.798494 -129.216652)
			(xy 105.791254 -129.21107) (xy 105.728262 -129.166874) (xy 105.710736 -129.162302) (xy 105.701338 -129.163318)
			(xy 105.69102 -129.164383) (xy 105.670308 -129.165527) (xy 105.659936 -129.165604) (xy 105.632681 -129.165151)
			(xy 105.578726 -129.157398) (xy 105.526423 -129.142045) (xy 105.476838 -129.119404) (xy 105.43098 -129.089937)
			(xy 105.389782 -129.054243) (xy 105.354084 -129.013049) (xy 105.324613 -128.967194) (xy 105.301967 -128.917611)
			(xy 105.286609 -128.865309) (xy 105.278851 -128.811355) (xy 104.038125 -128.811355) (xy 104.04463 -128.838168)
			(xy 104.056683 -128.922001) (xy 104.060713 -129.0066) (xy 104.056683 -129.091199) (xy 104.04463 -129.175032)
			(xy 104.024663 -129.257339) (xy 103.996962 -129.337376) (xy 103.96178 -129.414418) (xy 103.919433 -129.487766)
			(xy 103.870307 -129.556757) (xy 103.814844 -129.620766) (xy 103.753549 -129.679214) (xy 103.686976 -129.73157)
			(xy 103.61915 -129.775161) (xy 104.012994 -129.775161) (xy 104.012994 -129.711239) (xy 104.021005 -129.647821)
			(xy 104.036902 -129.585907) (xy 104.060434 -129.526474) (xy 104.091228 -129.470459) (xy 104.128801 -129.418744)
			(xy 104.172558 -129.372147) (xy 104.221811 -129.331402) (xy 104.275782 -129.297151) (xy 104.333621 -129.269934)
			(xy 104.394414 -129.250181) (xy 104.457204 -129.238203) (xy 104.521 -129.23419) (xy 104.584796 -129.238203)
			(xy 104.647586 -129.250181) (xy 104.708379 -129.269934) (xy 104.766218 -129.297151) (xy 104.820189 -129.331402)
			(xy 104.869442 -129.372147) (xy 104.913199 -129.418744) (xy 104.950772 -129.470459) (xy 104.981566 -129.526474)
			(xy 105.005098 -129.585907) (xy 105.020995 -129.647821) (xy 105.029006 -129.711239) (xy 105.029508 -129.7432)
			(xy 105.029006 -129.775161) (xy 105.020995 -129.838579) (xy 105.005098 -129.900493) (xy 104.981566 -129.959926)
			(xy 104.950772 -130.015941) (xy 104.913199 -130.067656) (xy 104.869442 -130.114253) (xy 104.820189 -130.154998)
			(xy 104.766218 -130.189249) (xy 104.708379 -130.216466) (xy 104.647586 -130.236219) (xy 104.584796 -130.248197)
			(xy 104.521 -130.252211) (xy 104.457204 -130.248197) (xy 104.394414 -130.236219) (xy 104.333621 -130.216466)
			(xy 104.275782 -130.189249) (xy 104.221811 -130.154998) (xy 104.172558 -130.114253) (xy 104.128801 -130.067656)
			(xy 104.091228 -130.015941) (xy 104.060434 -129.959926) (xy 104.036902 -129.900493) (xy 104.021005 -129.838579)
			(xy 104.012994 -129.775161) (xy 103.61915 -129.775161) (xy 103.615727 -129.777361) (xy 103.540448 -129.816173)
			(xy 103.461821 -129.847653) (xy 103.380558 -129.871517) (xy 103.297394 -129.887549) (xy 103.213083 -129.895603)
			(xy 103.170736 -129.896108) (xy 103.128959 -129.895628) (xy 103.045772 -129.887805) (xy 102.963685 -129.872214)
			(xy 102.883423 -129.848993) (xy 102.805692 -129.818346) (xy 102.731178 -129.780545) (xy 102.660538 -129.735922)
			(xy 102.594394 -129.68487) (xy 102.53333 -129.62784) (xy 102.477884 -129.565334) (xy 102.428544 -129.497903)
			(xy 102.385746 -129.426142) (xy 102.349867 -129.350684) (xy 102.321223 -129.272193) (xy 102.310184 -129.231898)
			(xy 102.307342 -129.222596) (xy 102.29585 -129.206924) (xy 102.287832 -129.201418) (xy 102.261162 -129.185162)
			(xy 102.252913 -129.18063) (xy 102.234414 -129.177244) (xy 102.225094 -129.178558) (xy 102.207669 -129.18165)
			(xy 102.172432 -129.184953) (xy 102.154736 -129.185162) (xy 102.127478 -129.184793) (xy 102.073517 -129.17704)
			(xy 102.021208 -129.161685) (xy 101.971618 -129.139042) (xy 101.925754 -129.109571) (xy 101.884552 -129.073873)
			(xy 101.84885 -129.032675) (xy 101.819376 -128.986814) (xy 101.796728 -128.937226) (xy 101.781368 -128.884918)
			(xy 101.773609 -128.830958) (xy 101.392815 -128.830958) (xy 101.392742 -128.835615) (xy 101.384731 -128.899033)
			(xy 101.368834 -128.960947) (xy 101.345302 -129.02038) (xy 101.314508 -129.076395) (xy 101.276935 -129.12811)
			(xy 101.233178 -129.174707) (xy 101.183925 -129.215452) (xy 101.129954 -129.249703) (xy 101.072115 -129.27692)
			(xy 101.011322 -129.296673) (xy 100.948532 -129.308651) (xy 100.884736 -129.312665) (xy 100.82094 -129.308651)
			(xy 100.75815 -129.296673) (xy 100.697357 -129.27692) (xy 100.639518 -129.249703) (xy 100.585547 -129.215452)
			(xy 100.536294 -129.174707) (xy 100.492537 -129.12811) (xy 100.454964 -129.076395) (xy 100.42417 -129.02038)
			(xy 100.400638 -128.960947) (xy 100.384741 -128.899033) (xy 100.37673 -128.835615) (xy 98.252397 -128.835615)
			(xy 98.251095 -128.856299) (xy 98.239116 -128.919092) (xy 98.219361 -128.979888) (xy 98.192142 -129.037729)
			(xy 98.157887 -129.091702) (xy 98.117138 -129.140956) (xy 98.070537 -129.184714) (xy 98.018818 -129.222285)
			(xy 97.962798 -129.253078) (xy 97.903361 -129.276607) (xy 97.841443 -129.2925) (xy 97.778021 -129.300508)
			(xy 97.746058 -129.300986) (xy 97.714178 -129.300454) (xy 97.650922 -129.292463) (xy 97.589161 -129.276625)
			(xy 97.529865 -129.253187) (xy 97.473966 -129.222519) (xy 97.447862 -129.204212) (xy 97.438713 -129.198147)
			(xy 97.417209 -129.19383) (xy 97.395869 -129.198892) (xy 97.386902 -129.205228) (xy 97.360056 -129.225388)
			(xy 97.302084 -129.259248) (xy 97.240159 -129.285181) (xy 97.175359 -129.302736) (xy 97.108812 -129.311606)
			(xy 97.075244 -129.312162) (xy 97.074736 -129.312162) (xy 97.042769 -129.311775) (xy 96.97934 -129.303766)
			(xy 96.917414 -129.28787) (xy 96.857969 -129.264338) (xy 96.801942 -129.233541) (xy 96.750217 -129.195964)
			(xy 96.70361 -129.1522) (xy 96.662856 -129.10294) (xy 96.628598 -129.04896) (xy 96.601375 -128.991112)
			(xy 96.581618 -128.930308) (xy 96.569637 -128.867507) (xy 96.565622 -128.8037) (xy 36.440267 -128.8037)
			(xy 36.443912 -128.840689) (xy 36.444428 -128.884426) (xy 36.444428 -128.88468) (xy 36.443924 -128.927028)
			(xy 36.435873 -129.011342) (xy 36.419844 -129.094508) (xy 36.395983 -129.175775) (xy 36.364504 -129.254405)
			(xy 36.325693 -129.329686) (xy 36.279903 -129.400938) (xy 36.227547 -129.467514) (xy 36.169099 -129.528812)
			(xy 36.105089 -129.584277) (xy 36.036097 -129.633406) (xy 35.962747 -129.675755) (xy 35.885704 -129.710939)
			(xy 35.805665 -129.738641) (xy 35.723356 -129.758609) (xy 35.639521 -129.770662) (xy 35.55492 -129.774693)
			(xy 35.470319 -129.770662) (xy 35.386484 -129.758609) (xy 35.304175 -129.738641) (xy 35.224136 -129.710939)
			(xy 35.147093 -129.675755) (xy 35.073743 -129.633406) (xy 35.004751 -129.584277) (xy 34.940741 -129.528812)
			(xy 34.882293 -129.467514) (xy 34.829937 -129.400938) (xy 34.784147 -129.329686) (xy 34.745336 -129.254405)
			(xy 34.713857 -129.175775) (xy 34.689996 -129.094508) (xy 34.673967 -129.011342) (xy 34.665916 -128.927028)
			(xy 34.665412 -128.88468) (xy 34.665412 -128.884426) (xy 34.665854 -128.844033) (xy 34.673178 -128.763579)
			(xy 34.687769 -128.68412) (xy 34.709506 -128.606313) (xy 34.738209 -128.530797) (xy 34.773644 -128.458196)
			(xy 34.79419 -128.423416) (xy 34.798793 -128.414934) (xy 34.80196 -128.395913) (xy 34.797921 -128.377059)
			(xy 34.79292 -128.368806) (xy 34.769005 -128.332183) (xy 34.727704 -128.255075) (xy 34.694175 -128.174283)
			(xy 34.668742 -128.090589) (xy 34.651652 -128.004801) (xy 34.64307 -127.917751) (xy 34.642552 -127.874014)
			(xy 21.98878 -127.874014) (xy 21.98878 -130.937465) (xy 87.566748 -130.937465) (xy 87.566748 -130.873543)
			(xy 87.574759 -130.810125) (xy 87.590656 -130.748211) (xy 87.614188 -130.688778) (xy 87.644982 -130.632763)
			(xy 87.682555 -130.581048) (xy 87.726312 -130.534451) (xy 87.775565 -130.493706) (xy 87.829536 -130.459455)
			(xy 87.887375 -130.432238) (xy 87.948168 -130.412485) (xy 88.010958 -130.400507) (xy 88.074754 -130.396494)
			(xy 88.13855 -130.400507) (xy 88.20134 -130.412485) (xy 88.262133 -130.432238) (xy 88.319972 -130.459455)
			(xy 88.373943 -130.493706) (xy 88.423196 -130.534451) (xy 88.466953 -130.581048) (xy 88.489692 -130.612345)
			(xy 118.526046 -130.612345) (xy 118.526046 -130.548423) (xy 118.534057 -130.485005) (xy 118.549954 -130.423091)
			(xy 118.573486 -130.363658) (xy 118.60428 -130.307643) (xy 118.641853 -130.255928) (xy 118.68561 -130.209331)
			(xy 118.734863 -130.168586) (xy 118.788834 -130.134335) (xy 118.846673 -130.107118) (xy 118.907466 -130.087365)
			(xy 118.970256 -130.075387) (xy 119.034052 -130.071374) (xy 119.097848 -130.075387) (xy 119.160638 -130.087365)
			(xy 119.221431 -130.107118) (xy 119.27927 -130.134335) (xy 119.333241 -130.168586) (xy 119.382494 -130.209331)
			(xy 119.426251 -130.255928) (xy 119.463824 -130.307643) (xy 119.494618 -130.363658) (xy 119.51815 -130.423091)
			(xy 119.534047 -130.485005) (xy 119.542058 -130.548423) (xy 119.54256 -130.580384) (xy 119.542058 -130.612345)
			(xy 119.534047 -130.675763) (xy 119.51815 -130.737677) (xy 119.494618 -130.79711) (xy 119.463824 -130.853125)
			(xy 119.426251 -130.90484) (xy 119.382494 -130.951437) (xy 119.333241 -130.992182) (xy 119.27927 -131.026433)
			(xy 119.221431 -131.05365) (xy 119.160638 -131.073403) (xy 119.097848 -131.085381) (xy 119.034052 -131.089395)
			(xy 118.970256 -131.085381) (xy 118.907466 -131.073403) (xy 118.846673 -131.05365) (xy 118.788834 -131.026433)
			(xy 118.734863 -130.992182) (xy 118.68561 -130.951437) (xy 118.641853 -130.90484) (xy 118.60428 -130.853125)
			(xy 118.573486 -130.79711) (xy 118.549954 -130.737677) (xy 118.534057 -130.675763) (xy 118.526046 -130.612345)
			(xy 88.489692 -130.612345) (xy 88.504526 -130.632763) (xy 88.53532 -130.688778) (xy 88.558852 -130.748211)
			(xy 88.574749 -130.810125) (xy 88.58276 -130.873543) (xy 88.583262 -130.905504) (xy 88.58276 -130.937465)
			(xy 88.574749 -131.000883) (xy 88.558852 -131.062797) (xy 88.53532 -131.12223) (xy 88.504526 -131.178245)
			(xy 88.478312 -131.214325) (xy 92.418402 -131.214325) (xy 92.418402 -131.150403) (xy 92.426413 -131.086985)
			(xy 92.44231 -131.025071) (xy 92.465842 -130.965638) (xy 92.496636 -130.909623) (xy 92.534209 -130.857908)
			(xy 92.577966 -130.811311) (xy 92.627219 -130.770566) (xy 92.68119 -130.736315) (xy 92.739029 -130.709098)
			(xy 92.799822 -130.689345) (xy 92.862612 -130.677367) (xy 92.926408 -130.673354) (xy 92.990204 -130.677367)
			(xy 93.052994 -130.689345) (xy 93.113787 -130.709098) (xy 93.171626 -130.736315) (xy 93.225597 -130.770566)
			(xy 93.27485 -130.811311) (xy 93.318607 -130.857908) (xy 93.35618 -130.909623) (xy 93.386974 -130.965638)
			(xy 93.410506 -131.025071) (xy 93.426403 -131.086985) (xy 93.434414 -131.150403) (xy 93.434916 -131.182364)
			(xy 93.434414 -131.214325) (xy 93.426403 -131.277743) (xy 93.410506 -131.339657) (xy 93.386974 -131.39909)
			(xy 93.35618 -131.455105) (xy 93.318607 -131.50682) (xy 93.27485 -131.553417) (xy 93.225597 -131.594162)
			(xy 93.171626 -131.628413) (xy 93.113787 -131.65563) (xy 93.052994 -131.675383) (xy 92.990204 -131.687361)
			(xy 92.926408 -131.691375) (xy 92.862612 -131.687361) (xy 92.799822 -131.675383) (xy 92.739029 -131.65563)
			(xy 92.68119 -131.628413) (xy 92.627219 -131.594162) (xy 92.577966 -131.553417) (xy 92.534209 -131.50682)
			(xy 92.496636 -131.455105) (xy 92.465842 -131.39909) (xy 92.44231 -131.339657) (xy 92.426413 -131.277743)
			(xy 92.418402 -131.214325) (xy 88.478312 -131.214325) (xy 88.466953 -131.22996) (xy 88.423196 -131.276557)
			(xy 88.373943 -131.317302) (xy 88.319972 -131.351553) (xy 88.262133 -131.37877) (xy 88.20134 -131.398523)
			(xy 88.13855 -131.410501) (xy 88.074754 -131.414515) (xy 88.010958 -131.410501) (xy 87.948168 -131.398523)
			(xy 87.887375 -131.37877) (xy 87.829536 -131.351553) (xy 87.775565 -131.317302) (xy 87.726312 -131.276557)
			(xy 87.682555 -131.22996) (xy 87.644982 -131.178245) (xy 87.614188 -131.12223) (xy 87.590656 -131.062797)
			(xy 87.574759 -131.000883) (xy 87.566748 -130.937465) (xy 21.98878 -130.937465) (xy 21.98878 -132.388864)
			(xy 30.324296 -132.388864) (xy 30.328367 -132.333242) (xy 30.340493 -132.278805) (xy 30.360416 -132.226714)
			(xy 30.387712 -132.178079) (xy 30.421798 -132.133936) (xy 30.461947 -132.095227) (xy 30.507305 -132.062776)
			(xy 30.556905 -132.037275) (xy 30.609689 -132.019268) (xy 30.664532 -132.009138) (xy 30.720266 -132.007101)
			(xy 30.775703 -132.013201) (xy 30.82966 -132.027307) (xy 30.880989 -132.049119) (xy 30.928595 -132.078173)
			(xy 30.971463 -132.113848) (xy 31.00868 -132.155385) (xy 31.039453 -132.201898) (xy 31.063125 -132.252395)
			(xy 31.079193 -132.305802) (xy 31.087313 -132.360978) (xy 31.087822 -132.388864) (xy 31.087313 -132.41675)
			(xy 31.079193 -132.471926) (xy 31.063125 -132.525333) (xy 31.039453 -132.57583) (xy 31.01076 -132.619199)
			(xy 36.825422 -132.619199) (xy 36.825422 -132.555277) (xy 36.833433 -132.491859) (xy 36.84933 -132.429945)
			(xy 36.872862 -132.370512) (xy 36.903656 -132.314497) (xy 36.941229 -132.262782) (xy 36.984986 -132.216185)
			(xy 37.034239 -132.17544) (xy 37.08821 -132.141189) (xy 37.146049 -132.113972) (xy 37.206842 -132.094219)
			(xy 37.269632 -132.082241) (xy 37.333428 -132.078228) (xy 37.397224 -132.082241) (xy 37.460014 -132.094219)
			(xy 37.520807 -132.113972) (xy 37.578646 -132.141189) (xy 37.632617 -132.17544) (xy 37.68187 -132.216185)
			(xy 37.725627 -132.262782) (xy 37.7632 -132.314497) (xy 37.793994 -132.370512) (xy 37.817526 -132.429945)
			(xy 37.833423 -132.491859) (xy 37.841434 -132.555277) (xy 37.841936 -132.587238) (xy 37.841434 -132.619199)
			(xy 37.833423 -132.682617) (xy 37.828164 -132.7031) (xy 54.783451 -132.7031) (xy 54.787465 -132.639299)
			(xy 54.799444 -132.576505) (xy 54.819198 -132.515707) (xy 54.846417 -132.457865) (xy 54.880671 -132.403889)
			(xy 54.921419 -132.354633) (xy 54.968019 -132.310872) (xy 55.019737 -132.273297) (xy 55.075756 -132.2425)
			(xy 55.135194 -132.218967) (xy 55.197112 -132.203068) (xy 55.260535 -132.195056) (xy 55.292498 -132.194554)
			(xy 55.32465 -132.195001) (xy 55.388441 -132.203101) (xy 55.4507 -132.219186) (xy 55.510432 -132.242999)
			(xy 55.566682 -132.274157) (xy 55.618551 -132.312164) (xy 55.66521 -132.356412) (xy 55.685944 -132.38099)
			(xy 55.692394 -132.388257) (xy 55.709384 -132.397653) (xy 55.718964 -132.399278) (xy 55.788814 -132.40766)
			(xy 55.79854 -132.408373) (xy 55.817348 -132.403272) (xy 55.82539 -132.397754) (xy 55.825644 -132.397754)
			(xy 55.847758 -132.381771) (xy 55.895641 -132.355614) (xy 55.946761 -132.33654) (xy 56.000075 -132.324937)
			(xy 56.054498 -132.321043) (xy 56.108921 -132.324937) (xy 56.162235 -132.33654) (xy 56.213355 -132.355614)
			(xy 56.261238 -132.381771) (xy 56.283352 -132.397754) (xy 56.283606 -132.397754) (xy 56.291646 -132.403281)
			(xy 56.310454 -132.40839) (xy 56.320182 -132.40766) (xy 56.390032 -132.399278) (xy 56.399598 -132.397616)
			(xy 56.416573 -132.388221) (xy 56.423052 -132.38099) (xy 56.443789 -132.356416) (xy 56.490453 -132.312175)
			(xy 56.542324 -132.274173) (xy 56.598573 -132.243017) (xy 56.658303 -132.219203) (xy 56.720559 -132.203113)
			(xy 56.784347 -132.195003) (xy 56.848649 -132.195003) (xy 56.912437 -132.203113) (xy 56.974693 -132.219203)
			(xy 57.034423 -132.243017) (xy 57.090672 -132.274173) (xy 57.142543 -132.312175) (xy 57.189207 -132.356416)
			(xy 57.209944 -132.38099) (xy 57.216394 -132.388257) (xy 57.233384 -132.397653) (xy 57.242964 -132.399278)
			(xy 57.312814 -132.40766) (xy 57.32254 -132.408373) (xy 57.341348 -132.403272) (xy 57.34939 -132.397754)
			(xy 57.349644 -132.397754) (xy 57.371758 -132.381771) (xy 57.419641 -132.355614) (xy 57.470761 -132.33654)
			(xy 57.524075 -132.324937) (xy 57.578498 -132.321043) (xy 57.632921 -132.324937) (xy 57.686235 -132.33654)
			(xy 57.737355 -132.355614) (xy 57.785238 -132.381771) (xy 57.807352 -132.397754) (xy 57.807606 -132.397754)
			(xy 57.815646 -132.403281) (xy 57.834454 -132.40839) (xy 57.844182 -132.40766) (xy 57.914032 -132.399278)
			(xy 57.923598 -132.397616) (xy 57.940573 -132.388221) (xy 57.947052 -132.38099) (xy 57.967831 -132.356455)
			(xy 58.014494 -132.312225) (xy 58.066361 -132.274231) (xy 58.122603 -132.243079) (xy 58.182325 -132.219266)
			(xy 58.244572 -132.203171) (xy 58.308351 -132.195053) (xy 58.340498 -132.194554) (xy 58.372458 -132.195111)
			(xy 58.435874 -132.203122) (xy 58.497786 -132.219018) (xy 58.557218 -132.242548) (xy 58.613231 -132.273342)
			(xy 58.664944 -132.310913) (xy 58.71154 -132.354669) (xy 58.752284 -132.40392) (xy 58.786534 -132.45789)
			(xy 58.81375 -132.515727) (xy 58.833502 -132.576518) (xy 58.84548 -132.639306) (xy 58.849494 -132.7031)
			(xy 58.84945 -132.7038) (xy 67.138113 -132.7038) (xy 67.142127 -132.64001) (xy 67.154103 -132.577227)
			(xy 67.173853 -132.516439) (xy 67.201065 -132.458606) (xy 67.235311 -132.404639) (xy 67.276051 -132.355389)
			(xy 67.322642 -132.311634) (xy 67.374349 -132.274063) (xy 67.430357 -132.243268) (xy 67.489783 -132.219735)
			(xy 67.551689 -132.203836) (xy 67.6151 -132.19582) (xy 67.647058 -132.195316) (xy 67.677295 -132.195727)
			(xy 67.737343 -132.202896) (xy 67.796117 -132.217138) (xy 67.852786 -132.238252) (xy 67.90655 -132.26594)
			(xy 67.95665 -132.29981) (xy 67.979798 -132.319268) (xy 67.98691 -132.325618) (xy 68.00469 -132.331968)
			(xy 68.092574 -132.329428) (xy 68.1101 -132.322062) (xy 68.116704 -132.315458) (xy 68.140497 -132.293181)
			(xy 68.192755 -132.254227) (xy 68.249562 -132.222268) (xy 68.309986 -132.197829) (xy 68.373037 -132.181309)
			(xy 68.437682 -132.172978) (xy 68.470272 -132.172456) (xy 68.502202 -132.17294) (xy 68.56556 -132.180928)
			(xy 68.627421 -132.196784) (xy 68.68681 -132.220256) (xy 68.742795 -132.250976) (xy 68.794496 -132.288462)
			(xy 68.841098 -132.332123) (xy 68.88187 -132.381273) (xy 68.91617 -132.435139) (xy 68.930266 -132.463794)
			(xy 68.934639 -132.472191) (xy 68.948333 -132.485244) (xy 68.956936 -132.489194) (xy 68.985638 -132.500878)
			(xy 68.994367 -132.503959) (xy 69.012858 -132.504358) (xy 69.021706 -132.50164) (xy 69.052587 -132.491423)
			(xy 69.116693 -132.480434) (xy 69.149214 -132.479796) (xy 69.149468 -132.479796) (xy 69.174398 -132.4802)
			(xy 69.223832 -132.486698) (xy 69.24802 -132.49275) (xy 69.257164 -132.49529) (xy 69.27596 -132.493004)
			(xy 69.354192 -132.452364) (xy 69.366384 -132.437886) (xy 69.369686 -132.428996) (xy 69.380709 -132.399841)
			(xy 69.408839 -132.344219) (xy 69.443555 -132.292451) (xy 69.484336 -132.245313) (xy 69.530571 -132.20351)
			(xy 69.581567 -132.16767) (xy 69.636561 -132.138329) (xy 69.694727 -132.115928) (xy 69.755194 -132.100801)
			(xy 69.817057 -132.093176) (xy 69.848222 -132.0927) (xy 69.880641 -132.09319) (xy 69.944954 -132.101434)
			(xy 70.007696 -132.117787) (xy 70.067851 -132.141983) (xy 70.124443 -132.173629) (xy 70.176552 -132.212212)
			(xy 70.223335 -132.257106) (xy 70.264031 -132.307582) (xy 70.297981 -132.362822) (xy 70.311772 -132.392166)
			(xy 70.316344 -132.402326) (xy 70.333362 -132.417058) (xy 70.430644 -132.444236) (xy 70.452742 -132.440426)
			(xy 70.46214 -132.433822) (xy 70.487687 -132.416754) (xy 70.542104 -132.388222) (xy 70.59956 -132.366453)
			(xy 70.659221 -132.351763) (xy 70.720217 -132.344366) (xy 70.750938 -132.343906) (xy 70.785793 -132.344504)
			(xy 70.854848 -132.354052) (xy 70.921956 -132.372925) (xy 70.954138 -132.386324) (xy 70.954392 -132.386324)
			(xy 70.96291 -132.389629) (xy 70.981145 -132.390535) (xy 70.989952 -132.388102) (xy 71.063358 -132.364226)
			(xy 71.077836 -132.352542) (xy 71.082408 -132.344668) (xy 71.097252 -132.320521) (xy 71.132881 -132.276441)
			(xy 71.174639 -132.238117) (xy 71.221606 -132.206391) (xy 71.27275 -132.181963) (xy 71.326945 -132.16537)
			(xy 71.382999 -132.156976) (xy 71.411338 -132.156454) (xy 71.441099 -132.157061) (xy 71.499899 -132.166309)
			(xy 71.55655 -132.184573) (xy 71.609678 -132.211412) (xy 71.657994 -132.246175) (xy 71.679562 -132.26669)
			(xy 71.68642 -132.273548) (xy 71.703692 -132.281168) (xy 71.791068 -132.284724) (xy 71.808594 -132.278882)
			(xy 71.81596 -132.272786) (xy 71.838824 -132.254382) (xy 71.888017 -132.222362) (xy 71.940569 -132.196219)
			(xy 71.995781 -132.1763) (xy 72.052919 -132.162871) (xy 72.111224 -132.156109) (xy 72.140572 -132.155692)
			(xy 72.172535 -132.156171) (xy 72.235959 -132.16418) (xy 72.297878 -132.180075) (xy 72.357317 -132.203606)
			(xy 72.413338 -132.234401) (xy 72.465057 -132.271974) (xy 72.511659 -132.315734) (xy 72.552409 -132.36499)
			(xy 72.586663 -132.418964) (xy 72.613883 -132.476807) (xy 72.633638 -132.537605) (xy 72.645617 -132.600399)
			(xy 72.649632 -132.6642) (xy 72.645617 -132.728001) (xy 72.633638 -132.790795) (xy 72.613883 -132.851593)
			(xy 72.586663 -132.909436) (xy 72.552409 -132.96341) (xy 72.511659 -133.012666) (xy 72.465057 -133.056426)
			(xy 72.413338 -133.093999) (xy 72.357317 -133.124794) (xy 72.297878 -133.148325) (xy 72.235959 -133.16422)
			(xy 72.172535 -133.172229) (xy 72.140572 -133.172708) (xy 72.107658 -133.172177) (xy 72.042381 -133.163683)
			(xy 71.978745 -133.146842) (xy 71.917811 -133.121935) (xy 71.860599 -133.089376) (xy 71.808064 -133.049711)
			(xy 71.761084 -133.003602) (xy 71.720442 -132.951819) (xy 71.703184 -132.923788) (xy 71.698358 -132.91566)
			(xy 71.68388 -132.903976) (xy 71.600314 -132.878322) (xy 71.581518 -132.879592) (xy 71.572882 -132.883656)
			(xy 71.547513 -132.894963) (xy 71.494315 -132.910919) (xy 71.439362 -132.918974) (xy 71.411592 -132.91947)
			(xy 71.411338 -132.91947) (xy 71.396995 -132.919326) (xy 71.36839 -132.917165) (xy 71.354188 -132.915152)
			(xy 71.35368 -132.915152) (xy 71.344587 -132.914229) (xy 71.326748 -132.918122) (xy 71.318882 -132.922772)
			(xy 71.254366 -132.964428) (xy 71.243444 -132.979414) (xy 71.240904 -132.988304) (xy 71.2316 -133.020045)
			(xy 71.205814 -133.080956) (xy 71.172346 -133.138009) (xy 71.131762 -133.19024) (xy 71.084747 -133.236766)
			(xy 71.032096 -133.276803) (xy 70.974697 -133.309674) (xy 70.91352 -133.334823) (xy 70.849598 -133.351826)
			(xy 70.78401 -133.360396) (xy 70.750938 -133.360922) (xy 70.718521 -133.360369) (xy 70.654212 -133.352132)
			(xy 70.591471 -133.335787) (xy 70.531317 -133.311599) (xy 70.474726 -133.279961) (xy 70.422616 -133.241386)
			(xy 70.375832 -133.1965) (xy 70.335134 -133.14603) (xy 70.301181 -133.090797) (xy 70.287388 -133.061456)
			(xy 70.282816 -133.051296) (xy 70.265798 -133.036564) (xy 70.168516 -133.009386) (xy 70.146418 -133.013196)
			(xy 70.13702 -133.0198) (xy 70.111458 -133.036845) (xy 70.057045 -133.06538) (xy 69.999592 -133.087154)
			(xy 69.939935 -133.101849) (xy 69.878942 -133.109252) (xy 69.848222 -133.109716) (xy 69.847968 -133.109716)
			(xy 69.815405 -133.10918) (xy 69.750816 -133.100846) (xy 69.687816 -133.084342) (xy 69.627435 -133.059939)
			(xy 69.598794 -133.044438) (xy 69.590412 -133.039612) (xy 69.571616 -133.036818) (xy 69.485764 -133.057138)
			(xy 69.470524 -133.067552) (xy 69.464936 -133.07568) (xy 69.449607 -133.09736) (xy 69.413982 -133.136728)
			(xy 69.373241 -133.170773) (xy 69.32817 -133.198836) (xy 69.279641 -133.220375) (xy 69.228594 -133.234973)
			(xy 69.176015 -133.242349) (xy 69.149468 -133.242812) (xy 69.122091 -133.242306) (xy 69.067898 -133.234475)
			(xy 69.015382 -133.218978) (xy 68.96562 -133.196134) (xy 68.919634 -133.166412) (xy 68.878368 -133.130422)
			(xy 68.860162 -133.10997) (xy 68.853789 -133.103277) (xy 68.837514 -133.094553) (xy 68.828412 -133.092952)
			(xy 68.797678 -133.088888) (xy 68.78825 -133.088012) (xy 68.769854 -133.092444) (xy 68.761864 -133.097524)
			(xy 68.736133 -133.114935) (xy 68.681281 -133.14411) (xy 68.623282 -133.166383) (xy 68.563001 -133.181421)
			(xy 68.501336 -133.189002) (xy 68.470272 -133.189472) (xy 68.440035 -133.189046) (xy 68.379988 -133.18188)
			(xy 68.321214 -133.167641) (xy 68.264545 -133.14653) (xy 68.210781 -133.118845) (xy 68.160681 -133.084977)
			(xy 68.137532 -133.06552) (xy 68.13042 -133.05917) (xy 68.11264 -133.05282) (xy 68.024756 -133.05536)
			(xy 68.00723 -133.062726) (xy 68.000626 -133.06933) (xy 67.976818 -133.091591) (xy 67.924563 -133.130547)
			(xy 67.86776 -133.162508) (xy 67.807338 -133.18695) (xy 67.74429 -133.203474) (xy 67.679647 -133.211808)
			(xy 67.647058 -133.212332) (xy 67.6151 -133.21178) (xy 67.551689 -133.203764) (xy 67.489783 -133.187865)
			(xy 67.430357 -133.164332) (xy 67.374349 -133.133537) (xy 67.322642 -133.095966) (xy 67.276051 -133.052211)
			(xy 67.235311 -133.002961) (xy 67.201065 -132.948994) (xy 67.173853 -132.891161) (xy 67.154103 -132.830373)
			(xy 67.142127 -132.76759) (xy 67.138113 -132.7038) (xy 58.84945 -132.7038) (xy 58.84548 -132.766894)
			(xy 58.833502 -132.829682) (xy 58.81375 -132.890473) (xy 58.786534 -132.94831) (xy 58.752284 -133.00228)
			(xy 58.71154 -133.051531) (xy 58.664944 -133.095287) (xy 58.613231 -133.132858) (xy 58.557218 -133.163652)
			(xy 58.497786 -133.187182) (xy 58.435874 -133.203078) (xy 58.372458 -133.211089) (xy 58.340498 -133.21157)
			(xy 58.308346 -133.211117) (xy 58.244556 -133.203017) (xy 58.182297 -133.186932) (xy 58.122566 -133.163121)
			(xy 58.066316 -133.131963) (xy 58.014446 -133.093957) (xy 57.967787 -133.049711) (xy 57.947052 -133.025134)
			(xy 57.940599 -133.01787) (xy 57.923612 -133.008471) (xy 57.914032 -133.006846) (xy 57.844182 -132.998464)
			(xy 57.834456 -132.997762) (xy 57.81565 -133.002858) (xy 57.807606 -133.00837) (xy 57.807352 -133.00837)
			(xy 57.785238 -133.024353) (xy 57.737355 -133.05051) (xy 57.686235 -133.069584) (xy 57.632921 -133.081187)
			(xy 57.578498 -133.085081) (xy 57.524075 -133.081187) (xy 57.470761 -133.069584) (xy 57.419641 -133.05051)
			(xy 57.371758 -133.024353) (xy 57.349644 -133.00837) (xy 57.34939 -133.00837) (xy 57.341349 -133.002843)
			(xy 57.322542 -132.997733) (xy 57.312814 -132.998464) (xy 57.242964 -133.006846) (xy 57.233395 -133.008499)
			(xy 57.216422 -133.0179) (xy 57.209944 -133.025134) (xy 57.189207 -133.049708) (xy 57.142543 -133.093949)
			(xy 57.090672 -133.131951) (xy 57.034423 -133.163107) (xy 56.974693 -133.186921) (xy 56.912437 -133.203011)
			(xy 56.848649 -133.211121) (xy 56.784347 -133.211121) (xy 56.720559 -133.203011) (xy 56.658303 -133.186921)
			(xy 56.598573 -133.163107) (xy 56.542324 -133.131951) (xy 56.490453 -133.093949) (xy 56.443789 -133.049708)
			(xy 56.423052 -133.025134) (xy 56.416599 -133.01787) (xy 56.399612 -133.008471) (xy 56.390032 -133.006846)
			(xy 56.320182 -132.998464) (xy 56.310456 -132.997762) (xy 56.29165 -133.002858) (xy 56.283606 -133.00837)
			(xy 56.283352 -133.00837) (xy 56.261238 -133.024353) (xy 56.213355 -133.05051) (xy 56.162235 -133.069584)
			(xy 56.108921 -133.081187) (xy 56.054498 -133.085081) (xy 56.000075 -133.081187) (xy 55.946761 -133.069584)
			(xy 55.895641 -133.05051) (xy 55.847758 -133.024353) (xy 55.825644 -133.00837) (xy 55.82539 -133.00837)
			(xy 55.817349 -133.002843) (xy 55.798542 -132.997733) (xy 55.788814 -132.998464) (xy 55.718964 -133.006846)
			(xy 55.709395 -133.008499) (xy 55.692422 -133.0179) (xy 55.685944 -133.025134) (xy 55.665173 -133.049676)
			(xy 55.618508 -133.093904) (xy 55.56664 -133.131897) (xy 55.510396 -133.163048) (xy 55.450673 -133.18686)
			(xy 55.388425 -133.202954) (xy 55.324645 -133.211071) (xy 55.292498 -133.21157) (xy 55.260535 -133.211144)
			(xy 55.197112 -133.203132) (xy 55.135194 -133.187233) (xy 55.075756 -133.1637) (xy 55.019737 -133.132903)
			(xy 54.968019 -133.095328) (xy 54.921419 -133.051567) (xy 54.880671 -133.002311) (xy 54.846417 -132.948335)
			(xy 54.819198 -132.890493) (xy 54.799444 -132.829695) (xy 54.787465 -132.766901) (xy 54.783451 -132.7031)
			(xy 37.828164 -132.7031) (xy 37.817526 -132.744531) (xy 37.793994 -132.803964) (xy 37.7632 -132.859979)
			(xy 37.725627 -132.911694) (xy 37.68187 -132.958291) (xy 37.632617 -132.999036) (xy 37.578646 -133.033287)
			(xy 37.520807 -133.060504) (xy 37.460014 -133.080257) (xy 37.397224 -133.092235) (xy 37.333428 -133.096249)
			(xy 37.269632 -133.092235) (xy 37.206842 -133.080257) (xy 37.146049 -133.060504) (xy 37.08821 -133.033287)
			(xy 37.034239 -132.999036) (xy 36.984986 -132.958291) (xy 36.941229 -132.911694) (xy 36.903656 -132.859979)
			(xy 36.872862 -132.803964) (xy 36.84933 -132.744531) (xy 36.833433 -132.682617) (xy 36.825422 -132.619199)
			(xy 31.01076 -132.619199) (xy 31.00868 -132.622343) (xy 30.971463 -132.66388) (xy 30.928595 -132.699555)
			(xy 30.880989 -132.728609) (xy 30.82966 -132.750421) (xy 30.775703 -132.764527) (xy 30.720266 -132.770627)
			(xy 30.664532 -132.76859) (xy 30.609689 -132.75846) (xy 30.556905 -132.740453) (xy 30.507305 -132.714952)
			(xy 30.461947 -132.682501) (xy 30.421798 -132.643792) (xy 30.387712 -132.599649) (xy 30.360416 -132.551014)
			(xy 30.340493 -132.498923) (xy 30.328367 -132.444486) (xy 30.324296 -132.388864) (xy 21.98878 -132.388864)
			(xy 21.98878 -133.370277) (xy 93.970342 -133.370277) (xy 93.970342 -133.306355) (xy 93.978353 -133.242937)
			(xy 93.99425 -133.181023) (xy 94.017782 -133.12159) (xy 94.048576 -133.065575) (xy 94.086149 -133.01386)
			(xy 94.129906 -132.967263) (xy 94.179159 -132.926518) (xy 94.23313 -132.892267) (xy 94.290969 -132.86505)
			(xy 94.351762 -132.845297) (xy 94.414552 -132.833319) (xy 94.478348 -132.829306) (xy 94.542144 -132.833319)
			(xy 94.604934 -132.845297) (xy 94.665727 -132.86505) (xy 94.723566 -132.892267) (xy 94.777537 -132.926518)
			(xy 94.82679 -132.967263) (xy 94.870547 -133.01386) (xy 94.90812 -133.065575) (xy 94.938914 -133.12159)
			(xy 94.962446 -133.181023) (xy 94.978343 -133.242937) (xy 94.986354 -133.306355) (xy 94.986653 -133.325362)
			(xy 95.107504 -133.325362) (xy 95.111575 -133.26974) (xy 95.123701 -133.215303) (xy 95.143624 -133.163212)
			(xy 95.17092 -133.114577) (xy 95.205006 -133.070434) (xy 95.245155 -133.031725) (xy 95.290513 -132.999274)
			(xy 95.340113 -132.973773) (xy 95.392897 -132.955766) (xy 95.44774 -132.945636) (xy 95.503474 -132.943599)
			(xy 95.558911 -132.949699) (xy 95.612868 -132.963805) (xy 95.664197 -132.985617) (xy 95.711803 -133.014671)
			(xy 95.754671 -133.050346) (xy 95.791888 -133.091883) (xy 95.822661 -133.138396) (xy 95.846333 -133.188893)
			(xy 95.862401 -133.2423) (xy 95.870521 -133.297476) (xy 95.87103 -133.325362) (xy 96.333816 -133.325362)
			(xy 96.337887 -133.26974) (xy 96.350013 -133.215303) (xy 96.369936 -133.163212) (xy 96.397232 -133.114577)
			(xy 96.431318 -133.070434) (xy 96.471467 -133.031725) (xy 96.516825 -132.999274) (xy 96.566425 -132.973773)
			(xy 96.619209 -132.955766) (xy 96.674052 -132.945636) (xy 96.729786 -132.943599) (xy 96.785223 -132.949699)
			(xy 96.83918 -132.963805) (xy 96.890509 -132.985617) (xy 96.938115 -133.014671) (xy 96.980983 -133.050346)
			(xy 97.0182 -133.091883) (xy 97.048973 -133.138396) (xy 97.072645 -133.188893) (xy 97.088713 -133.2423)
			(xy 97.096833 -133.297476) (xy 97.097342 -133.325362) (xy 97.096833 -133.353248) (xy 97.091554 -133.389116)
			(xy 98.027742 -133.389116) (xy 98.031813 -133.333494) (xy 98.043939 -133.279057) (xy 98.063862 -133.226966)
			(xy 98.091158 -133.178331) (xy 98.125244 -133.134188) (xy 98.165393 -133.095479) (xy 98.210751 -133.063028)
			(xy 98.260351 -133.037527) (xy 98.313135 -133.01952) (xy 98.367978 -133.00939) (xy 98.423712 -133.007353)
			(xy 98.479149 -133.013453) (xy 98.533106 -133.027559) (xy 98.584435 -133.049371) (xy 98.632041 -133.078425)
			(xy 98.674909 -133.1141) (xy 98.712126 -133.155637) (xy 98.742899 -133.20215) (xy 98.766571 -133.252647)
			(xy 98.782639 -133.306054) (xy 98.790759 -133.36123) (xy 98.791268 -133.389116) (xy 98.790759 -133.417002)
			(xy 98.782639 -133.472178) (xy 98.766571 -133.525585) (xy 98.742899 -133.576082) (xy 98.712126 -133.622595)
			(xy 98.674909 -133.664132) (xy 98.632041 -133.699807) (xy 98.584435 -133.728861) (xy 98.533106 -133.750673)
			(xy 98.479149 -133.764779) (xy 98.423712 -133.770879) (xy 98.367978 -133.768842) (xy 98.313135 -133.758712)
			(xy 98.260351 -133.740705) (xy 98.210751 -133.715204) (xy 98.165393 -133.682753) (xy 98.125244 -133.644044)
			(xy 98.091158 -133.599901) (xy 98.063862 -133.551266) (xy 98.043939 -133.499175) (xy 98.031813 -133.444738)
			(xy 98.027742 -133.389116) (xy 97.091554 -133.389116) (xy 97.088713 -133.408424) (xy 97.072645 -133.461831)
			(xy 97.048973 -133.512328) (xy 97.0182 -133.558841) (xy 96.980983 -133.600378) (xy 96.938115 -133.636053)
			(xy 96.890509 -133.665107) (xy 96.83918 -133.686919) (xy 96.785223 -133.701025) (xy 96.729786 -133.707125)
			(xy 96.674052 -133.705088) (xy 96.619209 -133.694958) (xy 96.566425 -133.676951) (xy 96.516825 -133.65145)
			(xy 96.471467 -133.618999) (xy 96.431318 -133.58029) (xy 96.397232 -133.536147) (xy 96.369936 -133.487512)
			(xy 96.350013 -133.435421) (xy 96.337887 -133.380984) (xy 96.333816 -133.325362) (xy 95.87103 -133.325362)
			(xy 95.870521 -133.353248) (xy 95.862401 -133.408424) (xy 95.846333 -133.461831) (xy 95.822661 -133.512328)
			(xy 95.791888 -133.558841) (xy 95.754671 -133.600378) (xy 95.711803 -133.636053) (xy 95.664197 -133.665107)
			(xy 95.612868 -133.686919) (xy 95.558911 -133.701025) (xy 95.503474 -133.707125) (xy 95.44774 -133.705088)
			(xy 95.392897 -133.694958) (xy 95.340113 -133.676951) (xy 95.290513 -133.65145) (xy 95.245155 -133.618999)
			(xy 95.205006 -133.58029) (xy 95.17092 -133.536147) (xy 95.143624 -133.487512) (xy 95.123701 -133.435421)
			(xy 95.111575 -133.380984) (xy 95.107504 -133.325362) (xy 94.986653 -133.325362) (xy 94.986856 -133.338316)
			(xy 94.986354 -133.370277) (xy 94.978343 -133.433695) (xy 94.962446 -133.495609) (xy 94.938914 -133.555042)
			(xy 94.90812 -133.611057) (xy 94.870547 -133.662772) (xy 94.82679 -133.709369) (xy 94.777537 -133.750114)
			(xy 94.734079 -133.777693) (xy 114.737636 -133.777693) (xy 114.737636 -133.713771) (xy 114.745647 -133.650353)
			(xy 114.761544 -133.588439) (xy 114.785076 -133.529006) (xy 114.81587 -133.472991) (xy 114.853443 -133.421276)
			(xy 114.8972 -133.374679) (xy 114.946453 -133.333934) (xy 115.000424 -133.299683) (xy 115.058263 -133.272466)
			(xy 115.119056 -133.252713) (xy 115.181846 -133.240735) (xy 115.245642 -133.236722) (xy 115.309438 -133.240735)
			(xy 115.372228 -133.252713) (xy 115.433021 -133.272466) (xy 115.49086 -133.299683) (xy 115.544831 -133.333934)
			(xy 115.594084 -133.374679) (xy 115.637841 -133.421276) (xy 115.675414 -133.472991) (xy 115.706208 -133.529006)
			(xy 115.72974 -133.588439) (xy 115.745637 -133.650353) (xy 115.753648 -133.713771) (xy 115.75415 -133.745732)
			(xy 115.753648 -133.777693) (xy 115.745637 -133.841111) (xy 115.72974 -133.903025) (xy 115.706208 -133.962458)
			(xy 115.675414 -134.018473) (xy 115.637841 -134.070188) (xy 115.594084 -134.116785) (xy 115.544831 -134.15753)
			(xy 115.49086 -134.191781) (xy 115.433021 -134.218998) (xy 115.372228 -134.238751) (xy 115.309438 -134.250729)
			(xy 115.245642 -134.254743) (xy 115.181846 -134.250729) (xy 115.119056 -134.238751) (xy 115.058263 -134.218998)
			(xy 115.000424 -134.191781) (xy 114.946453 -134.15753) (xy 114.8972 -134.116785) (xy 114.853443 -134.070188)
			(xy 114.81587 -134.018473) (xy 114.785076 -133.962458) (xy 114.761544 -133.903025) (xy 114.745647 -133.841111)
			(xy 114.737636 -133.777693) (xy 94.734079 -133.777693) (xy 94.723566 -133.784365) (xy 94.665727 -133.811582)
			(xy 94.604934 -133.831335) (xy 94.542144 -133.843313) (xy 94.478348 -133.847327) (xy 94.414552 -133.843313)
			(xy 94.351762 -133.831335) (xy 94.290969 -133.811582) (xy 94.23313 -133.784365) (xy 94.179159 -133.750114)
			(xy 94.129906 -133.709369) (xy 94.086149 -133.662772) (xy 94.048576 -133.611057) (xy 94.017782 -133.555042)
			(xy 93.99425 -133.495609) (xy 93.978353 -133.433695) (xy 93.970342 -133.370277) (xy 21.98878 -133.370277)
			(xy 21.98878 -133.857238) (xy 36.95141 -133.857238) (xy 36.955481 -133.801616) (xy 36.967607 -133.747179)
			(xy 36.98753 -133.695088) (xy 37.014826 -133.646453) (xy 37.048912 -133.60231) (xy 37.089061 -133.563601)
			(xy 37.134419 -133.53115) (xy 37.184019 -133.505649) (xy 37.236803 -133.487642) (xy 37.291646 -133.477512)
			(xy 37.34738 -133.475475) (xy 37.402817 -133.481575) (xy 37.456774 -133.495681) (xy 37.508103 -133.517493)
			(xy 37.555709 -133.546547) (xy 37.598577 -133.582222) (xy 37.635794 -133.623759) (xy 37.666567 -133.670272)
			(xy 37.690239 -133.720769) (xy 37.706307 -133.774176) (xy 37.714427 -133.829352) (xy 37.714936 -133.857238)
			(xy 37.714427 -133.885124) (xy 37.706307 -133.9403) (xy 37.690239 -133.993707) (xy 37.666567 -134.044204)
			(xy 37.635794 -134.090717) (xy 37.598577 -134.132254) (xy 37.555709 -134.167929) (xy 37.508103 -134.196983)
			(xy 37.456774 -134.218795) (xy 37.402817 -134.232901) (xy 37.34738 -134.239001) (xy 37.291646 -134.236964)
			(xy 37.236803 -134.226834) (xy 37.184019 -134.208827) (xy 37.134419 -134.183326) (xy 37.089061 -134.150875)
			(xy 37.048912 -134.112166) (xy 37.014826 -134.068023) (xy 36.98753 -134.019388) (xy 36.967607 -133.967297)
			(xy 36.955481 -133.91286) (xy 36.95141 -133.857238) (xy 21.98878 -133.857238) (xy 21.98878 -134.86257)
			(xy 33.86023 -134.86257) (xy 33.864301 -134.806948) (xy 33.876427 -134.752511) (xy 33.89635 -134.70042)
			(xy 33.923646 -134.651785) (xy 33.957732 -134.607642) (xy 33.997881 -134.568933) (xy 34.043239 -134.536482)
			(xy 34.092839 -134.510981) (xy 34.145623 -134.492974) (xy 34.200466 -134.482844) (xy 34.2562 -134.480807)
			(xy 34.311637 -134.486907) (xy 34.365594 -134.501013) (xy 34.416923 -134.522825) (xy 34.464529 -134.551879)
			(xy 34.507397 -134.587554) (xy 34.544614 -134.629091) (xy 34.575387 -134.675604) (xy 34.599059 -134.726101)
			(xy 34.615127 -134.779508) (xy 34.623247 -134.834684) (xy 34.623756 -134.86257) (xy 34.623247 -134.890456)
			(xy 34.615127 -134.945632) (xy 34.599059 -134.999039) (xy 34.575387 -135.049536) (xy 34.544614 -135.096049)
			(xy 34.507397 -135.137586) (xy 34.464529 -135.173261) (xy 34.416923 -135.202315) (xy 34.365594 -135.224127)
			(xy 34.311637 -135.238233) (xy 34.2562 -135.244333) (xy 34.200466 -135.242296) (xy 34.145623 -135.232166)
			(xy 34.092839 -135.214159) (xy 34.043239 -135.188658) (xy 33.997881 -135.156207) (xy 33.957732 -135.117498)
			(xy 33.923646 -135.073355) (xy 33.89635 -135.02472) (xy 33.876427 -134.972629) (xy 33.864301 -134.918192)
			(xy 33.86023 -134.86257) (xy 21.98878 -134.86257) (xy 21.98878 -137.925) (xy 82.248337 -137.925)
			(xy 82.25235 -137.861213) (xy 82.264326 -137.798432) (xy 82.284075 -137.737646) (xy 82.311287 -137.679816)
			(xy 82.345532 -137.625851) (xy 82.38627 -137.576604) (xy 82.43286 -137.532851) (xy 82.484565 -137.495281)
			(xy 82.540571 -137.464488) (xy 82.599995 -137.440957) (xy 82.661899 -137.425059) (xy 82.725307 -137.417044)
			(xy 82.757264 -137.41654) (xy 82.790822 -137.417066) (xy 82.857353 -137.425913) (xy 82.922143 -137.443434)
			(xy 82.984066 -137.469322) (xy 83.042046 -137.50313) (xy 83.095077 -137.544268) (xy 83.142238 -137.592023)
			(xy 83.162902 -137.61847) (xy 83.169546 -137.626486) (xy 83.18766 -137.63671) (xy 83.197954 -137.638282)
			(xy 83.27136 -137.646664) (xy 83.281783 -137.647271) (xy 83.301711 -137.641116) (xy 83.309968 -137.634726)
			(xy 83.330742 -137.617575) (xy 83.376244 -137.588734) (xy 83.425353 -137.566588) (xy 83.477091 -137.551577)
			(xy 83.530428 -137.544) (xy 83.557364 -137.54354) (xy 83.584622 -137.543905) (xy 83.638584 -137.551658)
			(xy 83.690892 -137.567013) (xy 83.740483 -137.589656) (xy 83.786347 -137.619127) (xy 83.827549 -137.654825)
			(xy 83.84069 -137.669989) (xy 88.535758 -137.669989) (xy 88.535758 -137.606067) (xy 88.543769 -137.542649)
			(xy 88.559666 -137.480735) (xy 88.583198 -137.421302) (xy 88.613992 -137.365287) (xy 88.651565 -137.313572)
			(xy 88.695322 -137.266975) (xy 88.744575 -137.22623) (xy 88.798546 -137.191979) (xy 88.856385 -137.164762)
			(xy 88.917178 -137.145009) (xy 88.979968 -137.133031) (xy 89.043764 -137.129018) (xy 89.10756 -137.133031)
			(xy 89.17035 -137.145009) (xy 89.231143 -137.164762) (xy 89.288982 -137.191979) (xy 89.342953 -137.22623)
			(xy 89.392206 -137.266975) (xy 89.435963 -137.313572) (xy 89.473536 -137.365287) (xy 89.50433 -137.421302)
			(xy 89.527862 -137.480735) (xy 89.543759 -137.542649) (xy 89.55177 -137.606067) (xy 89.552272 -137.638028)
			(xy 89.55177 -137.669989) (xy 89.543759 -137.733407) (xy 89.53989 -137.748475) (xy 94.810828 -137.748475)
			(xy 94.810828 -137.684553) (xy 94.818839 -137.621135) (xy 94.834736 -137.559221) (xy 94.858268 -137.499788)
			(xy 94.889062 -137.443773) (xy 94.926635 -137.392058) (xy 94.970392 -137.345461) (xy 95.019645 -137.304716)
			(xy 95.073616 -137.270465) (xy 95.131455 -137.243248) (xy 95.192248 -137.223495) (xy 95.255038 -137.211517)
			(xy 95.318834 -137.207504) (xy 95.38263 -137.211517) (xy 95.44542 -137.223495) (xy 95.506213 -137.243248)
			(xy 95.564052 -137.270465) (xy 95.618023 -137.304716) (xy 95.667276 -137.345461) (xy 95.711033 -137.392058)
			(xy 95.748606 -137.443773) (xy 95.7794 -137.499788) (xy 95.802932 -137.559221) (xy 95.818829 -137.621135)
			(xy 95.82684 -137.684553) (xy 95.827342 -137.716514) (xy 95.82684 -137.748475) (xy 95.818829 -137.811893)
			(xy 95.802932 -137.873807) (xy 95.7794 -137.93324) (xy 95.748606 -137.989255) (xy 95.711033 -138.04097)
			(xy 95.667276 -138.087567) (xy 95.618023 -138.128312) (xy 95.564052 -138.162563) (xy 95.506213 -138.18978)
			(xy 95.44542 -138.209533) (xy 95.38263 -138.221511) (xy 95.318834 -138.225525) (xy 95.255038 -138.221511)
			(xy 95.192248 -138.209533) (xy 95.131455 -138.18978) (xy 95.073616 -138.162563) (xy 95.019645 -138.128312)
			(xy 94.970392 -138.087567) (xy 94.926635 -138.04097) (xy 94.889062 -137.989255) (xy 94.858268 -137.93324)
			(xy 94.834736 -137.873807) (xy 94.818839 -137.811893) (xy 94.810828 -137.748475) (xy 89.53989 -137.748475)
			(xy 89.527862 -137.795321) (xy 89.50433 -137.854754) (xy 89.473536 -137.910769) (xy 89.435963 -137.962484)
			(xy 89.392206 -138.009081) (xy 89.342953 -138.049826) (xy 89.288982 -138.084077) (xy 89.231143 -138.111294)
			(xy 89.17035 -138.131047) (xy 89.10756 -138.143025) (xy 89.043764 -138.147039) (xy 88.979968 -138.143025)
			(xy 88.917178 -138.131047) (xy 88.856385 -138.111294) (xy 88.798546 -138.084077) (xy 88.744575 -138.049826)
			(xy 88.695322 -138.009081) (xy 88.651565 -137.962484) (xy 88.613992 -137.910769) (xy 88.583198 -137.854754)
			(xy 88.559666 -137.795321) (xy 88.543769 -137.733407) (xy 88.535758 -137.669989) (xy 83.84069 -137.669989)
			(xy 83.863251 -137.696024) (xy 83.892726 -137.741885) (xy 83.915374 -137.791474) (xy 83.930734 -137.843781)
			(xy 83.938493 -137.897742) (xy 83.938493 -137.952258) (xy 83.930734 -138.006219) (xy 83.915374 -138.058526)
			(xy 83.892726 -138.108115) (xy 83.863251 -138.153976) (xy 83.827549 -138.195175) (xy 83.786347 -138.230873)
			(xy 83.740483 -138.260344) (xy 83.690892 -138.282987) (xy 83.638584 -138.298342) (xy 83.584622 -138.306095)
			(xy 83.557364 -138.306556) (xy 83.53043 -138.306075) (xy 83.4771 -138.298489) (xy 83.425367 -138.283474)
			(xy 83.376263 -138.261328) (xy 83.330763 -138.232493) (xy 83.309968 -138.21537) (xy 83.301738 -138.208932)
			(xy 83.28179 -138.202776) (xy 83.27136 -138.203432) (xy 83.197954 -138.211814) (xy 83.187679 -138.213432)
			(xy 83.16959 -138.22366) (xy 83.162902 -138.231626) (xy 83.142228 -138.258066) (xy 83.09508 -138.305836)
			(xy 83.042055 -138.346984) (xy 82.984076 -138.380795) (xy 82.922151 -138.40668) (xy 82.857357 -138.42419)
			(xy 82.790823 -138.43302) (xy 82.757264 -138.433556) (xy 82.725307 -138.432956) (xy 82.661899 -138.424941)
			(xy 82.599995 -138.409043) (xy 82.540571 -138.385512) (xy 82.484565 -138.354719) (xy 82.43286 -138.317149)
			(xy 82.38627 -138.273396) (xy 82.345532 -138.224149) (xy 82.311287 -138.170184) (xy 82.284075 -138.112354)
			(xy 82.264326 -138.051568) (xy 82.25235 -137.988787) (xy 82.248337 -137.925) (xy 21.98878 -137.925)
			(xy 21.98878 -153.765504) (xy 24.441921 -153.765504) (xy 24.445917 -153.555618) (xy 24.457902 -153.346036)
			(xy 24.477856 -153.137062) (xy 24.505752 -152.929) (xy 24.541549 -152.72215) (xy 24.585194 -152.516813)
			(xy 24.636626 -152.313287) (xy 24.695768 -152.111866) (xy 24.762536 -151.912843) (xy 24.836832 -151.716506)
			(xy 24.91855 -151.52314) (xy 25.007569 -151.333025) (xy 25.103762 -151.146437) (xy 25.206989 -150.963646)
			(xy 25.3171 -150.784918) (xy 25.433935 -150.610511) (xy 25.557325 -150.440679) (xy 25.687092 -150.275667)
			(xy 25.823046 -150.115716) (xy 25.964992 -149.961056) (xy 26.112722 -149.811912) (xy 26.266024 -149.668501)
			(xy 26.424674 -149.53103) (xy 26.588443 -149.399698) (xy 26.757093 -149.274697) (xy 26.930379 -149.156206)
			(xy 27.108051 -149.044399) (xy 27.289851 -148.939437) (xy 27.475515 -148.841472) (xy 27.664773 -148.750647)
			(xy 27.857353 -148.667093) (xy 28.052974 -148.59093) (xy 28.251352 -148.522271) (xy 28.452201 -148.461214)
			(xy 28.655228 -148.407847) (xy 28.860141 -148.362249) (xy 29.06664 -148.324484) (xy 29.274427 -148.294609)
			(xy 29.483202 -148.272666) (xy 29.69266 -148.258687) (xy 29.902499 -148.252692) (xy 30.112413 -148.254691)
			(xy 30.3221 -148.264679) (xy 30.531254 -148.282644) (xy 30.739572 -148.308558) (xy 30.946753 -148.342383)
			(xy 31.152497 -148.384072) (xy 31.356503 -148.433564) (xy 31.558478 -148.490786) (xy 31.758128 -148.555656)
			(xy 31.955163 -148.62808) (xy 32.149299 -148.707953) (xy 32.340252 -148.795159) (xy 32.527748 -148.889571)
			(xy 32.711513 -148.991053) (xy 32.891281 -149.099457) (xy 33.066792 -149.214627) (xy 33.237791 -149.336395)
			(xy 33.404031 -149.464584) (xy 33.56527 -149.59901) (xy 33.721274 -149.739477) (xy 33.871817 -149.885781)
			(xy 34.016681 -150.03771) (xy 34.155656 -150.195044) (xy 34.288541 -150.357555) (xy 34.415142 -150.525008)
			(xy 34.535277 -150.697158) (xy 34.648771 -150.873758) (xy 34.755459 -151.05455) (xy 34.855186 -151.239273)
			(xy 34.947809 -151.427659) (xy 35.033193 -151.619434) (xy 35.111214 -151.814321) (xy 35.181759 -152.012037)
			(xy 35.244726 -152.212295) (xy 35.300023 -152.414805) (xy 35.34757 -152.619274) (xy 35.387298 -152.825405)
			(xy 35.41915 -153.032898) (xy 35.44308 -153.241454) (xy 35.459052 -153.45077) (xy 35.467044 -153.660542)
			(xy 35.467544 -153.765504) (xy 35.467044 -153.870466) (xy 35.459052 -154.080238) (xy 35.44308 -154.289554)
			(xy 35.41915 -154.49811) (xy 35.387298 -154.705603) (xy 35.34757 -154.911734) (xy 35.300023 -155.116203)
			(xy 35.244726 -155.318713) (xy 35.181759 -155.518971) (xy 35.111214 -155.716687) (xy 35.033193 -155.911574)
			(xy 34.947809 -156.103349) (xy 34.855186 -156.291735) (xy 34.755459 -156.476458) (xy 34.648771 -156.65725)
			(xy 34.535277 -156.83385) (xy 34.415142 -157.006) (xy 34.288541 -157.173453) (xy 34.155656 -157.335964)
			(xy 34.016681 -157.493298) (xy 33.871817 -157.645227) (xy 33.721274 -157.791531) (xy 33.56527 -157.931998)
			(xy 33.404031 -158.066424) (xy 33.237791 -158.194613) (xy 33.066792 -158.316381) (xy 32.891281 -158.431551)
			(xy 32.711513 -158.539955) (xy 32.527748 -158.641437) (xy 32.340252 -158.735849) (xy 32.149299 -158.823055)
			(xy 31.955163 -158.902928) (xy 31.758128 -158.975352) (xy 31.558478 -159.040222) (xy 31.356503 -159.097444)
			(xy 31.152497 -159.146936) (xy 30.946753 -159.188625) (xy 30.739572 -159.22245) (xy 30.531254 -159.248364)
			(xy 30.3221 -159.266329) (xy 30.112413 -159.276317) (xy 29.902499 -159.278316) (xy 29.69266 -159.272321)
			(xy 29.483202 -159.258342) (xy 29.274427 -159.236399) (xy 29.06664 -159.206524) (xy 28.860141 -159.168759)
			(xy 28.655228 -159.123161) (xy 28.452201 -159.069794) (xy 28.251352 -159.008737) (xy 28.052974 -158.940078)
			(xy 27.857353 -158.863915) (xy 27.664773 -158.780361) (xy 27.475515 -158.689536) (xy 27.289851 -158.591571)
			(xy 27.108051 -158.486609) (xy 26.930379 -158.374802) (xy 26.757093 -158.256311) (xy 26.588443 -158.13131)
			(xy 26.424674 -157.999978) (xy 26.266024 -157.862507) (xy 26.112722 -157.719096) (xy 25.964992 -157.569952)
			(xy 25.823046 -157.415292) (xy 25.687092 -157.255341) (xy 25.557325 -157.090329) (xy 25.433935 -156.920497)
			(xy 25.3171 -156.74609) (xy 25.206989 -156.567362) (xy 25.103762 -156.384571) (xy 25.007569 -156.197983)
			(xy 24.91855 -156.007868) (xy 24.836832 -155.814502) (xy 24.762536 -155.618165) (xy 24.695768 -155.419142)
			(xy 24.636626 -155.217721) (xy 24.585194 -155.014195) (xy 24.541549 -154.808858) (xy 24.505752 -154.602008)
			(xy 24.477856 -154.393946) (xy 24.457902 -154.184972) (xy 24.445917 -153.97539) (xy 24.441921 -153.765504)
			(xy 21.98878 -153.765504) (xy 21.98878 -158.077154) (xy 22.408642 -158.077154) (xy 22.4091 -158.045866)
			(xy 22.416777 -157.983762) (xy 22.432021 -157.923071) (xy 22.454603 -157.86471) (xy 22.48418 -157.809565)
			(xy 22.520304 -157.758468) (xy 22.562429 -157.712194) (xy 22.609917 -157.671442) (xy 22.635718 -157.653736)
			(xy 22.645872 -157.646216) (xy 22.657734 -157.623941) (xy 22.658324 -157.611318) (xy 22.658324 -157.52699)
			(xy 22.657711 -157.51438) (xy 22.645832 -157.492132) (xy 22.635718 -157.484572) (xy 22.609934 -157.466851)
			(xy 22.562471 -157.426085) (xy 22.52037 -157.379804) (xy 22.484266 -157.328706) (xy 22.454705 -157.273563)
			(xy 22.432134 -157.21521) (xy 22.416895 -157.154528) (xy 22.409217 -157.092435) (xy 22.409217 -157.029869)
			(xy 22.416894 -156.967776) (xy 22.432133 -156.907094) (xy 22.454703 -156.848741) (xy 22.484263 -156.793598)
			(xy 22.520367 -156.7425) (xy 22.562468 -156.696218) (xy 22.60993 -156.655452) (xy 22.635718 -156.637736)
			(xy 22.645872 -156.630216) (xy 22.657734 -156.607941) (xy 22.658324 -156.595318) (xy 22.658324 -156.51099)
			(xy 22.657711 -156.49838) (xy 22.645832 -156.476132) (xy 22.635718 -156.468572) (xy 22.609934 -156.450851)
			(xy 22.562471 -156.410085) (xy 22.52037 -156.363804) (xy 22.484266 -156.312706) (xy 22.454705 -156.257563)
			(xy 22.432134 -156.19921) (xy 22.416895 -156.138528) (xy 22.409217 -156.076435) (xy 22.409217 -156.013869)
			(xy 22.416894 -155.951776) (xy 22.432133 -155.891094) (xy 22.454703 -155.832741) (xy 22.484263 -155.777598)
			(xy 22.520367 -155.7265) (xy 22.562468 -155.680218) (xy 22.60993 -155.639452) (xy 22.635718 -155.621736)
			(xy 22.645872 -155.614216) (xy 22.657734 -155.591941) (xy 22.658324 -155.579318) (xy 22.658324 -155.49499)
			(xy 22.657711 -155.48238) (xy 22.645832 -155.460132) (xy 22.635718 -155.452572) (xy 22.609934 -155.434845)
			(xy 22.562455 -155.394089) (xy 22.520338 -155.347814) (xy 22.484219 -155.296719) (xy 22.454645 -155.241578)
			(xy 22.432062 -155.183223) (xy 22.416812 -155.122538) (xy 22.409125 -155.06044) (xy 22.408642 -155.029154)
			(xy 22.409144 -154.997193) (xy 22.417155 -154.933775) (xy 22.433052 -154.871861) (xy 22.456584 -154.812428)
			(xy 22.487378 -154.756413) (xy 22.524951 -154.704698) (xy 22.568708 -154.658101) (xy 22.617961 -154.617356)
			(xy 22.671932 -154.583105) (xy 22.729771 -154.555888) (xy 22.790564 -154.536135) (xy 22.853354 -154.524157)
			(xy 22.91715 -154.520144) (xy 22.980946 -154.524157) (xy 23.043736 -154.536135) (xy 23.104529 -154.555888)
			(xy 23.162368 -154.583105) (xy 23.216339 -154.617356) (xy 23.265592 -154.658101) (xy 23.309349 -154.704698)
			(xy 23.346922 -154.756413) (xy 23.377716 -154.812428) (xy 23.401248 -154.871861) (xy 23.417145 -154.933775)
			(xy 23.425156 -154.997193) (xy 23.425658 -155.029154) (xy 23.425207 -155.060443) (xy 23.417528 -155.122547)
			(xy 23.402283 -155.183238) (xy 23.3797 -155.241598) (xy 23.350123 -155.296744) (xy 23.313998 -155.34784)
			(xy 23.271872 -155.394115) (xy 23.224383 -155.434866) (xy 23.198582 -155.452572) (xy 23.18847 -155.460139)
			(xy 23.176587 -155.482379) (xy 23.175976 -155.49499) (xy 23.175976 -155.579318) (xy 23.176584 -155.591929)
			(xy 23.188466 -155.614177) (xy 23.198582 -155.621736) (xy 23.224374 -155.639447) (xy 23.271837 -155.680213)
			(xy 23.313938 -155.726496) (xy 23.350042 -155.777595) (xy 23.379603 -155.832738) (xy 23.402173 -155.891092)
			(xy 23.417413 -155.951775) (xy 23.42509 -156.013869) (xy 23.42509 -156.076436) (xy 23.417412 -156.13853)
			(xy 23.402172 -156.199212) (xy 23.379601 -156.257566) (xy 23.35004 -156.312709) (xy 23.313935 -156.363808)
			(xy 23.271833 -156.41009) (xy 23.22437 -156.450856) (xy 23.198582 -156.468572) (xy 23.18847 -156.476139)
			(xy 23.176587 -156.498379) (xy 23.175976 -156.51099) (xy 23.175976 -156.595318) (xy 23.176584 -156.607929)
			(xy 23.188466 -156.630177) (xy 23.198582 -156.637736) (xy 23.224374 -156.655447) (xy 23.271837 -156.696213)
			(xy 23.313938 -156.742496) (xy 23.350042 -156.793595) (xy 23.379603 -156.848738) (xy 23.402173 -156.907092)
			(xy 23.417413 -156.967775) (xy 23.42509 -157.029869) (xy 23.42509 -157.092436) (xy 23.417412 -157.15453)
			(xy 23.402172 -157.215212) (xy 23.379601 -157.273566) (xy 23.35004 -157.328709) (xy 23.313935 -157.379808)
			(xy 23.271833 -157.42609) (xy 23.22437 -157.466856) (xy 23.198582 -157.484572) (xy 23.18847 -157.492139)
			(xy 23.176587 -157.514379) (xy 23.175976 -157.52699) (xy 23.175976 -157.611318) (xy 23.176584 -157.623929)
			(xy 23.188466 -157.646177) (xy 23.198582 -157.653736) (xy 23.22437 -157.671457) (xy 23.271848 -157.712214)
			(xy 23.313965 -157.75849) (xy 23.350084 -157.809586) (xy 23.379658 -157.864728) (xy 23.40224 -157.923083)
			(xy 23.41749 -157.983769) (xy 23.425175 -158.045868) (xy 23.425658 -158.077154) (xy 23.425156 -158.109115)
			(xy 23.417145 -158.172533) (xy 23.401248 -158.234447) (xy 23.377716 -158.29388) (xy 23.346922 -158.349895)
			(xy 23.309349 -158.40161) (xy 23.265592 -158.448207) (xy 23.216339 -158.488952) (xy 23.162368 -158.523203)
			(xy 23.104529 -158.55042) (xy 23.043736 -158.570173) (xy 22.980946 -158.582151) (xy 22.91715 -158.586165)
			(xy 22.853354 -158.582151) (xy 22.790564 -158.570173) (xy 22.729771 -158.55042) (xy 22.671932 -158.523203)
			(xy 22.617961 -158.488952) (xy 22.568708 -158.448207) (xy 22.524951 -158.40161) (xy 22.487378 -158.349895)
			(xy 22.456584 -158.29388) (xy 22.433052 -158.234447) (xy 22.417155 -158.172533) (xy 22.409144 -158.109115)
			(xy 22.408642 -158.077154) (xy 21.98878 -158.077154) (xy 21.98878 -169.800524) (xy 32.9565 -169.800524)
			(xy 32.956954 -169.770117) (xy 32.964183 -169.709735) (xy 32.978566 -169.650648) (xy 32.999897 -169.593698)
			(xy 33.027871 -169.539701) (xy 33.062087 -169.489428) (xy 33.102059 -169.443596) (xy 33.147213 -169.402861)
			(xy 33.196905 -169.367806) (xy 33.223454 -169.352976) (xy 33.234029 -169.346512) (xy 33.247967 -169.326066)
			(xy 33.250124 -169.31386) (xy 33.259268 -169.230802) (xy 33.259827 -169.218462) (xy 33.250817 -169.195506)
			(xy 33.241996 -169.18686) (xy 33.221827 -169.168673) (xy 33.186361 -169.127546) (xy 33.157088 -169.081803)
			(xy 33.134602 -169.032369) (xy 33.119357 -168.980245) (xy 33.111661 -168.926486) (xy 33.111186 -168.899332)
			(xy 33.111672 -168.872081) (xy 33.119428 -168.818133) (xy 33.134783 -168.765838) (xy 33.157425 -168.716261)
			(xy 33.186891 -168.670411) (xy 33.222582 -168.62922) (xy 33.263773 -168.593529) (xy 33.309623 -168.564063)
			(xy 33.3592 -168.541421) (xy 33.411495 -168.526066) (xy 33.465443 -168.51831) (xy 33.519945 -168.51831)
			(xy 33.573893 -168.526066) (xy 33.626188 -168.541421) (xy 33.675765 -168.564063) (xy 33.721615 -168.593529)
			(xy 33.762806 -168.62922) (xy 33.798497 -168.670411) (xy 33.827963 -168.716261) (xy 33.850605 -168.765838)
			(xy 33.86596 -168.818133) (xy 33.873716 -168.872081) (xy 33.874202 -168.899332) (xy 33.873613 -168.928456)
			(xy 33.864755 -168.986027) (xy 33.848694 -169.037) (xy 37.63467 -169.037) (xy 37.638741 -168.981378)
			(xy 37.650867 -168.926941) (xy 37.67079 -168.87485) (xy 37.698086 -168.826215) (xy 37.732172 -168.782072)
			(xy 37.772321 -168.743363) (xy 37.817679 -168.710912) (xy 37.867279 -168.685411) (xy 37.920063 -168.667404)
			(xy 37.974906 -168.657274) (xy 38.03064 -168.655237) (xy 38.086077 -168.661337) (xy 38.140034 -168.675443)
			(xy 38.191363 -168.697255) (xy 38.238969 -168.726309) (xy 38.281837 -168.761984) (xy 38.319054 -168.803521)
			(xy 38.349827 -168.850034) (xy 38.373499 -168.900531) (xy 38.389567 -168.953938) (xy 38.397687 -169.009114)
			(xy 38.398196 -169.037) (xy 38.397687 -169.064886) (xy 38.389567 -169.120062) (xy 38.373499 -169.173469)
			(xy 38.349827 -169.223966) (xy 38.319054 -169.270479) (xy 38.281837 -169.312016) (xy 38.238969 -169.347691)
			(xy 38.191363 -169.376745) (xy 38.140034 -169.398557) (xy 38.086077 -169.412663) (xy 38.03064 -169.418763)
			(xy 37.974906 -169.416726) (xy 37.920063 -169.406596) (xy 37.867279 -169.388589) (xy 37.817679 -169.363088)
			(xy 37.772321 -169.330637) (xy 37.732172 -169.291928) (xy 37.698086 -169.247785) (xy 37.67079 -169.19915)
			(xy 37.650867 -169.147059) (xy 37.638741 -169.092622) (xy 37.63467 -169.037) (xy 33.848694 -169.037)
			(xy 33.84725 -169.041583) (xy 33.821504 -169.093833) (xy 33.788116 -169.141563) (xy 33.747862 -169.183663)
			(xy 33.725104 -169.201846) (xy 33.71578 -169.209979) (xy 33.705422 -169.232401) (xy 33.705292 -169.244772)
			(xy 33.70961 -169.328084) (xy 33.710979 -169.340241) (xy 33.723298 -169.361332) (xy 33.733232 -169.36847)
			(xy 33.733232 -169.368724) (xy 33.73374 -169.368724) (xy 33.75074 -169.379527) (xy 33.783163 -169.403431)
			(xy 33.79851 -169.416476) (xy 33.805368 -169.422572) (xy 33.822386 -169.428922) (xy 33.90773 -169.428922)
			(xy 33.924748 -169.422572) (xy 33.931606 -169.416476) (xy 33.954762 -169.396937) (xy 34.004916 -169.362938)
			(xy 34.058755 -169.335144) (xy 34.115517 -169.313947) (xy 34.174397 -169.299648) (xy 34.234559 -169.292451)
			(xy 34.264854 -169.292016) (xy 34.265108 -169.292016) (xy 34.29707 -169.29247) (xy 34.36049 -169.300483)
			(xy 34.422406 -169.316381) (xy 34.481842 -169.339914) (xy 34.537859 -169.370711) (xy 34.589574 -169.408285)
			(xy 34.636173 -169.452045) (xy 34.676919 -169.5013) (xy 34.711172 -169.555273) (xy 34.738389 -169.613114)
			(xy 34.749104 -169.646092) (xy 43.363642 -169.646092) (xy 43.364131 -169.61568) (xy 43.371398 -169.555291)
			(xy 43.385815 -169.4962) (xy 43.407177 -169.43925) (xy 43.435179 -169.385255) (xy 43.46942 -169.334984)
			(xy 43.509413 -169.289156) (xy 43.554586 -169.248425) (xy 43.604294 -169.213372) (xy 43.63085 -169.198544)
			(xy 43.63974 -169.193718) (xy 43.652186 -169.178986) (xy 43.679872 -169.093134) (xy 43.678602 -169.07383)
			(xy 43.674284 -169.06494) (xy 43.662344 -169.038982) (xy 43.64548 -168.984393) (xy 43.63695 -168.927899)
			(xy 43.636438 -168.899332) (xy 43.636924 -168.872081) (xy 43.64468 -168.818133) (xy 43.660035 -168.765838)
			(xy 43.682677 -168.716261) (xy 43.712143 -168.670411) (xy 43.747834 -168.62922) (xy 43.789025 -168.593529)
			(xy 43.834875 -168.564063) (xy 43.884452 -168.541421) (xy 43.936747 -168.526066) (xy 43.990695 -168.51831)
			(xy 44.045197 -168.51831) (xy 44.099145 -168.526066) (xy 44.15144 -168.541421) (xy 44.201017 -168.564063)
			(xy 44.246867 -168.593529) (xy 44.288058 -168.62922) (xy 44.323749 -168.670411) (xy 44.353215 -168.716261)
			(xy 44.375857 -168.765838) (xy 44.391212 -168.818133) (xy 44.398968 -168.872081) (xy 44.399454 -168.899332)
			(xy 44.398977 -168.92587) (xy 44.391622 -168.978434) (xy 44.377057 -169.029473) (xy 44.355564 -169.078003)
			(xy 44.327557 -169.123088) (xy 44.293576 -169.16386) (xy 44.274232 -169.182034) (xy 44.267247 -169.188862)
			(xy 44.258628 -169.206371) (xy 44.257468 -169.21607) (xy 44.252642 -169.28592) (xy 44.252352 -169.295654)
			(xy 44.258221 -169.314204) (xy 44.264072 -169.321988) (xy 44.282419 -169.344824) (xy 44.314299 -169.393969)
			(xy 44.340325 -169.446451) (xy 44.360152 -169.501574) (xy 44.373518 -169.558609) (xy 44.380246 -169.616802)
			(xy 44.380658 -169.646092) (xy 44.380156 -169.678053) (xy 44.372145 -169.741471) (xy 44.356248 -169.803385)
			(xy 44.332716 -169.862818) (xy 44.301922 -169.918833) (xy 44.264349 -169.970548) (xy 44.220592 -170.017145)
			(xy 44.171339 -170.05789) (xy 44.117368 -170.092141) (xy 44.059529 -170.119358) (xy 43.998736 -170.139111)
			(xy 43.935946 -170.151089) (xy 43.87215 -170.155103) (xy 43.808354 -170.151089) (xy 43.745564 -170.139111)
			(xy 43.684771 -170.119358) (xy 43.626932 -170.092141) (xy 43.572961 -170.05789) (xy 43.523708 -170.017145)
			(xy 43.479951 -169.970548) (xy 43.442378 -169.918833) (xy 43.411584 -169.862818) (xy 43.388052 -169.803385)
			(xy 43.372155 -169.741471) (xy 43.364144 -169.678053) (xy 43.363642 -169.646092) (xy 34.749104 -169.646092)
			(xy 34.758143 -169.67391) (xy 34.770121 -169.736702) (xy 34.774135 -169.8005) (xy 34.770121 -169.864298)
			(xy 34.758143 -169.92709) (xy 34.738389 -169.987886) (xy 34.711172 -170.045727) (xy 34.676919 -170.0997)
			(xy 34.636173 -170.148955) (xy 34.589574 -170.192715) (xy 34.537859 -170.230289) (xy 34.481842 -170.261086)
			(xy 34.422406 -170.284619) (xy 34.36049 -170.300517) (xy 34.29707 -170.30853) (xy 34.265108 -170.309032)
			(xy 34.264854 -170.309032) (xy 34.23456 -170.308594) (xy 34.174403 -170.301381) (xy 34.115528 -170.287073)
			(xy 34.05877 -170.265874) (xy 34.004931 -170.238083) (xy 33.954775 -170.204095) (xy 33.931606 -170.184572)
			(xy 33.924748 -170.178476) (xy 33.90773 -170.172126) (xy 33.822386 -170.172126) (xy 33.805368 -170.178476)
			(xy 33.79851 -170.184572) (xy 33.775341 -170.204095) (xy 33.725191 -170.238097) (xy 33.671355 -170.265895)
			(xy 33.614595 -170.287095) (xy 33.555717 -170.301396) (xy 33.495557 -170.308596) (xy 33.465262 -170.309032)
			(xy 33.465008 -170.309032) (xy 33.434278 -170.308536) (xy 33.373266 -170.301129) (xy 33.313592 -170.286422)
			(xy 33.256126 -170.26463) (xy 33.201705 -170.236069) (xy 33.151124 -170.201158) (xy 33.105119 -170.160404)
			(xy 33.064362 -170.114402) (xy 33.029447 -170.063822) (xy 33.000883 -170.009404) (xy 32.979087 -169.951938)
			(xy 32.964376 -169.892265) (xy 32.956965 -169.831254) (xy 32.9565 -169.800524) (xy 21.98878 -169.800524)
			(xy 21.98878 -170.324991) (xy 35.171628 -170.324991) (xy 35.171628 -170.261069) (xy 35.179639 -170.197651)
			(xy 35.195536 -170.135737) (xy 35.219068 -170.076304) (xy 35.249862 -170.020289) (xy 35.287435 -169.968574)
			(xy 35.331192 -169.921977) (xy 35.380445 -169.881232) (xy 35.434416 -169.846981) (xy 35.492255 -169.819764)
			(xy 35.553048 -169.800011) (xy 35.615838 -169.788033) (xy 35.679634 -169.78402) (xy 35.74343 -169.788033)
			(xy 35.80622 -169.800011) (xy 35.867013 -169.819764) (xy 35.924852 -169.846981) (xy 35.978823 -169.881232)
			(xy 36.028076 -169.921977) (xy 36.071833 -169.968574) (xy 36.109406 -170.020289) (xy 36.1402 -170.076304)
			(xy 36.163732 -170.135737) (xy 36.179629 -170.197651) (xy 36.18764 -170.261069) (xy 36.188142 -170.29303)
			(xy 36.18764 -170.324991) (xy 36.179629 -170.388409) (xy 36.168652 -170.431163) (xy 40.988482 -170.431163)
			(xy 40.988482 -170.367241) (xy 40.996493 -170.303823) (xy 41.01239 -170.241909) (xy 41.035922 -170.182476)
			(xy 41.066716 -170.126461) (xy 41.104289 -170.074746) (xy 41.148046 -170.028149) (xy 41.197299 -169.987404)
			(xy 41.25127 -169.953153) (xy 41.309109 -169.925936) (xy 41.369902 -169.906183) (xy 41.432692 -169.894205)
			(xy 41.496488 -169.890192) (xy 41.560284 -169.894205) (xy 41.623074 -169.906183) (xy 41.683867 -169.925936)
			(xy 41.741706 -169.953153) (xy 41.795677 -169.987404) (xy 41.84493 -170.028149) (xy 41.888687 -170.074746)
			(xy 41.92626 -170.126461) (xy 41.957054 -170.182476) (xy 41.980586 -170.241909) (xy 41.996483 -170.303823)
			(xy 42.004494 -170.367241) (xy 42.004996 -170.399202) (xy 42.004494 -170.431163) (xy 41.996483 -170.494581)
			(xy 41.980586 -170.556495) (xy 41.957054 -170.615928) (xy 41.92626 -170.671943) (xy 41.888687 -170.723658)
			(xy 41.84493 -170.770255) (xy 41.795677 -170.811) (xy 41.741706 -170.845251) (xy 41.683867 -170.872468)
			(xy 41.623074 -170.892221) (xy 41.560284 -170.904199) (xy 41.496488 -170.908213) (xy 41.432692 -170.904199)
			(xy 41.369902 -170.892221) (xy 41.309109 -170.872468) (xy 41.25127 -170.845251) (xy 41.197299 -170.811)
			(xy 41.148046 -170.770255) (xy 41.104289 -170.723658) (xy 41.066716 -170.671943) (xy 41.035922 -170.615928)
			(xy 41.01239 -170.556495) (xy 40.996493 -170.494581) (xy 40.988482 -170.431163) (xy 36.168652 -170.431163)
			(xy 36.163732 -170.450323) (xy 36.1402 -170.509756) (xy 36.109406 -170.565771) (xy 36.071833 -170.617486)
			(xy 36.028076 -170.664083) (xy 35.978823 -170.704828) (xy 35.924852 -170.739079) (xy 35.867013 -170.766296)
			(xy 35.80622 -170.786049) (xy 35.74343 -170.798027) (xy 35.679634 -170.802041) (xy 35.615838 -170.798027)
			(xy 35.553048 -170.786049) (xy 35.492255 -170.766296) (xy 35.434416 -170.739079) (xy 35.380445 -170.704828)
			(xy 35.331192 -170.664083) (xy 35.287435 -170.617486) (xy 35.249862 -170.565771) (xy 35.219068 -170.509756)
			(xy 35.195536 -170.450323) (xy 35.179639 -170.388409) (xy 35.171628 -170.324991) (xy 21.98878 -170.324991)
			(xy 21.98878 -171.445131) (xy 40.008296 -171.445131) (xy 40.008296 -171.381209) (xy 40.016307 -171.317791)
			(xy 40.032204 -171.255877) (xy 40.055736 -171.196444) (xy 40.08653 -171.140429) (xy 40.124103 -171.088714)
			(xy 40.16786 -171.042117) (xy 40.217113 -171.001372) (xy 40.271084 -170.967121) (xy 40.328923 -170.939904)
			(xy 40.389716 -170.920151) (xy 40.452506 -170.908173) (xy 40.516302 -170.90416) (xy 40.580098 -170.908173)
			(xy 40.642888 -170.920151) (xy 40.703681 -170.939904) (xy 40.76152 -170.967121) (xy 40.815491 -171.001372)
			(xy 40.864744 -171.042117) (xy 40.908501 -171.088714) (xy 40.946074 -171.140429) (xy 40.976868 -171.196444)
			(xy 41.0004 -171.255877) (xy 41.016297 -171.317791) (xy 41.024308 -171.381209) (xy 41.02481 -171.41317)
			(xy 41.024308 -171.445131) (xy 41.016297 -171.508549) (xy 41.0004 -171.570463) (xy 40.976868 -171.629896)
			(xy 40.946074 -171.685911) (xy 40.908501 -171.737626) (xy 40.864744 -171.784223) (xy 40.815491 -171.824968)
			(xy 40.76152 -171.859219) (xy 40.703681 -171.886436) (xy 40.642888 -171.906189) (xy 40.580098 -171.918167)
			(xy 40.516302 -171.922181) (xy 40.452506 -171.918167) (xy 40.389716 -171.906189) (xy 40.328923 -171.886436)
			(xy 40.271084 -171.859219) (xy 40.217113 -171.824968) (xy 40.16786 -171.784223) (xy 40.124103 -171.737626)
			(xy 40.08653 -171.685911) (xy 40.055736 -171.629896) (xy 40.032204 -171.570463) (xy 40.016307 -171.508549)
			(xy 40.008296 -171.445131) (xy 21.98878 -171.445131) (xy 21.98878 -172.571621) (xy 33.009834 -172.571621)
			(xy 33.009834 -172.507699) (xy 33.017845 -172.444281) (xy 33.033742 -172.382367) (xy 33.057274 -172.322934)
			(xy 33.088068 -172.266919) (xy 33.125641 -172.215204) (xy 33.169398 -172.168607) (xy 33.218651 -172.127862)
			(xy 33.272622 -172.093611) (xy 33.330461 -172.066394) (xy 33.391254 -172.046641) (xy 33.454044 -172.034663)
			(xy 33.51784 -172.03065) (xy 33.581636 -172.034663) (xy 33.644426 -172.046641) (xy 33.705219 -172.066394)
			(xy 33.763058 -172.093611) (xy 33.817029 -172.127862) (xy 33.866282 -172.168607) (xy 33.910039 -172.215204)
			(xy 33.947612 -172.266919) (xy 33.978406 -172.322934) (xy 34.001938 -172.382367) (xy 34.017835 -172.444281)
			(xy 34.025846 -172.507699) (xy 34.026348 -172.53966) (xy 34.025846 -172.571621) (xy 34.024916 -172.578987)
			(xy 40.762422 -172.578987) (xy 40.762422 -172.515065) (xy 40.770433 -172.451647) (xy 40.78633 -172.389733)
			(xy 40.809862 -172.3303) (xy 40.840656 -172.274285) (xy 40.878229 -172.22257) (xy 40.921986 -172.175973)
			(xy 40.971239 -172.135228) (xy 41.02521 -172.100977) (xy 41.083049 -172.07376) (xy 41.143842 -172.054007)
			(xy 41.206632 -172.042029) (xy 41.270428 -172.038016) (xy 41.334224 -172.042029) (xy 41.397014 -172.054007)
			(xy 41.457807 -172.07376) (xy 41.515646 -172.100977) (xy 41.569617 -172.135228) (xy 41.61887 -172.175973)
			(xy 41.662627 -172.22257) (xy 41.7002 -172.274285) (xy 41.730994 -172.3303) (xy 41.754526 -172.389733)
			(xy 41.770423 -172.451647) (xy 41.778434 -172.515065) (xy 41.778936 -172.547026) (xy 41.778434 -172.578987)
			(xy 41.770423 -172.642405) (xy 41.754526 -172.704319) (xy 41.730994 -172.763752) (xy 41.7002 -172.819767)
			(xy 41.662627 -172.871482) (xy 41.61887 -172.918079) (xy 41.569617 -172.958824) (xy 41.515646 -172.993075)
			(xy 41.457807 -173.020292) (xy 41.397014 -173.040045) (xy 41.334224 -173.052023) (xy 41.270428 -173.056037)
			(xy 41.206632 -173.052023) (xy 41.143842 -173.040045) (xy 41.083049 -173.020292) (xy 41.02521 -172.993075)
			(xy 40.971239 -172.958824) (xy 40.921986 -172.918079) (xy 40.878229 -172.871482) (xy 40.840656 -172.819767)
			(xy 40.809862 -172.763752) (xy 40.78633 -172.704319) (xy 40.770433 -172.642405) (xy 40.762422 -172.578987)
			(xy 34.024916 -172.578987) (xy 34.017835 -172.635039) (xy 34.001938 -172.696953) (xy 33.978406 -172.756386)
			(xy 33.947612 -172.812401) (xy 33.910039 -172.864116) (xy 33.866282 -172.910713) (xy 33.817029 -172.951458)
			(xy 33.763058 -172.985709) (xy 33.705219 -173.012926) (xy 33.644426 -173.032679) (xy 33.581636 -173.044657)
			(xy 33.51784 -173.048671) (xy 33.454044 -173.044657) (xy 33.391254 -173.032679) (xy 33.330461 -173.012926)
			(xy 33.272622 -172.985709) (xy 33.218651 -172.951458) (xy 33.169398 -172.910713) (xy 33.125641 -172.864116)
			(xy 33.088068 -172.812401) (xy 33.057274 -172.756386) (xy 33.033742 -172.696953) (xy 33.017845 -172.635039)
			(xy 33.009834 -172.571621) (xy 21.98878 -172.571621) (xy 21.98878 -174.348351) (xy 28.204662 -174.348351)
			(xy 28.204662 -174.284429) (xy 28.212673 -174.221011) (xy 28.22857 -174.159097) (xy 28.252102 -174.099664)
			(xy 28.282896 -174.043649) (xy 28.320469 -173.991934) (xy 28.364226 -173.945337) (xy 28.413479 -173.904592)
			(xy 28.46745 -173.870341) (xy 28.525289 -173.843124) (xy 28.586082 -173.823371) (xy 28.648872 -173.811393)
			(xy 28.712668 -173.80738) (xy 28.776464 -173.811393) (xy 28.839254 -173.823371) (xy 28.900047 -173.843124)
			(xy 28.957886 -173.870341) (xy 29.011857 -173.904592) (xy 29.06111 -173.945337) (xy 29.104867 -173.991934)
			(xy 29.14244 -174.043649) (xy 29.173234 -174.099664) (xy 29.196766 -174.159097) (xy 29.212663 -174.221011)
			(xy 29.217942 -174.2628) (xy 32.955964 -174.2628) (xy 32.959978 -174.199) (xy 32.971957 -174.136207)
			(xy 32.991711 -174.07541) (xy 33.01893 -174.017568) (xy 33.053184 -173.963594) (xy 33.093932 -173.914338)
			(xy 33.140532 -173.870579) (xy 33.192249 -173.833004) (xy 33.248268 -173.802208) (xy 33.307705 -173.778676)
			(xy 33.369623 -173.76278) (xy 33.433045 -173.754768) (xy 33.465008 -173.754288) (xy 33.465262 -173.754288)
			(xy 33.495556 -173.754711) (xy 33.555714 -173.761927) (xy 33.614589 -173.776237) (xy 33.671348 -173.797439)
			(xy 33.725186 -173.825232) (xy 33.775342 -173.859224) (xy 33.79851 -173.878748) (xy 33.805368 -173.884844)
			(xy 33.822386 -173.891194) (xy 33.90773 -173.891194) (xy 33.924748 -173.884844) (xy 33.931606 -173.878748)
			(xy 33.954772 -173.85922) (xy 34.004922 -173.825218) (xy 34.058759 -173.797421) (xy 34.115519 -173.776221)
			(xy 34.174398 -173.761921) (xy 34.234559 -173.754723) (xy 34.264854 -173.754288) (xy 34.265108 -173.754288)
			(xy 34.297068 -173.754798) (xy 34.360485 -173.762811) (xy 34.422398 -173.778708) (xy 34.48183 -173.80224)
			(xy 34.537844 -173.833034) (xy 34.589556 -173.870607) (xy 34.636152 -173.914364) (xy 34.676897 -173.963616)
			(xy 34.711147 -174.017586) (xy 34.738363 -174.075424) (xy 34.758115 -174.136216) (xy 34.770093 -174.199005)
			(xy 34.774107 -174.2628) (xy 34.770093 -174.326595) (xy 34.758115 -174.389384) (xy 34.757321 -174.391828)
			(xy 35.145218 -174.391828) (xy 35.145681 -174.364962) (xy 35.153217 -174.311762) (xy 35.168144 -174.260145)
			(xy 35.190166 -174.211134) (xy 35.218848 -174.165698) (xy 35.253621 -174.124736) (xy 35.293799 -174.089059)
			(xy 35.338585 -174.059372) (xy 35.362642 -174.047404) (xy 35.375561 -174.040748) (xy 35.397232 -174.0214)
			(xy 35.412575 -173.996731) (xy 35.420348 -173.96874) (xy 35.419921 -173.939692) (xy 35.411329 -173.91194)
			(xy 35.395268 -173.887733) (xy 35.384486 -173.877986) (xy 35.360625 -173.857251) (xy 35.317732 -173.810813)
			(xy 35.280928 -173.759415) (xy 35.25078 -173.703851) (xy 35.227753 -173.644977) (xy 35.212203 -173.583703)
			(xy 35.20437 -173.520974) (xy 35.203892 -173.489366) (xy 35.204394 -173.457405) (xy 35.212405 -173.393987)
			(xy 35.228302 -173.332073) (xy 35.251834 -173.27264) (xy 35.282628 -173.216625) (xy 35.320201 -173.16491)
			(xy 35.363958 -173.118313) (xy 35.413211 -173.077568) (xy 35.467182 -173.043317) (xy 35.525021 -173.0161)
			(xy 35.585814 -172.996347) (xy 35.648604 -172.984369) (xy 35.7124 -172.980356) (xy 35.776196 -172.984369)
			(xy 35.838986 -172.996347) (xy 35.899779 -173.0161) (xy 35.957618 -173.043317) (xy 36.011589 -173.077568)
			(xy 36.060842 -173.118313) (xy 36.104599 -173.16491) (xy 36.142172 -173.216625) (xy 36.172966 -173.27264)
			(xy 36.196498 -173.332073) (xy 36.212395 -173.393987) (xy 36.220406 -173.457405) (xy 36.220908 -173.489366)
			(xy 36.220375 -173.521817) (xy 36.218376 -173.537372) (xy 38.405052 -173.537372) (xy 38.409123 -173.48175)
			(xy 38.421249 -173.427313) (xy 38.441172 -173.375222) (xy 38.468468 -173.326587) (xy 38.502554 -173.282444)
			(xy 38.542703 -173.243735) (xy 38.588061 -173.211284) (xy 38.637661 -173.185783) (xy 38.690445 -173.167776)
			(xy 38.745288 -173.157646) (xy 38.801022 -173.155609) (xy 38.856459 -173.161709) (xy 38.910416 -173.175815)
			(xy 38.961745 -173.197627) (xy 39.009351 -173.226681) (xy 39.052219 -173.262356) (xy 39.089436 -173.303893)
			(xy 39.120209 -173.350406) (xy 39.143881 -173.400903) (xy 39.159949 -173.45431) (xy 39.168069 -173.509486)
			(xy 39.168578 -173.537372) (xy 39.168069 -173.565258) (xy 39.159949 -173.620434) (xy 39.143881 -173.673841)
			(xy 39.120209 -173.724338) (xy 39.089436 -173.770851) (xy 39.052219 -173.812388) (xy 39.009351 -173.848063)
			(xy 38.961745 -173.877117) (xy 38.946054 -173.883785) (xy 40.572684 -173.883785) (xy 40.572684 -173.819863)
			(xy 40.580695 -173.756445) (xy 40.596592 -173.694531) (xy 40.620124 -173.635098) (xy 40.650918 -173.579083)
			(xy 40.688491 -173.527368) (xy 40.732248 -173.480771) (xy 40.781501 -173.440026) (xy 40.835472 -173.405775)
			(xy 40.893311 -173.378558) (xy 40.954104 -173.358805) (xy 41.016894 -173.346827) (xy 41.08069 -173.342814)
			(xy 41.144486 -173.346827) (xy 41.207276 -173.358805) (xy 41.268069 -173.378558) (xy 41.325908 -173.405775)
			(xy 41.379879 -173.440026) (xy 41.429132 -173.480771) (xy 41.472889 -173.527368) (xy 41.510462 -173.579083)
			(xy 41.541256 -173.635098) (xy 41.564788 -173.694531) (xy 41.580685 -173.756445) (xy 41.588696 -173.819863)
			(xy 41.589198 -173.851824) (xy 41.588696 -173.883785) (xy 41.581728 -173.938946) (xy 43.306492 -173.938946)
			(xy 43.306974 -173.907703) (xy 43.314622 -173.845686) (xy 43.329809 -173.785073) (xy 43.352306 -173.726777)
			(xy 43.381773 -173.671676) (xy 43.417769 -173.620598) (xy 43.45975 -173.574315) (xy 43.507083 -173.533522)
			(xy 43.532806 -173.515782) (xy 43.540463 -173.510202) (xy 43.551288 -173.494667) (xy 43.553888 -173.485556)
			(xy 43.561254 -173.455584) (xy 43.563133 -173.446353) (xy 43.560635 -173.427692) (xy 43.556428 -173.419262)
			(xy 43.541863 -173.391143) (xy 43.521268 -173.331262) (xy 43.510824 -173.268806) (xy 43.5102 -173.237144)
			(xy 43.510612 -173.211427) (xy 43.517528 -173.16046) (xy 43.531228 -173.110883) (xy 43.551462 -173.063596)
			(xy 43.564302 -173.04131) (xy 43.564302 -173.041056) (xy 43.568445 -173.033292) (xy 43.571697 -173.016012)
			(xy 43.570652 -173.007274) (xy 43.559984 -172.94225) (xy 43.558237 -172.933531) (xy 43.549508 -172.918049)
			(xy 43.542966 -172.912024) (xy 43.542712 -172.91177) (xy 43.51906 -172.891011) (xy 43.476516 -172.84464)
			(xy 43.440019 -172.793373) (xy 43.410128 -172.737994) (xy 43.387299 -172.679349) (xy 43.371883 -172.618335)
			(xy 43.364114 -172.555886) (xy 43.363642 -172.52442) (xy 43.364144 -172.492459) (xy 43.372155 -172.429041)
			(xy 43.388052 -172.367127) (xy 43.411584 -172.307694) (xy 43.442378 -172.251679) (xy 43.479951 -172.199964)
			(xy 43.523708 -172.153367) (xy 43.572961 -172.112622) (xy 43.626932 -172.078371) (xy 43.684771 -172.051154)
			(xy 43.745564 -172.031401) (xy 43.808354 -172.019423) (xy 43.87215 -172.01541) (xy 43.935946 -172.019423)
			(xy 43.998736 -172.031401) (xy 44.059529 -172.051154) (xy 44.117368 -172.078371) (xy 44.171339 -172.112622)
			(xy 44.220592 -172.153367) (xy 44.264349 -172.199964) (xy 44.301922 -172.251679) (xy 44.332716 -172.307694)
			(xy 44.356248 -172.367127) (xy 44.372145 -172.429041) (xy 44.380156 -172.492459) (xy 44.380658 -172.52442)
			(xy 44.380092 -172.558823) (xy 44.370818 -172.627001) (xy 44.35243 -172.693305) (xy 44.325263 -172.75652)
			(xy 44.289814 -172.815492) (xy 44.246732 -172.869141) (xy 44.222162 -172.893228) (xy 44.215812 -172.899324)
			(xy 44.207684 -172.91558) (xy 44.199556 -172.989748) (xy 44.198925 -172.99871) (xy 44.20321 -173.016145)
			(xy 44.207938 -173.023784) (xy 44.223342 -173.047551) (xy 44.24774 -173.098661) (xy 44.264313 -173.152816)
			(xy 44.272696 -173.208827) (xy 44.273216 -173.237144) (xy 44.272754 -173.264443) (xy 44.264977 -173.318486)
			(xy 44.249573 -173.370866) (xy 44.226857 -173.420516) (xy 44.197295 -173.466419) (xy 44.179744 -173.487334)
			(xy 44.173935 -173.494681) (xy 44.167537 -173.512263) (xy 44.167298 -173.521624) (xy 44.167806 -173.552866)
			(xy 44.168431 -173.562329) (xy 44.175729 -173.579816) (xy 44.18203 -173.586902) (xy 44.204108 -173.610638)
			(xy 44.242656 -173.662756) (xy 44.274271 -173.719348) (xy 44.29844 -173.779499) (xy 44.314772 -173.842233)
			(xy 44.323002 -173.906534) (xy 44.323508 -173.938946) (xy 44.323006 -173.970907) (xy 44.314995 -174.034325)
			(xy 44.299098 -174.096239) (xy 44.275566 -174.155672) (xy 44.244772 -174.211687) (xy 44.207199 -174.263402)
			(xy 44.163442 -174.309999) (xy 44.114189 -174.350744) (xy 44.060218 -174.384995) (xy 44.002379 -174.412212)
			(xy 43.941586 -174.431965) (xy 43.878796 -174.443943) (xy 43.815 -174.447957) (xy 43.751204 -174.443943)
			(xy 43.688414 -174.431965) (xy 43.627621 -174.412212) (xy 43.569782 -174.384995) (xy 43.515811 -174.350744)
			(xy 43.466558 -174.309999) (xy 43.422801 -174.263402) (xy 43.385228 -174.211687) (xy 43.354434 -174.155672)
			(xy 43.330902 -174.096239) (xy 43.315005 -174.034325) (xy 43.306994 -173.970907) (xy 43.306492 -173.938946)
			(xy 41.581728 -173.938946) (xy 41.580685 -173.947203) (xy 41.564788 -174.009117) (xy 41.541256 -174.06855)
			(xy 41.510462 -174.124565) (xy 41.472889 -174.17628) (xy 41.429132 -174.222877) (xy 41.379879 -174.263622)
			(xy 41.325908 -174.297873) (xy 41.268069 -174.32509) (xy 41.207276 -174.344843) (xy 41.144486 -174.356821)
			(xy 41.08069 -174.360835) (xy 41.016894 -174.356821) (xy 40.954104 -174.344843) (xy 40.893311 -174.32509)
			(xy 40.835472 -174.297873) (xy 40.781501 -174.263622) (xy 40.732248 -174.222877) (xy 40.688491 -174.17628)
			(xy 40.650918 -174.124565) (xy 40.620124 -174.06855) (xy 40.596592 -174.009117) (xy 40.580695 -173.947203)
			(xy 40.572684 -173.883785) (xy 38.946054 -173.883785) (xy 38.910416 -173.898929) (xy 38.856459 -173.913035)
			(xy 38.801022 -173.919135) (xy 38.745288 -173.917098) (xy 38.690445 -173.906968) (xy 38.637661 -173.888961)
			(xy 38.588061 -173.86346) (xy 38.542703 -173.831009) (xy 38.502554 -173.7923) (xy 38.468468 -173.748157)
			(xy 38.441172 -173.699522) (xy 38.421249 -173.647431) (xy 38.409123 -173.592994) (xy 38.405052 -173.537372)
			(xy 36.218376 -173.537372) (xy 36.212101 -173.58619) (xy 36.195711 -173.648989) (xy 36.171468 -173.709194)
			(xy 36.139768 -173.765828) (xy 36.101124 -173.817972) (xy 36.056164 -173.864779) (xy 36.005617 -173.90549)
			(xy 35.950304 -173.939444) (xy 35.891123 -173.966089) (xy 35.860228 -173.97603) (xy 35.846489 -173.980701)
			(xy 35.822228 -173.996599) (xy 35.803423 -174.018684) (xy 35.791595 -174.045169) (xy 35.7877 -174.073912)
			(xy 35.792052 -174.10259) (xy 35.804301 -174.128883) (xy 35.813492 -174.140114) (xy 35.831273 -174.161096)
			(xy 35.861226 -174.207221) (xy 35.88425 -174.257167) (xy 35.899868 -174.309901) (xy 35.907756 -174.364329)
			(xy 35.908234 -174.391828) (xy 35.907748 -174.419079) (xy 35.899992 -174.473027) (xy 35.884637 -174.525322)
			(xy 35.861995 -174.574899) (xy 35.832529 -174.620749) (xy 35.796838 -174.66194) (xy 35.755647 -174.697631)
			(xy 35.709797 -174.727097) (xy 35.66022 -174.749739) (xy 35.607925 -174.765094) (xy 35.553977 -174.77285)
			(xy 35.499475 -174.77285) (xy 35.445527 -174.765094) (xy 35.393232 -174.749739) (xy 35.343655 -174.727097)
			(xy 35.297805 -174.697631) (xy 35.256614 -174.66194) (xy 35.220923 -174.620749) (xy 35.191457 -174.574899)
			(xy 35.168815 -174.525322) (xy 35.15346 -174.473027) (xy 35.145704 -174.419079) (xy 35.145218 -174.391828)
			(xy 34.757321 -174.391828) (xy 34.738363 -174.450176) (xy 34.711147 -174.508014) (xy 34.676897 -174.561984)
			(xy 34.636152 -174.611236) (xy 34.589556 -174.654993) (xy 34.537844 -174.692566) (xy 34.48183 -174.72336)
			(xy 34.422398 -174.746892) (xy 34.360485 -174.762789) (xy 34.297068 -174.770802) (xy 34.265108 -174.771304)
			(xy 34.264854 -174.771304) (xy 34.23456 -174.770873) (xy 34.174402 -174.763659) (xy 34.115527 -174.749351)
			(xy 34.058769 -174.72815) (xy 34.00493 -174.700358) (xy 33.954774 -174.666368) (xy 33.931606 -174.646844)
			(xy 33.924748 -174.640748) (xy 33.90773 -174.634398) (xy 33.822386 -174.634398) (xy 33.805368 -174.640748)
			(xy 33.79851 -174.646844) (xy 33.775337 -174.666363) (xy 33.725189 -174.700366) (xy 33.671353 -174.728165)
			(xy 33.614594 -174.749366) (xy 33.555717 -174.763668) (xy 33.495557 -174.770868) (xy 33.465262 -174.771304)
			(xy 33.465008 -174.771304) (xy 33.433045 -174.770832) (xy 33.369623 -174.76282) (xy 33.307705 -174.746924)
			(xy 33.248268 -174.723392) (xy 33.192249 -174.692596) (xy 33.140532 -174.655021) (xy 33.093932 -174.611262)
			(xy 33.053184 -174.562006) (xy 33.01893 -174.508032) (xy 32.991711 -174.45019) (xy 32.971957 -174.389393)
			(xy 32.959978 -174.3266) (xy 32.955964 -174.2628) (xy 29.217942 -174.2628) (xy 29.220674 -174.284429)
			(xy 29.221176 -174.31639) (xy 29.220674 -174.348351) (xy 29.212663 -174.411769) (xy 29.196766 -174.473683)
			(xy 29.173234 -174.533116) (xy 29.14244 -174.589131) (xy 29.104867 -174.640846) (xy 29.06111 -174.687443)
			(xy 29.011857 -174.728188) (xy 28.957886 -174.762439) (xy 28.900047 -174.789656) (xy 28.839254 -174.809409)
			(xy 28.776464 -174.821387) (xy 28.712668 -174.825401) (xy 28.648872 -174.821387) (xy 28.586082 -174.809409)
			(xy 28.525289 -174.789656) (xy 28.46745 -174.762439) (xy 28.413479 -174.728188) (xy 28.364226 -174.687443)
			(xy 28.320469 -174.640846) (xy 28.282896 -174.589131) (xy 28.252102 -174.533116) (xy 28.22857 -174.473683)
			(xy 28.212673 -174.411769) (xy 28.204662 -174.348351) (xy 21.98878 -174.348351) (xy 21.98878 -178.896518)
			(xy 21.988353 -178.906586) (xy 21.980632 -178.925184) (xy 21.973794 -178.932586) (xy 17.39646 -183.50992)
			(xy 28.061412 -183.50992) (xy 28.061834 -183.471632) (xy 28.068459 -183.395341) (xy 28.08161 -183.319901)
			(xy 28.10119 -183.245869) (xy 28.113736 -183.209692) (xy 28.116377 -183.201253) (xy 28.116384 -183.183584)
			(xy 28.113736 -183.175148) (xy 28.101158 -183.138981) (xy 28.081567 -183.064949) (xy 28.068422 -182.989505)
			(xy 28.061819 -182.91321) (xy 28.061412 -182.87492) (xy 28.061834 -182.836632) (xy 28.068459 -182.760341)
			(xy 28.08161 -182.684901) (xy 28.10119 -182.610869) (xy 28.113736 -182.574692) (xy 28.116377 -182.566253)
			(xy 28.116384 -182.548584) (xy 28.113736 -182.540148) (xy 28.101158 -182.503981) (xy 28.081567 -182.429949)
			(xy 28.068422 -182.354505) (xy 28.061819 -182.27821) (xy 28.061412 -182.23992) (xy 28.061834 -182.201632)
			(xy 28.068459 -182.125341) (xy 28.08161 -182.049901) (xy 28.10119 -181.975869) (xy 28.113736 -181.939692)
			(xy 28.116377 -181.931253) (xy 28.116384 -181.913584) (xy 28.113736 -181.905148) (xy 28.101158 -181.868981)
			(xy 28.081567 -181.794949) (xy 28.068422 -181.719505) (xy 28.061819 -181.64321) (xy 28.061412 -181.60492)
			(xy 28.061871 -181.563817) (xy 28.069455 -181.48196) (xy 28.084559 -181.401153) (xy 28.107055 -181.322084)
			(xy 28.13675 -181.245428) (xy 28.173392 -181.171839) (xy 28.216668 -181.101945) (xy 28.266209 -181.036343)
			(xy 28.321591 -180.975591) (xy 28.382343 -180.920209) (xy 28.447945 -180.870668) (xy 28.517839 -180.827392)
			(xy 28.591428 -180.79075) (xy 28.668084 -180.761055) (xy 28.747153 -180.738559) (xy 28.82796 -180.723455)
			(xy 28.909817 -180.715871) (xy 28.95092 -180.715412) (xy 28.989208 -180.715851) (xy 29.065498 -180.722471)
			(xy 29.140938 -180.735617) (xy 29.21497 -180.755193) (xy 29.251148 -180.767736) (xy 29.259585 -180.770387)
			(xy 29.277255 -180.770387) (xy 29.285692 -180.767736) (xy 29.321865 -180.755175) (xy 29.395895 -180.735579)
			(xy 29.471337 -180.722429) (xy 29.54763 -180.715822) (xy 29.58592 -180.715412) (xy 29.624208 -180.715851)
			(xy 29.700498 -180.722471) (xy 29.775938 -180.735617) (xy 29.84997 -180.755193) (xy 29.886148 -180.767736)
			(xy 29.894585 -180.770387) (xy 29.912255 -180.770387) (xy 29.920692 -180.767736) (xy 29.956865 -180.755175)
			(xy 30.030895 -180.735579) (xy 30.106337 -180.722429) (xy 30.18263 -180.715822) (xy 30.22092 -180.715412)
			(xy 30.259208 -180.715851) (xy 30.335498 -180.722471) (xy 30.410938 -180.735617) (xy 30.48497 -180.755193)
			(xy 30.521148 -180.767736) (xy 30.529585 -180.770387) (xy 30.547255 -180.770387) (xy 30.555692 -180.767736)
			(xy 30.591865 -180.755175) (xy 30.665895 -180.735579) (xy 30.741337 -180.722429) (xy 30.81763 -180.715822)
			(xy 30.85592 -180.715412) (xy 30.894208 -180.715851) (xy 30.970498 -180.722471) (xy 31.045938 -180.735617)
			(xy 31.11997 -180.755193) (xy 31.156148 -180.767736) (xy 31.164585 -180.770387) (xy 31.182255 -180.770387)
			(xy 31.190692 -180.767736) (xy 31.226865 -180.755175) (xy 31.300895 -180.735579) (xy 31.376337 -180.722429)
			(xy 31.45263 -180.715822) (xy 31.49092 -180.715412) (xy 31.532023 -180.715848) (xy 31.613879 -180.723435)
			(xy 31.694686 -180.738542) (xy 31.773754 -180.761041) (xy 31.850409 -180.790739) (xy 31.923997 -180.827383)
			(xy 31.99389 -180.870661) (xy 32.059491 -180.920203) (xy 32.120241 -180.975587) (xy 32.175622 -181.03634)
			(xy 32.225162 -181.101943) (xy 32.268436 -181.171838) (xy 32.305077 -181.245427) (xy 32.334772 -181.322084)
			(xy 32.34977 -181.3748) (xy 51.611482 -181.3748) (xy 51.615397 -181.297604) (xy 51.627102 -181.2212)
			(xy 51.646477 -181.146372) (xy 51.673323 -181.073888) (xy 51.707365 -181.004493) (xy 51.748253 -180.938897)
			(xy 51.795567 -180.877775) (xy 51.848823 -180.821754) (xy 51.907473 -180.771408) (xy 51.970916 -180.727253)
			(xy 52.038501 -180.689745) (xy 52.109533 -180.659266) (xy 52.183285 -180.63613) (xy 52.258999 -180.620575)
			(xy 52.335898 -180.612759) (xy 52.374546 -180.612288) (xy 52.41129 -180.612756) (xy 52.484438 -180.619817)
			(xy 52.556568 -180.633878) (xy 52.627012 -180.654809) (xy 52.695117 -180.682416) (xy 52.760252 -180.716443)
			(xy 52.821813 -180.756576) (xy 52.850796 -180.779166) (xy 52.860114 -180.785939) (xy 52.882546 -180.791077)
			(xy 52.904978 -180.785939) (xy 52.914296 -180.779166) (xy 52.943263 -180.756554) (xy 53.004826 -180.716419)
			(xy 53.069964 -180.68239) (xy 53.138071 -180.654781) (xy 53.208517 -180.633848) (xy 53.28065 -180.619786)
			(xy 53.353801 -180.612725) (xy 53.390546 -180.612288) (xy 53.429189 -180.612788) (xy 53.50608 -180.620611)
			(xy 53.581784 -180.636173) (xy 53.655525 -180.659313) (xy 53.726547 -180.689795) (xy 53.794122 -180.727305)
			(xy 53.857554 -180.771459) (xy 53.916195 -180.821804) (xy 53.969441 -180.877822) (xy 54.016748 -180.93894)
			(xy 54.057628 -181.00453) (xy 54.091664 -181.07392) (xy 54.118505 -181.146396) (xy 54.137877 -181.221216)
			(xy 54.14958 -181.297612) (xy 54.153494 -181.3748) (xy 54.14958 -181.451988) (xy 54.137877 -181.528384)
			(xy 54.118505 -181.603204) (xy 54.091664 -181.67568) (xy 54.057628 -181.74507) (xy 54.016748 -181.81066)
			(xy 53.969441 -181.871778) (xy 53.916195 -181.927796) (xy 53.857554 -181.978141) (xy 53.794122 -182.022295)
			(xy 53.726547 -182.059805) (xy 53.655525 -182.090287) (xy 53.581784 -182.113427) (xy 53.50608 -182.128989)
			(xy 53.429189 -182.136812) (xy 53.390546 -182.137304) (xy 53.353802 -182.136842) (xy 53.280654 -182.129781)
			(xy 53.208524 -182.115719) (xy 53.13808 -182.094787) (xy 53.069975 -182.067179) (xy 53.00484 -182.03315)
			(xy 52.943278 -181.993017) (xy 52.914296 -181.970426) (xy 52.904978 -181.963653) (xy 52.882546 -181.958515)
			(xy 52.860114 -181.963653) (xy 52.850796 -181.970426) (xy 52.821796 -181.992994) (xy 52.760239 -182.033133)
			(xy 52.695108 -182.067168) (xy 52.627006 -182.094784) (xy 52.556565 -182.115723) (xy 52.484437 -182.129793)
			(xy 52.41129 -182.136863) (xy 52.374546 -182.137304) (xy 52.335898 -182.136841) (xy 52.258999 -182.129025)
			(xy 52.183285 -182.11347) (xy 52.109533 -182.090334) (xy 52.038501 -182.059855) (xy 51.970916 -182.022347)
			(xy 51.907473 -181.978192) (xy 51.848823 -181.927846) (xy 51.795567 -181.871825) (xy 51.748253 -181.810703)
			(xy 51.707365 -181.745107) (xy 51.673323 -181.675712) (xy 51.646477 -181.603228) (xy 51.627102 -181.5284)
			(xy 51.615397 -181.451996) (xy 51.611482 -181.3748) (xy 32.34977 -181.3748) (xy 32.357267 -181.401153)
			(xy 32.372371 -181.48196) (xy 32.379954 -181.563817) (xy 32.380428 -181.60492) (xy 32.379986 -181.643208)
			(xy 32.373367 -181.719498) (xy 32.360221 -181.794938) (xy 32.340647 -181.86897) (xy 32.328104 -181.905148)
			(xy 32.325445 -181.913582) (xy 32.325451 -181.931255) (xy 32.328104 -181.939692) (xy 32.340667 -181.975864)
			(xy 32.360261 -182.049895) (xy 32.373411 -182.125337) (xy 32.380018 -182.20163) (xy 32.380428 -182.23992)
			(xy 32.379986 -182.278208) (xy 32.373367 -182.354498) (xy 32.360221 -182.429938) (xy 32.340647 -182.50397)
			(xy 32.328104 -182.540148) (xy 32.325445 -182.548582) (xy 32.325451 -182.566255) (xy 32.328104 -182.574692)
			(xy 32.340667 -182.610864) (xy 32.360261 -182.684895) (xy 32.373411 -182.760337) (xy 32.380018 -182.83663)
			(xy 32.380428 -182.87492) (xy 32.379986 -182.913208) (xy 32.373367 -182.989498) (xy 32.360221 -183.064938)
			(xy 32.340647 -183.13897) (xy 32.328104 -183.175148) (xy 32.325445 -183.183582) (xy 32.325451 -183.201255)
			(xy 32.328104 -183.209692) (xy 32.340667 -183.245864) (xy 32.360261 -183.319895) (xy 32.373411 -183.395337)
			(xy 32.380018 -183.47163) (xy 32.380428 -183.50992) (xy 32.379952 -183.551022) (xy 32.372366 -183.632876)
			(xy 32.35726 -183.71368) (xy 32.334762 -183.792746) (xy 32.305065 -183.8694) (xy 32.268423 -183.942986)
			(xy 32.225148 -184.012877) (xy 32.175608 -184.078477) (xy 32.120227 -184.139227) (xy 32.059477 -184.194608)
			(xy 31.993877 -184.244148) (xy 31.923986 -184.287423) (xy 31.8504 -184.324065) (xy 31.773746 -184.353762)
			(xy 31.69468 -184.37626) (xy 31.613876 -184.391366) (xy 31.532022 -184.398952) (xy 31.49092 -184.399428)
			(xy 31.452632 -184.399004) (xy 31.376341 -184.392379) (xy 31.300901 -184.379229) (xy 31.226869 -184.359649)
			(xy 31.190692 -184.347104) (xy 31.182255 -184.344453) (xy 31.164585 -184.344453) (xy 31.156148 -184.347104)
			(xy 31.119981 -184.359684) (xy 31.045949 -184.379274) (xy 30.970505 -184.392419) (xy 30.89421 -184.399021)
			(xy 30.85592 -184.399428) (xy 30.817632 -184.399004) (xy 30.741341 -184.392379) (xy 30.665901 -184.379229)
			(xy 30.591869 -184.359649) (xy 30.555692 -184.347104) (xy 30.547255 -184.344453) (xy 30.529585 -184.344453)
			(xy 30.521148 -184.347104) (xy 30.484981 -184.359684) (xy 30.410949 -184.379274) (xy 30.335505 -184.392419)
			(xy 30.25921 -184.399021) (xy 30.22092 -184.399428) (xy 30.182632 -184.399004) (xy 30.106341 -184.392379)
			(xy 30.030901 -184.379229) (xy 29.956869 -184.359649) (xy 29.920692 -184.347104) (xy 29.912255 -184.344453)
			(xy 29.894585 -184.344453) (xy 29.886148 -184.347104) (xy 29.849981 -184.359684) (xy 29.775949 -184.379274)
			(xy 29.700505 -184.392419) (xy 29.62421 -184.399021) (xy 29.58592 -184.399428) (xy 29.547632 -184.399004)
			(xy 29.471341 -184.392379) (xy 29.395901 -184.379229) (xy 29.321869 -184.359649) (xy 29.285692 -184.347104)
			(xy 29.277255 -184.344453) (xy 29.259585 -184.344453) (xy 29.251148 -184.347104) (xy 29.214981 -184.359684)
			(xy 29.140949 -184.379274) (xy 29.065505 -184.392419) (xy 28.98921 -184.399021) (xy 28.95092 -184.399428)
			(xy 28.909818 -184.398914) (xy 28.827966 -184.391331) (xy 28.747162 -184.376228) (xy 28.668096 -184.353734)
			(xy 28.591444 -184.324041) (xy 28.517857 -184.287401) (xy 28.447966 -184.244129) (xy 28.382365 -184.194592)
			(xy 28.321615 -184.139213) (xy 28.266234 -184.078465) (xy 28.216694 -184.012867) (xy 28.173418 -183.942977)
			(xy 28.136775 -183.869393) (xy 28.107078 -183.792742) (xy 28.084581 -183.713677) (xy 28.069474 -183.632874)
			(xy 28.061888 -183.551022) (xy 28.061412 -183.50992) (xy 17.39646 -183.50992) (xy 14.32103 -186.58535)
			(xy 17.790174 -186.58535) (xy 17.794166 -186.496463) (xy 17.80611 -186.408292) (xy 17.825909 -186.321547)
			(xy 17.853404 -186.236926) (xy 17.888374 -186.15511) (xy 17.930537 -186.076757) (xy 17.979553 -186.0025)
			(xy 18.035029 -185.932936) (xy 18.096517 -185.868624) (xy 18.163522 -185.810083) (xy 18.235505 -185.757784)
			(xy 18.311887 -185.712148) (xy 18.392051 -185.673542) (xy 18.475354 -185.642278) (xy 18.561124 -185.618607)
			(xy 18.64867 -185.602719) (xy 18.737288 -185.594743) (xy 18.781776 -185.594244) (xy 20.534376 -185.594244)
			(xy 20.578865 -185.594724) (xy 20.667485 -185.6027) (xy 20.755034 -185.618587) (xy 20.840806 -185.642259)
			(xy 20.92411 -185.673523) (xy 21.004277 -185.712129) (xy 21.080661 -185.757766) (xy 21.152646 -185.810066)
			(xy 21.219653 -185.868608) (xy 21.281143 -185.932921) (xy 21.33662 -186.002487) (xy 21.385638 -186.076746)
			(xy 21.427802 -186.155099) (xy 21.462773 -186.236917) (xy 21.490269 -186.321541) (xy 21.510068 -186.408288)
			(xy 21.522012 -186.496461) (xy 21.526004 -186.58535) (xy 25.334225 -186.58535) (xy 25.338216 -186.496463)
			(xy 25.35016 -186.408292) (xy 25.369959 -186.321546) (xy 25.397454 -186.236925) (xy 25.432424 -186.155108)
			(xy 25.474587 -186.076756) (xy 25.523604 -186.002499) (xy 25.57908 -185.932934) (xy 25.640568 -185.868623)
			(xy 25.707574 -185.810082) (xy 25.779558 -185.757783) (xy 25.855939 -185.712147) (xy 25.936104 -185.673541)
			(xy 26.019407 -185.642277) (xy 26.105177 -185.618606) (xy 26.192724 -185.602719) (xy 26.281342 -185.594743)
			(xy 26.32583 -185.594244) (xy 28.07843 -185.594244) (xy 28.122918 -185.594739) (xy 28.211537 -185.602715)
			(xy 28.299084 -185.618602) (xy 28.384854 -185.642273) (xy 28.468157 -185.673538) (xy 28.548323 -185.712143)
			(xy 28.624705 -185.757779) (xy 28.696688 -185.810078) (xy 28.763694 -185.86862) (xy 28.825183 -185.932932)
			(xy 28.880659 -186.002497) (xy 28.929676 -186.076754) (xy 28.971839 -186.155107) (xy 29.006809 -186.236923)
			(xy 29.034305 -186.321545) (xy 29.054104 -186.408291) (xy 29.066048 -186.496463) (xy 29.07004 -186.58535)
			(xy 32.878025 -186.58535) (xy 32.882016 -186.496463) (xy 32.89396 -186.408292) (xy 32.913759 -186.321546)
			(xy 32.941254 -186.236925) (xy 32.976224 -186.155108) (xy 33.018387 -186.076756) (xy 33.067404 -186.002499)
			(xy 33.12288 -185.932934) (xy 33.184368 -185.868623) (xy 33.251374 -185.810082) (xy 33.323358 -185.757783)
			(xy 33.399739 -185.712147) (xy 33.479904 -185.673541) (xy 33.563207 -185.642277) (xy 33.648977 -185.618606)
			(xy 33.736524 -185.602719) (xy 33.825142 -185.594743) (xy 33.86963 -185.594244) (xy 35.62223 -185.594244)
			(xy 35.666718 -185.594739) (xy 35.755337 -185.602715) (xy 35.842884 -185.618602) (xy 35.928654 -185.642273)
			(xy 36.011957 -185.673538) (xy 36.092123 -185.712143) (xy 36.168505 -185.757779) (xy 36.240488 -185.810078)
			(xy 36.307494 -185.86862) (xy 36.368983 -185.932932) (xy 36.424459 -186.002497) (xy 36.473476 -186.076754)
			(xy 36.515639 -186.155107) (xy 36.550609 -186.236923) (xy 36.578105 -186.321545) (xy 36.597904 -186.408291)
			(xy 36.609848 -186.496463) (xy 36.61384 -186.58535) (xy 40.42206 -186.58535) (xy 40.426052 -186.496462)
			(xy 40.437996 -186.408289) (xy 40.457795 -186.321542) (xy 40.485291 -186.236919) (xy 40.520262 -186.155101)
			(xy 40.562426 -186.076748) (xy 40.611444 -186.002489) (xy 40.66692 -185.932923) (xy 40.72841 -185.868611)
			(xy 40.795417 -185.810069) (xy 40.867402 -185.757769) (xy 40.943785 -185.712133) (xy 41.023951 -185.673527)
			(xy 41.107256 -185.642262) (xy 41.193027 -185.618591) (xy 41.280575 -185.602704) (xy 41.369195 -185.594728)
			(xy 41.413684 -185.594244) (xy 43.166284 -185.594244) (xy 43.210772 -185.594739) (xy 43.299391 -185.602715)
			(xy 43.386937 -185.618603) (xy 43.472707 -185.642274) (xy 43.55601 -185.673539) (xy 43.636175 -185.712144)
			(xy 43.712557 -185.757781) (xy 43.78454 -185.81008) (xy 43.842136 -185.8604) (xy 47.257025 -185.8604)
			(xy 47.261039 -185.796611) (xy 47.273015 -185.733828) (xy 47.292765 -185.673041) (xy 47.319978 -185.615208)
			(xy 47.354224 -185.561242) (xy 47.394964 -185.511993) (xy 47.441554 -185.468239) (xy 47.493262 -185.430669)
			(xy 47.54927 -185.399875) (xy 47.608695 -185.376344) (xy 47.670602 -185.360446) (xy 47.734012 -185.352432)
			(xy 47.76597 -185.351928) (xy 47.798223 -185.352408) (xy 47.86221 -185.360562) (xy 47.924653 -185.376744)
			(xy 47.984548 -185.400693) (xy 48.040933 -185.432024) (xy 48.092902 -185.470235) (xy 48.139622 -185.514711)
			(xy 48.180342 -185.56474) (xy 48.214407 -185.619516) (xy 48.241272 -185.678161) (xy 48.251364 -185.708798)
			(xy 48.255519 -185.719965) (xy 48.272087 -185.737049) (xy 48.283114 -185.741564) (xy 48.371252 -185.772552)
			(xy 48.395128 -185.769504) (xy 48.405034 -185.7629) (xy 48.440041 -185.739887) (xy 48.513258 -185.69916)
			(xy 48.589655 -185.664763) (xy 48.668684 -185.636944) (xy 48.74978 -185.6159) (xy 48.832365 -185.601782)
			(xy 48.915847 -185.59469) (xy 48.957738 -185.594244) (xy 50.710338 -185.594244) (xy 50.754827 -185.594724)
			(xy 50.843447 -185.6027) (xy 50.930995 -185.618588) (xy 51.016767 -185.642259) (xy 51.100072 -185.673524)
			(xy 51.180238 -185.71213) (xy 51.256622 -185.757766) (xy 51.328607 -185.810066) (xy 51.395614 -185.868609)
			(xy 51.457103 -185.932921) (xy 51.51258 -186.002487) (xy 51.561598 -186.076746) (xy 51.572152 -186.096359)
			(xy 51.88051 -186.096359) (xy 51.88051 -186.032437) (xy 51.888521 -185.969019) (xy 51.904418 -185.907105)
			(xy 51.92795 -185.847672) (xy 51.958744 -185.791657) (xy 51.996317 -185.739942) (xy 52.040074 -185.693345)
			(xy 52.089327 -185.6526) (xy 52.143298 -185.618349) (xy 52.201137 -185.591132) (xy 52.26193 -185.571379)
			(xy 52.32472 -185.559401) (xy 52.388516 -185.555388) (xy 52.452312 -185.559401) (xy 52.515102 -185.571379)
			(xy 52.575895 -185.591132) (xy 52.633734 -185.618349) (xy 52.687705 -185.6526) (xy 52.736958 -185.693345)
			(xy 52.780715 -185.739942) (xy 52.818288 -185.791657) (xy 52.849082 -185.847672) (xy 52.872614 -185.907105)
			(xy 52.888511 -185.969019) (xy 52.896522 -186.032437) (xy 52.897024 -186.064398) (xy 52.896522 -186.096359)
			(xy 52.888511 -186.159777) (xy 52.872614 -186.221691) (xy 52.849082 -186.281124) (xy 52.818288 -186.337139)
			(xy 52.780715 -186.388854) (xy 52.736958 -186.435451) (xy 52.687705 -186.476196) (xy 52.633734 -186.510447)
			(xy 52.575895 -186.537664) (xy 52.515102 -186.557417) (xy 52.452312 -186.569395) (xy 52.388516 -186.573409)
			(xy 52.32472 -186.569395) (xy 52.26193 -186.557417) (xy 52.201137 -186.537664) (xy 52.143298 -186.510447)
			(xy 52.089327 -186.476196) (xy 52.040074 -186.435451) (xy 51.996317 -186.388854) (xy 51.958744 -186.337139)
			(xy 51.92795 -186.281124) (xy 51.904418 -186.221691) (xy 51.888521 -186.159777) (xy 51.88051 -186.096359)
			(xy 51.572152 -186.096359) (xy 51.603762 -186.1551) (xy 51.638733 -186.236918) (xy 51.666229 -186.321541)
			(xy 51.686028 -186.408288) (xy 51.697972 -186.496461) (xy 51.701964 -186.58535) (xy 51.697972 -186.674239)
			(xy 51.686028 -186.762412) (xy 51.666229 -186.849159) (xy 51.638733 -186.933782) (xy 51.603762 -187.0156)
			(xy 51.561598 -187.093954) (xy 51.51258 -187.168213) (xy 51.457103 -187.237779) (xy 51.397308 -187.300319)
			(xy 52.052976 -187.300319) (xy 52.052976 -187.236397) (xy 52.060987 -187.172979) (xy 52.076884 -187.111065)
			(xy 52.100416 -187.051632) (xy 52.13121 -186.995617) (xy 52.168783 -186.943902) (xy 52.21254 -186.897305)
			(xy 52.261793 -186.85656) (xy 52.315764 -186.822309) (xy 52.373603 -186.795092) (xy 52.434396 -186.775339)
			(xy 52.497186 -186.763361) (xy 52.560982 -186.759348) (xy 52.624778 -186.763361) (xy 52.687568 -186.775339)
			(xy 52.748361 -186.795092) (xy 52.8062 -186.822309) (xy 52.860171 -186.85656) (xy 52.909424 -186.897305)
			(xy 52.953181 -186.943902) (xy 52.990754 -186.995617) (xy 53.021548 -187.051632) (xy 53.04508 -187.111065)
			(xy 53.060977 -187.172979) (xy 53.068988 -187.236397) (xy 53.06949 -187.268358) (xy 53.068988 -187.300319)
			(xy 53.060977 -187.363737) (xy 53.04508 -187.425651) (xy 53.021548 -187.485084) (xy 52.990754 -187.541099)
			(xy 52.953181 -187.592814) (xy 52.909424 -187.639411) (xy 52.860171 -187.680156) (xy 52.8062 -187.714407)
			(xy 52.748361 -187.741624) (xy 52.687568 -187.761377) (xy 52.624778 -187.773355) (xy 52.560982 -187.777369)
			(xy 52.497186 -187.773355) (xy 52.434396 -187.761377) (xy 52.373603 -187.741624) (xy 52.315764 -187.714407)
			(xy 52.261793 -187.680156) (xy 52.21254 -187.639411) (xy 52.168783 -187.592814) (xy 52.13121 -187.541099)
			(xy 52.100416 -187.485084) (xy 52.076884 -187.425651) (xy 52.060987 -187.363737) (xy 52.052976 -187.300319)
			(xy 51.397308 -187.300319) (xy 51.395614 -187.302091) (xy 51.328607 -187.360634) (xy 51.256622 -187.412934)
			(xy 51.180238 -187.45857) (xy 51.100072 -187.497176) (xy 51.016767 -187.528441) (xy 50.930995 -187.552112)
			(xy 50.843447 -187.568) (xy 50.754827 -187.575976) (xy 50.710338 -187.57646) (xy 48.957738 -187.57646)
			(xy 48.911945 -187.575905) (xy 48.82075 -187.567456) (xy 48.730723 -187.550628) (xy 48.642634 -187.525563)
			(xy 48.557234 -187.492476) (xy 48.475252 -187.451649) (xy 48.397387 -187.40343) (xy 48.324304 -187.348231)
			(xy 48.256628 -187.286524) (xy 48.194934 -187.218834) (xy 48.139751 -187.14574) (xy 48.091549 -187.067865)
			(xy 48.050739 -186.985874) (xy 48.01767 -186.900467) (xy 47.992624 -186.812372) (xy 47.975815 -186.722342)
			(xy 47.967386 -186.631145) (xy 47.966884 -186.585352) (xy 47.967067 -186.557159) (xy 47.970244 -186.500864)
			(xy 47.973234 -186.47283) (xy 47.973234 -186.472576) (xy 47.973905 -186.460783) (xy 47.965681 -186.438667)
			(xy 47.957486 -186.430158) (xy 47.898304 -186.374024) (xy 47.889256 -186.366409) (xy 47.866614 -186.359665)
			(xy 47.85487 -186.36107) (xy 47.854362 -186.36107) (xy 47.832447 -186.364732) (xy 47.788187 -186.368674)
			(xy 47.76597 -186.368944) (xy 47.734012 -186.368368) (xy 47.670602 -186.360354) (xy 47.608695 -186.344456)
			(xy 47.54927 -186.320925) (xy 47.493262 -186.290131) (xy 47.441554 -186.252561) (xy 47.394964 -186.208807)
			(xy 47.354224 -186.159558) (xy 47.319978 -186.105592) (xy 47.292765 -186.047759) (xy 47.273015 -185.986972)
			(xy 47.261039 -185.924189) (xy 47.257025 -185.8604) (xy 43.842136 -185.8604) (xy 43.851546 -185.868621)
			(xy 43.913034 -185.932933) (xy 43.96851 -186.002498) (xy 44.017527 -186.076755) (xy 44.05969 -186.155108)
			(xy 44.09466 -186.236924) (xy 44.122155 -186.321546) (xy 44.141954 -186.408292) (xy 44.153898 -186.496463)
			(xy 44.15789 -186.58535) (xy 44.153898 -186.674237) (xy 44.141954 -186.762408) (xy 44.122155 -186.849154)
			(xy 44.09466 -186.933776) (xy 44.05969 -187.015592) (xy 44.017527 -187.093945) (xy 43.96851 -187.168202)
			(xy 43.913034 -187.237767) (xy 43.851546 -187.302079) (xy 43.78454 -187.36062) (xy 43.712557 -187.412919)
			(xy 43.636175 -187.458556) (xy 43.55601 -187.497161) (xy 43.472707 -187.528426) (xy 43.386937 -187.552097)
			(xy 43.299391 -187.567985) (xy 43.210772 -187.575961) (xy 43.166284 -187.57646) (xy 41.413684 -187.57646)
			(xy 41.369195 -187.575972) (xy 41.280575 -187.567996) (xy 41.193027 -187.552109) (xy 41.107256 -187.528438)
			(xy 41.023951 -187.497173) (xy 40.943785 -187.458567) (xy 40.867402 -187.412931) (xy 40.795417 -187.360631)
			(xy 40.72841 -187.302089) (xy 40.66692 -187.237777) (xy 40.611444 -187.168211) (xy 40.562426 -187.093952)
			(xy 40.520262 -187.015599) (xy 40.485291 -186.933781) (xy 40.457795 -186.849158) (xy 40.437996 -186.762411)
			(xy 40.426052 -186.674238) (xy 40.42206 -186.58535) (xy 36.61384 -186.58535) (xy 36.609848 -186.674237)
			(xy 36.597904 -186.762409) (xy 36.578105 -186.849155) (xy 36.550609 -186.933777) (xy 36.515639 -187.015593)
			(xy 36.473476 -187.093946) (xy 36.424459 -187.168203) (xy 36.368983 -187.237768) (xy 36.307494 -187.30208)
			(xy 36.240488 -187.360622) (xy 36.168505 -187.412921) (xy 36.092123 -187.458557) (xy 36.011957 -187.497162)
			(xy 35.928654 -187.528427) (xy 35.842884 -187.552098) (xy 35.755337 -187.567985) (xy 35.666718 -187.575961)
			(xy 35.62223 -187.57646) (xy 33.86963 -187.57646) (xy 33.825142 -187.575957) (xy 33.736524 -187.567981)
			(xy 33.648977 -187.552094) (xy 33.563207 -187.528423) (xy 33.479904 -187.497159) (xy 33.399739 -187.458553)
			(xy 33.323358 -187.412917) (xy 33.251374 -187.360618) (xy 33.184368 -187.302077) (xy 33.12288 -187.237766)
			(xy 33.067404 -187.168201) (xy 33.018387 -187.093944) (xy 32.976224 -187.015592) (xy 32.941254 -186.933775)
			(xy 32.913759 -186.849154) (xy 32.89396 -186.762408) (xy 32.882016 -186.674237) (xy 32.878025 -186.58535)
			(xy 29.07004 -186.58535) (xy 29.066048 -186.674237) (xy 29.054104 -186.762409) (xy 29.034305 -186.849155)
			(xy 29.006809 -186.933777) (xy 28.971839 -187.015593) (xy 28.929676 -187.093946) (xy 28.880659 -187.168203)
			(xy 28.825183 -187.237768) (xy 28.763694 -187.30208) (xy 28.696688 -187.360622) (xy 28.624705 -187.412921)
			(xy 28.548323 -187.458557) (xy 28.468157 -187.497162) (xy 28.384854 -187.528427) (xy 28.299084 -187.552098)
			(xy 28.211537 -187.567985) (xy 28.122918 -187.575961) (xy 28.07843 -187.57646) (xy 26.32583 -187.57646)
			(xy 26.281342 -187.575957) (xy 26.192724 -187.567981) (xy 26.105177 -187.552094) (xy 26.019407 -187.528423)
			(xy 25.936104 -187.497159) (xy 25.855939 -187.458553) (xy 25.779558 -187.412917) (xy 25.707574 -187.360618)
			(xy 25.640568 -187.302077) (xy 25.57908 -187.237766) (xy 25.523604 -187.168201) (xy 25.474587 -187.093944)
			(xy 25.432424 -187.015592) (xy 25.397454 -186.933775) (xy 25.369959 -186.849154) (xy 25.35016 -186.762408)
			(xy 25.338216 -186.674237) (xy 25.334225 -186.58535) (xy 21.526004 -186.58535) (xy 21.522012 -186.674239)
			(xy 21.510068 -186.762412) (xy 21.490269 -186.849159) (xy 21.462773 -186.933783) (xy 21.427802 -187.015601)
			(xy 21.385638 -187.093954) (xy 21.33662 -187.168213) (xy 21.281143 -187.237779) (xy 21.219653 -187.302092)
			(xy 21.152646 -187.360634) (xy 21.080661 -187.412934) (xy 21.004277 -187.458571) (xy 20.92411 -187.497177)
			(xy 20.840806 -187.528441) (xy 20.755034 -187.552113) (xy 20.667485 -187.568) (xy 20.578865 -187.575976)
			(xy 20.534376 -187.57646) (xy 18.781776 -187.57646) (xy 18.737288 -187.575957) (xy 18.64867 -187.567981)
			(xy 18.561124 -187.552093) (xy 18.475354 -187.528422) (xy 18.392051 -187.497158) (xy 18.311887 -187.458552)
			(xy 18.235505 -187.412916) (xy 18.163522 -187.360617) (xy 18.096517 -187.302076) (xy 18.035029 -187.237764)
			(xy 17.979553 -187.1682) (xy 17.930537 -187.093943) (xy 17.888374 -187.01559) (xy 17.853404 -186.933774)
			(xy 17.825909 -186.849153) (xy 17.80611 -186.762408) (xy 17.794166 -186.674237) (xy 17.790174 -186.58535)
			(xy 14.32103 -186.58535) (xy 13.58138 -187.325) (xy 13.574698 -187.332411) (xy 13.57275 -187.337149)
			(xy 14.54378 -187.337149) (xy 14.54378 -187.273227) (xy 14.551791 -187.209809) (xy 14.567688 -187.147895)
			(xy 14.59122 -187.088462) (xy 14.622014 -187.032447) (xy 14.659587 -186.980732) (xy 14.703344 -186.934135)
			(xy 14.752597 -186.89339) (xy 14.806568 -186.859139) (xy 14.864407 -186.831922) (xy 14.9252 -186.812169)
			(xy 14.98799 -186.800191) (xy 15.051786 -186.796178) (xy 15.115582 -186.800191) (xy 15.178372 -186.812169)
			(xy 15.239165 -186.831922) (xy 15.297004 -186.859139) (xy 15.350975 -186.89339) (xy 15.400228 -186.934135)
			(xy 15.443985 -186.980732) (xy 15.481558 -187.032447) (xy 15.512352 -187.088462) (xy 15.535884 -187.147895)
			(xy 15.551781 -187.209809) (xy 15.559792 -187.273227) (xy 15.560294 -187.305188) (xy 15.559792 -187.337149)
			(xy 15.551781 -187.400567) (xy 15.535884 -187.462481) (xy 15.512352 -187.521914) (xy 15.481558 -187.577929)
			(xy 15.443985 -187.629644) (xy 15.400228 -187.676241) (xy 15.350975 -187.716986) (xy 15.297004 -187.751237)
			(xy 15.239165 -187.778454) (xy 15.178372 -187.798207) (xy 15.115582 -187.810185) (xy 15.051786 -187.814199)
			(xy 14.98799 -187.810185) (xy 14.9252 -187.798207) (xy 14.864407 -187.778454) (xy 14.806568 -187.751237)
			(xy 14.752597 -187.716986) (xy 14.703344 -187.676241) (xy 14.659587 -187.629644) (xy 14.622014 -187.577929)
			(xy 14.59122 -187.521914) (xy 14.567688 -187.462481) (xy 14.551791 -187.400567) (xy 14.54378 -187.337149)
			(xy 13.57275 -187.337149) (xy 13.567119 -187.350846) (xy 13.566648 -187.360814) (xy 13.566648 -189.003643)
			(xy 58.669168 -189.003643) (xy 58.669168 -188.939721) (xy 58.677179 -188.876303) (xy 58.693076 -188.814389)
			(xy 58.716608 -188.754956) (xy 58.747402 -188.698941) (xy 58.784975 -188.647226) (xy 58.828732 -188.600629)
			(xy 58.877985 -188.559884) (xy 58.931956 -188.525633) (xy 58.989795 -188.498416) (xy 59.050588 -188.478663)
			(xy 59.113378 -188.466685) (xy 59.177174 -188.462672) (xy 59.24097 -188.466685) (xy 59.30376 -188.478663)
			(xy 59.364553 -188.498416) (xy 59.422392 -188.525633) (xy 59.476363 -188.559884) (xy 59.525616 -188.600629)
			(xy 59.569373 -188.647226) (xy 59.606946 -188.698941) (xy 59.63774 -188.754956) (xy 59.661272 -188.814389)
			(xy 59.677169 -188.876303) (xy 59.68518 -188.939721) (xy 59.685682 -188.971682) (xy 59.68518 -189.003643)
			(xy 59.677169 -189.067061) (xy 59.661272 -189.128975) (xy 59.63774 -189.188408) (xy 59.606946 -189.244423)
			(xy 59.569373 -189.296138) (xy 59.525616 -189.342735) (xy 59.476363 -189.38348) (xy 59.422392 -189.417731)
			(xy 59.364553 -189.444948) (xy 59.30376 -189.464701) (xy 59.24097 -189.476679) (xy 59.177174 -189.480693)
			(xy 59.113378 -189.476679) (xy 59.050588 -189.464701) (xy 58.989795 -189.444948) (xy 58.931956 -189.417731)
			(xy 58.877985 -189.38348) (xy 58.828732 -189.342735) (xy 58.784975 -189.296138) (xy 58.747402 -189.244423)
			(xy 58.716608 -189.188408) (xy 58.693076 -189.128975) (xy 58.677179 -189.067061) (xy 58.669168 -189.003643)
			(xy 13.566648 -189.003643) (xy 13.566648 -193.085212) (xy 15.588234 -193.085212) (xy 15.588742 -193.043487)
			(xy 15.596712 -192.960419) (xy 15.612533 -192.878483) (xy 15.636063 -192.798419) (xy 15.667089 -192.720951)
			(xy 15.68577 -192.683638) (xy 15.690774 -192.672482) (xy 15.690761 -192.648066) (xy 15.68577 -192.636902)
			(xy 15.667085 -192.59959) (xy 15.63604 -192.522128) (xy 15.612502 -192.442064) (xy 15.596683 -192.360125)
			(xy 15.588726 -192.277054) (xy 15.588234 -192.235328) (xy 15.588731 -192.193584) (xy 15.596667 -192.110474)
			(xy 15.612467 -192.028496) (xy 15.635988 -191.94839) (xy 15.667017 -191.870882) (xy 15.705274 -191.796676)
			(xy 15.75041 -191.726441) (xy 15.802019 -191.660815) (xy 15.859632 -191.600393) (xy 15.922728 -191.54572)
			(xy 15.990735 -191.497292) (xy 16.063038 -191.455548) (xy 16.138981 -191.420866) (xy 16.217877 -191.39356)
			(xy 16.299011 -191.373877) (xy 16.381649 -191.361996) (xy 16.465042 -191.358023) (xy 16.548435 -191.361996)
			(xy 16.631073 -191.373877) (xy 16.712207 -191.39356) (xy 16.791103 -191.420866) (xy 16.867046 -191.455548)
			(xy 16.939349 -191.497292) (xy 17.007356 -191.54572) (xy 17.070452 -191.600393) (xy 17.128065 -191.660815)
			(xy 17.179674 -191.726441) (xy 17.22481 -191.796676) (xy 17.263067 -191.870882) (xy 17.294096 -191.94839)
			(xy 17.317617 -192.028496) (xy 17.333417 -192.110474) (xy 17.341353 -192.193584) (xy 17.34165 -192.218564)
			(xy 18.394441 -192.218564) (xy 18.398376 -192.164793) (xy 18.410099 -192.112169) (xy 18.429359 -192.061812)
			(xy 18.455745 -192.014795) (xy 18.488697 -191.972122) (xy 18.52751 -191.934701) (xy 18.571358 -191.903331)
			(xy 18.619306 -191.878679) (xy 18.670333 -191.861271) (xy 18.723351 -191.851478) (xy 18.77723 -191.849509)
			(xy 18.830821 -191.855406) (xy 18.882982 -191.869042) (xy 18.932602 -191.890129) (xy 18.978623 -191.918215)
			(xy 19.020065 -191.952703) (xy 19.056043 -191.992857) (xy 19.085791 -192.037821) (xy 19.108676 -192.086638)
			(xy 19.124208 -192.138267) (xy 19.132058 -192.191607) (xy 19.13255 -192.218564) (xy 20.183109 -192.218564)
			(xy 20.187044 -192.164793) (xy 20.198767 -192.112169) (xy 20.218027 -192.061812) (xy 20.244413 -192.014795)
			(xy 20.277365 -191.972122) (xy 20.316178 -191.934701) (xy 20.360026 -191.903331) (xy 20.407974 -191.878679)
			(xy 20.459001 -191.861271) (xy 20.512019 -191.851478) (xy 20.565898 -191.849509) (xy 20.619489 -191.855406)
			(xy 20.67165 -191.869042) (xy 20.72127 -191.890129) (xy 20.767291 -191.918215) (xy 20.808733 -191.952703)
			(xy 20.844711 -191.992857) (xy 20.874459 -192.037821) (xy 20.897344 -192.086638) (xy 20.912876 -192.138267)
			(xy 20.920726 -192.191607) (xy 20.921218 -192.218564) (xy 20.920912 -192.23533) (xy 21.973803 -192.23533)
			(xy 21.977776 -192.151937) (xy 21.989657 -192.069299) (xy 22.00934 -191.988164) (xy 22.036646 -191.909268)
			(xy 22.071328 -191.833325) (xy 22.113072 -191.761022) (xy 22.1615 -191.693015) (xy 22.216173 -191.629919)
			(xy 22.276596 -191.572306) (xy 22.342222 -191.520697) (xy 22.412457 -191.47556) (xy 22.486664 -191.437303)
			(xy 22.564171 -191.406274) (xy 22.644277 -191.382753) (xy 22.726256 -191.366953) (xy 22.809366 -191.359017)
			(xy 22.85111 -191.35852) (xy 22.893324 -191.359027) (xy 22.977361 -191.367147) (xy 23.060227 -191.383312)
			(xy 23.141154 -191.407371) (xy 23.219393 -191.439101) (xy 23.294218 -191.478208) (xy 23.364934 -191.524329)
			(xy 23.398226 -191.55029) (xy 23.407544 -191.557063) (xy 23.429976 -191.562201) (xy 23.452408 -191.557063)
			(xy 23.461726 -191.55029) (xy 23.495038 -191.524328) (xy 23.565794 -191.478204) (xy 23.640656 -191.439097)
			(xy 23.718931 -191.407367) (xy 23.799894 -191.383308) (xy 23.882795 -191.367144) (xy 23.966865 -191.359024)
			(xy 24.009096 -191.35852) (xy 24.052147 -191.359007) (xy 24.137833 -191.367446) (xy 24.22228 -191.384244)
			(xy 24.304673 -191.409238) (xy 24.38422 -191.442188) (xy 24.460154 -191.482776) (xy 24.531744 -191.530612)
			(xy 24.5983 -191.585234) (xy 24.659182 -191.646118) (xy 24.713803 -191.712676) (xy 24.761637 -191.784267)
			(xy 24.802223 -191.860202) (xy 24.83517 -191.93975) (xy 24.860162 -192.022144) (xy 24.876957 -192.106591)
			(xy 24.885394 -192.192277) (xy 24.885705 -192.218564) (xy 25.938495 -192.218564) (xy 25.94243 -192.164793)
			(xy 25.954153 -192.112169) (xy 25.973413 -192.061812) (xy 25.999799 -192.014795) (xy 26.032751 -191.972122)
			(xy 26.071564 -191.934701) (xy 26.115412 -191.903331) (xy 26.16336 -191.878679) (xy 26.214387 -191.861271)
			(xy 26.267405 -191.851478) (xy 26.321284 -191.849509) (xy 26.374875 -191.855406) (xy 26.427036 -191.869042)
			(xy 26.476656 -191.890129) (xy 26.522677 -191.918215) (xy 26.564119 -191.952703) (xy 26.600097 -191.992857)
			(xy 26.629845 -192.037821) (xy 26.65273 -192.086638) (xy 26.668262 -192.138267) (xy 26.676112 -192.191607)
			(xy 26.676604 -192.218564) (xy 27.727163 -192.218564) (xy 27.731098 -192.164793) (xy 27.742821 -192.112169)
			(xy 27.762081 -192.061812) (xy 27.788467 -192.014795) (xy 27.821419 -191.972122) (xy 27.860232 -191.934701)
			(xy 27.90408 -191.903331) (xy 27.952028 -191.878679) (xy 28.003055 -191.861271) (xy 28.056073 -191.851478)
			(xy 28.109952 -191.849509) (xy 28.163543 -191.855406) (xy 28.215704 -191.869042) (xy 28.265324 -191.890129)
			(xy 28.311345 -191.918215) (xy 28.352787 -191.952703) (xy 28.388765 -191.992857) (xy 28.418513 -192.037821)
			(xy 28.441398 -192.086638) (xy 28.45693 -192.138267) (xy 28.46478 -192.191607) (xy 28.465272 -192.218564)
			(xy 28.464966 -192.23533) (xy 29.517837 -192.23533) (xy 29.52181 -192.151935) (xy 29.533692 -192.069295)
			(xy 29.553375 -191.988159) (xy 29.580682 -191.909261) (xy 29.615365 -191.833316) (xy 29.65711 -191.761012)
			(xy 29.705539 -191.693004) (xy 29.760213 -191.629907) (xy 29.820638 -191.572292) (xy 29.886265 -191.520683)
			(xy 29.956501 -191.475545) (xy 30.03071 -191.437288) (xy 30.108219 -191.406258) (xy 30.188327 -191.382737)
			(xy 30.270308 -191.366937) (xy 30.353419 -191.359001) (xy 30.395164 -191.35852) (xy 30.437369 -191.359036)
			(xy 30.521389 -191.367148) (xy 30.604242 -191.383291) (xy 30.685162 -191.407316) (xy 30.7634 -191.439001)
			(xy 30.838235 -191.478052) (xy 30.908973 -191.52411) (xy 30.94228 -191.550036) (xy 30.951598 -191.556809)
			(xy 30.97403 -191.561947) (xy 30.996462 -191.556809) (xy 31.00578 -191.550036) (xy 31.039095 -191.524118)
			(xy 31.109827 -191.478051) (xy 31.184659 -191.438992) (xy 31.262896 -191.407302) (xy 31.343816 -191.383275)
			(xy 31.426669 -191.367132) (xy 31.51069 -191.359023) (xy 31.552896 -191.35852) (xy 31.595947 -191.359007)
			(xy 31.681633 -191.367446) (xy 31.76608 -191.384244) (xy 31.848473 -191.409238) (xy 31.92802 -191.442188)
			(xy 32.003954 -191.482776) (xy 32.075544 -191.530612) (xy 32.1421 -191.585234) (xy 32.202982 -191.646118)
			(xy 32.257603 -191.712676) (xy 32.305437 -191.784267) (xy 32.346023 -191.860202) (xy 32.37897 -191.93975)
			(xy 32.403962 -192.022144) (xy 32.420757 -192.106591) (xy 32.429194 -192.192277) (xy 32.429505 -192.218564)
			(xy 33.444195 -192.218564) (xy 33.44813 -192.164793) (xy 33.459853 -192.112169) (xy 33.479113 -192.061812)
			(xy 33.505499 -192.014795) (xy 33.538451 -191.972122) (xy 33.577264 -191.934701) (xy 33.621112 -191.903331)
			(xy 33.66906 -191.878679) (xy 33.720087 -191.861271) (xy 33.773105 -191.851478) (xy 33.826984 -191.849509)
			(xy 33.880575 -191.855406) (xy 33.932736 -191.869042) (xy 33.982356 -191.890129) (xy 34.028377 -191.918215)
			(xy 34.069819 -191.952703) (xy 34.105797 -191.992857) (xy 34.135545 -192.037821) (xy 34.15843 -192.086638)
			(xy 34.173962 -192.138267) (xy 34.181812 -192.191607) (xy 34.182304 -192.218564) (xy 35.270963 -192.218564)
			(xy 35.274898 -192.164793) (xy 35.286621 -192.112169) (xy 35.305881 -192.061812) (xy 35.332267 -192.014795)
			(xy 35.365219 -191.972122) (xy 35.404032 -191.934701) (xy 35.44788 -191.903331) (xy 35.495828 -191.878679)
			(xy 35.546855 -191.861271) (xy 35.599873 -191.851478) (xy 35.653752 -191.849509) (xy 35.707343 -191.855406)
			(xy 35.759504 -191.869042) (xy 35.809124 -191.890129) (xy 35.855145 -191.918215) (xy 35.896587 -191.952703)
			(xy 35.932565 -191.992857) (xy 35.962313 -192.037821) (xy 35.985198 -192.086638) (xy 36.00073 -192.138267)
			(xy 36.00858 -192.191607) (xy 36.009072 -192.218564) (xy 36.008766 -192.23533) (xy 37.061637 -192.23533)
			(xy 37.06561 -192.151935) (xy 37.077492 -192.069295) (xy 37.097175 -191.988159) (xy 37.124482 -191.909261)
			(xy 37.159165 -191.833316) (xy 37.20091 -191.761012) (xy 37.249339 -191.693004) (xy 37.304013 -191.629907)
			(xy 37.364438 -191.572292) (xy 37.430065 -191.520683) (xy 37.500301 -191.475545) (xy 37.57451 -191.437288)
			(xy 37.652019 -191.406258) (xy 37.732127 -191.382737) (xy 37.814108 -191.366937) (xy 37.897219 -191.359001)
			(xy 37.938964 -191.35852) (xy 37.981194 -191.359048) (xy 38.065264 -191.367164) (xy 38.148164 -191.383324)
			(xy 38.229127 -191.407379) (xy 38.307402 -191.439105) (xy 38.382265 -191.47821) (xy 38.453022 -191.52433)
			(xy 38.486334 -191.55029) (xy 38.495652 -191.557063) (xy 38.518084 -191.562201) (xy 38.540516 -191.557063)
			(xy 38.549834 -191.55029) (xy 38.58314 -191.524351) (xy 38.653864 -191.478248) (xy 38.72869 -191.439152)
			(xy 38.806926 -191.407426) (xy 38.887848 -191.383362) (xy 38.970708 -191.367183) (xy 39.054738 -191.359039)
			(xy 39.09695 -191.35852) (xy 39.14 -191.359051) (xy 39.225685 -191.367486) (xy 39.310131 -191.384279)
			(xy 39.392524 -191.409269) (xy 39.47207 -191.442215) (xy 39.548004 -191.4828) (xy 39.619594 -191.530632)
			(xy 39.686151 -191.585252) (xy 39.747033 -191.646133) (xy 39.801655 -191.712688) (xy 39.849489 -191.784277)
			(xy 39.890076 -191.86021) (xy 39.923024 -191.939756) (xy 39.948016 -192.022148) (xy 39.964811 -192.106593)
			(xy 39.973248 -192.192278) (xy 39.973559 -192.218564) (xy 41.026349 -192.218564) (xy 41.030284 -192.164793)
			(xy 41.042007 -192.112169) (xy 41.061267 -192.061812) (xy 41.087653 -192.014795) (xy 41.120605 -191.972122)
			(xy 41.159418 -191.934701) (xy 41.203266 -191.903331) (xy 41.251214 -191.878679) (xy 41.302241 -191.861271)
			(xy 41.355259 -191.851478) (xy 41.409138 -191.849509) (xy 41.462729 -191.855406) (xy 41.51489 -191.869042)
			(xy 41.56451 -191.890129) (xy 41.610531 -191.918215) (xy 41.651973 -191.952703) (xy 41.687951 -191.992857)
			(xy 41.717699 -192.037821) (xy 41.740584 -192.086638) (xy 41.756116 -192.138267) (xy 41.763966 -192.191607)
			(xy 41.764458 -192.218564) (xy 42.815017 -192.218564) (xy 42.818952 -192.164793) (xy 42.830675 -192.112169)
			(xy 42.849935 -192.061812) (xy 42.876321 -192.014795) (xy 42.909273 -191.972122) (xy 42.948086 -191.934701)
			(xy 42.991934 -191.903331) (xy 43.039882 -191.878679) (xy 43.090909 -191.861271) (xy 43.143927 -191.851478)
			(xy 43.197806 -191.849509) (xy 43.251397 -191.855406) (xy 43.303558 -191.869042) (xy 43.353178 -191.890129)
			(xy 43.399199 -191.918215) (xy 43.440641 -191.952703) (xy 43.476619 -191.992857) (xy 43.506367 -192.037821)
			(xy 43.529252 -192.086638) (xy 43.544784 -192.138267) (xy 43.552634 -192.191607) (xy 43.553126 -192.218564)
			(xy 43.552821 -192.2353) (xy 44.605707 -192.2353) (xy 44.60968 -192.151907) (xy 44.621562 -192.069269)
			(xy 44.641245 -191.988135) (xy 44.668551 -191.909239) (xy 44.703234 -191.833296) (xy 44.744978 -191.760994)
			(xy 44.793406 -191.692988) (xy 44.84808 -191.629893) (xy 44.908503 -191.57228) (xy 44.974129 -191.520672)
			(xy 45.044364 -191.475536) (xy 45.118571 -191.437281) (xy 45.196079 -191.406253) (xy 45.276185 -191.382733)
			(xy 45.358164 -191.366935) (xy 45.441274 -191.359) (xy 45.483018 -191.35852) (xy 45.525232 -191.359022)
			(xy 45.609269 -191.367144) (xy 45.692135 -191.383309) (xy 45.773063 -191.407368) (xy 45.851301 -191.439099)
			(xy 45.926126 -191.478207) (xy 45.996843 -191.524329) (xy 46.030134 -191.55029) (xy 46.039452 -191.557063)
			(xy 46.061884 -191.562201) (xy 46.084316 -191.557063) (xy 46.093634 -191.55029) (xy 46.126943 -191.524324)
			(xy 46.197699 -191.478201) (xy 46.272562 -191.439094) (xy 46.350838 -191.407364) (xy 46.431801 -191.383306)
			(xy 46.514702 -191.367143) (xy 46.598773 -191.359024) (xy 46.641004 -191.35852) (xy 46.684055 -191.359)
			(xy 46.769741 -191.367439) (xy 46.854188 -191.384238) (xy 46.936582 -191.409232) (xy 47.016128 -191.442183)
			(xy 47.092062 -191.482772) (xy 47.163652 -191.530608) (xy 47.230209 -191.585231) (xy 47.29109 -191.646115)
			(xy 47.345711 -191.712673) (xy 47.393545 -191.784265) (xy 47.434131 -191.860201) (xy 47.467078 -191.939749)
			(xy 47.49207 -192.022143) (xy 47.508865 -192.10659) (xy 47.517302 -192.192277) (xy 47.517613 -192.218564)
			(xy 48.570403 -192.218564) (xy 48.574338 -192.164793) (xy 48.586061 -192.112169) (xy 48.605321 -192.061812)
			(xy 48.631707 -192.014795) (xy 48.664659 -191.972122) (xy 48.703472 -191.934701) (xy 48.74732 -191.903331)
			(xy 48.795268 -191.878679) (xy 48.846295 -191.861271) (xy 48.899313 -191.851478) (xy 48.953192 -191.849509)
			(xy 49.006783 -191.855406) (xy 49.058944 -191.869042) (xy 49.108564 -191.890129) (xy 49.154585 -191.918215)
			(xy 49.196027 -191.952703) (xy 49.232005 -191.992857) (xy 49.261753 -192.037821) (xy 49.284638 -192.086638)
			(xy 49.30017 -192.138267) (xy 49.30802 -192.191607) (xy 49.308512 -192.218564) (xy 50.359071 -192.218564)
			(xy 50.363006 -192.164793) (xy 50.374729 -192.112169) (xy 50.393989 -192.061812) (xy 50.420375 -192.014795)
			(xy 50.453327 -191.972122) (xy 50.49214 -191.934701) (xy 50.535988 -191.903331) (xy 50.583936 -191.878679)
			(xy 50.634963 -191.861271) (xy 50.687981 -191.851478) (xy 50.74186 -191.849509) (xy 50.795451 -191.855406)
			(xy 50.847612 -191.869042) (xy 50.897232 -191.890129) (xy 50.943253 -191.918215) (xy 50.984695 -191.952703)
			(xy 51.020673 -191.992857) (xy 51.050421 -192.037821) (xy 51.073306 -192.086638) (xy 51.088838 -192.138267)
			(xy 51.096688 -192.191607) (xy 51.09718 -192.218564) (xy 51.096875 -192.2353) (xy 52.149823 -192.2353)
			(xy 52.153795 -192.151911) (xy 52.165676 -192.069278) (xy 52.185357 -191.988147) (xy 52.212662 -191.909255)
			(xy 52.247341 -191.833316) (xy 52.289082 -191.761017) (xy 52.337506 -191.693013) (xy 52.392175 -191.629919)
			(xy 52.452594 -191.572308) (xy 52.518216 -191.520701) (xy 52.588445 -191.475565) (xy 52.662647 -191.437309)
			(xy 52.74015 -191.40628) (xy 52.820251 -191.382758) (xy 52.902225 -191.366956) (xy 52.98533 -191.359018)
			(xy 53.027072 -191.35852) (xy 53.069302 -191.359044) (xy 53.153372 -191.36716) (xy 53.236272 -191.383321)
			(xy 53.317235 -191.407377) (xy 53.39551 -191.439104) (xy 53.470373 -191.478209) (xy 53.54113 -191.524329)
			(xy 53.574442 -191.55029) (xy 53.58376 -191.557063) (xy 53.606192 -191.562201) (xy 53.628624 -191.557063)
			(xy 53.637942 -191.55029) (xy 53.671245 -191.524347) (xy 53.74197 -191.478244) (xy 53.816797 -191.439149)
			(xy 53.895033 -191.407423) (xy 53.975956 -191.38336) (xy 54.058815 -191.367182) (xy 54.142846 -191.359039)
			(xy 54.185058 -191.35852) (xy 54.228108 -191.359043) (xy 54.313793 -191.367479) (xy 54.398239 -191.384273)
			(xy 54.480632 -191.409264) (xy 54.560179 -191.44221) (xy 54.636113 -191.482796) (xy 54.707703 -191.530629)
			(xy 54.77426 -191.585249) (xy 54.835142 -191.64613) (xy 54.889763 -191.712686) (xy 54.937597 -191.784275)
			(xy 54.978184 -191.860209) (xy 55.011132 -191.939755) (xy 55.036124 -192.022147) (xy 55.052919 -192.106593)
			(xy 55.061356 -192.192278) (xy 55.061667 -192.218564) (xy 56.114457 -192.218564) (xy 56.118392 -192.164793)
			(xy 56.130115 -192.112169) (xy 56.149375 -192.061812) (xy 56.175761 -192.014795) (xy 56.208713 -191.972122)
			(xy 56.247526 -191.934701) (xy 56.291374 -191.903331) (xy 56.339322 -191.878679) (xy 56.390349 -191.861271)
			(xy 56.443367 -191.851478) (xy 56.497246 -191.849509) (xy 56.550837 -191.855406) (xy 56.602998 -191.869042)
			(xy 56.652618 -191.890129) (xy 56.698639 -191.918215) (xy 56.740081 -191.952703) (xy 56.776059 -191.992857)
			(xy 56.805807 -192.037821) (xy 56.828692 -192.086638) (xy 56.844224 -192.138267) (xy 56.852074 -192.191607)
			(xy 56.852566 -192.218564) (xy 57.903125 -192.218564) (xy 57.90706 -192.164793) (xy 57.918783 -192.112169)
			(xy 57.938043 -192.061812) (xy 57.964429 -192.014795) (xy 57.997381 -191.972122) (xy 58.036194 -191.934701)
			(xy 58.080042 -191.903331) (xy 58.12799 -191.878679) (xy 58.179017 -191.861271) (xy 58.232035 -191.851478)
			(xy 58.285914 -191.849509) (xy 58.339505 -191.855406) (xy 58.391666 -191.869042) (xy 58.441286 -191.890129)
			(xy 58.487307 -191.918215) (xy 58.528749 -191.952703) (xy 58.564727 -191.992857) (xy 58.594475 -192.037821)
			(xy 58.61736 -192.086638) (xy 58.632892 -192.138267) (xy 58.640742 -192.191607) (xy 58.641234 -192.218564)
			(xy 58.640742 -192.245521) (xy 58.636099 -192.277072) (xy 59.694815 -192.277072) (xy 59.694815 -192.193584)
			(xy 59.702751 -192.110474) (xy 59.718551 -192.028496) (xy 59.742072 -191.94839) (xy 59.773101 -191.870882)
			(xy 59.811358 -191.796676) (xy 59.856494 -191.726441) (xy 59.908103 -191.660815) (xy 59.965716 -191.600393)
			(xy 60.028812 -191.54572) (xy 60.096819 -191.497292) (xy 60.169122 -191.455548) (xy 60.245065 -191.420866)
			(xy 60.323961 -191.39356) (xy 60.405095 -191.373877) (xy 60.487733 -191.361996) (xy 60.571126 -191.358023)
			(xy 60.654519 -191.361996) (xy 60.737157 -191.373877) (xy 60.818291 -191.39356) (xy 60.897187 -191.420866)
			(xy 60.97313 -191.455548) (xy 61.045433 -191.497292) (xy 61.11344 -191.54572) (xy 61.176536 -191.600393)
			(xy 61.234149 -191.660815) (xy 61.285758 -191.726441) (xy 61.330894 -191.796676) (xy 61.369151 -191.870882)
			(xy 61.40018 -191.94839) (xy 61.423701 -192.028496) (xy 61.439501 -192.110474) (xy 61.447437 -192.193584)
			(xy 61.447934 -192.235328) (xy 61.447437 -192.277072) (xy 61.439501 -192.360182) (xy 61.423701 -192.44216)
			(xy 61.40018 -192.522266) (xy 61.369151 -192.599774) (xy 61.330894 -192.673981) (xy 61.285758 -192.744215)
			(xy 61.234149 -192.809841) (xy 61.176536 -192.870263) (xy 61.11344 -192.924936) (xy 61.045433 -192.973364)
			(xy 60.97313 -193.015108) (xy 60.897187 -193.04979) (xy 60.818291 -193.077096) (xy 60.737157 -193.096779)
			(xy 60.654519 -193.10866) (xy 60.571126 -193.112633) (xy 60.487733 -193.10866) (xy 60.405095 -193.096779)
			(xy 60.323961 -193.077096) (xy 60.245065 -193.04979) (xy 60.169122 -193.015108) (xy 60.096819 -192.973364)
			(xy 60.028812 -192.924936) (xy 59.965716 -192.870263) (xy 59.908103 -192.809841) (xy 59.856494 -192.744215)
			(xy 59.811358 -192.673981) (xy 59.773101 -192.599774) (xy 59.742072 -192.522266) (xy 59.718551 -192.44216)
			(xy 59.702751 -192.360182) (xy 59.694815 -192.277072) (xy 58.636099 -192.277072) (xy 58.632892 -192.298861)
			(xy 58.61736 -192.35049) (xy 58.594475 -192.399307) (xy 58.564727 -192.444271) (xy 58.528749 -192.484425)
			(xy 58.487307 -192.518913) (xy 58.441286 -192.546999) (xy 58.391666 -192.568086) (xy 58.339505 -192.581722)
			(xy 58.285914 -192.587619) (xy 58.232035 -192.58565) (xy 58.179017 -192.575857) (xy 58.12799 -192.558449)
			(xy 58.080042 -192.533797) (xy 58.036194 -192.502427) (xy 57.997381 -192.465006) (xy 57.964429 -192.422333)
			(xy 57.938043 -192.375316) (xy 57.918783 -192.324959) (xy 57.90706 -192.272335) (xy 57.903125 -192.218564)
			(xy 56.852566 -192.218564) (xy 56.852074 -192.245521) (xy 56.844224 -192.298861) (xy 56.828692 -192.35049)
			(xy 56.805807 -192.399307) (xy 56.776059 -192.444271) (xy 56.740081 -192.484425) (xy 56.698639 -192.518913)
			(xy 56.652618 -192.546999) (xy 56.602998 -192.568086) (xy 56.550837 -192.581722) (xy 56.497246 -192.587619)
			(xy 56.443367 -192.58565) (xy 56.390349 -192.575857) (xy 56.339322 -192.558449) (xy 56.291374 -192.533797)
			(xy 56.247526 -192.502427) (xy 56.208713 -192.465006) (xy 56.175761 -192.422333) (xy 56.149375 -192.375316)
			(xy 56.130115 -192.324959) (xy 56.118392 -192.272335) (xy 56.114457 -192.218564) (xy 55.061667 -192.218564)
			(xy 55.061866 -192.235328) (xy 55.061333 -192.277052) (xy 55.053369 -192.36012) (xy 55.037553 -192.442056)
			(xy 55.014029 -192.52212) (xy 54.983008 -192.599589) (xy 54.96433 -192.636902) (xy 54.959366 -192.648072)
			(xy 54.959353 -192.672475) (xy 54.96433 -192.683638) (xy 54.98303 -192.720943) (xy 55.014072 -192.798407)
			(xy 55.037607 -192.878473) (xy 55.053423 -192.960413) (xy 55.061375 -193.043486) (xy 55.061866 -193.085212)
			(xy 55.061388 -193.12759) (xy 55.053212 -193.21195) (xy 55.036929 -193.295127) (xy 55.01269 -193.376343)
			(xy 54.980722 -193.454839) (xy 54.941323 -193.529881) (xy 54.894863 -193.600767) (xy 54.841774 -193.666837)
			(xy 54.782554 -193.727471) (xy 54.717756 -193.782103) (xy 54.683152 -193.806572) (xy 54.675492 -193.812373)
			(xy 54.664794 -193.828314) (xy 54.660687 -193.847069) (xy 54.661816 -193.85661) (xy 54.664777 -193.876097)
			(xy 54.667956 -193.915387) (xy 54.668166 -193.935096) (xy 54.668166 -193.93535) (xy 54.667728 -193.964885)
			(xy 54.663938 -193.996582) (xy 55.987422 -193.996582) (xy 55.991271 -193.934903) (xy 56.002755 -193.874179)
			(xy 56.021695 -193.815353) (xy 56.047798 -193.759337) (xy 56.08066 -193.706998) (xy 56.11977 -193.659148)
			(xy 56.164523 -193.616529) (xy 56.214225 -193.579802) (xy 56.240934 -193.564256) (xy 56.251856 -193.55816)
			(xy 56.265572 -193.536824) (xy 56.274208 -193.427604) (xy 56.264048 -193.404236) (xy 56.254142 -193.396362)
			(xy 56.232808 -193.378792) (xy 56.195169 -193.338323) (xy 56.163995 -193.292687) (xy 56.139985 -193.242907)
			(xy 56.123677 -193.190101) (xy 56.115437 -193.135452) (xy 56.11495 -193.107818) (xy 56.11495 -193.107564)
			(xy 56.115466 -193.079964) (xy 56.123693 -193.025381) (xy 56.139963 -192.972634) (xy 56.163913 -192.922902)
			(xy 56.195008 -192.877294) (xy 56.232553 -192.83683) (xy 56.27571 -192.802413) (xy 56.323514 -192.774814)
			(xy 56.374898 -192.754647) (xy 56.428713 -192.742364) (xy 56.483758 -192.738239) (xy 56.538803 -192.742364)
			(xy 56.592618 -192.754647) (xy 56.644002 -192.774814) (xy 56.691806 -192.802413) (xy 56.734963 -192.83683)
			(xy 56.772508 -192.877294) (xy 56.803603 -192.922902) (xy 56.827553 -192.972634) (xy 56.843823 -193.025381)
			(xy 56.85205 -193.079964) (xy 56.852566 -193.107564) (xy 56.852566 -193.107818) (xy 56.852047 -193.135448)
			(xy 56.843788 -193.190087) (xy 56.827472 -193.242883) (xy 56.803466 -193.292656) (xy 56.772304 -193.338292)
			(xy 56.734685 -193.37877) (xy 56.713374 -193.396362) (xy 56.703468 -193.404236) (xy 56.693308 -193.427604)
			(xy 56.701944 -193.536824) (xy 56.71566 -193.55816) (xy 56.726582 -193.564256) (xy 56.75326 -193.579851)
			(xy 56.802964 -193.61657) (xy 56.847719 -193.659181) (xy 56.886831 -193.707024) (xy 56.919694 -193.759356)
			(xy 56.945799 -193.815367) (xy 56.96474 -193.874188) (xy 56.976225 -193.934907) (xy 56.980074 -193.996582)
			(xy 56.976229 -194.058258) (xy 56.964749 -194.118978) (xy 56.945812 -194.1778) (xy 56.919711 -194.233813)
			(xy 56.886851 -194.286148) (xy 56.847743 -194.333993) (xy 56.802991 -194.376607) (xy 56.75329 -194.413329)
			(xy 56.726582 -194.428872) (xy 56.71566 -194.434968) (xy 56.701944 -194.456304) (xy 56.69618 -194.529202)
			(xy 57.724294 -194.529202) (xy 57.72475 -194.499182) (xy 57.731826 -194.439561) (xy 57.745869 -194.381187)
			(xy 57.766684 -194.32487) (xy 57.79398 -194.271395) (xy 57.82738 -194.221503) (xy 57.866419 -194.175887)
			(xy 57.910554 -194.135183) (xy 57.934606 -194.117214) (xy 57.942118 -194.111317) (xy 57.952424 -194.095254)
			(xy 57.954672 -194.085972) (xy 57.960768 -194.055492) (xy 57.962195 -194.046275) (xy 57.959069 -194.027904)
			(xy 57.954672 -194.019678) (xy 57.942547 -193.998288) (xy 57.923431 -193.952987) (xy 57.910508 -193.905547)
			(xy 57.904007 -193.856811) (xy 57.903618 -193.832226) (xy 57.904134 -193.804626) (xy 57.912361 -193.750043)
			(xy 57.928631 -193.697296) (xy 57.952581 -193.647564) (xy 57.983676 -193.601956) (xy 58.021221 -193.561492)
			(xy 58.064378 -193.527075) (xy 58.112182 -193.499476) (xy 58.163566 -193.479309) (xy 58.217381 -193.467026)
			(xy 58.272426 -193.462901) (xy 58.327471 -193.467026) (xy 58.381286 -193.479309) (xy 58.43267 -193.499476)
			(xy 58.480474 -193.527075) (xy 58.523631 -193.561492) (xy 58.561176 -193.601956) (xy 58.592271 -193.647564)
			(xy 58.616221 -193.697296) (xy 58.632491 -193.750043) (xy 58.640718 -193.804626) (xy 58.641234 -193.832226)
			(xy 58.640668 -193.862102) (xy 58.631032 -193.921071) (xy 58.612018 -193.977716) (xy 58.584121 -194.030555)
			(xy 58.566558 -194.05473) (xy 58.561373 -194.062427) (xy 58.556281 -194.080256) (xy 58.556652 -194.089528)
			(xy 58.559192 -194.120516) (xy 58.560421 -194.129988) (xy 58.568901 -194.147085) (xy 58.575702 -194.15379)
			(xy 58.59772 -194.174433) (xy 58.63716 -194.220125) (xy 58.670911 -194.270165) (xy 58.698501 -194.323849)
			(xy 58.71954 -194.380422) (xy 58.733732 -194.439089) (xy 58.740879 -194.499023) (xy 58.74131 -194.529202)
			(xy 58.740742 -194.562749) (xy 58.731908 -194.629258) (xy 58.714408 -194.694029) (xy 58.688545 -194.755937)
			(xy 58.654767 -194.813907) (xy 58.613662 -194.866934) (xy 58.59018 -194.890898) (xy 58.582814 -194.898264)
			(xy 58.57494 -194.916806) (xy 58.575448 -195.010278) (xy 58.583322 -195.02882) (xy 58.590688 -195.035932)
			(xy 58.614521 -195.059973) (xy 58.656319 -195.113222) (xy 58.690682 -195.171547) (xy 58.717001 -195.233916)
			(xy 58.734811 -195.299225) (xy 58.743798 -195.366321) (xy 58.744358 -195.400168) (xy 58.743856 -195.432129)
			(xy 58.735845 -195.495547) (xy 58.719948 -195.557461) (xy 58.696416 -195.616894) (xy 58.686258 -195.635372)
			(xy 60.088018 -195.635372) (xy 60.088545 -195.604115) (xy 60.096384 -195.542093) (xy 60.111958 -195.48155)
			(xy 60.13502 -195.423445) (xy 60.165205 -195.368701) (xy 60.202033 -195.318186) (xy 60.244921 -195.272702)
			(xy 60.293186 -195.232972) (xy 60.346064 -195.199625) (xy 60.402715 -195.173192) (xy 60.46224 -195.15409)
			(xy 60.523694 -195.142624) (xy 60.55487 -195.140326) (xy 60.568974 -195.139105) (xy 60.595701 -195.129798)
			(xy 60.618844 -195.113509) (xy 60.636625 -195.091491) (xy 60.647675 -195.065436) (xy 60.651145 -195.037349)
			(xy 60.646768 -195.009388) (xy 60.634881 -194.983705) (xy 60.62599 -194.972686) (xy 60.606586 -194.949531)
			(xy 60.572789 -194.899457) (xy 60.545162 -194.845731) (xy 60.524093 -194.789111) (xy 60.509881 -194.730394)
			(xy 60.502724 -194.670406) (xy 60.502292 -194.6402) (xy 60.502794 -194.608239) (xy 60.510805 -194.544821)
			(xy 60.526702 -194.482907) (xy 60.550234 -194.423474) (xy 60.581028 -194.367459) (xy 60.618601 -194.315744)
			(xy 60.662358 -194.269147) (xy 60.711611 -194.228402) (xy 60.765582 -194.194151) (xy 60.823421 -194.166934)
			(xy 60.884214 -194.147181) (xy 60.947004 -194.135203) (xy 61.0108 -194.13119) (xy 61.074596 -194.135203)
			(xy 61.137386 -194.147181) (xy 61.198179 -194.166934) (xy 61.256018 -194.194151) (xy 61.309989 -194.228402)
			(xy 61.359242 -194.269147) (xy 61.402999 -194.315744) (xy 61.440572 -194.367459) (xy 61.471366 -194.423474)
			(xy 61.494898 -194.482907) (xy 61.510795 -194.544821) (xy 61.518806 -194.608239) (xy 61.519308 -194.6402)
			(xy 61.518885 -194.672484) (xy 61.510724 -194.736533) (xy 61.49452 -194.799033) (xy 61.470535 -194.85898)
			(xy 61.439153 -194.915407) (xy 61.400881 -194.967408) (xy 61.356333 -195.014146) (xy 61.306227 -195.054868)
			(xy 61.251369 -195.088919) (xy 61.192642 -195.115752) (xy 61.130991 -195.134934) (xy 61.067407 -195.146157)
			(xy 61.035184 -195.1482) (xy 61.021065 -195.149332) (xy 60.994242 -195.158404) (xy 60.970936 -195.174484)
			(xy 60.952933 -195.196339) (xy 60.941614 -195.222293) (xy 60.937846 -195.250356) (xy 60.941919 -195.278376)
			(xy 60.95352 -195.304206) (xy 60.962286 -195.315332) (xy 60.980715 -195.337736) (xy 61.01277 -195.38609)
			(xy 61.038962 -195.437855) (xy 61.058933 -195.492324) (xy 61.07241 -195.548751) (xy 61.079208 -195.606365)
			(xy 61.079634 -195.635372) (xy 61.079145 -195.666535) (xy 61.071333 -195.728369) (xy 61.055833 -195.788737)
			(xy 61.03289 -195.846685) (xy 61.002864 -195.901302) (xy 60.96623 -195.951724) (xy 60.923565 -195.997158)
			(xy 60.875543 -196.036886) (xy 60.822919 -196.070281) (xy 60.766525 -196.096818) (xy 60.70725 -196.116078)
			(xy 60.646029 -196.127757) (xy 60.583826 -196.13167) (xy 60.521623 -196.127757) (xy 60.460402 -196.116078)
			(xy 60.401127 -196.096818) (xy 60.344733 -196.070281) (xy 60.292109 -196.036886) (xy 60.244087 -195.997158)
			(xy 60.201422 -195.951724) (xy 60.164788 -195.901302) (xy 60.134762 -195.846685) (xy 60.111819 -195.788737)
			(xy 60.096319 -195.728369) (xy 60.088507 -195.666535) (xy 60.088018 -195.635372) (xy 58.686258 -195.635372)
			(xy 58.665622 -195.672909) (xy 58.628049 -195.724624) (xy 58.584292 -195.771221) (xy 58.535039 -195.811966)
			(xy 58.481068 -195.846217) (xy 58.423229 -195.873434) (xy 58.362436 -195.893187) (xy 58.299646 -195.905165)
			(xy 58.23585 -195.909179) (xy 58.172054 -195.905165) (xy 58.109264 -195.893187) (xy 58.048471 -195.873434)
			(xy 57.990632 -195.846217) (xy 57.936661 -195.811966) (xy 57.887408 -195.771221) (xy 57.843651 -195.724624)
			(xy 57.806078 -195.672909) (xy 57.775284 -195.616894) (xy 57.751752 -195.557461) (xy 57.735855 -195.495547)
			(xy 57.727844 -195.432129) (xy 57.727342 -195.400168) (xy 57.727875 -195.36662) (xy 57.736714 -195.300109)
			(xy 57.75422 -195.235337) (xy 57.78009 -195.173429) (xy 57.813874 -195.115459) (xy 57.854986 -195.062434)
			(xy 57.878472 -195.038472) (xy 57.885838 -195.031106) (xy 57.893712 -195.012564) (xy 57.893204 -194.919092)
			(xy 57.88533 -194.90055) (xy 57.877964 -194.893438) (xy 57.854107 -194.86942) (xy 57.812314 -194.816164)
			(xy 57.777955 -194.757834) (xy 57.751641 -194.695462) (xy 57.733834 -194.630149) (xy 57.724852 -194.56305)
			(xy 57.724294 -194.529202) (xy 56.69618 -194.529202) (xy 56.693308 -194.565524) (xy 56.703468 -194.588892)
			(xy 56.713374 -194.596766) (xy 56.734677 -194.614372) (xy 56.772317 -194.654834) (xy 56.803494 -194.700463)
			(xy 56.827509 -194.750235) (xy 56.843824 -194.803035) (xy 56.852074 -194.857679) (xy 56.852566 -194.88531)
			(xy 56.852566 -194.885564) (xy 56.85205 -194.913164) (xy 56.843823 -194.967747) (xy 56.827553 -195.020494)
			(xy 56.803603 -195.070227) (xy 56.772508 -195.115834) (xy 56.734963 -195.156298) (xy 56.691806 -195.190715)
			(xy 56.644002 -195.218314) (xy 56.592618 -195.238481) (xy 56.538803 -195.250764) (xy 56.483758 -195.254889)
			(xy 56.428713 -195.250764) (xy 56.374898 -195.238481) (xy 56.323514 -195.218314) (xy 56.27571 -195.190715)
			(xy 56.232553 -195.156298) (xy 56.195008 -195.115834) (xy 56.163913 -195.070227) (xy 56.139963 -195.020494)
			(xy 56.123693 -194.967747) (xy 56.115466 -194.913164) (xy 56.11495 -194.885564) (xy 56.11495 -194.88531)
			(xy 56.11545 -194.85768) (xy 56.123717 -194.803041) (xy 56.140039 -194.750246) (xy 56.164049 -194.700474)
			(xy 56.195212 -194.654838) (xy 56.232831 -194.614359) (xy 56.254142 -194.596766) (xy 56.264048 -194.588892)
			(xy 56.274208 -194.565524) (xy 56.265572 -194.456304) (xy 56.251856 -194.434968) (xy 56.240934 -194.428872)
			(xy 56.214196 -194.413379) (xy 56.164496 -194.376648) (xy 56.119746 -194.334026) (xy 56.080639 -194.286173)
			(xy 56.047781 -194.233832) (xy 56.021682 -194.177814) (xy 56.002746 -194.118987) (xy 55.991267 -194.058262)
			(xy 55.987422 -193.996582) (xy 54.663938 -193.996582) (xy 54.660714 -194.023538) (xy 54.646781 -194.080942)
			(xy 54.626124 -194.136283) (xy 54.599037 -194.188777) (xy 54.565904 -194.237681) (xy 54.527195 -194.2823)
			(xy 54.483458 -194.322004) (xy 54.459632 -194.339464) (xy 54.45125 -194.34556) (xy 54.440328 -194.363086)
			(xy 54.427882 -194.445636) (xy 54.426859 -194.455723) (xy 54.43182 -194.475362) (xy 54.437534 -194.483736)
			(xy 54.438042 -194.484244) (xy 54.457268 -194.510276) (xy 54.489547 -194.566369) (xy 54.514249 -194.626186)
			(xy 54.530952 -194.688709) (xy 54.539373 -194.752876) (xy 54.539896 -194.785234) (xy 54.539409 -194.817697)
			(xy 54.53093 -194.882068) (xy 54.514122 -194.944782) (xy 54.489272 -195.004765) (xy 54.456806 -195.060992)
			(xy 54.417278 -195.1125) (xy 54.371365 -195.158408) (xy 54.319854 -195.197931) (xy 54.263624 -195.230392)
			(xy 54.203638 -195.255237) (xy 54.140923 -195.272039) (xy 54.076552 -195.280512) (xy 54.044088 -195.281042)
			(xy 54.013854 -195.280641) (xy 53.953836 -195.273286) (xy 53.895158 -195.258685) (xy 53.838691 -195.237057)
			(xy 53.785274 -195.208722) (xy 53.735699 -195.174101) (xy 53.690703 -195.133708) (xy 53.650954 -195.088142)
			(xy 53.633624 -195.063364) (xy 53.626053 -195.053422) (xy 53.603943 -195.041839) (xy 53.59146 -195.041266)
			(xy 53.506878 -195.04152) (xy 53.494263 -195.042268) (xy 53.472134 -195.054405) (xy 53.464714 -195.064634)
			(xy 53.44974 -195.086711) (xy 53.41589 -195.127944) (xy 53.39715 -195.14693) (xy 53.39035 -195.154301)
			(xy 53.382503 -195.172733) (xy 53.38191 -195.182744) (xy 53.381148 -195.254118) (xy 53.381537 -195.264036)
			(xy 53.388833 -195.282468) (xy 53.395372 -195.289932) (xy 53.395626 -195.290186) (xy 53.41745 -195.313366)
			(xy 53.455568 -195.36436) (xy 53.486844 -195.419815) (xy 53.510764 -195.478817) (xy 53.526934 -195.540396)
			(xy 53.535088 -195.603539) (xy 53.53558 -195.635372) (xy 53.535091 -195.666535) (xy 53.527279 -195.728369)
			(xy 53.511779 -195.788737) (xy 53.488836 -195.846685) (xy 53.45881 -195.901302) (xy 53.422176 -195.951724)
			(xy 53.379511 -195.997158) (xy 53.331489 -196.036886) (xy 53.278865 -196.070281) (xy 53.222471 -196.096818)
			(xy 53.163196 -196.116078) (xy 53.101975 -196.127757) (xy 53.039772 -196.13167) (xy 52.977569 -196.127757)
			(xy 52.916348 -196.116078) (xy 52.857073 -196.096818) (xy 52.800679 -196.070281) (xy 52.748055 -196.036886)
			(xy 52.700033 -195.997158) (xy 52.657368 -195.951724) (xy 52.620734 -195.901302) (xy 52.590708 -195.846685)
			(xy 52.567765 -195.788737) (xy 52.552265 -195.728369) (xy 52.544453 -195.666535) (xy 52.543964 -195.635372)
			(xy 52.544408 -195.603536) (xy 52.552557 -195.540389) (xy 52.56873 -195.478806) (xy 52.59266 -195.419802)
			(xy 52.623952 -195.364351) (xy 52.662092 -195.313367) (xy 52.683918 -195.290186) (xy 52.684172 -195.289932)
			(xy 52.690708 -195.282464) (xy 52.698026 -195.264036) (xy 52.698396 -195.254118) (xy 52.697634 -195.182744)
			(xy 52.697107 -195.172716) (xy 52.689265 -195.154251) (xy 52.682394 -195.14693) (xy 52.658899 -195.122976)
			(xy 52.617774 -195.069957) (xy 52.583984 -195.011988) (xy 52.558116 -194.950076) (xy 52.540619 -194.885299)
			(xy 52.531798 -194.818783) (xy 52.531264 -194.785234) (xy 52.53177 -194.754504) (xy 52.539174 -194.693491)
			(xy 52.553878 -194.633815) (xy 52.575669 -194.576347) (xy 52.604228 -194.521925) (xy 52.639138 -194.471341)
			(xy 52.679891 -194.425335) (xy 52.725893 -194.384576) (xy 52.776472 -194.34966) (xy 52.83089 -194.321094)
			(xy 52.888356 -194.299297) (xy 52.94803 -194.284585) (xy 53.009042 -194.277173) (xy 53.039772 -194.276726)
			(xy 53.071219 -194.277213) (xy 53.133633 -194.284984) (xy 53.194613 -194.300386) (xy 53.253231 -194.323184)
			(xy 53.308593 -194.353032) (xy 53.359855 -194.389473) (xy 53.406237 -194.431953) (xy 53.447031 -194.479825)
			(xy 53.464714 -194.505834) (xy 53.472188 -194.516007) (xy 53.494283 -194.528143) (xy 53.506878 -194.528948)
			(xy 53.60416 -194.529456) (xy 53.626512 -194.517772) (xy 53.633624 -194.507104) (xy 53.650554 -194.482902)
			(xy 53.68926 -194.438285) (xy 53.732992 -194.398581) (xy 53.756814 -194.38112) (xy 53.765196 -194.375024)
			(xy 53.776118 -194.357498) (xy 53.788564 -194.274948) (xy 53.789606 -194.264861) (xy 53.784633 -194.24522)
			(xy 53.778912 -194.236848) (xy 53.778404 -194.23634) (xy 53.759163 -194.210318) (xy 53.726888 -194.154222)
			(xy 53.70219 -194.094403) (xy 53.68549 -194.031877) (xy 53.677072 -193.967709) (xy 53.67655 -193.93535)
			(xy 53.676835 -193.9119) (xy 53.681288 -193.865213) (xy 53.68544 -193.842132) (xy 53.686848 -193.832644)
			(xy 53.683317 -193.813807) (xy 53.673113 -193.797584) (xy 53.665628 -193.791586) (xy 53.633584 -193.767457)
			(xy 53.573555 -193.714243) (xy 53.51864 -193.655766) (xy 53.469298 -193.592515) (xy 53.425942 -193.52502)
			(xy 53.388936 -193.453846) (xy 53.358588 -193.379589) (xy 53.335152 -193.302868) (xy 53.318826 -193.224327)
			(xy 53.313838 -193.184526) (xy 53.31216 -193.174128) (xy 53.301668 -193.155891) (xy 53.293518 -193.14922)
			(xy 53.23332 -193.105024) (xy 53.224592 -193.099316) (xy 53.204279 -193.094708) (xy 53.19395 -193.096134)
			(xy 53.193442 -193.096134) (xy 53.152257 -193.103618) (xy 53.068929 -193.111637) (xy 53.027072 -193.112136)
			(xy 52.98533 -193.111582) (xy 52.902225 -193.103644) (xy 52.820251 -193.087842) (xy 52.74015 -193.06432)
			(xy 52.662647 -193.033291) (xy 52.588445 -192.995035) (xy 52.518216 -192.949899) (xy 52.452594 -192.898292)
			(xy 52.392175 -192.840681) (xy 52.337506 -192.777587) (xy 52.289082 -192.709583) (xy 52.247341 -192.637284)
			(xy 52.212662 -192.561345) (xy 52.185357 -192.482453) (xy 52.165676 -192.401322) (xy 52.153795 -192.318689)
			(xy 52.149823 -192.2353) (xy 51.096875 -192.2353) (xy 51.096688 -192.245521) (xy 51.088838 -192.298861)
			(xy 51.073306 -192.35049) (xy 51.050421 -192.399307) (xy 51.020673 -192.444271) (xy 50.984695 -192.484425)
			(xy 50.943253 -192.518913) (xy 50.897232 -192.546999) (xy 50.847612 -192.568086) (xy 50.795451 -192.581722)
			(xy 50.74186 -192.587619) (xy 50.687981 -192.58565) (xy 50.634963 -192.575857) (xy 50.583936 -192.558449)
			(xy 50.535988 -192.533797) (xy 50.49214 -192.502427) (xy 50.453327 -192.465006) (xy 50.420375 -192.422333)
			(xy 50.393989 -192.375316) (xy 50.374729 -192.324959) (xy 50.363006 -192.272335) (xy 50.359071 -192.218564)
			(xy 49.308512 -192.218564) (xy 49.30802 -192.245521) (xy 49.30017 -192.298861) (xy 49.284638 -192.35049)
			(xy 49.261753 -192.399307) (xy 49.232005 -192.444271) (xy 49.196027 -192.484425) (xy 49.154585 -192.518913)
			(xy 49.108564 -192.546999) (xy 49.058944 -192.568086) (xy 49.006783 -192.581722) (xy 48.953192 -192.587619)
			(xy 48.899313 -192.58565) (xy 48.846295 -192.575857) (xy 48.795268 -192.558449) (xy 48.74732 -192.533797)
			(xy 48.703472 -192.502427) (xy 48.664659 -192.465006) (xy 48.631707 -192.422333) (xy 48.605321 -192.375316)
			(xy 48.586061 -192.324959) (xy 48.574338 -192.272335) (xy 48.570403 -192.218564) (xy 47.517613 -192.218564)
			(xy 47.517812 -192.235328) (xy 47.517274 -192.277052) (xy 47.509311 -192.360119) (xy 47.493496 -192.442055)
			(xy 47.469972 -192.522119) (xy 47.438954 -192.599588) (xy 47.420276 -192.636902) (xy 47.415316 -192.648073)
			(xy 47.415303 -192.672475) (xy 47.420276 -192.683638) (xy 47.43898 -192.720941) (xy 47.47002 -192.798406)
			(xy 47.493554 -192.878472) (xy 47.509369 -192.960413) (xy 47.517322 -193.043486) (xy 47.517812 -193.085212)
			(xy 47.517314 -193.127589) (xy 47.509139 -193.211949) (xy 47.492857 -193.295124) (xy 47.468619 -193.376339)
			(xy 47.436653 -193.454834) (xy 47.397256 -193.529876) (xy 47.350798 -193.600763) (xy 47.297713 -193.666833)
			(xy 47.238495 -193.727468) (xy 47.1737 -193.782102) (xy 47.139098 -193.806572) (xy 47.131446 -193.812383)
			(xy 47.120742 -193.828318) (xy 47.116633 -193.84707) (xy 47.117762 -193.85661) (xy 47.120723 -193.876097)
			(xy 47.123902 -193.915387) (xy 47.124112 -193.935096) (xy 47.124112 -193.93535) (xy 47.123597 -193.967183)
			(xy 47.119809 -193.996582) (xy 48.443344 -193.996582) (xy 48.447194 -193.934901) (xy 48.458679 -193.874175)
			(xy 48.477621 -193.815348) (xy 48.503727 -193.759331) (xy 48.536592 -193.706992) (xy 48.575706 -193.659143)
			(xy 48.620463 -193.616525) (xy 48.670169 -193.5798) (xy 48.69688 -193.564256) (xy 48.707802 -193.55816)
			(xy 48.721518 -193.536824) (xy 48.730154 -193.427604) (xy 48.719994 -193.404236) (xy 48.710088 -193.396362)
			(xy 48.688764 -193.378781) (xy 48.651122 -193.338315) (xy 48.619946 -193.292682) (xy 48.595934 -193.242904)
			(xy 48.579625 -193.190099) (xy 48.571384 -193.135451) (xy 48.570896 -193.107818) (xy 48.570896 -193.107564)
			(xy 48.571412 -193.079964) (xy 48.579639 -193.025381) (xy 48.595909 -192.972634) (xy 48.619859 -192.922902)
			(xy 48.650954 -192.877294) (xy 48.688499 -192.83683) (xy 48.731656 -192.802413) (xy 48.77946 -192.774814)
			(xy 48.830844 -192.754647) (xy 48.884659 -192.742364) (xy 48.939704 -192.738239) (xy 48.994749 -192.742364)
			(xy 49.048564 -192.754647) (xy 49.099948 -192.774814) (xy 49.147752 -192.802413) (xy 49.190909 -192.83683)
			(xy 49.228454 -192.877294) (xy 49.259549 -192.922902) (xy 49.283499 -192.972634) (xy 49.299769 -193.025381)
			(xy 49.307996 -193.079964) (xy 49.308512 -193.107564) (xy 49.308512 -193.107818) (xy 49.307975 -193.135447)
			(xy 49.299718 -193.190085) (xy 49.283405 -193.24288) (xy 49.259401 -193.292652) (xy 49.228244 -193.338289)
			(xy 49.190629 -193.378769) (xy 49.16932 -193.396362) (xy 49.159414 -193.404236) (xy 49.149254 -193.427604)
			(xy 49.15789 -193.536824) (xy 49.171606 -193.55816) (xy 49.182528 -193.564256) (xy 49.209204 -193.579853)
			(xy 49.258904 -193.616574) (xy 49.303654 -193.659186) (xy 49.342763 -193.70703) (xy 49.375623 -193.759362)
			(xy 49.401725 -193.815372) (xy 49.420664 -193.874192) (xy 49.432148 -193.934909) (xy 49.435997 -193.996582)
			(xy 49.432152 -194.058256) (xy 49.420673 -194.118974) (xy 49.401738 -194.177795) (xy 49.37564 -194.233807)
			(xy 49.342783 -194.286142) (xy 49.303678 -194.333988) (xy 49.258931 -194.376603) (xy 49.209234 -194.413328)
			(xy 49.182528 -194.428872) (xy 49.171606 -194.434968) (xy 49.15789 -194.456304) (xy 49.149254 -194.565524)
			(xy 49.159414 -194.588892) (xy 49.16932 -194.596766) (xy 49.190611 -194.614385) (xy 49.228254 -194.654843)
			(xy 49.259434 -194.700469) (xy 49.283452 -194.750239) (xy 49.299769 -194.803037) (xy 49.308019 -194.857679)
			(xy 49.308512 -194.88531) (xy 49.308512 -194.885564) (xy 49.307996 -194.913164) (xy 49.299769 -194.967747)
			(xy 49.283499 -195.020494) (xy 49.259549 -195.070227) (xy 49.228454 -195.115834) (xy 49.190909 -195.156298)
			(xy 49.147752 -195.190715) (xy 49.099948 -195.218314) (xy 49.048564 -195.238481) (xy 48.994749 -195.250764)
			(xy 48.939704 -195.254889) (xy 48.884659 -195.250764) (xy 48.830844 -195.238481) (xy 48.77946 -195.218314)
			(xy 48.731656 -195.190715) (xy 48.688499 -195.156298) (xy 48.650954 -195.115834) (xy 48.619859 -195.070227)
			(xy 48.595909 -195.020494) (xy 48.579639 -194.967747) (xy 48.571412 -194.913164) (xy 48.570896 -194.885564)
			(xy 48.570896 -194.88531) (xy 48.571379 -194.857679) (xy 48.579647 -194.803039) (xy 48.595971 -194.750242)
			(xy 48.619985 -194.70047) (xy 48.651152 -194.654835) (xy 48.688775 -194.614358) (xy 48.710088 -194.596766)
			(xy 48.719994 -194.588892) (xy 48.730154 -194.565524) (xy 48.721518 -194.456304) (xy 48.707802 -194.434968)
			(xy 48.69688 -194.428872) (xy 48.67014 -194.413381) (xy 48.620436 -194.376652) (xy 48.575682 -194.334031)
			(xy 48.536571 -194.286179) (xy 48.50371 -194.233838) (xy 48.477608 -194.177819) (xy 48.45867 -194.11899)
			(xy 48.44719 -194.058264) (xy 48.443344 -193.996582) (xy 47.119809 -193.996582) (xy 47.11546 -194.030327)
			(xy 47.099299 -194.091908) (xy 47.075382 -194.150911) (xy 47.044103 -194.206364) (xy 47.005978 -194.257352)
			(xy 46.984158 -194.280536) (xy 46.977046 -194.287902) (xy 46.96968 -194.30619) (xy 46.97095 -194.398138)
			(xy 46.97857 -194.416426) (xy 46.985682 -194.423538) (xy 47.009176 -194.447493) (xy 47.050298 -194.500513)
			(xy 47.084087 -194.558483) (xy 47.109955 -194.620394) (xy 47.127453 -194.68517) (xy 47.136276 -194.751685)
			(xy 47.136812 -194.785234) (xy 47.13631 -194.817195) (xy 47.128299 -194.880613) (xy 47.112402 -194.942527)
			(xy 47.08887 -195.00196) (xy 47.058076 -195.057975) (xy 47.020503 -195.10969) (xy 46.976746 -195.156287)
			(xy 46.927493 -195.197032) (xy 46.873522 -195.231283) (xy 46.815683 -195.2585) (xy 46.75489 -195.278253)
			(xy 46.6921 -195.290231) (xy 46.628304 -195.294245) (xy 46.564508 -195.290231) (xy 46.501718 -195.278253)
			(xy 46.440925 -195.2585) (xy 46.383086 -195.231283) (xy 46.329115 -195.197032) (xy 46.279862 -195.156287)
			(xy 46.236105 -195.10969) (xy 46.198532 -195.057975) (xy 46.167738 -195.00196) (xy 46.144206 -194.942527)
			(xy 46.128309 -194.880613) (xy 46.120298 -194.817195) (xy 46.119796 -194.785234) (xy 46.120321 -194.751686)
			(xy 46.129162 -194.685175) (xy 46.146671 -194.620403) (xy 46.172543 -194.558495) (xy 46.206328 -194.500525)
			(xy 46.24744 -194.4475) (xy 46.270926 -194.423538) (xy 46.277618 -194.416191) (xy 46.285334 -194.397899)
			(xy 46.285912 -194.387978) (xy 46.286928 -194.30619) (xy 46.279562 -194.287902) (xy 46.27245 -194.280536)
			(xy 46.250632 -194.257351) (xy 46.212514 -194.206357) (xy 46.181238 -194.150903) (xy 46.157317 -194.091902)
			(xy 46.141145 -194.030324) (xy 46.132989 -193.967183) (xy 46.132496 -193.93535) (xy 46.13278 -193.9119)
			(xy 46.137233 -193.865213) (xy 46.141386 -193.842132) (xy 46.142816 -193.832645) (xy 46.139281 -193.813803)
			(xy 46.129065 -193.79758) (xy 46.121574 -193.791586) (xy 46.08954 -193.767444) (xy 46.02951 -193.714232)
			(xy 45.974593 -193.655757) (xy 45.92525 -193.592509) (xy 45.881893 -193.525016) (xy 45.844885 -193.453843)
			(xy 45.814536 -193.379586) (xy 45.791099 -193.302867) (xy 45.774772 -193.224327) (xy 45.769784 -193.184526)
			(xy 45.76809 -193.174132) (xy 45.757608 -193.155895) (xy 45.749464 -193.14922) (xy 45.689266 -193.105024)
			(xy 45.680554 -193.099288) (xy 45.660228 -193.094697) (xy 45.649896 -193.096134) (xy 45.649388 -193.096134)
			(xy 45.608204 -193.103626) (xy 45.524875 -193.111639) (xy 45.483018 -193.112136) (xy 45.441274 -193.1116)
			(xy 45.358164 -193.103665) (xy 45.276185 -193.087867) (xy 45.196079 -193.064347) (xy 45.118571 -193.033319)
			(xy 45.044364 -192.995064) (xy 44.974129 -192.949928) (xy 44.908503 -192.89832) (xy 44.84808 -192.840707)
			(xy 44.793406 -192.777612) (xy 44.744978 -192.709606) (xy 44.703234 -192.637304) (xy 44.668551 -192.561361)
			(xy 44.641245 -192.482465) (xy 44.621562 -192.401331) (xy 44.60968 -192.318693) (xy 44.605707 -192.2353)
			(xy 43.552821 -192.2353) (xy 43.552634 -192.245521) (xy 43.544784 -192.298861) (xy 43.529252 -192.35049)
			(xy 43.506367 -192.399307) (xy 43.476619 -192.444271) (xy 43.440641 -192.484425) (xy 43.399199 -192.518913)
			(xy 43.353178 -192.546999) (xy 43.303558 -192.568086) (xy 43.251397 -192.581722) (xy 43.197806 -192.587619)
			(xy 43.143927 -192.58565) (xy 43.090909 -192.575857) (xy 43.039882 -192.558449) (xy 42.991934 -192.533797)
			(xy 42.948086 -192.502427) (xy 42.909273 -192.465006) (xy 42.876321 -192.422333) (xy 42.849935 -192.375316)
			(xy 42.830675 -192.324959) (xy 42.818952 -192.272335) (xy 42.815017 -192.218564) (xy 41.764458 -192.218564)
			(xy 41.763966 -192.245521) (xy 41.756116 -192.298861) (xy 41.740584 -192.35049) (xy 41.717699 -192.399307)
			(xy 41.687951 -192.444271) (xy 41.651973 -192.484425) (xy 41.610531 -192.518913) (xy 41.56451 -192.546999)
			(xy 41.51489 -192.568086) (xy 41.462729 -192.581722) (xy 41.409138 -192.587619) (xy 41.355259 -192.58565)
			(xy 41.302241 -192.575857) (xy 41.251214 -192.558449) (xy 41.203266 -192.533797) (xy 41.159418 -192.502427)
			(xy 41.120605 -192.465006) (xy 41.087653 -192.422333) (xy 41.061267 -192.375316) (xy 41.042007 -192.324959)
			(xy 41.030284 -192.272335) (xy 41.026349 -192.218564) (xy 39.973559 -192.218564) (xy 39.973758 -192.235328)
			(xy 39.973226 -192.277052) (xy 39.965262 -192.36012) (xy 39.949446 -192.442056) (xy 39.925921 -192.52212)
			(xy 39.894901 -192.599589) (xy 39.876222 -192.636902) (xy 39.871259 -192.648072) (xy 39.871246 -192.672475)
			(xy 39.876222 -192.683638) (xy 39.894921 -192.720943) (xy 39.925963 -192.798407) (xy 39.949499 -192.878473)
			(xy 39.965315 -192.960413) (xy 39.973267 -193.043486) (xy 39.973758 -193.085212) (xy 39.973284 -193.12759)
			(xy 39.965108 -193.211951) (xy 39.948824 -193.295128) (xy 39.924585 -193.376344) (xy 39.892616 -193.454839)
			(xy 39.853217 -193.529881) (xy 39.806756 -193.600768) (xy 39.753667 -193.666837) (xy 39.694447 -193.727471)
			(xy 39.629648 -193.782104) (xy 39.595044 -193.806572) (xy 39.587383 -193.812371) (xy 39.576685 -193.828314)
			(xy 39.572579 -193.847069) (xy 39.573708 -193.85661) (xy 39.576669 -193.876097) (xy 39.579848 -193.915387)
			(xy 39.580058 -193.935096) (xy 39.580058 -193.93535) (xy 39.579558 -193.967184) (xy 39.575769 -193.996582)
			(xy 40.899318 -193.996582) (xy 40.903167 -193.934903) (xy 40.914651 -193.87418) (xy 40.93359 -193.815354)
			(xy 40.959693 -193.759338) (xy 40.992554 -193.706999) (xy 41.031664 -193.659149) (xy 41.076416 -193.61653)
			(xy 41.126118 -193.579802) (xy 41.152826 -193.564256) (xy 41.163748 -193.55816) (xy 41.177464 -193.536824)
			(xy 41.1861 -193.427604) (xy 41.17594 -193.404236) (xy 41.166034 -193.396362) (xy 41.144698 -193.378794)
			(xy 41.10706 -193.338324) (xy 41.075887 -193.292687) (xy 41.051877 -193.242908) (xy 41.035569 -193.190101)
			(xy 41.027329 -193.135452) (xy 41.026842 -193.107818) (xy 41.026842 -193.107564) (xy 41.027358 -193.079964)
			(xy 41.035585 -193.025381) (xy 41.051855 -192.972634) (xy 41.075805 -192.922902) (xy 41.1069 -192.877294)
			(xy 41.144445 -192.83683) (xy 41.187602 -192.802413) (xy 41.235406 -192.774814) (xy 41.28679 -192.754647)
			(xy 41.340605 -192.742364) (xy 41.39565 -192.738239) (xy 41.450695 -192.742364) (xy 41.50451 -192.754647)
			(xy 41.555894 -192.774814) (xy 41.603698 -192.802413) (xy 41.646855 -192.83683) (xy 41.6844 -192.877294)
			(xy 41.715495 -192.922902) (xy 41.739445 -192.972634) (xy 41.755715 -193.025381) (xy 41.763942 -193.079964)
			(xy 41.764458 -193.107564) (xy 41.764458 -193.107818) (xy 41.763904 -193.135446) (xy 41.755648 -193.190082)
			(xy 41.739337 -193.242876) (xy 41.715336 -193.292648) (xy 41.684183 -193.338285) (xy 41.646573 -193.378767)
			(xy 41.625266 -193.396362) (xy 41.61536 -193.404236) (xy 41.6052 -193.427604) (xy 41.613836 -193.536824)
			(xy 41.627552 -193.55816) (xy 41.638474 -193.564256) (xy 41.665148 -193.579855) (xy 41.714843 -193.616578)
			(xy 41.75959 -193.659192) (xy 41.798695 -193.707036) (xy 41.831552 -193.759368) (xy 41.857651 -193.815377)
			(xy 41.876589 -193.874195) (xy 41.888071 -193.934911) (xy 41.891918 -193.996564) (xy 42.815017 -193.996564)
			(xy 42.818952 -193.942793) (xy 42.830675 -193.890169) (xy 42.849935 -193.839812) (xy 42.876321 -193.792795)
			(xy 42.909273 -193.750122) (xy 42.948086 -193.712701) (xy 42.991934 -193.681331) (xy 43.039882 -193.656679)
			(xy 43.090909 -193.639271) (xy 43.143927 -193.629478) (xy 43.197806 -193.627509) (xy 43.251397 -193.633406)
			(xy 43.303558 -193.647042) (xy 43.353178 -193.668129) (xy 43.399199 -193.696215) (xy 43.440641 -193.730703)
			(xy 43.476619 -193.770857) (xy 43.506367 -193.815821) (xy 43.529252 -193.864638) (xy 43.544784 -193.916267)
			(xy 43.552634 -193.969607) (xy 43.553126 -193.996564) (xy 43.552634 -194.023521) (xy 43.544784 -194.076861)
			(xy 43.529252 -194.12849) (xy 43.506367 -194.177307) (xy 43.476619 -194.222271) (xy 43.440641 -194.262425)
			(xy 43.399199 -194.296913) (xy 43.353178 -194.324999) (xy 43.303558 -194.346086) (xy 43.251397 -194.359722)
			(xy 43.197806 -194.365619) (xy 43.143927 -194.36365) (xy 43.090909 -194.353857) (xy 43.039882 -194.336449)
			(xy 42.991934 -194.311797) (xy 42.948086 -194.280427) (xy 42.909273 -194.243006) (xy 42.876321 -194.200333)
			(xy 42.849935 -194.153316) (xy 42.830675 -194.102959) (xy 42.818952 -194.050335) (xy 42.815017 -193.996564)
			(xy 41.891918 -193.996564) (xy 41.891919 -193.996582) (xy 41.888075 -194.058254) (xy 41.876597 -194.118971)
			(xy 41.857664 -194.17779) (xy 41.831569 -194.233801) (xy 41.798716 -194.286136) (xy 41.759614 -194.333982)
			(xy 41.71487 -194.376599) (xy 41.665178 -194.413326) (xy 41.638474 -194.428872) (xy 41.627552 -194.434968)
			(xy 41.613836 -194.456304) (xy 41.6052 -194.565524) (xy 41.61536 -194.588892) (xy 41.625266 -194.596766)
			(xy 41.646567 -194.614374) (xy 41.684208 -194.654836) (xy 41.715385 -194.700464) (xy 41.739401 -194.750236)
			(xy 41.755716 -194.803035) (xy 41.763966 -194.857679) (xy 41.764458 -194.88531) (xy 41.764458 -194.885564)
			(xy 41.763942 -194.913164) (xy 41.755715 -194.967747) (xy 41.739445 -195.020494) (xy 41.715495 -195.070227)
			(xy 41.6844 -195.115834) (xy 41.646855 -195.156298) (xy 41.603698 -195.190715) (xy 41.555894 -195.218314)
			(xy 41.50451 -195.238481) (xy 41.450695 -195.250764) (xy 41.39565 -195.254889) (xy 41.340605 -195.250764)
			(xy 41.28679 -195.238481) (xy 41.235406 -195.218314) (xy 41.187602 -195.190715) (xy 41.144445 -195.156298)
			(xy 41.1069 -195.115834) (xy 41.075805 -195.070227) (xy 41.051855 -195.020494) (xy 41.035585 -194.967747)
			(xy 41.027358 -194.913164) (xy 41.026842 -194.885564) (xy 41.026842 -194.88531) (xy 41.027345 -194.85768)
			(xy 41.035612 -194.803042) (xy 41.051933 -194.750246) (xy 41.075943 -194.700475) (xy 41.107105 -194.654839)
			(xy 41.144724 -194.61436) (xy 41.166034 -194.596766) (xy 41.17594 -194.588892) (xy 41.1861 -194.565524)
			(xy 41.177464 -194.456304) (xy 41.163748 -194.434968) (xy 41.152826 -194.428872) (xy 41.126088 -194.413379)
			(xy 41.076389 -194.376647) (xy 41.03164 -194.334025) (xy 40.992533 -194.286172) (xy 40.959676 -194.233831)
			(xy 40.933578 -194.177813) (xy 40.914642 -194.118986) (xy 40.903163 -194.058262) (xy 40.899318 -193.996582)
			(xy 39.575769 -193.996582) (xy 39.57142 -194.030329) (xy 39.555257 -194.091911) (xy 39.531338 -194.150914)
			(xy 39.500055 -194.206366) (xy 39.461926 -194.257353) (xy 39.440104 -194.280536) (xy 39.432992 -194.287902)
			(xy 39.425626 -194.30619) (xy 39.426896 -194.398138) (xy 39.434516 -194.416426) (xy 39.441628 -194.423538)
			(xy 39.465112 -194.447503) (xy 39.506237 -194.50052) (xy 39.540028 -194.558487) (xy 39.565899 -194.620396)
			(xy 39.583398 -194.685171) (xy 39.592222 -194.751685) (xy 39.592758 -194.785234) (xy 39.592256 -194.817195)
			(xy 39.584245 -194.880613) (xy 39.568348 -194.942527) (xy 39.544816 -195.00196) (xy 39.514022 -195.057975)
			(xy 39.476449 -195.10969) (xy 39.432692 -195.156287) (xy 39.383439 -195.197032) (xy 39.329468 -195.231283)
			(xy 39.271629 -195.2585) (xy 39.210836 -195.278253) (xy 39.148046 -195.290231) (xy 39.08425 -195.294245)
			(xy 39.020454 -195.290231) (xy 38.957664 -195.278253) (xy 38.896871 -195.2585) (xy 38.839032 -195.231283)
			(xy 38.785061 -195.197032) (xy 38.735808 -195.156287) (xy 38.692051 -195.10969) (xy 38.654478 -195.057975)
			(xy 38.623684 -195.00196) (xy 38.600152 -194.942527) (xy 38.584255 -194.880613) (xy 38.576244 -194.817195)
			(xy 38.575742 -194.785234) (xy 38.576253 -194.751685) (xy 38.585096 -194.685173) (xy 38.602606 -194.620401)
			(xy 38.62848 -194.558492) (xy 38.662268 -194.500523) (xy 38.703384 -194.447499) (xy 38.726872 -194.423538)
			(xy 38.733557 -194.416185) (xy 38.741278 -194.397897) (xy 38.741858 -194.387978) (xy 38.742874 -194.30619)
			(xy 38.735508 -194.287902) (xy 38.728396 -194.280536) (xy 38.706586 -194.257343) (xy 38.668466 -194.206352)
			(xy 38.637187 -194.1509) (xy 38.613265 -194.0919) (xy 38.597092 -194.030323) (xy 38.588935 -193.967183)
			(xy 38.588442 -193.93535) (xy 38.588727 -193.9119) (xy 38.59318 -193.865213) (xy 38.597332 -193.842132)
			(xy 38.598743 -193.832644) (xy 38.595211 -193.813806) (xy 38.585006 -193.797583) (xy 38.57752 -193.791586)
			(xy 38.545474 -193.767459) (xy 38.485446 -193.714245) (xy 38.430531 -193.655767) (xy 38.381189 -193.592516)
			(xy 38.337834 -193.525021) (xy 38.300827 -193.453847) (xy 38.27048 -193.379589) (xy 38.247044 -193.302868)
			(xy 38.230718 -193.224327) (xy 38.22573 -193.184526) (xy 38.224054 -193.174127) (xy 38.213561 -193.15589)
			(xy 38.20541 -193.14922) (xy 38.145212 -193.105024) (xy 38.136486 -193.099312) (xy 38.116171 -193.094706)
			(xy 38.105842 -193.096134) (xy 38.105334 -193.096134) (xy 38.064149 -193.103619) (xy 37.980821 -193.111637)
			(xy 37.938964 -193.112136) (xy 37.897219 -193.111659) (xy 37.814108 -193.103723) (xy 37.732127 -193.087923)
			(xy 37.652019 -193.064402) (xy 37.57451 -193.033372) (xy 37.500301 -192.995115) (xy 37.430065 -192.949977)
			(xy 37.364438 -192.898368) (xy 37.304013 -192.840753) (xy 37.249339 -192.777656) (xy 37.20091 -192.709648)
			(xy 37.159165 -192.637344) (xy 37.124482 -192.561399) (xy 37.097175 -192.482501) (xy 37.077492 -192.401365)
			(xy 37.06561 -192.318725) (xy 37.061637 -192.23533) (xy 36.008766 -192.23533) (xy 36.00858 -192.245521)
			(xy 36.00073 -192.298861) (xy 35.985198 -192.35049) (xy 35.962313 -192.399307) (xy 35.932565 -192.444271)
			(xy 35.896587 -192.484425) (xy 35.855145 -192.518913) (xy 35.809124 -192.546999) (xy 35.759504 -192.568086)
			(xy 35.707343 -192.581722) (xy 35.653752 -192.587619) (xy 35.599873 -192.58565) (xy 35.546855 -192.575857)
			(xy 35.495828 -192.558449) (xy 35.44788 -192.533797) (xy 35.404032 -192.502427) (xy 35.365219 -192.465006)
			(xy 35.332267 -192.422333) (xy 35.305881 -192.375316) (xy 35.286621 -192.324959) (xy 35.274898 -192.272335)
			(xy 35.270963 -192.218564) (xy 34.182304 -192.218564) (xy 34.181812 -192.245521) (xy 34.173962 -192.298861)
			(xy 34.15843 -192.35049) (xy 34.135545 -192.399307) (xy 34.105797 -192.444271) (xy 34.069819 -192.484425)
			(xy 34.028377 -192.518913) (xy 33.982356 -192.546999) (xy 33.932736 -192.568086) (xy 33.880575 -192.581722)
			(xy 33.826984 -192.587619) (xy 33.773105 -192.58565) (xy 33.720087 -192.575857) (xy 33.66906 -192.558449)
			(xy 33.621112 -192.533797) (xy 33.577264 -192.502427) (xy 33.538451 -192.465006) (xy 33.505499 -192.422333)
			(xy 33.479113 -192.375316) (xy 33.459853 -192.324959) (xy 33.44813 -192.272335) (xy 33.444195 -192.218564)
			(xy 32.429505 -192.218564) (xy 32.429704 -192.235328) (xy 32.429167 -192.277052) (xy 32.421203 -192.360119)
			(xy 32.405388 -192.442055) (xy 32.381865 -192.52212) (xy 32.350846 -192.599589) (xy 32.332168 -192.636902)
			(xy 32.327208 -192.648073) (xy 32.327196 -192.672474) (xy 32.332168 -192.683638) (xy 32.350871 -192.720941)
			(xy 32.381912 -192.798406) (xy 32.405446 -192.878472) (xy 32.421261 -192.960413) (xy 32.429214 -193.043486)
			(xy 32.429704 -193.085212) (xy 32.42921 -193.127589) (xy 32.421034 -193.211949) (xy 32.404752 -193.295125)
			(xy 32.380514 -193.37634) (xy 32.348547 -193.454835) (xy 32.30915 -193.529877) (xy 32.262692 -193.600764)
			(xy 32.209606 -193.666833) (xy 32.150388 -193.727469) (xy 32.085592 -193.782102) (xy 32.05099 -193.806572)
			(xy 32.043337 -193.812381) (xy 32.032634 -193.828318) (xy 32.028525 -193.84707) (xy 32.029654 -193.85661)
			(xy 32.032614 -193.876097) (xy 32.035794 -193.915387) (xy 32.036004 -193.935096) (xy 32.036004 -193.93535)
			(xy 32.035491 -193.967183) (xy 32.031703 -193.996582) (xy 33.31714 -193.996582) (xy 33.32099 -193.934901)
			(xy 33.332475 -193.874176) (xy 33.351417 -193.815349) (xy 33.377522 -193.759332) (xy 33.410386 -193.706993)
			(xy 33.4495 -193.659144) (xy 33.494256 -193.616526) (xy 33.543962 -193.5798) (xy 33.570672 -193.564256)
			(xy 33.581594 -193.55816) (xy 33.59531 -193.536824) (xy 33.603946 -193.427604) (xy 33.593786 -193.404236)
			(xy 33.58388 -193.396362) (xy 33.562554 -193.378783) (xy 33.524913 -193.338316) (xy 33.493737 -193.292682)
			(xy 33.469726 -193.242905) (xy 33.453417 -193.1901) (xy 33.445176 -193.135451) (xy 33.444688 -193.107818)
			(xy 33.444688 -193.107564) (xy 33.445204 -193.079964) (xy 33.453431 -193.025381) (xy 33.469701 -192.972634)
			(xy 33.493651 -192.922902) (xy 33.524746 -192.877294) (xy 33.562291 -192.83683) (xy 33.605448 -192.802413)
			(xy 33.653252 -192.774814) (xy 33.704636 -192.754647) (xy 33.758451 -192.742364) (xy 33.813496 -192.738239)
			(xy 33.868541 -192.742364) (xy 33.922356 -192.754647) (xy 33.97374 -192.774814) (xy 34.021544 -192.802413)
			(xy 34.064701 -192.83683) (xy 34.102246 -192.877294) (xy 34.133341 -192.922902) (xy 34.157291 -192.972634)
			(xy 34.173561 -193.025381) (xy 34.181788 -193.079964) (xy 34.182304 -193.107564) (xy 34.182304 -193.107818)
			(xy 34.18177 -193.135447) (xy 34.173512 -193.190085) (xy 34.157199 -193.242881) (xy 34.133195 -193.292653)
			(xy 34.102037 -193.338289) (xy 34.064422 -193.378769) (xy 34.043112 -193.396362) (xy 34.033206 -193.404236)
			(xy 34.023046 -193.427604) (xy 34.031682 -193.536824) (xy 34.045398 -193.55816) (xy 34.05632 -193.564256)
			(xy 34.082997 -193.579853) (xy 34.132697 -193.616573) (xy 34.177448 -193.659186) (xy 34.216557 -193.707029)
			(xy 34.249418 -193.759361) (xy 34.27552 -193.815371) (xy 34.29446 -193.874191) (xy 34.305944 -193.934908)
			(xy 34.309793 -193.996582) (xy 34.305948 -194.058257) (xy 34.294469 -194.118975) (xy 34.275533 -194.177796)
			(xy 34.249435 -194.233808) (xy 34.216578 -194.286143) (xy 34.177472 -194.333989) (xy 34.132724 -194.376604)
			(xy 34.083026 -194.413328) (xy 34.05632 -194.428872) (xy 34.045398 -194.434968) (xy 34.031682 -194.456304)
			(xy 34.023046 -194.565524) (xy 34.033206 -194.588892) (xy 34.043112 -194.596766) (xy 34.064402 -194.614387)
			(xy 34.102045 -194.654845) (xy 34.133226 -194.70047) (xy 34.157244 -194.750239) (xy 34.173561 -194.803037)
			(xy 34.181811 -194.857679) (xy 34.182304 -194.88531) (xy 34.182304 -194.885564) (xy 34.181788 -194.913164)
			(xy 34.173561 -194.967747) (xy 34.157291 -195.020494) (xy 34.133341 -195.070227) (xy 34.102246 -195.115834)
			(xy 34.064701 -195.156298) (xy 34.021544 -195.190715) (xy 33.97374 -195.218314) (xy 33.922356 -195.238481)
			(xy 33.868541 -195.250764) (xy 33.813496 -195.254889) (xy 33.758451 -195.250764) (xy 33.704636 -195.238481)
			(xy 33.653252 -195.218314) (xy 33.605448 -195.190715) (xy 33.562291 -195.156298) (xy 33.524746 -195.115834)
			(xy 33.493651 -195.070227) (xy 33.469701 -195.020494) (xy 33.453431 -194.967747) (xy 33.445204 -194.913164)
			(xy 33.444688 -194.885564) (xy 33.444688 -194.88531) (xy 33.445174 -194.857679) (xy 33.453442 -194.803039)
			(xy 33.469765 -194.750243) (xy 33.493778 -194.700471) (xy 33.524945 -194.654836) (xy 33.562567 -194.614358)
			(xy 33.58388 -194.596766) (xy 33.593786 -194.588892) (xy 33.603946 -194.565524) (xy 33.59531 -194.456304)
			(xy 33.581594 -194.434968) (xy 33.570672 -194.428872) (xy 33.543932 -194.413381) (xy 33.494229 -194.376651)
			(xy 33.449476 -194.33403) (xy 33.410366 -194.286178) (xy 33.377505 -194.233837) (xy 33.351404 -194.177818)
			(xy 33.332466 -194.11899) (xy 33.320986 -194.058264) (xy 33.31714 -193.996582) (xy 32.031703 -193.996582)
			(xy 32.027354 -194.030327) (xy 32.011193 -194.091909) (xy 31.987276 -194.150912) (xy 31.955996 -194.206364)
			(xy 31.91787 -194.257352) (xy 31.89605 -194.280536) (xy 31.888938 -194.287902) (xy 31.881572 -194.30619)
			(xy 31.882842 -194.398138) (xy 31.890462 -194.416426) (xy 31.897574 -194.423538) (xy 31.921066 -194.447495)
			(xy 31.962189 -194.500514) (xy 31.995978 -194.558483) (xy 32.021846 -194.620394) (xy 32.039345 -194.68517)
			(xy 32.048168 -194.751685) (xy 32.048704 -194.785234) (xy 32.048202 -194.817195) (xy 32.040191 -194.880613)
			(xy 32.024294 -194.942527) (xy 32.000762 -195.00196) (xy 31.969968 -195.057975) (xy 31.932395 -195.10969)
			(xy 31.888638 -195.156287) (xy 31.839385 -195.197032) (xy 31.785414 -195.231283) (xy 31.727575 -195.2585)
			(xy 31.666782 -195.278253) (xy 31.603992 -195.290231) (xy 31.540196 -195.294245) (xy 31.4764 -195.290231)
			(xy 31.41361 -195.278253) (xy 31.352817 -195.2585) (xy 31.294978 -195.231283) (xy 31.241007 -195.197032)
			(xy 31.191754 -195.156287) (xy 31.147997 -195.10969) (xy 31.110424 -195.057975) (xy 31.07963 -195.00196)
			(xy 31.056098 -194.942527) (xy 31.040201 -194.880613) (xy 31.03219 -194.817195) (xy 31.031688 -194.785234)
			(xy 31.032215 -194.751686) (xy 31.041057 -194.685175) (xy 31.058565 -194.620404) (xy 31.084436 -194.558496)
			(xy 31.118221 -194.500526) (xy 31.159332 -194.4475) (xy 31.182818 -194.423538) (xy 31.189509 -194.41619)
			(xy 31.197226 -194.397898) (xy 31.197804 -194.387978) (xy 31.19882 -194.30619) (xy 31.191454 -194.287902)
			(xy 31.184342 -194.280536) (xy 31.162541 -194.257336) (xy 31.124418 -194.206347) (xy 31.093137 -194.150897)
			(xy 31.069212 -194.091898) (xy 31.053039 -194.030322) (xy 31.044881 -193.967182) (xy 31.044388 -193.93535)
			(xy 31.044672 -193.9119) (xy 31.049125 -193.865213) (xy 31.053278 -193.842132) (xy 31.054711 -193.832645)
			(xy 31.051176 -193.813802) (xy 31.040958 -193.79758) (xy 31.033466 -193.791586) (xy 31.00143 -193.767446)
			(xy 30.9414 -193.714234) (xy 30.886484 -193.655759) (xy 30.837141 -193.59251) (xy 30.793784 -193.525017)
			(xy 30.756776 -193.453844) (xy 30.726427 -193.379587) (xy 30.702991 -193.302867) (xy 30.686664 -193.224327)
			(xy 30.681676 -193.184526) (xy 30.679984 -193.174131) (xy 30.669501 -193.155894) (xy 30.661356 -193.14922)
			(xy 30.601158 -193.105024) (xy 30.592448 -193.099283) (xy 30.57212 -193.094695) (xy 30.561788 -193.096134)
			(xy 30.56128 -193.096134) (xy 30.520159 -193.103618) (xy 30.436957 -193.111631) (xy 30.395164 -193.112136)
			(xy 30.353419 -193.111659) (xy 30.270308 -193.103723) (xy 30.188327 -193.087923) (xy 30.108219 -193.064402)
			(xy 30.03071 -193.033372) (xy 29.956501 -192.995115) (xy 29.886265 -192.949977) (xy 29.820638 -192.898368)
			(xy 29.760213 -192.840753) (xy 29.705539 -192.777656) (xy 29.65711 -192.709648) (xy 29.615365 -192.637344)
			(xy 29.580682 -192.561399) (xy 29.553375 -192.482501) (xy 29.533692 -192.401365) (xy 29.52181 -192.318725)
			(xy 29.517837 -192.23533) (xy 28.464966 -192.23533) (xy 28.46478 -192.245521) (xy 28.45693 -192.298861)
			(xy 28.441398 -192.35049) (xy 28.418513 -192.399307) (xy 28.388765 -192.444271) (xy 28.352787 -192.484425)
			(xy 28.311345 -192.518913) (xy 28.265324 -192.546999) (xy 28.215704 -192.568086) (xy 28.163543 -192.581722)
			(xy 28.109952 -192.587619) (xy 28.056073 -192.58565) (xy 28.003055 -192.575857) (xy 27.952028 -192.558449)
			(xy 27.90408 -192.533797) (xy 27.860232 -192.502427) (xy 27.821419 -192.465006) (xy 27.788467 -192.422333)
			(xy 27.762081 -192.375316) (xy 27.742821 -192.324959) (xy 27.731098 -192.272335) (xy 27.727163 -192.218564)
			(xy 26.676604 -192.218564) (xy 26.676112 -192.245521) (xy 26.668262 -192.298861) (xy 26.65273 -192.35049)
			(xy 26.629845 -192.399307) (xy 26.600097 -192.444271) (xy 26.564119 -192.484425) (xy 26.522677 -192.518913)
			(xy 26.476656 -192.546999) (xy 26.427036 -192.568086) (xy 26.374875 -192.581722) (xy 26.321284 -192.587619)
			(xy 26.267405 -192.58565) (xy 26.214387 -192.575857) (xy 26.16336 -192.558449) (xy 26.115412 -192.533797)
			(xy 26.071564 -192.502427) (xy 26.032751 -192.465006) (xy 25.999799 -192.422333) (xy 25.973413 -192.375316)
			(xy 25.954153 -192.324959) (xy 25.94243 -192.272335) (xy 25.938495 -192.218564) (xy 24.885705 -192.218564)
			(xy 24.885904 -192.235328) (xy 24.885367 -192.277052) (xy 24.877403 -192.360119) (xy 24.861588 -192.442055)
			(xy 24.838065 -192.52212) (xy 24.807046 -192.599589) (xy 24.788368 -192.636902) (xy 24.783408 -192.648073)
			(xy 24.783396 -192.672474) (xy 24.788368 -192.683638) (xy 24.807071 -192.720941) (xy 24.838112 -192.798406)
			(xy 24.861646 -192.878472) (xy 24.877461 -192.960413) (xy 24.885414 -193.043486) (xy 24.885904 -193.085212)
			(xy 24.88541 -193.127589) (xy 24.877234 -193.211949) (xy 24.860952 -193.295125) (xy 24.836714 -193.37634)
			(xy 24.804747 -193.454835) (xy 24.76535 -193.529877) (xy 24.718892 -193.600764) (xy 24.665806 -193.666833)
			(xy 24.606588 -193.727469) (xy 24.541792 -193.782102) (xy 24.50719 -193.806572) (xy 24.499537 -193.812381)
			(xy 24.488834 -193.828318) (xy 24.484725 -193.84707) (xy 24.485854 -193.85661) (xy 24.488814 -193.876097)
			(xy 24.491994 -193.915387) (xy 24.492204 -193.935096) (xy 24.492204 -193.93535) (xy 24.491691 -193.967183)
			(xy 24.487905 -193.996562) (xy 25.811475 -193.996562) (xy 25.815322 -193.934885) (xy 25.826804 -193.874164)
			(xy 25.845742 -193.81534) (xy 25.871843 -193.759326) (xy 25.904703 -193.706989) (xy 25.943812 -193.659142)
			(xy 25.988563 -193.616525) (xy 26.038264 -193.5798) (xy 26.064972 -193.564256) (xy 26.075894 -193.55816)
			(xy 26.08961 -193.536824) (xy 26.098246 -193.427604) (xy 26.088086 -193.404236) (xy 26.07818 -193.396362)
			(xy 26.056854 -193.378783) (xy 26.019213 -193.338316) (xy 25.988037 -193.292682) (xy 25.964026 -193.242905)
			(xy 25.947717 -193.1901) (xy 25.939476 -193.135451) (xy 25.938988 -193.107818) (xy 25.938988 -193.107564)
			(xy 25.939504 -193.079964) (xy 25.947731 -193.025381) (xy 25.964001 -192.972634) (xy 25.987951 -192.922902)
			(xy 26.019046 -192.877294) (xy 26.056591 -192.83683) (xy 26.099748 -192.802413) (xy 26.147552 -192.774814)
			(xy 26.198936 -192.754647) (xy 26.252751 -192.742364) (xy 26.307796 -192.738239) (xy 26.362841 -192.742364)
			(xy 26.416656 -192.754647) (xy 26.46804 -192.774814) (xy 26.515844 -192.802413) (xy 26.559001 -192.83683)
			(xy 26.596546 -192.877294) (xy 26.627641 -192.922902) (xy 26.651591 -192.972634) (xy 26.667861 -193.025381)
			(xy 26.676088 -193.079964) (xy 26.676604 -193.107564) (xy 26.676604 -193.107818) (xy 26.67607 -193.135447)
			(xy 26.667812 -193.190085) (xy 26.651499 -193.242881) (xy 26.627495 -193.292653) (xy 26.596337 -193.338289)
			(xy 26.558722 -193.378769) (xy 26.537412 -193.396362) (xy 26.527506 -193.404236) (xy 26.517346 -193.427604)
			(xy 26.525982 -193.536824) (xy 26.539698 -193.55816) (xy 26.55062 -193.564256) (xy 26.577332 -193.579794)
			(xy 26.627034 -193.616519) (xy 26.671787 -193.659136) (xy 26.710897 -193.706984) (xy 26.743758 -193.759321)
			(xy 26.76986 -193.815337) (xy 26.788799 -193.874161) (xy 26.800281 -193.934884) (xy 26.804128 -193.996562)
			(xy 26.80028 -194.05824) (xy 26.788798 -194.118962) (xy 26.769859 -194.177787) (xy 26.743756 -194.233802)
			(xy 26.710895 -194.286139) (xy 26.671784 -194.333987) (xy 26.627031 -194.376603) (xy 26.577329 -194.413328)
			(xy 26.55062 -194.428872) (xy 26.539698 -194.434968) (xy 26.525982 -194.456304) (xy 26.517346 -194.565524)
			(xy 26.527506 -194.588892) (xy 26.537412 -194.596766) (xy 26.558702 -194.614387) (xy 26.596345 -194.654845)
			(xy 26.627526 -194.70047) (xy 26.651544 -194.750239) (xy 26.667861 -194.803037) (xy 26.676111 -194.857679)
			(xy 26.676604 -194.88531) (xy 26.676604 -194.885564) (xy 26.676088 -194.913164) (xy 26.667861 -194.967747)
			(xy 26.651591 -195.020494) (xy 26.627641 -195.070227) (xy 26.596546 -195.115834) (xy 26.559001 -195.156298)
			(xy 26.515844 -195.190715) (xy 26.46804 -195.218314) (xy 26.416656 -195.238481) (xy 26.362841 -195.250764)
			(xy 26.307796 -195.254889) (xy 26.252751 -195.250764) (xy 26.198936 -195.238481) (xy 26.147552 -195.218314)
			(xy 26.099748 -195.190715) (xy 26.056591 -195.156298) (xy 26.019046 -195.115834) (xy 25.987951 -195.070227)
			(xy 25.964001 -195.020494) (xy 25.947731 -194.967747) (xy 25.939504 -194.913164) (xy 25.938988 -194.885564)
			(xy 25.938988 -194.88531) (xy 25.939474 -194.857679) (xy 25.947742 -194.803039) (xy 25.964065 -194.750243)
			(xy 25.988078 -194.700471) (xy 26.019245 -194.654836) (xy 26.056867 -194.614358) (xy 26.07818 -194.596766)
			(xy 26.088086 -194.588892) (xy 26.098246 -194.565524) (xy 26.08961 -194.456304) (xy 26.075894 -194.434968)
			(xy 26.064972 -194.428872) (xy 26.038267 -194.413322) (xy 25.988566 -194.376597) (xy 25.943815 -194.333981)
			(xy 25.904705 -194.286134) (xy 25.871845 -194.233798) (xy 25.845743 -194.177784) (xy 25.826805 -194.11896)
			(xy 25.815323 -194.058239) (xy 25.811475 -193.996562) (xy 24.487905 -193.996562) (xy 24.483554 -194.030327)
			(xy 24.467393 -194.091909) (xy 24.443476 -194.150912) (xy 24.412196 -194.206364) (xy 24.37407 -194.257352)
			(xy 24.35225 -194.280536) (xy 24.345138 -194.287902) (xy 24.337772 -194.30619) (xy 24.339042 -194.398138)
			(xy 24.346662 -194.416426) (xy 24.353774 -194.423538) (xy 24.377266 -194.447495) (xy 24.418389 -194.500514)
			(xy 24.452178 -194.558483) (xy 24.478046 -194.620394) (xy 24.495545 -194.68517) (xy 24.504368 -194.751685)
			(xy 24.504904 -194.785234) (xy 24.504402 -194.817195) (xy 24.496391 -194.880613) (xy 24.480494 -194.942527)
			(xy 24.456962 -195.00196) (xy 24.426168 -195.057975) (xy 24.388595 -195.10969) (xy 24.344838 -195.156287)
			(xy 24.295585 -195.197032) (xy 24.241614 -195.231283) (xy 24.183775 -195.2585) (xy 24.122982 -195.278253)
			(xy 24.060192 -195.290231) (xy 23.996396 -195.294245) (xy 23.9326 -195.290231) (xy 23.86981 -195.278253)
			(xy 23.809017 -195.2585) (xy 23.751178 -195.231283) (xy 23.697207 -195.197032) (xy 23.647954 -195.156287)
			(xy 23.604197 -195.10969) (xy 23.566624 -195.057975) (xy 23.53583 -195.00196) (xy 23.512298 -194.942527)
			(xy 23.496401 -194.880613) (xy 23.48839 -194.817195) (xy 23.487888 -194.785234) (xy 23.488415 -194.751686)
			(xy 23.497257 -194.685175) (xy 23.514765 -194.620404) (xy 23.540636 -194.558496) (xy 23.574421 -194.500526)
			(xy 23.615532 -194.4475) (xy 23.639018 -194.423538) (xy 23.645709 -194.41619) (xy 23.653426 -194.397898)
			(xy 23.654004 -194.387978) (xy 23.65502 -194.30619) (xy 23.647654 -194.287902) (xy 23.640542 -194.280536)
			(xy 23.618741 -194.257336) (xy 23.580618 -194.206347) (xy 23.549337 -194.150897) (xy 23.525412 -194.091898)
			(xy 23.509239 -194.030322) (xy 23.501081 -193.967182) (xy 23.500588 -193.93535) (xy 23.500872 -193.9119)
			(xy 23.505325 -193.865213) (xy 23.509478 -193.842132) (xy 23.510911 -193.832645) (xy 23.507376 -193.813802)
			(xy 23.497158 -193.79758) (xy 23.489666 -193.791586) (xy 23.45763 -193.767446) (xy 23.3976 -193.714234)
			(xy 23.342684 -193.655759) (xy 23.293341 -193.59251) (xy 23.249984 -193.525017) (xy 23.212976 -193.453844)
			(xy 23.182627 -193.379587) (xy 23.159191 -193.302867) (xy 23.142864 -193.224327) (xy 23.137876 -193.184526)
			(xy 23.136184 -193.174131) (xy 23.125701 -193.155894) (xy 23.117556 -193.14922) (xy 23.057358 -193.105024)
			(xy 23.048648 -193.099283) (xy 23.02832 -193.094695) (xy 23.017988 -193.096134) (xy 23.01748 -193.096134)
			(xy 22.976296 -193.103627) (xy 22.892967 -193.11164) (xy 22.85111 -193.112136) (xy 22.809366 -193.111643)
			(xy 22.726256 -193.103707) (xy 22.644277 -193.087907) (xy 22.564171 -193.064386) (xy 22.486664 -193.033357)
			(xy 22.412457 -192.9951) (xy 22.342222 -192.949963) (xy 22.276596 -192.898354) (xy 22.216173 -192.840741)
			(xy 22.1615 -192.777645) (xy 22.113072 -192.709638) (xy 22.071328 -192.637335) (xy 22.036646 -192.561392)
			(xy 22.00934 -192.482496) (xy 21.989657 -192.401361) (xy 21.977776 -192.318723) (xy 21.973803 -192.23533)
			(xy 20.920912 -192.23533) (xy 20.920726 -192.245521) (xy 20.912876 -192.298861) (xy 20.897344 -192.35049)
			(xy 20.874459 -192.399307) (xy 20.844711 -192.444271) (xy 20.808733 -192.484425) (xy 20.767291 -192.518913)
			(xy 20.72127 -192.546999) (xy 20.67165 -192.568086) (xy 20.619489 -192.581722) (xy 20.565898 -192.587619)
			(xy 20.512019 -192.58565) (xy 20.459001 -192.575857) (xy 20.407974 -192.558449) (xy 20.360026 -192.533797)
			(xy 20.316178 -192.502427) (xy 20.277365 -192.465006) (xy 20.244413 -192.422333) (xy 20.218027 -192.375316)
			(xy 20.198767 -192.324959) (xy 20.187044 -192.272335) (xy 20.183109 -192.218564) (xy 19.13255 -192.218564)
			(xy 19.132058 -192.245521) (xy 19.124208 -192.298861) (xy 19.108676 -192.35049) (xy 19.085791 -192.399307)
			(xy 19.056043 -192.444271) (xy 19.020065 -192.484425) (xy 18.978623 -192.518913) (xy 18.932602 -192.546999)
			(xy 18.882982 -192.568086) (xy 18.830821 -192.581722) (xy 18.77723 -192.587619) (xy 18.723351 -192.58565)
			(xy 18.670333 -192.575857) (xy 18.619306 -192.558449) (xy 18.571358 -192.533797) (xy 18.52751 -192.502427)
			(xy 18.488697 -192.465006) (xy 18.455745 -192.422333) (xy 18.429359 -192.375316) (xy 18.410099 -192.324959)
			(xy 18.398376 -192.272335) (xy 18.394441 -192.218564) (xy 17.34165 -192.218564) (xy 17.34185 -192.235328)
			(xy 17.341308 -192.277052) (xy 17.333345 -192.360119) (xy 17.31753 -192.442055) (xy 17.294008 -192.522119)
			(xy 17.262991 -192.599588) (xy 17.244314 -192.636902) (xy 17.239351 -192.648072) (xy 17.239338 -192.672475)
			(xy 17.244314 -192.683638) (xy 17.263013 -192.720943) (xy 17.294055 -192.798408) (xy 17.31759 -192.878473)
			(xy 17.333406 -192.960413) (xy 17.341359 -193.043486) (xy 17.34185 -193.085212) (xy 17.341584 -193.107564)
			(xy 18.394441 -193.107564) (xy 18.398376 -193.053793) (xy 18.410099 -193.001169) (xy 18.429359 -192.950812)
			(xy 18.455745 -192.903795) (xy 18.488697 -192.861122) (xy 18.52751 -192.823701) (xy 18.571358 -192.792331)
			(xy 18.619306 -192.767679) (xy 18.670333 -192.750271) (xy 18.723351 -192.740478) (xy 18.77723 -192.738509)
			(xy 18.830821 -192.744406) (xy 18.882982 -192.758042) (xy 18.932602 -192.779129) (xy 18.978623 -192.807215)
			(xy 19.020065 -192.841703) (xy 19.056043 -192.881857) (xy 19.085791 -192.926821) (xy 19.108676 -192.975638)
			(xy 19.124208 -193.027267) (xy 19.132058 -193.080607) (xy 19.13255 -193.107564) (xy 19.132058 -193.134521)
			(xy 19.124208 -193.187861) (xy 19.108676 -193.23949) (xy 19.085791 -193.288307) (xy 19.056043 -193.333271)
			(xy 19.020065 -193.373425) (xy 18.978623 -193.407913) (xy 18.932602 -193.435999) (xy 18.882982 -193.457086)
			(xy 18.830821 -193.470722) (xy 18.77723 -193.476619) (xy 18.723351 -193.47465) (xy 18.670333 -193.464857)
			(xy 18.619306 -193.447449) (xy 18.571358 -193.422797) (xy 18.52751 -193.391427) (xy 18.488697 -193.354006)
			(xy 18.455745 -193.311333) (xy 18.429359 -193.264316) (xy 18.410099 -193.213959) (xy 18.398376 -193.161335)
			(xy 18.394441 -193.107564) (xy 17.341584 -193.107564) (xy 17.341353 -193.126956) (xy 17.333417 -193.210066)
			(xy 17.317617 -193.292044) (xy 17.294096 -193.37215) (xy 17.263067 -193.449658) (xy 17.22481 -193.523865)
			(xy 17.179674 -193.594099) (xy 17.128065 -193.659725) (xy 17.070452 -193.720147) (xy 17.007356 -193.77482)
			(xy 16.939349 -193.823248) (xy 16.867046 -193.864992) (xy 16.791103 -193.899674) (xy 16.712207 -193.92698)
			(xy 16.631073 -193.946663) (xy 16.548435 -193.958544) (xy 16.465042 -193.962517) (xy 16.381649 -193.958544)
			(xy 16.299011 -193.946663) (xy 16.217877 -193.92698) (xy 16.138981 -193.899674) (xy 16.063038 -193.864992)
			(xy 15.990735 -193.823248) (xy 15.922728 -193.77482) (xy 15.859632 -193.720147) (xy 15.802019 -193.659725)
			(xy 15.75041 -193.594099) (xy 15.705274 -193.523865) (xy 15.667017 -193.449658) (xy 15.635988 -193.37215)
			(xy 15.612467 -193.292044) (xy 15.596667 -193.210066) (xy 15.588731 -193.126956) (xy 15.588234 -193.085212)
			(xy 13.566648 -193.085212) (xy 13.566648 -194.641681) (xy 13.827754 -194.641681) (xy 13.827754 -194.577759)
			(xy 13.835765 -194.514341) (xy 13.851662 -194.452427) (xy 13.875194 -194.392994) (xy 13.905988 -194.336979)
			(xy 13.943561 -194.285264) (xy 13.987318 -194.238667) (xy 14.036571 -194.197922) (xy 14.090542 -194.163671)
			(xy 14.148381 -194.136454) (xy 14.209174 -194.116701) (xy 14.271964 -194.104723) (xy 14.33576 -194.10071)
			(xy 14.399556 -194.104723) (xy 14.462346 -194.116701) (xy 14.523139 -194.136454) (xy 14.580978 -194.163671)
			(xy 14.634949 -194.197922) (xy 14.684202 -194.238667) (xy 14.727959 -194.285264) (xy 14.765532 -194.336979)
			(xy 14.796326 -194.392994) (xy 14.819858 -194.452427) (xy 14.835755 -194.514341) (xy 14.843766 -194.577759)
			(xy 14.844268 -194.60972) (xy 14.843766 -194.641681) (xy 14.835755 -194.705099) (xy 14.819858 -194.767013)
			(xy 14.796326 -194.826446) (xy 14.765532 -194.882461) (xy 14.727959 -194.934176) (xy 14.684202 -194.980773)
			(xy 14.634949 -195.021518) (xy 14.580978 -195.055769) (xy 14.523139 -195.082986) (xy 14.462346 -195.102739)
			(xy 14.399556 -195.114717) (xy 14.33576 -195.118731) (xy 14.271964 -195.114717) (xy 14.209174 -195.102739)
			(xy 14.148381 -195.082986) (xy 14.090542 -195.055769) (xy 14.036571 -195.021518) (xy 13.987318 -194.980773)
			(xy 13.943561 -194.934176) (xy 13.905988 -194.882461) (xy 13.875194 -194.826446) (xy 13.851662 -194.767013)
			(xy 13.835765 -194.705099) (xy 13.827754 -194.641681) (xy 13.566648 -194.641681) (xy 13.566648 -195.233501)
			(xy 15.143474 -195.233501) (xy 15.143474 -195.169579) (xy 15.151485 -195.106161) (xy 15.167382 -195.044247)
			(xy 15.190914 -194.984814) (xy 15.221708 -194.928799) (xy 15.259281 -194.877084) (xy 15.303038 -194.830487)
			(xy 15.352291 -194.789742) (xy 15.406262 -194.755491) (xy 15.464101 -194.728274) (xy 15.524894 -194.708521)
			(xy 15.587684 -194.696543) (xy 15.65148 -194.69253) (xy 15.715276 -194.696543) (xy 15.778066 -194.708521)
			(xy 15.838859 -194.728274) (xy 15.896698 -194.755491) (xy 15.950669 -194.789742) (xy 15.999922 -194.830487)
			(xy 16.043679 -194.877084) (xy 16.081252 -194.928799) (xy 16.112046 -194.984814) (xy 16.135578 -195.044247)
			(xy 16.151475 -195.106161) (xy 16.159486 -195.169579) (xy 16.159988 -195.20154) (xy 16.159486 -195.233501)
			(xy 16.157235 -195.251324) (xy 18.283174 -195.251324) (xy 18.28376 -195.218412) (xy 18.292498 -195.153172)
			(xy 18.309798 -195.089662) (xy 18.335354 -195.029002) (xy 18.368717 -194.972261) (xy 18.388584 -194.946016)
			(xy 18.395027 -194.936878) (xy 18.400061 -194.91512) (xy 18.395384 -194.893283) (xy 18.389092 -194.88404)
			(xy 18.370343 -194.858245) (xy 18.338947 -194.802738) (xy 18.314935 -194.74366) (xy 18.298705 -194.68199)
			(xy 18.290524 -194.618745) (xy 18.290032 -194.58686) (xy 18.290521 -194.555697) (xy 18.298333 -194.493863)
			(xy 18.313833 -194.433495) (xy 18.336776 -194.375547) (xy 18.366802 -194.32093) (xy 18.403436 -194.270508)
			(xy 18.446101 -194.225074) (xy 18.494123 -194.185346) (xy 18.546747 -194.151951) (xy 18.603141 -194.125414)
			(xy 18.662416 -194.106154) (xy 18.723637 -194.094475) (xy 18.78584 -194.090562) (xy 18.848043 -194.094475)
			(xy 18.909264 -194.106154) (xy 18.968539 -194.125414) (xy 19.024933 -194.151951) (xy 19.077557 -194.185346)
			(xy 19.125579 -194.225074) (xy 19.168244 -194.270508) (xy 19.204878 -194.32093) (xy 19.234904 -194.375547)
			(xy 19.257847 -194.433495) (xy 19.273347 -194.493863) (xy 19.281159 -194.555697) (xy 19.281648 -194.58686)
			(xy 19.281104 -194.619773) (xy 19.272355 -194.685015) (xy 19.255045 -194.748525) (xy 19.22948 -194.809184)
			(xy 19.196109 -194.865925) (xy 19.176238 -194.892168) (xy 19.169807 -194.901314) (xy 19.164767 -194.923067)
			(xy 19.169439 -194.944902) (xy 19.17573 -194.954144) (xy 19.194475 -194.979942) (xy 19.225871 -195.035448)
			(xy 19.249883 -195.094525) (xy 19.266115 -195.156195) (xy 19.274297 -195.219439) (xy 19.27479 -195.251324)
			(xy 19.274301 -195.282487) (xy 19.266489 -195.344321) (xy 19.250989 -195.404689) (xy 19.228046 -195.462637)
			(xy 19.19802 -195.517254) (xy 19.161386 -195.567676) (xy 19.118721 -195.61311) (xy 19.070699 -195.652838)
			(xy 19.018075 -195.686233) (xy 18.961681 -195.71277) (xy 18.902406 -195.73203) (xy 18.841185 -195.743709)
			(xy 18.778982 -195.747622) (xy 18.716779 -195.743709) (xy 18.655558 -195.73203) (xy 18.596283 -195.71277)
			(xy 18.539889 -195.686233) (xy 18.487265 -195.652838) (xy 18.439243 -195.61311) (xy 18.396578 -195.567676)
			(xy 18.359944 -195.517254) (xy 18.329918 -195.462637) (xy 18.306975 -195.404689) (xy 18.291475 -195.344321)
			(xy 18.283663 -195.282487) (xy 18.283174 -195.251324) (xy 16.157235 -195.251324) (xy 16.151475 -195.296919)
			(xy 16.135578 -195.358833) (xy 16.112046 -195.418266) (xy 16.081252 -195.474281) (xy 16.043679 -195.525996)
			(xy 15.999922 -195.572593) (xy 15.950669 -195.613338) (xy 15.896698 -195.647589) (xy 15.838859 -195.674806)
			(xy 15.778066 -195.694559) (xy 15.715276 -195.706537) (xy 15.65148 -195.710551) (xy 15.587684 -195.706537)
			(xy 15.524894 -195.694559) (xy 15.464101 -195.674806) (xy 15.406262 -195.647589) (xy 15.352291 -195.613338)
			(xy 15.303038 -195.572593) (xy 15.259281 -195.525996) (xy 15.221708 -195.474281) (xy 15.190914 -195.418266)
			(xy 15.167382 -195.358833) (xy 15.151485 -195.296919) (xy 15.143474 -195.233501) (xy 13.566648 -195.233501)
			(xy 13.566648 -195.926964) (xy 20.010628 -195.926964) (xy 20.011089 -195.89501) (xy 20.019112 -195.831607)
			(xy 20.035015 -195.769709) (xy 20.058548 -195.710291) (xy 20.089338 -195.654289) (xy 20.126902 -195.602586)
			(xy 20.170648 -195.555996) (xy 20.219885 -195.515253) (xy 20.246594 -195.497704) (xy 20.256702 -195.490487)
			(xy 20.26897 -195.468933) (xy 20.269962 -195.456556) (xy 20.273264 -195.360036) (xy 20.262342 -195.33743)
			(xy 20.252182 -195.330064) (xy 20.224939 -195.309494) (xy 20.175739 -195.262171) (xy 20.13331 -195.208692)
			(xy 20.098414 -195.15002) (xy 20.071678 -195.087208) (xy 20.053582 -195.021385) (xy 20.044453 -194.953733)
			(xy 20.043902 -194.9196) (xy 20.044409 -194.888557) (xy 20.051946 -194.82693) (xy 20.066933 -194.76668)
			(xy 20.089146 -194.708704) (xy 20.118255 -194.653864) (xy 20.153826 -194.602978) (xy 20.195329 -194.556803)
			(xy 20.242148 -194.516027) (xy 20.293584 -194.481256) (xy 20.321016 -194.466718) (xy 20.328602 -194.462442)
			(xy 20.340613 -194.449856) (xy 20.347688 -194.433963) (xy 20.348702 -194.425316) (xy 20.355306 -194.33921)
			(xy 20.355663 -194.330578) (xy 20.351225 -194.313893) (xy 20.341491 -194.299633) (xy 20.334732 -194.294252)
			(xy 20.311738 -194.276758) (xy 20.270984 -194.235807) (xy 20.237116 -194.189) (xy 20.210964 -194.137484)
			(xy 20.193167 -194.082519) (xy 20.184161 -194.025451) (xy 20.183602 -193.996564) (xy 20.184118 -193.968964)
			(xy 20.192345 -193.914381) (xy 20.208615 -193.861634) (xy 20.232565 -193.811902) (xy 20.26366 -193.766294)
			(xy 20.301205 -193.72583) (xy 20.344362 -193.691413) (xy 20.392166 -193.663814) (xy 20.44355 -193.643647)
			(xy 20.497365 -193.631364) (xy 20.55241 -193.627239) (xy 20.607455 -193.631364) (xy 20.66127 -193.643647)
			(xy 20.712654 -193.663814) (xy 20.760458 -193.691413) (xy 20.803615 -193.72583) (xy 20.84116 -193.766294)
			(xy 20.872255 -193.811902) (xy 20.896205 -193.861634) (xy 20.912475 -193.914381) (xy 20.920702 -193.968964)
			(xy 20.921218 -193.996564) (xy 20.920636 -194.025449) (xy 20.911621 -194.082511) (xy 20.893821 -194.13747)
			(xy 20.867672 -194.188983) (xy 20.833813 -194.23579) (xy 20.793071 -194.276747) (xy 20.770088 -194.294252)
			(xy 20.763311 -194.299613) (xy 20.753577 -194.313879) (xy 20.749157 -194.330575) (xy 20.749514 -194.33921)
			(xy 20.756118 -194.425316) (xy 20.757103 -194.43397) (xy 20.764188 -194.449871) (xy 20.776195 -194.462477)
			(xy 20.783804 -194.466718) (xy 20.811214 -194.481296) (xy 20.862639 -194.516074) (xy 20.909451 -194.556853)
			(xy 20.950952 -194.603025) (xy 20.986525 -194.653904) (xy 21.015643 -194.708734) (xy 21.037872 -194.7667)
			(xy 21.052881 -194.82694) (xy 21.060448 -194.888559) (xy 21.060918 -194.9196) (xy 21.060408 -194.951552)
			(xy 21.05239 -195.014952) (xy 21.036493 -195.076848) (xy 21.012967 -195.136265) (xy 20.982183 -195.192267)
			(xy 20.944626 -195.243971) (xy 20.900888 -195.290563) (xy 20.851657 -195.331309) (xy 20.824952 -195.34886)
			(xy 20.814806 -195.356032) (xy 20.80256 -195.37762) (xy 20.801584 -195.390008) (xy 20.798282 -195.486528)
			(xy 20.809204 -195.509134) (xy 20.819364 -195.5165) (xy 20.846578 -195.537107) (xy 20.895782 -195.584422)
			(xy 20.936214 -195.635372) (xy 22.368002 -195.635372) (xy 22.368538 -195.602652) (xy 22.377134 -195.53778)
			(xy 22.394187 -195.474601) (xy 22.4194 -195.414214) (xy 22.452335 -195.357666) (xy 22.492421 -195.305941)
			(xy 22.515322 -195.282566) (xy 22.522248 -195.275125) (xy 22.530112 -195.256399) (xy 22.530562 -195.246244)
			(xy 22.530562 -195.174362) (xy 22.530099 -195.164205) (xy 22.52226 -195.145469) (xy 22.515322 -195.13804)
			(xy 22.492423 -195.114663) (xy 22.452342 -195.062935) (xy 22.419408 -195.006387) (xy 22.394193 -194.946001)
			(xy 22.377134 -194.882824) (xy 22.368527 -194.817954) (xy 22.368002 -194.785234) (xy 22.368491 -194.754071)
			(xy 22.376303 -194.692237) (xy 22.391803 -194.631869) (xy 22.414746 -194.573921) (xy 22.444772 -194.519304)
			(xy 22.481406 -194.468882) (xy 22.524071 -194.423448) (xy 22.572093 -194.38372) (xy 22.624717 -194.350325)
			(xy 22.681111 -194.323788) (xy 22.740386 -194.304528) (xy 22.801607 -194.292849) (xy 22.86381 -194.288936)
			(xy 22.926013 -194.292849) (xy 22.987234 -194.304528) (xy 23.046509 -194.323788) (xy 23.102903 -194.350325)
			(xy 23.155527 -194.38372) (xy 23.203549 -194.423448) (xy 23.246214 -194.468882) (xy 23.282848 -194.519304)
			(xy 23.312874 -194.573921) (xy 23.335817 -194.631869) (xy 23.351317 -194.692237) (xy 23.359129 -194.754071)
			(xy 23.359618 -194.785234) (xy 23.35908 -194.817954) (xy 23.350483 -194.882826) (xy 23.333431 -194.946004)
			(xy 23.308218 -195.006392) (xy 23.275283 -195.062939) (xy 23.235199 -195.114665) (xy 23.212298 -195.13804)
			(xy 23.205359 -195.14547) (xy 23.197505 -195.164205) (xy 23.197058 -195.174362) (xy 23.197058 -195.246244)
			(xy 23.197512 -195.256402) (xy 23.205357 -195.275138) (xy 23.212298 -195.282566) (xy 23.235185 -195.305955)
			(xy 23.27527 -195.357678) (xy 23.308208 -195.414223) (xy 23.333425 -195.474607) (xy 23.350486 -195.537783)
			(xy 23.359092 -195.602653) (xy 23.359618 -195.635372) (xy 23.359129 -195.666535) (xy 23.351317 -195.728369)
			(xy 23.335817 -195.788737) (xy 23.312874 -195.846685) (xy 23.282848 -195.901302) (xy 23.264203 -195.926964)
			(xy 27.554682 -195.926964) (xy 27.555164 -195.895011) (xy 27.563186 -195.83161) (xy 27.579088 -195.769713)
			(xy 27.602618 -195.710296) (xy 27.633406 -195.654294) (xy 27.670966 -195.602591) (xy 27.714708 -195.555999)
			(xy 27.763942 -195.515255) (xy 27.790648 -195.497704) (xy 27.800766 -195.4905) (xy 27.813027 -195.468936)
			(xy 27.814016 -195.456556) (xy 27.817318 -195.360036) (xy 27.806396 -195.33743) (xy 27.796236 -195.330064)
			(xy 27.769005 -195.309479) (xy 27.719802 -195.26216) (xy 27.67737 -195.208685) (xy 27.642472 -195.150015)
			(xy 27.615734 -195.087205) (xy 27.597637 -195.021383) (xy 27.588507 -194.953732) (xy 27.587956 -194.9196)
			(xy 27.588434 -194.888556) (xy 27.595972 -194.826927) (xy 27.61096 -194.766674) (xy 27.633176 -194.708697)
			(xy 27.662288 -194.653856) (xy 27.697863 -194.60297) (xy 27.739371 -194.556796) (xy 27.786194 -194.516022)
			(xy 27.837635 -194.481254) (xy 27.86507 -194.466718) (xy 27.872668 -194.462461) (xy 27.884673 -194.449865)
			(xy 27.891744 -194.433965) (xy 27.892756 -194.425316) (xy 27.89936 -194.33921) (xy 27.899736 -194.330578)
			(xy 27.895293 -194.313889) (xy 27.88555 -194.29963) (xy 27.878786 -194.294252) (xy 27.855782 -194.276771)
			(xy 27.815031 -194.235816) (xy 27.781166 -194.189006) (xy 27.755015 -194.137487) (xy 27.73722 -194.082521)
			(xy 27.728215 -194.025452) (xy 27.727656 -193.996564) (xy 27.728172 -193.968964) (xy 27.736399 -193.914381)
			(xy 27.752669 -193.861634) (xy 27.776619 -193.811902) (xy 27.807714 -193.766294) (xy 27.845259 -193.72583)
			(xy 27.888416 -193.691413) (xy 27.93622 -193.663814) (xy 27.987604 -193.643647) (xy 28.041419 -193.631364)
			(xy 28.096464 -193.627239) (xy 28.151509 -193.631364) (xy 28.205324 -193.643647) (xy 28.256708 -193.663814)
			(xy 28.304512 -193.691413) (xy 28.347669 -193.72583) (xy 28.385214 -193.766294) (xy 28.416309 -193.811902)
			(xy 28.440259 -193.861634) (xy 28.456529 -193.914381) (xy 28.464756 -193.968964) (xy 28.465272 -193.996564)
			(xy 28.464708 -194.02545) (xy 28.455692 -194.082514) (xy 28.43789 -194.137474) (xy 28.411737 -194.188987)
			(xy 28.377874 -194.235794) (xy 28.337128 -194.276749) (xy 28.314142 -194.294252) (xy 28.307356 -194.299603)
			(xy 28.297628 -194.313875) (xy 28.293211 -194.330574) (xy 28.293568 -194.33921) (xy 28.300172 -194.425316)
			(xy 28.30118 -194.433966) (xy 28.308258 -194.449864) (xy 28.320254 -194.462473) (xy 28.327858 -194.466718)
			(xy 28.35528 -194.481272) (xy 28.406704 -194.516056) (xy 28.453513 -194.556839) (xy 28.495012 -194.603014)
			(xy 28.530584 -194.653896) (xy 28.5597 -194.708728) (xy 28.581927 -194.766696) (xy 28.596936 -194.826938)
			(xy 28.601016 -194.860164) (xy 29.886656 -194.860164) (xy 29.887145 -194.829001) (xy 29.894957 -194.767167)
			(xy 29.910457 -194.706799) (xy 29.9334 -194.648851) (xy 29.963426 -194.594234) (xy 30.00006 -194.543812)
			(xy 30.042725 -194.498378) (xy 30.090747 -194.45865) (xy 30.143371 -194.425255) (xy 30.199765 -194.398718)
			(xy 30.25904 -194.379458) (xy 30.320261 -194.367779) (xy 30.382464 -194.363866) (xy 30.444667 -194.367779)
			(xy 30.505888 -194.379458) (xy 30.565163 -194.398718) (xy 30.621557 -194.425255) (xy 30.674181 -194.45865)
			(xy 30.722203 -194.498378) (xy 30.764868 -194.543812) (xy 30.801502 -194.594234) (xy 30.831528 -194.648851)
			(xy 30.854471 -194.706799) (xy 30.869971 -194.767167) (xy 30.877783 -194.829001) (xy 30.878272 -194.860164)
			(xy 30.877828 -194.889778) (xy 30.870776 -194.948584) (xy 30.856767 -195.006131) (xy 30.836001 -195.061598)
			(xy 30.808775 -195.114197) (xy 30.775476 -195.163177) (xy 30.756352 -195.185792) (xy 30.750365 -195.193257)
			(xy 30.743968 -195.211275) (xy 30.743906 -195.220844) (xy 30.744922 -195.251832) (xy 30.74562 -195.261345)
			(xy 30.75321 -195.278833) (xy 30.759654 -195.285868) (xy 30.78206 -195.309179) (xy 30.821263 -195.360598)
			(xy 30.853453 -195.416674) (xy 30.878087 -195.476457) (xy 30.894747 -195.538932) (xy 30.903149 -195.603043)
			(xy 30.903672 -195.635372) (xy 30.903183 -195.666535) (xy 30.895371 -195.728369) (xy 30.879871 -195.788737)
			(xy 30.856928 -195.846685) (xy 30.835974 -195.8848) (xy 35.13201 -195.8848) (xy 35.132509 -195.85164)
			(xy 35.141127 -195.785881) (xy 35.158218 -195.721801) (xy 35.183491 -195.660484) (xy 35.216518 -195.602972)
			(xy 35.256738 -195.550239) (xy 35.30347 -195.50318) (xy 35.329368 -195.482464) (xy 35.338271 -195.474907)
			(xy 35.348602 -195.453995) (xy 35.34918 -195.442332) (xy 35.34918 -195.362068) (xy 35.348564 -195.350416)
			(xy 35.338238 -195.329518) (xy 35.329368 -195.321936) (xy 35.303472 -195.301219) (xy 35.256749 -195.254156)
			(xy 35.216536 -195.201421) (xy 35.183516 -195.143908) (xy 35.158248 -195.082593) (xy 35.141161 -195.018514)
			(xy 35.132545 -194.952759) (xy 35.13201 -194.9196) (xy 35.132435 -194.888568) (xy 35.140003 -194.826966)
			(xy 35.155016 -194.766744) (xy 35.177248 -194.708798) (xy 35.206371 -194.65399) (xy 35.241949 -194.603136)
			(xy 35.283455 -194.556991) (xy 35.33027 -194.516243) (xy 35.381697 -194.481498) (xy 35.409124 -194.466972)
			(xy 35.416661 -194.462749) (xy 35.428506 -194.450183) (xy 35.435522 -194.434403) (xy 35.436556 -194.425824)
			(xy 35.443414 -194.339464) (xy 35.443788 -194.330766) (xy 35.439307 -194.313955) (xy 35.429434 -194.299628)
			(xy 35.422586 -194.294252) (xy 35.399582 -194.276771) (xy 35.358831 -194.235816) (xy 35.324966 -194.189006)
			(xy 35.298815 -194.137487) (xy 35.28102 -194.082521) (xy 35.272015 -194.025452) (xy 35.271456 -193.996564)
			(xy 35.271972 -193.968964) (xy 35.280199 -193.914381) (xy 35.296469 -193.861634) (xy 35.320419 -193.811902)
			(xy 35.351514 -193.766294) (xy 35.389059 -193.72583) (xy 35.432216 -193.691413) (xy 35.48002 -193.663814)
			(xy 35.531404 -193.643647) (xy 35.585219 -193.631364) (xy 35.640264 -193.627239) (xy 35.695309 -193.631364)
			(xy 35.749124 -193.643647) (xy 35.800508 -193.663814) (xy 35.848312 -193.691413) (xy 35.891469 -193.72583)
			(xy 35.929014 -193.766294) (xy 35.960109 -193.811902) (xy 35.984059 -193.861634) (xy 36.000329 -193.914381)
			(xy 36.008556 -193.968964) (xy 36.009072 -193.996564) (xy 36.008508 -194.02545) (xy 35.999492 -194.082514)
			(xy 35.98169 -194.137474) (xy 35.955537 -194.188987) (xy 35.921674 -194.235794) (xy 35.880928 -194.276749)
			(xy 35.857942 -194.294252) (xy 35.851156 -194.299603) (xy 35.841428 -194.313875) (xy 35.837011 -194.330574)
			(xy 35.837368 -194.33921) (xy 35.845242 -194.438778) (xy 35.85972 -194.460622) (xy 35.871658 -194.466718)
			(xy 35.899087 -194.481282) (xy 35.950563 -194.516027) (xy 35.997422 -194.556783) (xy 36.038967 -194.602946)
			(xy 36.074578 -194.653825) (xy 36.103726 -194.708664) (xy 36.125975 -194.766646) (xy 36.140994 -194.826907)
			(xy 36.148561 -194.888548) (xy 36.149026 -194.9196) (xy 36.148513 -194.95276) (xy 36.139895 -195.018517)
			(xy 36.122806 -195.082597) (xy 36.097535 -195.143912) (xy 36.064511 -195.201425) (xy 36.024293 -195.254158)
			(xy 35.977565 -195.301219) (xy 35.951668 -195.321936) (xy 35.942771 -195.329499) (xy 35.932435 -195.350406)
			(xy 35.931856 -195.362068) (xy 35.931856 -195.442332) (xy 35.932459 -195.453986) (xy 35.942793 -195.474885)
			(xy 35.951668 -195.482464) (xy 35.977572 -195.503172) (xy 36.024293 -195.550237) (xy 36.064504 -195.602974)
			(xy 36.083103 -195.635372) (xy 37.455856 -195.635372) (xy 37.456376 -195.602651) (xy 37.464973 -195.537778)
			(xy 37.482028 -195.474598) (xy 37.507244 -195.41421) (xy 37.540183 -195.357663) (xy 37.580273 -195.30594)
			(xy 37.603176 -195.282566) (xy 37.610109 -195.275131) (xy 37.617968 -195.2564) (xy 37.618416 -195.246244)
			(xy 37.618416 -195.174362) (xy 37.617965 -195.164204) (xy 37.610119 -195.145467) (xy 37.603176 -195.13804)
			(xy 37.580287 -195.114653) (xy 37.540203 -195.062928) (xy 37.507266 -195.006383) (xy 37.482049 -194.945999)
			(xy 37.464989 -194.882823) (xy 37.456382 -194.817953) (xy 37.455856 -194.785234) (xy 37.456345 -194.754071)
			(xy 37.464157 -194.692237) (xy 37.479657 -194.631869) (xy 37.5026 -194.573921) (xy 37.532626 -194.519304)
			(xy 37.56926 -194.468882) (xy 37.611925 -194.423448) (xy 37.659947 -194.38372) (xy 37.712571 -194.350325)
			(xy 37.768965 -194.323788) (xy 37.82824 -194.304528) (xy 37.889461 -194.292849) (xy 37.951664 -194.288936)
			(xy 38.013867 -194.292849) (xy 38.075088 -194.304528) (xy 38.134363 -194.323788) (xy 38.190757 -194.350325)
			(xy 38.243381 -194.38372) (xy 38.291403 -194.423448) (xy 38.334068 -194.468882) (xy 38.370702 -194.519304)
			(xy 38.400728 -194.573921) (xy 38.423671 -194.631869) (xy 38.439171 -194.692237) (xy 38.446983 -194.754071)
			(xy 38.447472 -194.785234) (xy 38.446948 -194.817954) (xy 38.43835 -194.882828) (xy 38.421296 -194.946007)
			(xy 38.396081 -195.006394) (xy 38.363143 -195.062941) (xy 38.323055 -195.114666) (xy 38.300152 -195.13804)
			(xy 38.29322 -195.145476) (xy 38.28536 -195.164206) (xy 38.284912 -195.174362) (xy 38.284912 -195.246244)
			(xy 38.285352 -195.256404) (xy 38.293205 -195.275141) (xy 38.300152 -195.282566) (xy 38.323049 -195.305945)
			(xy 38.363131 -195.357672) (xy 38.396066 -195.414219) (xy 38.421282 -195.474605) (xy 38.43834 -195.537782)
			(xy 38.446946 -195.602652) (xy 38.447472 -195.635372) (xy 38.446983 -195.666535) (xy 38.439171 -195.728369)
			(xy 38.423671 -195.788737) (xy 38.400728 -195.846685) (xy 38.370702 -195.901302) (xy 38.370512 -195.901564)
			(xy 42.66819 -195.901564) (xy 42.668632 -195.870792) (xy 42.676054 -195.809696) (xy 42.690796 -195.749944)
			(xy 42.712644 -195.692408) (xy 42.741278 -195.63793) (xy 42.776279 -195.587307) (xy 42.817134 -195.541279)
			(xy 42.839894 -195.520564) (xy 42.847713 -195.513042) (xy 42.856664 -195.493302) (xy 42.857166 -195.482464)
			(xy 42.857166 -195.406264) (xy 42.856609 -195.395436) (xy 42.847683 -195.375703) (xy 42.839894 -195.368164)
			(xy 42.817158 -195.347424) (xy 42.776308 -195.301396) (xy 42.741311 -195.250776) (xy 42.712677 -195.196302)
			(xy 42.690825 -195.138772) (xy 42.676075 -195.079025) (xy 42.668642 -195.017934) (xy 42.66819 -194.987164)
			(xy 42.668692 -194.955203) (xy 42.676703 -194.891785) (xy 42.6926 -194.829871) (xy 42.716132 -194.770438)
			(xy 42.746926 -194.714423) (xy 42.784499 -194.662708) (xy 42.828256 -194.616111) (xy 42.877509 -194.575366)
			(xy 42.93148 -194.541115) (xy 42.989319 -194.513898) (xy 43.050112 -194.494145) (xy 43.112902 -194.482167)
			(xy 43.176698 -194.478154) (xy 43.240494 -194.482167) (xy 43.303284 -194.494145) (xy 43.364077 -194.513898)
			(xy 43.421916 -194.541115) (xy 43.475887 -194.575366) (xy 43.52514 -194.616111) (xy 43.568897 -194.662708)
			(xy 43.60647 -194.714423) (xy 43.637264 -194.770438) (xy 43.660796 -194.829871) (xy 43.676693 -194.891785)
			(xy 43.684704 -194.955203) (xy 43.685206 -194.987164) (xy 43.684785 -195.017937) (xy 43.67736 -195.079033)
			(xy 43.662614 -195.138786) (xy 43.640762 -195.196322) (xy 43.612125 -195.2508) (xy 43.577122 -195.301422)
			(xy 43.536263 -195.347449) (xy 43.513502 -195.368164) (xy 43.50567 -195.375674) (xy 43.496726 -195.395423)
			(xy 43.49623 -195.406264) (xy 43.49623 -195.482464) (xy 43.496772 -195.493293) (xy 43.505709 -195.513026)
			(xy 43.513502 -195.520564) (xy 43.53625 -195.54129) (xy 43.5771 -195.58732) (xy 43.610319 -195.635372)
			(xy 44.99991 -195.635372) (xy 45.000444 -195.602652) (xy 45.00904 -195.537779) (xy 45.026093 -195.474601)
			(xy 45.051306 -195.414213) (xy 45.084242 -195.357666) (xy 45.124328 -195.305941) (xy 45.14723 -195.282566)
			(xy 45.154157 -195.275126) (xy 45.16202 -195.256399) (xy 45.16247 -195.246244) (xy 45.16247 -195.174362)
			(xy 45.162005 -195.164206) (xy 45.154167 -195.14547) (xy 45.14723 -195.13804) (xy 45.124332 -195.114662)
			(xy 45.084251 -195.062934) (xy 45.051316 -195.006387) (xy 45.026101 -194.946001) (xy 45.009042 -194.882824)
			(xy 45.000435 -194.817954) (xy 44.99991 -194.785234) (xy 45.000399 -194.754071) (xy 45.008211 -194.692237)
			(xy 45.023711 -194.631869) (xy 45.046654 -194.573921) (xy 45.07668 -194.519304) (xy 45.113314 -194.468882)
			(xy 45.155979 -194.423448) (xy 45.204001 -194.38372) (xy 45.256625 -194.350325) (xy 45.313019 -194.323788)
			(xy 45.372294 -194.304528) (xy 45.433515 -194.292849) (xy 45.495718 -194.288936) (xy 45.557921 -194.292849)
			(xy 45.619142 -194.304528) (xy 45.678417 -194.323788) (xy 45.734811 -194.350325) (xy 45.787435 -194.38372)
			(xy 45.835457 -194.423448) (xy 45.878122 -194.468882) (xy 45.914756 -194.519304) (xy 45.944782 -194.573921)
			(xy 45.967725 -194.631869) (xy 45.983225 -194.692237) (xy 45.991037 -194.754071) (xy 45.991526 -194.785234)
			(xy 45.990986 -194.817954) (xy 45.982389 -194.882826) (xy 45.965337 -194.946004) (xy 45.940124 -195.006391)
			(xy 45.90719 -195.062939) (xy 45.867106 -195.114664) (xy 45.844206 -195.13804) (xy 45.837268 -195.14547)
			(xy 45.829413 -195.164205) (xy 45.828966 -195.174362) (xy 45.828966 -195.246244) (xy 45.829418 -195.256402)
			(xy 45.837264 -195.275139) (xy 45.844206 -195.282566) (xy 45.867094 -195.305953) (xy 45.907179 -195.357677)
			(xy 45.924376 -195.3872) (xy 49.694403 -195.3872) (xy 49.698417 -195.323409) (xy 49.710393 -195.260625)
			(xy 49.730143 -195.199836) (xy 49.757356 -195.142002) (xy 49.791602 -195.088034) (xy 49.832342 -195.038784)
			(xy 49.878934 -194.995028) (xy 49.930641 -194.957456) (xy 49.98665 -194.92666) (xy 50.046076 -194.903127)
			(xy 50.107984 -194.887227) (xy 50.171396 -194.879211) (xy 50.203354 -194.878706) (xy 50.221388 -194.87896)
			(xy 50.224513 -194.846724) (xy 50.237852 -194.783346) (xy 50.259127 -194.722174) (xy 50.287994 -194.664196)
			(xy 50.323986 -194.610352) (xy 50.366521 -194.561511) (xy 50.414911 -194.518464) (xy 50.468374 -194.481907)
			(xy 50.496978 -194.466718) (xy 50.504578 -194.462464) (xy 50.516582 -194.449866) (xy 50.523652 -194.433965)
			(xy 50.524664 -194.425316) (xy 50.531268 -194.33921) (xy 50.53164 -194.330578) (xy 50.527199 -194.31389)
			(xy 50.517457 -194.299631) (xy 50.510694 -194.294252) (xy 50.487692 -194.276769) (xy 50.44694 -194.235814)
			(xy 50.413074 -194.189005) (xy 50.386924 -194.137487) (xy 50.369128 -194.082521) (xy 50.360123 -194.025452)
			(xy 50.359564 -193.996564) (xy 50.36008 -193.968964) (xy 50.368307 -193.914381) (xy 50.384577 -193.861634)
			(xy 50.408527 -193.811902) (xy 50.439622 -193.766294) (xy 50.477167 -193.72583) (xy 50.520324 -193.691413)
			(xy 50.568128 -193.663814) (xy 50.619512 -193.643647) (xy 50.673327 -193.631364) (xy 50.728372 -193.627239)
			(xy 50.783417 -193.631364) (xy 50.837232 -193.643647) (xy 50.888616 -193.663814) (xy 50.93642 -193.691413)
			(xy 50.979577 -193.72583) (xy 51.017122 -193.766294) (xy 51.048217 -193.811902) (xy 51.072167 -193.861634)
			(xy 51.088437 -193.914381) (xy 51.096664 -193.968964) (xy 51.09718 -193.996564) (xy 51.096613 -194.02545)
			(xy 51.087597 -194.082513) (xy 51.069795 -194.137473) (xy 51.043643 -194.188987) (xy 51.009781 -194.235793)
			(xy 50.969035 -194.276748) (xy 50.94605 -194.294252) (xy 50.939265 -194.299604) (xy 50.929536 -194.313876)
			(xy 50.925119 -194.330574) (xy 50.925476 -194.33921) (xy 50.93208 -194.425316) (xy 50.933084 -194.433966)
			(xy 50.940163 -194.449866) (xy 50.952161 -194.462474) (xy 50.959766 -194.466718) (xy 50.987167 -194.481312)
			(xy 51.038594 -194.516087) (xy 51.085407 -194.556863) (xy 51.126909 -194.603032) (xy 51.162484 -194.653909)
			(xy 51.191603 -194.708738) (xy 51.213833 -194.766702) (xy 51.228843 -194.826941) (xy 51.23641 -194.88856)
			(xy 51.23688 -194.9196) (xy 51.236462 -194.950333) (xy 51.229053 -195.011351) (xy 51.214343 -195.071032)
			(xy 51.192546 -195.128503) (xy 51.16398 -195.182929) (xy 51.129062 -195.233514) (xy 51.088301 -195.279521)
			(xy 51.042292 -195.320279) (xy 50.991705 -195.355194) (xy 50.937278 -195.383757) (xy 50.879805 -195.405551)
			(xy 50.820124 -195.420258) (xy 50.759105 -195.427664) (xy 50.728372 -195.428108) (xy 50.710338 -195.427854)
			(xy 50.707364 -195.459317) (xy 50.694524 -195.521199) (xy 50.674117 -195.581015) (xy 50.646458 -195.637841)
			(xy 50.611972 -195.690804) (xy 50.571192 -195.739087) (xy 50.524745 -195.781947) (xy 50.473347 -195.818723)
			(xy 50.417788 -195.848849) (xy 50.358926 -195.871861) (xy 50.297667 -195.887405) (xy 50.234954 -195.89524)
			(xy 50.203354 -195.895722) (xy 50.171396 -195.895189) (xy 50.107984 -195.887173) (xy 50.046076 -195.871273)
			(xy 49.98665 -195.84774) (xy 49.930641 -195.816944) (xy 49.878934 -195.779372) (xy 49.832342 -195.735616)
			(xy 49.791602 -195.686366) (xy 49.757356 -195.632398) (xy 49.730143 -195.574564) (xy 49.710393 -195.513775)
			(xy 49.698417 -195.450991) (xy 49.694403 -195.3872) (xy 45.924376 -195.3872) (xy 45.940116 -195.414223)
			(xy 45.965334 -195.474607) (xy 45.982394 -195.537783) (xy 45.991 -195.602653) (xy 45.991526 -195.635372)
			(xy 45.991037 -195.666535) (xy 45.983225 -195.728369) (xy 45.967725 -195.788737) (xy 45.944782 -195.846685)
			(xy 45.914756 -195.901302) (xy 45.878122 -195.951724) (xy 45.835457 -195.997158) (xy 45.787435 -196.036886)
			(xy 45.734811 -196.070281) (xy 45.678417 -196.096818) (xy 45.619142 -196.116078) (xy 45.557921 -196.127757)
			(xy 45.495718 -196.13167) (xy 45.433515 -196.127757) (xy 45.372294 -196.116078) (xy 45.313019 -196.096818)
			(xy 45.256625 -196.070281) (xy 45.204001 -196.036886) (xy 45.155979 -195.997158) (xy 45.113314 -195.951724)
			(xy 45.07668 -195.901302) (xy 45.046654 -195.846685) (xy 45.023711 -195.788737) (xy 45.008211 -195.728369)
			(xy 45.000399 -195.666535) (xy 44.99991 -195.635372) (xy 43.610319 -195.635372) (xy 43.612096 -195.637943)
			(xy 43.640728 -195.692419) (xy 43.662578 -195.749952) (xy 43.677326 -195.809701) (xy 43.684756 -195.870793)
			(xy 43.685206 -195.901564) (xy 43.684704 -195.933525) (xy 43.676693 -195.996943) (xy 43.660796 -196.058857)
			(xy 43.637264 -196.11829) (xy 43.60647 -196.174305) (xy 43.568897 -196.22602) (xy 43.52514 -196.272617)
			(xy 43.475887 -196.313362) (xy 43.421916 -196.347613) (xy 43.364077 -196.37483) (xy 43.303284 -196.394583)
			(xy 43.240494 -196.406561) (xy 43.176698 -196.410575) (xy 43.112902 -196.406561) (xy 43.050112 -196.394583)
			(xy 42.989319 -196.37483) (xy 42.93148 -196.347613) (xy 42.877509 -196.313362) (xy 42.828256 -196.272617)
			(xy 42.784499 -196.22602) (xy 42.746926 -196.174305) (xy 42.716132 -196.11829) (xy 42.6926 -196.058857)
			(xy 42.676703 -195.996943) (xy 42.668692 -195.933525) (xy 42.66819 -195.901564) (xy 38.370512 -195.901564)
			(xy 38.334068 -195.951724) (xy 38.291403 -195.997158) (xy 38.243381 -196.036886) (xy 38.190757 -196.070281)
			(xy 38.134363 -196.096818) (xy 38.075088 -196.116078) (xy 38.013867 -196.127757) (xy 37.951664 -196.13167)
			(xy 37.889461 -196.127757) (xy 37.82824 -196.116078) (xy 37.768965 -196.096818) (xy 37.712571 -196.070281)
			(xy 37.659947 -196.036886) (xy 37.611925 -195.997158) (xy 37.56926 -195.951724) (xy 37.532626 -195.901302)
			(xy 37.5026 -195.846685) (xy 37.479657 -195.788737) (xy 37.464157 -195.728369) (xy 37.456345 -195.666535)
			(xy 37.455856 -195.635372) (xy 36.083103 -195.635372) (xy 36.097523 -195.660489) (xy 36.122789 -195.721805)
			(xy 36.139875 -195.785885) (xy 36.148492 -195.851641) (xy 36.149026 -195.8848) (xy 36.148524 -195.916761)
			(xy 36.140513 -195.980179) (xy 36.124616 -196.042093) (xy 36.101084 -196.101526) (xy 36.07029 -196.157541)
			(xy 36.032717 -196.209256) (xy 35.98896 -196.255853) (xy 35.939707 -196.296598) (xy 35.885736 -196.330849)
			(xy 35.827897 -196.358066) (xy 35.767104 -196.377819) (xy 35.704314 -196.389797) (xy 35.640518 -196.393811)
			(xy 35.576722 -196.389797) (xy 35.513932 -196.377819) (xy 35.453139 -196.358066) (xy 35.3953 -196.330849)
			(xy 35.341329 -196.296598) (xy 35.292076 -196.255853) (xy 35.248319 -196.209256) (xy 35.210746 -196.157541)
			(xy 35.179952 -196.101526) (xy 35.15642 -196.042093) (xy 35.140523 -195.980179) (xy 35.132512 -195.916761)
			(xy 35.13201 -195.8848) (xy 30.835974 -195.8848) (xy 30.826902 -195.901302) (xy 30.790268 -195.951724)
			(xy 30.747603 -195.997158) (xy 30.699581 -196.036886) (xy 30.646957 -196.070281) (xy 30.590563 -196.096818)
			(xy 30.531288 -196.116078) (xy 30.470067 -196.127757) (xy 30.407864 -196.13167) (xy 30.345661 -196.127757)
			(xy 30.28444 -196.116078) (xy 30.225165 -196.096818) (xy 30.168771 -196.070281) (xy 30.116147 -196.036886)
			(xy 30.068125 -195.997158) (xy 30.02546 -195.951724) (xy 29.988826 -195.901302) (xy 29.9588 -195.846685)
			(xy 29.935857 -195.788737) (xy 29.920357 -195.728369) (xy 29.912545 -195.666535) (xy 29.912056 -195.635372)
			(xy 29.912479 -195.605758) (xy 29.919538 -195.546952) (xy 29.933552 -195.489405) (xy 29.954322 -195.433938)
			(xy 29.981551 -195.381339) (xy 30.014852 -195.332359) (xy 30.033976 -195.309744) (xy 30.03995 -195.302271)
			(xy 30.046354 -195.284259) (xy 30.046422 -195.274692) (xy 30.045406 -195.243704) (xy 30.044683 -195.234195)
			(xy 30.03711 -195.216706) (xy 30.030674 -195.209668) (xy 30.00829 -195.186336) (xy 29.969085 -195.134922)
			(xy 29.93689 -195.078851) (xy 29.912252 -195.019072) (xy 29.895588 -194.9566) (xy 29.887181 -194.892492)
			(xy 29.886656 -194.860164) (xy 28.601016 -194.860164) (xy 28.604502 -194.888558) (xy 28.604972 -194.9196)
			(xy 28.604483 -194.951553) (xy 28.596464 -195.014955) (xy 28.580565 -195.076852) (xy 28.557037 -195.13627)
			(xy 28.52625 -195.192272) (xy 28.48869 -195.243976) (xy 28.444948 -195.290567) (xy 28.395713 -195.33131)
			(xy 28.369006 -195.34886) (xy 28.358871 -195.356045) (xy 28.346616 -195.377623) (xy 28.345638 -195.390008)
			(xy 28.342336 -195.486528) (xy 28.353258 -195.509134) (xy 28.363418 -195.5165) (xy 28.390644 -195.537092)
			(xy 28.439845 -195.584411) (xy 28.482275 -195.637886) (xy 28.517174 -195.696554) (xy 28.543912 -195.759363)
			(xy 28.562011 -195.825183) (xy 28.571145 -195.892832) (xy 28.571698 -195.926964) (xy 28.571196 -195.958925)
			(xy 28.563185 -196.022343) (xy 28.547288 -196.084257) (xy 28.523756 -196.14369) (xy 28.492962 -196.199705)
			(xy 28.455389 -196.25142) (xy 28.411632 -196.298017) (xy 28.362379 -196.338762) (xy 28.308408 -196.373013)
			(xy 28.250569 -196.40023) (xy 28.189776 -196.419983) (xy 28.126986 -196.431961) (xy 28.06319 -196.435975)
			(xy 27.999394 -196.431961) (xy 27.936604 -196.419983) (xy 27.875811 -196.40023) (xy 27.817972 -196.373013)
			(xy 27.764001 -196.338762) (xy 27.714748 -196.298017) (xy 27.670991 -196.25142) (xy 27.633418 -196.199705)
			(xy 27.602624 -196.14369) (xy 27.579092 -196.084257) (xy 27.563195 -196.022343) (xy 27.555184 -195.958925)
			(xy 27.554682 -195.926964) (xy 23.264203 -195.926964) (xy 23.246214 -195.951724) (xy 23.203549 -195.997158)
			(xy 23.155527 -196.036886) (xy 23.102903 -196.070281) (xy 23.046509 -196.096818) (xy 22.987234 -196.116078)
			(xy 22.926013 -196.127757) (xy 22.86381 -196.13167) (xy 22.801607 -196.127757) (xy 22.740386 -196.116078)
			(xy 22.681111 -196.096818) (xy 22.624717 -196.070281) (xy 22.572093 -196.036886) (xy 22.524071 -195.997158)
			(xy 22.481406 -195.951724) (xy 22.444772 -195.901302) (xy 22.414746 -195.846685) (xy 22.391803 -195.788737)
			(xy 22.376303 -195.728369) (xy 22.368491 -195.666535) (xy 22.368002 -195.635372) (xy 20.936214 -195.635372)
			(xy 20.938215 -195.637893) (xy 20.973115 -195.696559) (xy 20.999856 -195.759366) (xy 21.017956 -195.825185)
			(xy 21.027091 -195.892833) (xy 21.027644 -195.926964) (xy 21.027142 -195.958925) (xy 21.019131 -196.022343)
			(xy 21.003234 -196.084257) (xy 20.979702 -196.14369) (xy 20.948908 -196.199705) (xy 20.911335 -196.25142)
			(xy 20.867578 -196.298017) (xy 20.818325 -196.338762) (xy 20.764354 -196.373013) (xy 20.706515 -196.40023)
			(xy 20.645722 -196.419983) (xy 20.582932 -196.431961) (xy 20.519136 -196.435975) (xy 20.45534 -196.431961)
			(xy 20.39255 -196.419983) (xy 20.331757 -196.40023) (xy 20.273918 -196.373013) (xy 20.219947 -196.338762)
			(xy 20.170694 -196.298017) (xy 20.126937 -196.25142) (xy 20.089364 -196.199705) (xy 20.05857 -196.14369)
			(xy 20.035038 -196.084257) (xy 20.019141 -196.022343) (xy 20.01113 -195.958925) (xy 20.010628 -195.926964)
			(xy 13.566648 -195.926964) (xy 13.566648 -197.593712) (xy 13.567126 -197.603678) (xy 13.574705 -197.622111)
			(xy 13.58138 -197.629526) (xy 13.795502 -197.843648) (xy 13.801002 -197.848634) (xy 13.814168 -197.855478)
			(xy 13.82141 -197.85711) (xy 13.831062 -197.858126)
		)
		(stroke
			(width 0)
			(type solid)
		)
		(fill yes)
		(layer "In15.Cu")
		(net "P3V3_AUX")
	)
	(gr_poly
		(pts
			(xy 394.943076 -201.749914) (xy 394.95177 -201.749573) (xy 394.968148 -201.74374) (xy 394.97508 -201.738484)
			(xy 394.97889 -201.735182) (xy 411.395672 -185.3184) (xy 411.403074 -185.311565) (xy 411.421673 -185.303856)
			(xy 411.43174 -185.303414) (xy 426.508672 -185.303414) (xy 426.517366 -185.303073) (xy 426.533745 -185.297241)
			(xy 426.540676 -185.291984) (xy 426.544486 -185.288682) (xy 430.544224 -181.288944) (xy 430.546934 -181.286096)
			(xy 430.551535 -181.279721) (xy 430.553368 -181.276244) (xy 430.555951 -181.270817) (xy 430.558774 -181.259138)
			(xy 430.558956 -181.25313) (xy 430.558956 -164.767768) (xy 430.558835 -164.762814) (xy 430.556912 -164.753094)
			(xy 430.555146 -164.748464) (xy 430.550828 -164.73805) (xy 430.550828 -160.13557) (xy 430.550476 -160.126881)
			(xy 430.544622 -160.11052) (xy 430.539398 -160.103566) (xy 430.536096 -160.099756) (xy 429.919892 -159.483552)
			(xy 429.916161 -159.480032) (xy 429.907586 -159.474405) (xy 429.902874 -159.472376) (xy 429.894238 -159.46882)
			(xy 420.601902 -159.46882) (xy 420.591831 -159.468398) (xy 420.573224 -159.460686) (xy 420.565834 -159.453834)
			(xy 419.97884 -158.867094) (xy 419.971438 -158.860258) (xy 419.95284 -158.852546) (xy 419.942772 -158.852108)
			(xy 419.655498 -158.852108) (xy 419.627522 -158.851537) (xy 419.572263 -158.842747) (xy 419.519057 -158.825429)
			(xy 419.469211 -158.80001) (xy 419.42395 -158.767113) (xy 419.403784 -158.747714) (xy 418.267896 -157.611826)
			(xy 418.260498 -157.604977) (xy 418.2419 -157.59724) (xy 418.231828 -157.59684) (xy 411.884622 -157.59684)
			(xy 411.874559 -157.596401) (xy 411.855981 -157.58866) (xy 411.848554 -157.581854) (xy 409.793694 -155.526994)
			(xy 409.786849 -155.519595) (xy 409.779118 -155.500997) (xy 409.778708 -155.490926) (xy 409.778708 -148.22678)
			(xy 409.778282 -148.216711) (xy 409.770563 -148.198111) (xy 409.763722 -148.190712) (xy 403.694392 -142.121382)
			(xy 403.686997 -142.114528) (xy 403.668398 -142.106784) (xy 403.658324 -142.106396) (xy 402.760942 -142.106396)
			(xy 402.751257 -142.106821) (xy 402.733254 -142.113969) (xy 402.719145 -142.127241) (xy 402.714714 -142.13586)
			(xy 402.703153 -142.159693) (xy 402.674294 -142.204112) (xy 402.639436 -142.243996) (xy 402.599281 -142.278543)
			(xy 402.554638 -142.307054) (xy 402.506408 -142.328956) (xy 402.455562 -142.343807) (xy 402.403125 -142.351309)
			(xy 402.350155 -142.351309) (xy 402.297718 -142.343807) (xy 402.246872 -142.328956) (xy 402.198642 -142.307054)
			(xy 402.153999 -142.278543) (xy 402.113844 -142.243996) (xy 402.078986 -142.204112) (xy 402.050127 -142.159693)
			(xy 402.038566 -142.13586) (xy 402.034135 -142.127224) (xy 402.020068 -142.113873) (xy 402.002037 -142.106732)
			(xy 401.992338 -142.106396) (xy 391.47242 -142.106396) (xy 391.462848 -142.106741) (xy 391.445002 -142.113657)
			(xy 391.430943 -142.126642) (xy 391.426446 -142.135098) (xy 391.426446 -142.135352) (xy 391.414499 -142.159435)
			(xy 391.384844 -142.204274) (xy 391.349186 -142.244503) (xy 391.30823 -142.279325) (xy 391.262789 -142.30805)
			(xy 391.213764 -142.330106) (xy 391.162127 -142.345059) (xy 391.108901 -142.352609) (xy 391.055143 -142.352609)
			(xy 391.001917 -142.345059) (xy 390.95028 -142.330106) (xy 390.901255 -142.30805) (xy 390.855814 -142.279325)
			(xy 390.814858 -142.244503) (xy 390.7792 -142.204274) (xy 390.749545 -142.159435) (xy 390.737598 -142.135352)
			(xy 390.737598 -142.135098) (xy 390.733078 -142.126655) (xy 390.719027 -142.113662) (xy 390.701194 -142.106716)
			(xy 390.691624 -142.106396) (xy 388.547356 -142.106396) (xy 388.536028 -142.107004) (xy 388.515583 -142.116766)
			(xy 388.507986 -142.125192) (xy 388.458202 -142.18666) (xy 388.451633 -142.195811) (xy 388.446364 -142.217685)
			(xy 388.448042 -142.228824) (xy 388.451833 -142.24816) (xy 388.455909 -142.287354) (xy 388.45617 -142.307056)
			(xy 388.455684 -142.334307) (xy 388.447928 -142.388255) (xy 388.432573 -142.44055) (xy 388.409931 -142.490127)
			(xy 388.380465 -142.535977) (xy 388.344774 -142.577168) (xy 388.303583 -142.612859) (xy 388.257733 -142.642325)
			(xy 388.208156 -142.664967) (xy 388.155861 -142.680322) (xy 388.101913 -142.688078) (xy 388.047411 -142.688078)
			(xy 387.993463 -142.680322) (xy 387.941168 -142.664967) (xy 387.891591 -142.642325) (xy 387.845741 -142.612859)
			(xy 387.80455 -142.577168) (xy 387.768859 -142.535977) (xy 387.739393 -142.490127) (xy 387.716751 -142.44055)
			(xy 387.701396 -142.388255) (xy 387.69364 -142.334307) (xy 387.693154 -142.307056) (xy 387.693397 -142.287352)
			(xy 387.697464 -142.248156) (xy 387.701282 -142.228824) (xy 387.703568 -142.217394) (xy 387.698234 -142.19555)
			(xy 387.641338 -142.125192) (xy 387.633715 -142.116807) (xy 387.613282 -142.107075) (xy 387.601968 -142.106396)
			(xy 385.653788 -142.106396) (xy 385.643719 -142.10597) (xy 385.625118 -142.098253) (xy 385.61772 -142.09141)
			(xy 384.423666 -140.897356) (xy 384.416819 -140.889958) (xy 384.40909 -140.871359) (xy 384.40868 -140.861288)
			(xy 384.40868 -136.515602) (xy 384.408335 -136.50691) (xy 384.402493 -136.490539) (xy 384.39725 -136.483598)
			(xy 384.393948 -136.479788) (xy 382.404112 -134.489952) (xy 382.400382 -134.48643) (xy 382.391808 -134.4808)
			(xy 382.387094 -134.478776) (xy 382.378458 -134.47522) (xy 375.15038 -134.47522) (xy 375.141814 -134.475595)
			(xy 375.12566 -134.481311) (xy 375.112269 -134.492003) (xy 375.107454 -134.499096) (xy 375.06275 -134.57047)
			(xy 375.060663 -134.573918) (xy 375.05747 -134.581317) (xy 375.0564 -134.585202) (xy 375.055098 -134.59103)
			(xy 375.054978 -134.602967) (xy 375.056146 -134.608824) (xy 375.05894 -134.620762) (xy 375.061226 -134.625842)
			(xy 375.061226 -134.626096) (xy 375.072434 -134.651359) (xy 375.088263 -134.70431) (xy 375.096282 -134.758991)
			(xy 375.096786 -134.786624) (xy 375.0963 -134.813875) (xy 375.088544 -134.867823) (xy 375.073189 -134.920118)
			(xy 375.050547 -134.969695) (xy 375.021081 -135.015545) (xy 374.98539 -135.056736) (xy 374.944199 -135.092427)
			(xy 374.898349 -135.121893) (xy 374.848772 -135.144535) (xy 374.796477 -135.15989) (xy 374.742529 -135.167646)
			(xy 374.688027 -135.167646) (xy 374.634079 -135.15989) (xy 374.581784 -135.144535) (xy 374.532207 -135.121893)
			(xy 374.486357 -135.092427) (xy 374.445166 -135.056736) (xy 374.409475 -135.015545) (xy 374.380009 -134.969695)
			(xy 374.357367 -134.920118) (xy 374.342012 -134.867823) (xy 374.334256 -134.813875) (xy 374.33377 -134.786624)
			(xy 374.334281 -134.758992) (xy 374.342301 -134.704312) (xy 374.358132 -134.651363) (xy 374.36933 -134.626096)
			(xy 374.36933 -134.625842) (xy 374.371616 -134.620762) (xy 374.37441 -134.608824) (xy 374.375542 -134.602966)
			(xy 374.375403 -134.591038) (xy 374.374156 -134.585202) (xy 374.373098 -134.581312) (xy 374.369912 -134.573907)
			(xy 374.367806 -134.57047) (xy 374.323102 -134.499096) (xy 374.318288 -134.491998) (xy 374.304917 -134.481277)
			(xy 374.288746 -134.475598) (xy 374.280176 -134.47522) (xy 372.75643 -134.47522) (xy 372.747868 -134.475603)
			(xy 372.731726 -134.481329) (xy 372.718348 -134.492026) (xy 372.713504 -134.499096) (xy 372.6688 -134.57047)
			(xy 372.666711 -134.573917) (xy 372.663515 -134.581315) (xy 372.66245 -134.585202) (xy 372.661149 -134.59103)
			(xy 372.661029 -134.602967) (xy 372.662196 -134.608824) (xy 372.66499 -134.620762) (xy 372.667276 -134.625842)
			(xy 372.667276 -134.626096) (xy 372.678486 -134.651358) (xy 372.694317 -134.704309) (xy 372.702336 -134.758991)
			(xy 372.702836 -134.786624) (xy 372.70235 -134.813875) (xy 372.694594 -134.867823) (xy 372.679239 -134.920118)
			(xy 372.656597 -134.969695) (xy 372.627131 -135.015545) (xy 372.59144 -135.056736) (xy 372.550249 -135.092427)
			(xy 372.504399 -135.121893) (xy 372.454822 -135.144535) (xy 372.402527 -135.15989) (xy 372.348579 -135.167646)
			(xy 372.294077 -135.167646) (xy 372.240129 -135.15989) (xy 372.187834 -135.144535) (xy 372.138257 -135.121893)
			(xy 372.092407 -135.092427) (xy 372.051216 -135.056736) (xy 372.015525 -135.015545) (xy 371.986059 -134.969695)
			(xy 371.963417 -134.920118) (xy 371.948062 -134.867823) (xy 371.940306 -134.813875) (xy 371.93982 -134.786624)
			(xy 371.940331 -134.758992) (xy 371.94835 -134.704311) (xy 371.964179 -134.651361) (xy 371.97538 -134.626096)
			(xy 371.97538 -134.625842) (xy 371.977666 -134.620762) (xy 371.98046 -134.608824) (xy 371.981591 -134.602965)
			(xy 371.981452 -134.591038) (xy 371.980206 -134.585202) (xy 371.979147 -134.581313) (xy 371.975959 -134.573909)
			(xy 371.973856 -134.57047) (xy 371.929152 -134.499096) (xy 371.92434 -134.491993) (xy 371.910971 -134.481258)
			(xy 371.894799 -134.475564) (xy 371.886226 -134.47522) (xy 368.153442 -134.47522) (xy 368.144754 -134.475575)
			(xy 368.128395 -134.481432) (xy 368.121438 -134.48665) (xy 368.117628 -134.489952) (xy 365.580168 -137.027412)
			(xy 373.67032 -137.027412) (xy 373.674391 -136.97179) (xy 373.686517 -136.917353) (xy 373.70644 -136.865262)
			(xy 373.733736 -136.816627) (xy 373.767822 -136.772484) (xy 373.807971 -136.733775) (xy 373.853329 -136.701324)
			(xy 373.902929 -136.675823) (xy 373.955713 -136.657816) (xy 374.010556 -136.647686) (xy 374.06629 -136.645649)
			(xy 374.121727 -136.651749) (xy 374.175684 -136.665855) (xy 374.227013 -136.687667) (xy 374.274619 -136.716721)
			(xy 374.317487 -136.752396) (xy 374.354704 -136.793933) (xy 374.385477 -136.840446) (xy 374.409149 -136.890943)
			(xy 374.425217 -136.94435) (xy 374.433337 -136.999526) (xy 374.433846 -137.027412) (xy 374.433337 -137.055298)
			(xy 374.42674 -137.100125) (xy 378.717621 -137.100125) (xy 378.717624 -137.045631) (xy 378.725382 -136.991692)
			(xy 378.740737 -136.939406) (xy 378.763377 -136.889837) (xy 378.79284 -136.843995) (xy 378.828528 -136.802812)
			(xy 378.869713 -136.767127) (xy 378.915557 -136.737666) (xy 378.965126 -136.715029) (xy 379.017413 -136.699677)
			(xy 379.071353 -136.691922) (xy 379.125847 -136.691922) (xy 379.179787 -136.699677) (xy 379.232074 -136.715029)
			(xy 379.281643 -136.737666) (xy 379.327487 -136.767127) (xy 379.368672 -136.802812) (xy 379.40436 -136.843995)
			(xy 379.433823 -136.889837) (xy 379.456463 -136.939406) (xy 379.471818 -136.991692) (xy 379.479576 -137.045631)
			(xy 379.480064 -137.072878) (xy 379.480064 -137.073132) (xy 379.479736 -137.095178) (xy 379.474646 -137.138976)
			(xy 379.469904 -137.160508) (xy 379.466856 -137.17397) (xy 379.47473 -137.200386) (xy 379.550676 -137.269474)
			(xy 379.557512 -137.275303) (xy 379.574139 -137.282082) (xy 379.592086 -137.282652) (xy 379.600714 -137.280142)
			(xy 379.600968 -137.280142) (xy 379.630234 -137.271046) (xy 379.690723 -137.261217) (xy 379.721364 -137.260584)
			(xy 379.721618 -137.260584) (xy 379.748869 -137.261061) (xy 379.802817 -137.26882) (xy 379.855111 -137.284177)
			(xy 379.904688 -137.306819) (xy 379.950538 -137.336287) (xy 379.991728 -137.371979) (xy 380.027419 -137.41317)
			(xy 380.056885 -137.459021) (xy 380.079527 -137.508598) (xy 380.094882 -137.560893) (xy 380.10264 -137.614841)
			(xy 380.103126 -137.642092) (xy 380.103028 -137.652912) (xy 380.101757 -137.674515) (xy 380.100586 -137.685272)
			(xy 380.100035 -137.697457) (xy 380.108925 -137.720134) (xy 380.117604 -137.728706) (xy 380.18974 -137.79246)
			(xy 380.213616 -137.798302) (xy 380.225808 -137.795254) (xy 380.248065 -137.790152) (xy 380.2934 -137.78468)
			(xy 380.316232 -137.784332) (xy 380.31674 -137.784332) (xy 380.343987 -137.784821) (xy 380.397926 -137.792582)
			(xy 380.450211 -137.807939) (xy 380.499779 -137.830581) (xy 380.54562 -137.860047) (xy 380.586802 -137.895736)
			(xy 380.622485 -137.936922) (xy 380.651944 -137.982768) (xy 380.674579 -138.032339) (xy 380.68993 -138.084626)
			(xy 380.697683 -138.138566) (xy 380.697681 -138.19306) (xy 380.689924 -138.247) (xy 380.67457 -138.299286)
			(xy 380.651932 -138.348856) (xy 380.622469 -138.394699) (xy 380.586783 -138.435883) (xy 380.545599 -138.471569)
			(xy 380.499756 -138.501032) (xy 380.450186 -138.52367) (xy 380.3979 -138.539024) (xy 380.393005 -138.539728)
			(xy 381.147572 -138.539728) (xy 381.151643 -138.484106) (xy 381.163769 -138.429669) (xy 381.183692 -138.377578)
			(xy 381.210988 -138.328943) (xy 381.245074 -138.2848) (xy 381.285223 -138.246091) (xy 381.330581 -138.21364)
			(xy 381.380181 -138.188139) (xy 381.432965 -138.170132) (xy 381.487808 -138.160002) (xy 381.543542 -138.157965)
			(xy 381.598979 -138.164065) (xy 381.652936 -138.178171) (xy 381.704265 -138.199983) (xy 381.751871 -138.229037)
			(xy 381.794739 -138.264712) (xy 381.831956 -138.306249) (xy 381.862729 -138.352762) (xy 381.886401 -138.403259)
			(xy 381.902469 -138.456666) (xy 381.910589 -138.511842) (xy 381.911098 -138.539728) (xy 381.910589 -138.567614)
			(xy 381.902469 -138.62279) (xy 381.886401 -138.676197) (xy 381.862729 -138.726694) (xy 381.831956 -138.773207)
			(xy 381.794739 -138.814744) (xy 381.751871 -138.850419) (xy 381.704265 -138.879473) (xy 381.652936 -138.901285)
			(xy 381.598979 -138.915391) (xy 381.543542 -138.921491) (xy 381.487808 -138.919454) (xy 381.432965 -138.909324)
			(xy 381.380181 -138.891317) (xy 381.330581 -138.865816) (xy 381.285223 -138.833365) (xy 381.245074 -138.794656)
			(xy 381.210988 -138.750513) (xy 381.183692 -138.701878) (xy 381.163769 -138.649787) (xy 381.151643 -138.59535)
			(xy 381.147572 -138.539728) (xy 380.393005 -138.539728) (xy 380.34396 -138.546781) (xy 380.289466 -138.546783)
			(xy 380.235526 -138.53903) (xy 380.183239 -138.523679) (xy 380.133668 -138.501044) (xy 380.087822 -138.471585)
			(xy 380.046636 -138.435902) (xy 380.010947 -138.39472) (xy 379.981481 -138.348879) (xy 379.958839 -138.299311)
			(xy 379.943482 -138.247026) (xy 379.935721 -138.193087) (xy 379.935232 -138.16584) (xy 379.935333 -138.15502)
			(xy 379.936601 -138.133417) (xy 379.937772 -138.12266) (xy 379.938285 -138.110477) (xy 379.929418 -138.087803)
			(xy 379.920754 -138.079226) (xy 379.848618 -138.015472) (xy 379.824742 -138.00963) (xy 379.81255 -138.012678)
			(xy 379.790291 -138.017769) (xy 379.744957 -138.023248) (xy 379.722126 -138.0236) (xy 379.721618 -138.0236)
			(xy 379.694365 -138.023128) (xy 379.640414 -138.015373) (xy 379.588116 -138.000019) (xy 379.538535 -137.977378)
			(xy 379.492682 -137.947911) (xy 379.451489 -137.912218) (xy 379.415795 -137.871026) (xy 379.386327 -137.825173)
			(xy 379.363684 -137.775593) (xy 379.348329 -137.723296) (xy 379.340573 -137.669345) (xy 379.34011 -137.642092)
			(xy 379.34011 -137.641838) (xy 379.340434 -137.619792) (xy 379.345527 -137.575994) (xy 379.35027 -137.554462)
			(xy 379.353318 -137.541) (xy 379.345444 -137.514584) (xy 379.269498 -137.445496) (xy 379.262626 -137.439715)
			(xy 379.246018 -137.432925) (xy 379.228085 -137.432332) (xy 379.21946 -137.434828) (xy 379.219206 -137.434828)
			(xy 379.189942 -137.443932) (xy 379.129451 -137.453755) (xy 379.09881 -137.454386) (xy 379.098556 -137.454386)
			(xy 379.071309 -137.453875) (xy 379.01737 -137.446113) (xy 378.965085 -137.430755) (xy 378.915518 -137.408113)
			(xy 378.869677 -137.378647) (xy 378.828496 -137.342957) (xy 378.792814 -137.30177) (xy 378.763356 -137.255924)
			(xy 378.740722 -137.206353) (xy 378.725372 -137.154065) (xy 378.717621 -137.100125) (xy 374.42674 -137.100125)
			(xy 374.425217 -137.110474) (xy 374.409149 -137.163881) (xy 374.385477 -137.214378) (xy 374.354704 -137.260891)
			(xy 374.317487 -137.302428) (xy 374.274619 -137.338103) (xy 374.227013 -137.367157) (xy 374.175684 -137.388969)
			(xy 374.121727 -137.403075) (xy 374.06629 -137.409175) (xy 374.010556 -137.407138) (xy 373.955713 -137.397008)
			(xy 373.902929 -137.379001) (xy 373.853329 -137.3535) (xy 373.807971 -137.321049) (xy 373.767822 -137.28234)
			(xy 373.733736 -137.238197) (xy 373.70644 -137.189562) (xy 373.686517 -137.137471) (xy 373.674391 -137.083034)
			(xy 373.67032 -137.027412) (xy 365.580168 -137.027412) (xy 365.353346 -137.254234) (xy 365.345948 -137.261079)
			(xy 365.327349 -137.268804) (xy 365.317278 -137.26922) (xy 345.535758 -137.26922) (xy 345.525691 -137.26879)
			(xy 345.507095 -137.261067) (xy 345.49969 -137.254234) (xy 339.515196 -131.26974) (xy 339.507799 -131.26289)
			(xy 339.489201 -131.255151) (xy 339.479128 -131.254754) (xy 330.675742 -131.254754) (xy 330.665678 -131.255189)
			(xy 330.647094 -131.262924) (xy 330.639674 -131.26974) (xy 330.381102 -131.528312) (xy 330.379324 -131.528312)
			(xy 329.778614 -132.129276) (xy 329.768653 -132.129765) (xy 329.750231 -132.137355) (xy 329.7428 -132.144008)
			(xy 328.530851 -133.355957) (xy 330.367519 -133.355957) (xy 330.367519 -133.301443) (xy 330.375278 -133.247483)
			(xy 330.390637 -133.195177) (xy 330.413285 -133.14559) (xy 330.442759 -133.09973) (xy 330.478461 -133.058533)
			(xy 330.519662 -133.022835) (xy 330.565525 -132.993366) (xy 330.615115 -132.970723) (xy 330.667422 -132.955369)
			(xy 330.721383 -132.947616) (xy 330.74864 -132.947156) (xy 330.749148 -132.947156) (xy 330.763877 -132.947302)
			(xy 330.793248 -132.949592) (xy 330.807822 -132.951728) (xy 330.818236 -132.953506) (xy 330.838556 -132.948426)
			(xy 330.905104 -132.897118) (xy 330.912956 -132.890443) (xy 330.923052 -132.872498) (xy 330.924662 -132.86232)
			(xy 330.924662 -132.862066) (xy 330.92807 -132.834301) (xy 330.942037 -132.780133) (xy 330.96376 -132.728583)
			(xy 330.992775 -132.680757) (xy 331.028459 -132.637677) (xy 331.070049 -132.600266) (xy 331.116654 -132.569327)
			(xy 331.167275 -132.545521) (xy 331.220829 -132.529358) (xy 331.276168 -132.521184) (xy 331.304138 -132.52069)
			(xy 331.328938 -132.521109) (xy 331.378116 -132.527578) (xy 331.426042 -132.540362) (xy 331.471908 -132.559246)
			(xy 331.493622 -132.571236) (xy 331.493876 -132.57149) (xy 331.501989 -132.5756) (xy 331.519958 -132.578329)
			(xy 331.528928 -132.576824) (xy 331.604366 -132.56133) (xy 331.61986 -132.551424) (xy 331.625448 -132.543804)
			(xy 331.64358 -132.520479) (xy 331.68586 -132.479218) (xy 331.733991 -132.444961) (xy 331.786824 -132.418526)
			(xy 331.843099 -132.400546) (xy 331.901471 -132.391447) (xy 331.93101 -132.390896) (xy 331.958721 -132.391366)
			(xy 332.013559 -132.399387) (xy 332.06666 -132.415257) (xy 332.116906 -132.438643) (xy 332.163239 -132.469052)
			(xy 332.204686 -132.505846) (xy 332.240372 -132.548249) (xy 332.269548 -132.595369) (xy 332.2916 -132.646215)
			(xy 332.29931 -132.672836) (xy 332.302139 -132.681576) (xy 332.312944 -132.696416) (xy 332.320392 -132.701792)
			(xy 332.384654 -132.74421) (xy 332.402942 -132.74802) (xy 332.412086 -132.74675) (xy 332.425788 -132.744864)
			(xy 332.453374 -132.742831) (xy 332.467204 -132.742686) (xy 332.494455 -132.743174) (xy 332.548402 -132.750931)
			(xy 332.600697 -132.766286) (xy 332.650274 -132.788927) (xy 332.696124 -132.818394) (xy 332.737314 -132.854085)
			(xy 332.773005 -132.895275) (xy 332.802472 -132.941125) (xy 332.825113 -132.990701) (xy 332.840469 -133.042996)
			(xy 332.848226 -133.096943) (xy 332.848712 -133.124194) (xy 332.848263 -133.150619) (xy 332.840943 -133.202961)
			(xy 332.826471 -133.253792) (xy 332.805124 -133.30214) (xy 332.777308 -133.347079) (xy 332.743558 -133.387751)
			(xy 332.704519 -133.423376) (xy 332.660937 -133.453273) (xy 332.613646 -133.476871) (xy 332.563552 -133.493717)
			(xy 332.511612 -133.50349) (xy 332.485238 -133.505194) (xy 332.484984 -133.505194) (xy 332.475773 -133.506055)
			(xy 332.458846 -133.513489) (xy 332.451964 -133.519672) (xy 332.40345 -133.567678) (xy 332.397138 -133.574439)
			(xy 332.389455 -133.591247) (xy 332.388464 -133.600444) (xy 332.388464 -133.600698) (xy 332.386225 -133.62945)
			(xy 332.374164 -133.685843) (xy 332.353749 -133.739777) (xy 332.325446 -133.790023) (xy 332.289901 -133.835434)
			(xy 332.247922 -133.874975) (xy 332.200469 -133.907745) (xy 332.148623 -133.932996) (xy 332.093565 -133.950152)
			(xy 332.036552 -133.958823) (xy 332.007718 -133.959346) (xy 331.98238 -133.958906) (xy 331.932151 -133.9522)
			(xy 331.883252 -133.938903) (xy 331.836543 -133.91925) (xy 331.792847 -133.893586) (xy 331.752933 -133.862364)
			(xy 331.734922 -133.844538) (xy 331.728318 -133.83768) (xy 331.711046 -133.829806) (xy 331.62367 -133.824472)
			(xy 331.606144 -133.83006) (xy 331.598524 -133.836156) (xy 331.578119 -133.851968) (xy 331.533876 -133.878562)
			(xy 331.486454 -133.898957) (xy 331.436718 -133.91278) (xy 331.385574 -133.91978) (xy 331.359764 -133.92023)
			(xy 331.330759 -133.919685) (xy 331.27342 -133.910885) (xy 331.218073 -133.893508) (xy 331.165993 -133.867956)
			(xy 331.118381 -133.834815) (xy 331.076333 -133.794851) (xy 331.040817 -133.748983) (xy 331.026262 -133.723888)
			(xy 331.02169 -133.715506) (xy 331.007466 -133.703568) (xy 330.93406 -133.678676) (xy 330.925177 -133.676035)
			(xy 330.906672 -133.676696) (xy 330.897992 -133.679946) (xy 330.897738 -133.679946) (xy 330.874141 -133.689491)
			(xy 330.825046 -133.702935) (xy 330.774599 -133.709734) (xy 330.749148 -133.710172) (xy 330.74864 -133.710172)
			(xy 330.721383 -133.709784) (xy 330.667422 -133.702031) (xy 330.615115 -133.686677) (xy 330.565525 -133.664034)
			(xy 330.519662 -133.634565) (xy 330.478461 -133.598867) (xy 330.442759 -133.55767) (xy 330.413285 -133.51181)
			(xy 330.390637 -133.462223) (xy 330.375278 -133.409917) (xy 330.367519 -133.355957) (xy 328.530851 -133.355957)
			(xy 327.387458 -134.49935) (xy 327.384749 -134.502199) (xy 327.380148 -134.508573) (xy 327.378314 -134.51205)
			(xy 327.375731 -134.517477) (xy 327.372908 -134.529156) (xy 327.372726 -134.535164) (xy 327.372726 -135.940292)
			(xy 327.372426 -135.94755) (xy 327.368297 -135.961471) (xy 327.364598 -135.967724) (xy 327.363836 -135.968994)
			(xy 327.361296 -135.973058) (xy 327.35774 -135.986266) (xy 327.35774 -136.473946) (xy 330.23505 -136.473946)
			(xy 330.239121 -136.418324) (xy 330.251247 -136.363887) (xy 330.27117 -136.311796) (xy 330.298466 -136.263161)
			(xy 330.332552 -136.219018) (xy 330.372701 -136.180309) (xy 330.418059 -136.147858) (xy 330.467659 -136.122357)
			(xy 330.520443 -136.10435) (xy 330.575286 -136.09422) (xy 330.63102 -136.092183) (xy 330.686457 -136.098283)
			(xy 330.740414 -136.112389) (xy 330.791743 -136.134201) (xy 330.839349 -136.163255) (xy 330.882217 -136.19893)
			(xy 330.919434 -136.240467) (xy 330.950207 -136.28698) (xy 330.973879 -136.337477) (xy 330.989947 -136.390884)
			(xy 330.998067 -136.44606) (xy 330.998576 -136.473946) (xy 330.998067 -136.501832) (xy 330.989947 -136.557008)
			(xy 330.973879 -136.610415) (xy 330.950207 -136.660912) (xy 330.919434 -136.707425) (xy 330.882217 -136.748962)
			(xy 330.839349 -136.784637) (xy 330.791743 -136.813691) (xy 330.740414 -136.835503) (xy 330.686457 -136.849609)
			(xy 330.63102 -136.855709) (xy 330.575286 -136.853672) (xy 330.520443 -136.843542) (xy 330.467659 -136.825535)
			(xy 330.418059 -136.800034) (xy 330.372701 -136.767583) (xy 330.332552 -136.728874) (xy 330.298466 -136.684731)
			(xy 330.27117 -136.636096) (xy 330.251247 -136.584005) (xy 330.239121 -136.529568) (xy 330.23505 -136.473946)
			(xy 327.35774 -136.473946) (xy 327.35774 -137.849864) (xy 328.187556 -137.849864) (xy 328.191627 -137.794242)
			(xy 328.203753 -137.739805) (xy 328.223676 -137.687714) (xy 328.250972 -137.639079) (xy 328.285058 -137.594936)
			(xy 328.325207 -137.556227) (xy 328.370565 -137.523776) (xy 328.420165 -137.498275) (xy 328.472949 -137.480268)
			(xy 328.527792 -137.470138) (xy 328.583526 -137.468101) (xy 328.638963 -137.474201) (xy 328.69292 -137.488307)
			(xy 328.744249 -137.510119) (xy 328.791855 -137.539173) (xy 328.834723 -137.574848) (xy 328.87194 -137.616385)
			(xy 328.902713 -137.662898) (xy 328.926385 -137.713395) (xy 328.942453 -137.766802) (xy 328.950573 -137.821978)
			(xy 328.951082 -137.849864) (xy 328.950573 -137.87775) (xy 328.942453 -137.932926) (xy 328.926385 -137.986333)
			(xy 328.902713 -138.03683) (xy 328.87194 -138.083343) (xy 328.834723 -138.12488) (xy 328.791855 -138.160555)
			(xy 328.744249 -138.189609) (xy 328.69292 -138.211421) (xy 328.638963 -138.225527) (xy 328.583526 -138.231627)
			(xy 328.527792 -138.22959) (xy 328.472949 -138.21946) (xy 328.420165 -138.201453) (xy 328.370565 -138.175952)
			(xy 328.325207 -138.143501) (xy 328.285058 -138.104792) (xy 328.250972 -138.060649) (xy 328.223676 -138.012014)
			(xy 328.203753 -137.959923) (xy 328.191627 -137.905486) (xy 328.187556 -137.849864) (xy 327.35774 -137.849864)
			(xy 327.35774 -138.424158) (xy 371.38432 -138.424158) (xy 371.388391 -138.368536) (xy 371.400517 -138.314099)
			(xy 371.42044 -138.262008) (xy 371.447736 -138.213373) (xy 371.481822 -138.16923) (xy 371.521971 -138.130521)
			(xy 371.567329 -138.09807) (xy 371.616929 -138.072569) (xy 371.669713 -138.054562) (xy 371.724556 -138.044432)
			(xy 371.78029 -138.042395) (xy 371.835727 -138.048495) (xy 371.889684 -138.062601) (xy 371.941013 -138.084413)
			(xy 371.988619 -138.113467) (xy 372.031487 -138.149142) (xy 372.068704 -138.190679) (xy 372.073186 -138.197453)
			(xy 375.096236 -138.197453) (xy 375.096236 -138.142947) (xy 375.103993 -138.088995) (xy 375.119348 -138.036696)
			(xy 375.14199 -137.987115) (xy 375.171458 -137.941261) (xy 375.207151 -137.900066) (xy 375.248343 -137.864371)
			(xy 375.294196 -137.834901) (xy 375.343776 -137.812256) (xy 375.396073 -137.796897) (xy 375.450025 -137.789137)
			(xy 375.477278 -137.78865) (xy 375.504916 -137.78913) (xy 375.559612 -137.797126) (xy 375.612583 -137.812924)
			(xy 375.662724 -137.836194) (xy 375.708985 -137.866451) (xy 375.7504 -137.903061) (xy 375.786104 -137.94526)
			(xy 375.815351 -137.992166) (xy 375.837529 -138.042799) (xy 375.845324 -138.06932) (xy 375.848626 -138.081766)
			(xy 375.865898 -138.100054) (xy 375.970292 -138.134852) (xy 375.995438 -138.130534) (xy 376.005344 -138.12266)
			(xy 376.016336 -138.114309) (xy 376.039348 -138.099056) (xy 376.051318 -138.09218) (xy 376.051572 -138.09218)
			(xy 376.059695 -138.087119) (xy 376.071697 -138.072229) (xy 376.07494 -138.063224) (xy 376.095768 -137.997438)
			(xy 376.098269 -137.988288) (xy 376.097111 -137.96937) (xy 376.093482 -137.960608) (xy 376.08218 -137.935237)
			(xy 376.066223 -137.88204) (xy 376.058166 -137.827088) (xy 376.057668 -137.799318) (xy 376.058195 -137.772068)
			(xy 376.065948 -137.718123) (xy 376.0813 -137.665831) (xy 376.103937 -137.616255) (xy 376.133399 -137.570406)
			(xy 376.169087 -137.529216) (xy 376.210272 -137.493525) (xy 376.256118 -137.464057) (xy 376.305691 -137.441415)
			(xy 376.357982 -137.426057) (xy 376.411926 -137.418298) (xy 376.439176 -137.41781) (xy 376.463206 -137.418166)
			(xy 376.510884 -137.424213) (xy 376.557425 -137.436202) (xy 376.579892 -137.444734) (xy 376.588528 -137.44829)
			(xy 376.60707 -137.448544) (xy 376.679206 -137.422382) (xy 376.687693 -137.418853) (xy 376.701619 -137.406875)
			(xy 376.706384 -137.399014) (xy 376.706638 -137.399014) (xy 376.706638 -137.398506) (xy 376.721085 -137.373101)
			(xy 376.756578 -137.326669) (xy 376.798733 -137.286189) (xy 376.846565 -137.252607) (xy 376.898956 -137.226708)
			(xy 376.954683 -137.209096) (xy 377.012442 -137.200183) (xy 377.041664 -137.199624) (xy 377.068921 -137.20002)
			(xy 377.12288 -137.207774) (xy 377.175187 -137.223128) (xy 377.224776 -137.245771) (xy 377.270637 -137.27524)
			(xy 377.311838 -137.310937) (xy 377.347538 -137.352134) (xy 377.377012 -137.397993) (xy 377.399659 -137.447579)
			(xy 377.415018 -137.499885) (xy 377.422777 -137.553843) (xy 377.422777 -137.608357) (xy 377.415018 -137.662315)
			(xy 377.399659 -137.714621) (xy 377.377012 -137.764207) (xy 377.347538 -137.810066) (xy 377.314594 -137.848083)
			(xy 377.700412 -137.848083) (xy 377.708165 -137.794125) (xy 377.723517 -137.74182) (xy 377.746157 -137.692232)
			(xy 377.775624 -137.646371) (xy 377.811317 -137.605171) (xy 377.852511 -137.569469) (xy 377.898366 -137.539993)
			(xy 377.947949 -137.517344) (xy 378.000251 -137.501981) (xy 378.054207 -137.494218) (xy 378.108719 -137.494212)
			(xy 378.162676 -137.501965) (xy 378.214981 -137.517317) (xy 378.264569 -137.539958) (xy 378.31043 -137.569424)
			(xy 378.35163 -137.605118) (xy 378.387332 -137.646312) (xy 378.416807 -137.692167) (xy 378.439457 -137.74175)
			(xy 378.45482 -137.794052) (xy 378.462582 -137.848008) (xy 378.463048 -137.875264) (xy 378.463048 -137.884662)
			(xy 378.462794 -137.895584) (xy 378.470922 -137.91565) (xy 378.543312 -137.982452) (xy 378.563886 -137.98931)
			(xy 378.574554 -137.988294) (xy 378.612908 -137.986262) (xy 378.640161 -137.986764) (xy 378.694111 -137.994522)
			(xy 378.746408 -138.009879) (xy 378.795987 -138.032523) (xy 378.841839 -138.061992) (xy 378.88303 -138.097686)
			(xy 378.918722 -138.13888) (xy 378.948188 -138.184734) (xy 378.970829 -138.234314) (xy 378.986183 -138.286612)
			(xy 378.993938 -138.340563) (xy 378.993936 -138.395068) (xy 378.986176 -138.449018) (xy 378.970818 -138.501315)
			(xy 378.948174 -138.550893) (xy 378.918704 -138.596745) (xy 378.883008 -138.637935) (xy 378.841814 -138.673627)
			(xy 378.79596 -138.703092) (xy 378.746379 -138.725732) (xy 378.694081 -138.741084) (xy 378.64013 -138.748838)
			(xy 378.585625 -138.748835) (xy 378.531675 -138.741075) (xy 378.479378 -138.725716) (xy 378.4298 -138.70307)
			(xy 378.383949 -138.673599) (xy 378.342759 -138.637903) (xy 378.307069 -138.596708) (xy 378.277605 -138.550854)
			(xy 378.254966 -138.501272) (xy 378.239614 -138.448974) (xy 378.231861 -138.395023) (xy 378.2314 -138.36777)
			(xy 378.2314 -138.358372) (xy 378.231654 -138.34745) (xy 378.223526 -138.327384) (xy 378.151136 -138.260582)
			(xy 378.130562 -138.253724) (xy 378.119894 -138.25474) (xy 378.08154 -138.256772) (xy 378.054284 -138.256388)
			(xy 378.000327 -138.248636) (xy 377.948021 -138.233283) (xy 377.898434 -138.210644) (xy 377.852573 -138.181177)
			(xy 377.811372 -138.145484) (xy 377.77567 -138.104291) (xy 377.746194 -138.058436) (xy 377.723544 -138.008852)
			(xy 377.708181 -137.95655) (xy 377.700418 -137.902594) (xy 377.700412 -137.848083) (xy 377.314594 -137.848083)
			(xy 377.311838 -137.851263) (xy 377.270637 -137.88696) (xy 377.224776 -137.916429) (xy 377.175187 -137.939072)
			(xy 377.12288 -137.954426) (xy 377.068921 -137.96218) (xy 377.041664 -137.96264) (xy 377.017634 -137.962275)
			(xy 376.969956 -137.956232) (xy 376.923416 -137.944246) (xy 376.900948 -137.935716) (xy 376.892312 -137.93216)
			(xy 376.87377 -137.931906) (xy 376.801634 -137.958068) (xy 376.793145 -137.961594) (xy 376.779219 -137.973573)
			(xy 376.774456 -137.981436) (xy 376.774202 -137.981436) (xy 376.774202 -137.981944) (xy 376.761061 -138.005019)
			(xy 376.729399 -138.04765) (xy 376.692144 -138.085489) (xy 376.650011 -138.11781) (xy 376.627136 -138.131296)
			(xy 376.626882 -138.131296) (xy 376.618776 -138.136379) (xy 376.606763 -138.151253) (xy 376.603514 -138.160252)
			(xy 376.582686 -138.226038) (xy 376.580148 -138.23518) (xy 376.581331 -138.254105) (xy 376.584972 -138.262868)
			(xy 376.596264 -138.288243) (xy 376.612225 -138.341439) (xy 376.620286 -138.396389) (xy 376.620786 -138.424158)
			(xy 376.620306 -138.451411) (xy 376.612554 -138.505362) (xy 376.597202 -138.557661) (xy 376.574563 -138.607243)
			(xy 376.545097 -138.653097) (xy 376.509405 -138.694291) (xy 376.468213 -138.729985) (xy 376.42236 -138.759453)
			(xy 376.37278 -138.782095) (xy 376.320482 -138.797449) (xy 376.266531 -138.805204) (xy 376.239278 -138.805666)
			(xy 376.211639 -138.805214) (xy 376.156943 -138.797212) (xy 376.103971 -138.781409) (xy 376.053831 -138.758135)
			(xy 376.007571 -138.727875) (xy 375.966156 -138.691261) (xy 375.930452 -138.64906) (xy 375.901206 -138.602152)
			(xy 375.879027 -138.551518) (xy 375.871232 -138.524996) (xy 375.86793 -138.51255) (xy 375.850658 -138.494262)
			(xy 375.746264 -138.459464) (xy 375.721118 -138.463782) (xy 375.711212 -138.471656) (xy 375.691075 -138.486752)
			(xy 375.647602 -138.512108) (xy 375.60117 -138.53152) (xy 375.552586 -138.544648) (xy 375.502696 -138.551266)
			(xy 375.477532 -138.551666) (xy 375.477278 -138.551666) (xy 375.450025 -138.551263) (xy 375.396073 -138.543503)
			(xy 375.343776 -138.528144) (xy 375.294196 -138.505499) (xy 375.248343 -138.476029) (xy 375.207151 -138.440334)
			(xy 375.171458 -138.399139) (xy 375.14199 -138.353285) (xy 375.119348 -138.303704) (xy 375.103993 -138.251405)
			(xy 375.096236 -138.197453) (xy 372.073186 -138.197453) (xy 372.099477 -138.237192) (xy 372.123149 -138.287689)
			(xy 372.139217 -138.341096) (xy 372.147337 -138.396272) (xy 372.147846 -138.424158) (xy 372.147337 -138.452044)
			(xy 372.139217 -138.50722) (xy 372.123149 -138.560627) (xy 372.099477 -138.611124) (xy 372.068704 -138.657637)
			(xy 372.031487 -138.699174) (xy 371.988619 -138.734849) (xy 371.941013 -138.763903) (xy 371.889684 -138.785715)
			(xy 371.835727 -138.799821) (xy 371.78029 -138.805921) (xy 371.724556 -138.803884) (xy 371.669713 -138.793754)
			(xy 371.616929 -138.775747) (xy 371.567329 -138.750246) (xy 371.521971 -138.717795) (xy 371.481822 -138.679086)
			(xy 371.447736 -138.634943) (xy 371.42044 -138.586308) (xy 371.400517 -138.534217) (xy 371.388391 -138.47978)
			(xy 371.38432 -138.424158) (xy 327.35774 -138.424158) (xy 327.35774 -139.178792) (xy 373.863614 -139.178792)
			(xy 373.867685 -139.12317) (xy 373.879811 -139.068733) (xy 373.899734 -139.016642) (xy 373.92703 -138.968007)
			(xy 373.961116 -138.923864) (xy 374.001265 -138.885155) (xy 374.046623 -138.852704) (xy 374.096223 -138.827203)
			(xy 374.149007 -138.809196) (xy 374.20385 -138.799066) (xy 374.259584 -138.797029) (xy 374.315021 -138.803129)
			(xy 374.368978 -138.817235) (xy 374.420307 -138.839047) (xy 374.467913 -138.868101) (xy 374.510781 -138.903776)
			(xy 374.547998 -138.945313) (xy 374.578771 -138.991826) (xy 374.602443 -139.042323) (xy 374.618511 -139.09573)
			(xy 374.622511 -139.122912) (xy 375.06732 -139.122912) (xy 375.071391 -139.06729) (xy 375.083517 -139.012853)
			(xy 375.10344 -138.960762) (xy 375.130736 -138.912127) (xy 375.164822 -138.867984) (xy 375.204971 -138.829275)
			(xy 375.250329 -138.796824) (xy 375.299929 -138.771323) (xy 375.352713 -138.753316) (xy 375.407556 -138.743186)
			(xy 375.46329 -138.741149) (xy 375.518727 -138.747249) (xy 375.572684 -138.761355) (xy 375.624013 -138.783167)
			(xy 375.671619 -138.812221) (xy 375.714487 -138.847896) (xy 375.751704 -138.889433) (xy 375.782477 -138.935946)
			(xy 375.806149 -138.986443) (xy 375.822217 -139.03985) (xy 375.830337 -139.095026) (xy 375.830846 -139.122912)
			(xy 375.830337 -139.150798) (xy 375.822217 -139.205974) (xy 375.806149 -139.259381) (xy 375.782477 -139.309878)
			(xy 375.751704 -139.356391) (xy 375.714487 -139.397928) (xy 375.671619 -139.433603) (xy 375.624013 -139.462657)
			(xy 375.572684 -139.484469) (xy 375.518727 -139.498575) (xy 375.46329 -139.504675) (xy 375.407556 -139.502638)
			(xy 375.352713 -139.492508) (xy 375.299929 -139.474501) (xy 375.250329 -139.449) (xy 375.204971 -139.416549)
			(xy 375.164822 -139.37784) (xy 375.130736 -139.333697) (xy 375.10344 -139.285062) (xy 375.083517 -139.232971)
			(xy 375.071391 -139.178534) (xy 375.06732 -139.122912) (xy 374.622511 -139.122912) (xy 374.626631 -139.150906)
			(xy 374.62714 -139.178792) (xy 374.626631 -139.206678) (xy 374.618511 -139.261854) (xy 374.602443 -139.315261)
			(xy 374.578771 -139.365758) (xy 374.547998 -139.412271) (xy 374.510781 -139.453808) (xy 374.467913 -139.489483)
			(xy 374.420307 -139.518537) (xy 374.368978 -139.540349) (xy 374.315021 -139.554455) (xy 374.259584 -139.560555)
			(xy 374.20385 -139.558518) (xy 374.149007 -139.548388) (xy 374.096223 -139.530381) (xy 374.046623 -139.50488)
			(xy 374.001265 -139.472429) (xy 373.961116 -139.43372) (xy 373.92703 -139.389577) (xy 373.899734 -139.340942)
			(xy 373.879811 -139.288851) (xy 373.867685 -139.234414) (xy 373.863614 -139.178792) (xy 327.35774 -139.178792)
			(xy 327.35774 -140.015214) (xy 373.57126 -140.015214) (xy 373.575331 -139.959592) (xy 373.587457 -139.905155)
			(xy 373.60738 -139.853064) (xy 373.634676 -139.804429) (xy 373.668762 -139.760286) (xy 373.708911 -139.721577)
			(xy 373.754269 -139.689126) (xy 373.803869 -139.663625) (xy 373.856653 -139.645618) (xy 373.911496 -139.635488)
			(xy 373.96723 -139.633451) (xy 374.022667 -139.639551) (xy 374.076624 -139.653657) (xy 374.127953 -139.675469)
			(xy 374.175559 -139.704523) (xy 374.188132 -139.714986) (xy 382.423668 -139.714986) (xy 382.427739 -139.659364)
			(xy 382.439865 -139.604927) (xy 382.459788 -139.552836) (xy 382.487084 -139.504201) (xy 382.52117 -139.460058)
			(xy 382.561319 -139.421349) (xy 382.606677 -139.388898) (xy 382.656277 -139.363397) (xy 382.709061 -139.34539)
			(xy 382.763904 -139.33526) (xy 382.819638 -139.333223) (xy 382.875075 -139.339323) (xy 382.929032 -139.353429)
			(xy 382.980361 -139.375241) (xy 383.027967 -139.404295) (xy 383.070835 -139.43997) (xy 383.108052 -139.481507)
			(xy 383.138825 -139.52802) (xy 383.162497 -139.578517) (xy 383.178565 -139.631924) (xy 383.186685 -139.6871)
			(xy 383.187194 -139.714986) (xy 383.186685 -139.742872) (xy 383.178565 -139.798048) (xy 383.162497 -139.851455)
			(xy 383.138825 -139.901952) (xy 383.108052 -139.948465) (xy 383.070835 -139.990002) (xy 383.027967 -140.025677)
			(xy 382.980361 -140.054731) (xy 382.929032 -140.076543) (xy 382.875075 -140.090649) (xy 382.819638 -140.096749)
			(xy 382.763904 -140.094712) (xy 382.709061 -140.084582) (xy 382.656277 -140.066575) (xy 382.606677 -140.041074)
			(xy 382.561319 -140.008623) (xy 382.52117 -139.969914) (xy 382.487084 -139.925771) (xy 382.459788 -139.877136)
			(xy 382.439865 -139.825045) (xy 382.427739 -139.770608) (xy 382.423668 -139.714986) (xy 374.188132 -139.714986)
			(xy 374.218427 -139.740198) (xy 374.255644 -139.781735) (xy 374.286417 -139.828248) (xy 374.310089 -139.878745)
			(xy 374.326157 -139.932152) (xy 374.334277 -139.987328) (xy 374.334786 -140.015214) (xy 374.334277 -140.0431)
			(xy 374.326157 -140.098276) (xy 374.310089 -140.151683) (xy 374.286417 -140.20218) (xy 374.255644 -140.248693)
			(xy 374.218427 -140.29023) (xy 374.175559 -140.325905) (xy 374.127953 -140.354959) (xy 374.076624 -140.376771)
			(xy 374.022667 -140.390877) (xy 373.96723 -140.396977) (xy 373.911496 -140.39494) (xy 373.856653 -140.38481)
			(xy 373.803869 -140.366803) (xy 373.754269 -140.341302) (xy 373.708911 -140.308851) (xy 373.668762 -140.270142)
			(xy 373.634676 -140.225999) (xy 373.60738 -140.177364) (xy 373.587457 -140.125273) (xy 373.575331 -140.070836)
			(xy 373.57126 -140.015214) (xy 327.35774 -140.015214) (xy 327.35774 -140.408152) (xy 332.324962 -140.408152)
			(xy 332.329033 -140.35253) (xy 332.341159 -140.298093) (xy 332.361082 -140.246002) (xy 332.388378 -140.197367)
			(xy 332.422464 -140.153224) (xy 332.462613 -140.114515) (xy 332.507971 -140.082064) (xy 332.557571 -140.056563)
			(xy 332.610355 -140.038556) (xy 332.665198 -140.028426) (xy 332.720932 -140.026389) (xy 332.776369 -140.032489)
			(xy 332.830326 -140.046595) (xy 332.881655 -140.068407) (xy 332.929261 -140.097461) (xy 332.972129 -140.133136)
			(xy 333.009346 -140.174673) (xy 333.040119 -140.221186) (xy 333.063791 -140.271683) (xy 333.079859 -140.32509)
			(xy 333.087979 -140.380266) (xy 333.088488 -140.408152) (xy 333.087979 -140.436038) (xy 333.079859 -140.491214)
			(xy 333.063791 -140.544621) (xy 333.040119 -140.595118) (xy 333.009346 -140.641631) (xy 332.972129 -140.683168)
			(xy 332.929261 -140.718843) (xy 332.881655 -140.747897) (xy 332.830326 -140.769709) (xy 332.776369 -140.783815)
			(xy 332.720932 -140.789915) (xy 332.665198 -140.787878) (xy 332.610355 -140.777748) (xy 332.557571 -140.759741)
			(xy 332.507971 -140.73424) (xy 332.462613 -140.701789) (xy 332.422464 -140.66308) (xy 332.388378 -140.618937)
			(xy 332.361082 -140.570302) (xy 332.341159 -140.518211) (xy 332.329033 -140.463774) (xy 332.324962 -140.408152)
			(xy 327.35774 -140.408152) (xy 327.35774 -140.975334) (xy 371.09273 -140.975334) (xy 371.093216 -140.948083)
			(xy 371.100972 -140.894135) (xy 371.116327 -140.84184) (xy 371.138969 -140.792263) (xy 371.168435 -140.746413)
			(xy 371.204126 -140.705222) (xy 371.245317 -140.669531) (xy 371.291167 -140.640065) (xy 371.340744 -140.617423)
			(xy 371.393039 -140.602068) (xy 371.446987 -140.594312) (xy 371.501489 -140.594312) (xy 371.555437 -140.602068)
			(xy 371.607732 -140.617423) (xy 371.657309 -140.640065) (xy 371.703159 -140.669531) (xy 371.74435 -140.705222)
			(xy 371.780041 -140.746413) (xy 371.809507 -140.792263) (xy 371.832149 -140.84184) (xy 371.847504 -140.894135)
			(xy 371.85526 -140.948083) (xy 371.855746 -140.975334) (xy 371.855239 -141.004699) (xy 371.846308 -141.062744)
			(xy 371.837966 -141.090904) (xy 371.834337 -141.103868) (xy 371.833141 -141.130748) (xy 371.839019 -141.157005)
			(xy 371.851561 -141.18081) (xy 371.869893 -141.200504) (xy 371.89274 -141.214717) (xy 371.918509 -141.222459)
			(xy 371.931946 -141.223238) (xy 371.958688 -141.224443) (xy 372.011468 -141.233379) (xy 372.062478 -141.24961)
			(xy 372.110717 -141.272817) (xy 372.155236 -141.302542) (xy 372.195159 -141.338202) (xy 372.229702 -141.379096)
			(xy 372.258186 -141.424419) (xy 372.28005 -141.473281) (xy 372.294866 -141.52472) (xy 372.30234 -141.577727)
			(xy 372.302786 -141.604492) (xy 372.3023 -141.631743) (xy 372.294544 -141.685691) (xy 372.279189 -141.737986)
			(xy 372.256547 -141.787563) (xy 372.227081 -141.833413) (xy 372.19139 -141.874604) (xy 372.150199 -141.910295)
			(xy 372.104349 -141.939761) (xy 372.054772 -141.962403) (xy 372.002477 -141.977758) (xy 371.948529 -141.985514)
			(xy 371.894027 -141.985514) (xy 371.840079 -141.977758) (xy 371.787784 -141.962403) (xy 371.738207 -141.939761)
			(xy 371.692357 -141.910295) (xy 371.651166 -141.874604) (xy 371.615475 -141.833413) (xy 371.586009 -141.787563)
			(xy 371.563367 -141.737986) (xy 371.548012 -141.685691) (xy 371.540256 -141.631743) (xy 371.53977 -141.604492)
			(xy 371.540286 -141.575128) (xy 371.549211 -141.517082) (xy 371.55755 -141.488922) (xy 371.561249 -141.475977)
			(xy 371.562429 -141.449089) (xy 371.556537 -141.422828) (xy 371.543983 -141.399022) (xy 371.52564 -141.379326)
			(xy 371.502786 -141.365112) (xy 371.477011 -141.357369) (xy 371.46357 -141.356588) (xy 371.436825 -141.355433)
			(xy 371.384046 -141.346486) (xy 371.333036 -141.330246) (xy 371.284799 -141.307032) (xy 371.240282 -141.277301)
			(xy 371.200361 -141.241636) (xy 371.165819 -141.200739) (xy 371.137336 -141.155413) (xy 371.115471 -141.106549)
			(xy 371.100655 -141.055108) (xy 371.093178 -141.0021) (xy 371.09273 -140.975334) (xy 327.35774 -140.975334)
			(xy 327.35774 -142.578074) (xy 328.532234 -142.578074) (xy 328.536305 -142.522452) (xy 328.548431 -142.468015)
			(xy 328.568354 -142.415924) (xy 328.59565 -142.367289) (xy 328.629736 -142.323146) (xy 328.669885 -142.284437)
			(xy 328.715243 -142.251986) (xy 328.764843 -142.226485) (xy 328.817627 -142.208478) (xy 328.87247 -142.198348)
			(xy 328.928204 -142.196311) (xy 328.935138 -142.197074) (xy 332.301086 -142.197074) (xy 332.305157 -142.141452)
			(xy 332.317283 -142.087015) (xy 332.337206 -142.034924) (xy 332.364502 -141.986289) (xy 332.398588 -141.942146)
			(xy 332.438737 -141.903437) (xy 332.484095 -141.870986) (xy 332.533695 -141.845485) (xy 332.586479 -141.827478)
			(xy 332.641322 -141.817348) (xy 332.697056 -141.815311) (xy 332.752493 -141.821411) (xy 332.80645 -141.835517)
			(xy 332.857779 -141.857329) (xy 332.905385 -141.886383) (xy 332.948253 -141.922058) (xy 332.98547 -141.963595)
			(xy 333.016243 -142.010108) (xy 333.039915 -142.060605) (xy 333.055983 -142.114012) (xy 333.064103 -142.169188)
			(xy 333.064612 -142.197074) (xy 333.064103 -142.22496) (xy 333.055983 -142.280136) (xy 333.039915 -142.333543)
			(xy 333.016243 -142.38404) (xy 332.98547 -142.430553) (xy 332.948253 -142.47209) (xy 332.905385 -142.507765)
			(xy 332.857779 -142.536819) (xy 332.80645 -142.558631) (xy 332.752493 -142.572737) (xy 332.697056 -142.578837)
			(xy 332.641322 -142.5768) (xy 332.586479 -142.56667) (xy 332.533695 -142.548663) (xy 332.484095 -142.523162)
			(xy 332.438737 -142.490711) (xy 332.398588 -142.452002) (xy 332.364502 -142.407859) (xy 332.337206 -142.359224)
			(xy 332.317283 -142.307133) (xy 332.305157 -142.252696) (xy 332.301086 -142.197074) (xy 328.935138 -142.197074)
			(xy 328.983641 -142.202411) (xy 329.037598 -142.216517) (xy 329.088927 -142.238329) (xy 329.136533 -142.267383)
			(xy 329.179401 -142.303058) (xy 329.216618 -142.344595) (xy 329.247391 -142.391108) (xy 329.271063 -142.441605)
			(xy 329.287131 -142.495012) (xy 329.295251 -142.550188) (xy 329.29576 -142.578074) (xy 329.295251 -142.60596)
			(xy 329.287131 -142.661136) (xy 329.275822 -142.698724) (xy 337.332572 -142.698724) (xy 337.336643 -142.643102)
			(xy 337.348769 -142.588665) (xy 337.368692 -142.536574) (xy 337.395988 -142.487939) (xy 337.430074 -142.443796)
			(xy 337.470223 -142.405087) (xy 337.515581 -142.372636) (xy 337.565181 -142.347135) (xy 337.617965 -142.329128)
			(xy 337.672808 -142.318998) (xy 337.728542 -142.316961) (xy 337.783979 -142.323061) (xy 337.837936 -142.337167)
			(xy 337.889265 -142.358979) (xy 337.916974 -142.37589) (xy 365.645444 -142.37589) (xy 365.649515 -142.320268)
			(xy 365.661641 -142.265831) (xy 365.681564 -142.21374) (xy 365.70886 -142.165105) (xy 365.742946 -142.120962)
			(xy 365.783095 -142.082253) (xy 365.828453 -142.049802) (xy 365.878053 -142.024301) (xy 365.930837 -142.006294)
			(xy 365.98568 -141.996164) (xy 366.041414 -141.994127) (xy 366.096851 -142.000227) (xy 366.150808 -142.014333)
			(xy 366.202137 -142.036145) (xy 366.249743 -142.065199) (xy 366.292611 -142.100874) (xy 366.329828 -142.142411)
			(xy 366.360601 -142.188924) (xy 366.384273 -142.239421) (xy 366.400341 -142.292828) (xy 366.408461 -142.348004)
			(xy 366.40897 -142.37589) (xy 366.408461 -142.403776) (xy 366.400341 -142.458952) (xy 366.391554 -142.488158)
			(xy 371.53926 -142.488158) (xy 371.543331 -142.432536) (xy 371.555457 -142.378099) (xy 371.57538 -142.326008)
			(xy 371.602676 -142.277373) (xy 371.636762 -142.23323) (xy 371.676911 -142.194521) (xy 371.722269 -142.16207)
			(xy 371.771869 -142.136569) (xy 371.824653 -142.118562) (xy 371.879496 -142.108432) (xy 371.93523 -142.106395)
			(xy 371.990667 -142.112495) (xy 372.044624 -142.126601) (xy 372.095953 -142.148413) (xy 372.143559 -142.177467)
			(xy 372.186427 -142.213142) (xy 372.223644 -142.254679) (xy 372.254417 -142.301192) (xy 372.278089 -142.351689)
			(xy 372.294157 -142.405096) (xy 372.302277 -142.460272) (xy 372.302786 -142.488158) (xy 372.302277 -142.516044)
			(xy 372.294157 -142.57122) (xy 372.278089 -142.624627) (xy 372.254417 -142.675124) (xy 372.223644 -142.721637)
			(xy 372.186427 -142.763174) (xy 372.143559 -142.798849) (xy 372.095953 -142.827903) (xy 372.044624 -142.849715)
			(xy 371.990667 -142.863821) (xy 371.93523 -142.869921) (xy 371.879496 -142.867884) (xy 371.824653 -142.857754)
			(xy 371.771869 -142.839747) (xy 371.722269 -142.814246) (xy 371.676911 -142.781795) (xy 371.636762 -142.743086)
			(xy 371.602676 -142.698943) (xy 371.57538 -142.650308) (xy 371.555457 -142.598217) (xy 371.543331 -142.54378)
			(xy 371.53926 -142.488158) (xy 366.391554 -142.488158) (xy 366.384273 -142.512359) (xy 366.360601 -142.562856)
			(xy 366.329828 -142.609369) (xy 366.292611 -142.650906) (xy 366.249743 -142.686581) (xy 366.202137 -142.715635)
			(xy 366.150808 -142.737447) (xy 366.096851 -142.751553) (xy 366.041414 -142.757653) (xy 365.98568 -142.755616)
			(xy 365.930837 -142.745486) (xy 365.878053 -142.727479) (xy 365.828453 -142.701978) (xy 365.783095 -142.669527)
			(xy 365.742946 -142.630818) (xy 365.70886 -142.586675) (xy 365.681564 -142.53804) (xy 365.661641 -142.485949)
			(xy 365.649515 -142.431512) (xy 365.645444 -142.37589) (xy 337.916974 -142.37589) (xy 337.936871 -142.388033)
			(xy 337.979739 -142.423708) (xy 338.016956 -142.465245) (xy 338.047729 -142.511758) (xy 338.071401 -142.562255)
			(xy 338.087469 -142.615662) (xy 338.095589 -142.670838) (xy 338.096098 -142.698724) (xy 338.095589 -142.72661)
			(xy 338.087469 -142.781786) (xy 338.071401 -142.835193) (xy 338.047729 -142.88569) (xy 338.016956 -142.932203)
			(xy 337.979739 -142.97374) (xy 337.936871 -143.009415) (xy 337.889265 -143.038469) (xy 337.837936 -143.060281)
			(xy 337.783979 -143.074387) (xy 337.728542 -143.080487) (xy 337.672808 -143.07845) (xy 337.617965 -143.06832)
			(xy 337.565181 -143.050313) (xy 337.515581 -143.024812) (xy 337.470223 -142.992361) (xy 337.430074 -142.953652)
			(xy 337.395988 -142.909509) (xy 337.368692 -142.860874) (xy 337.348769 -142.808783) (xy 337.336643 -142.754346)
			(xy 337.332572 -142.698724) (xy 329.275822 -142.698724) (xy 329.271063 -142.714543) (xy 329.247391 -142.76504)
			(xy 329.216618 -142.811553) (xy 329.179401 -142.85309) (xy 329.136533 -142.888765) (xy 329.088927 -142.917819)
			(xy 329.037598 -142.939631) (xy 328.983641 -142.953737) (xy 328.928204 -142.959837) (xy 328.87247 -142.9578)
			(xy 328.817627 -142.94767) (xy 328.764843 -142.929663) (xy 328.715243 -142.904162) (xy 328.669885 -142.871711)
			(xy 328.629736 -142.833002) (xy 328.59565 -142.788859) (xy 328.568354 -142.740224) (xy 328.548431 -142.688133)
			(xy 328.536305 -142.633696) (xy 328.532234 -142.578074) (xy 327.35774 -142.578074) (xy 327.35774 -152.278151)
			(xy 329.15858 -152.278151) (xy 329.15858 -152.223649) (xy 329.166336 -152.169701) (xy 329.181691 -152.117407)
			(xy 329.204332 -152.06783) (xy 329.233798 -152.02198) (xy 329.26949 -151.98079) (xy 329.31068 -151.945098)
			(xy 329.35653 -151.915632) (xy 329.406107 -151.892991) (xy 329.458401 -151.877636) (xy 329.512349 -151.86988)
			(xy 329.5396 -151.869394) (xy 329.568519 -151.869877) (xy 329.625693 -151.878608) (xy 329.680894 -151.895871)
			(xy 329.732857 -151.921269) (xy 329.780389 -151.95422) (xy 329.822403 -151.99397) (xy 329.84059 -152.01646)
			(xy 329.848201 -152.025263) (xy 329.869099 -152.035446) (xy 329.880722 -152.036018) (xy 329.960478 -152.036018)
			(xy 329.972106 -152.035446) (xy 329.993015 -152.02528) (xy 330.00061 -152.01646) (xy 330.018785 -151.993963)
			(xy 330.060809 -151.954231) (xy 330.108348 -151.921295) (xy 330.160312 -151.895909) (xy 330.215512 -151.878655)
			(xy 330.272683 -151.869928) (xy 330.3016 -151.869394) (xy 330.328851 -151.869876) (xy 330.382799 -151.877632)
			(xy 330.435094 -151.892988) (xy 330.484672 -151.915629) (xy 330.530523 -151.945095) (xy 330.571713 -151.980787)
			(xy 330.607405 -152.021977) (xy 330.636871 -152.067828) (xy 330.659512 -152.117406) (xy 330.674868 -152.169701)
			(xy 330.682624 -152.223649) (xy 330.682624 -152.278151) (xy 330.674868 -152.332099) (xy 330.659512 -152.384394)
			(xy 330.636871 -152.433972) (xy 330.607405 -152.479823) (xy 330.571713 -152.521013) (xy 330.530523 -152.556705)
			(xy 330.484672 -152.586171) (xy 330.435094 -152.608812) (xy 330.382799 -152.624168) (xy 330.328851 -152.631924)
			(xy 330.3016 -152.63241) (xy 330.272681 -152.631926) (xy 330.215507 -152.623195) (xy 330.160306 -152.605932)
			(xy 330.108344 -152.580534) (xy 330.060811 -152.547583) (xy 330.018798 -152.507834) (xy 330.00061 -152.485344)
			(xy 329.992998 -152.476542) (xy 329.972101 -152.466358) (xy 329.960478 -152.465786) (xy 329.880722 -152.465786)
			(xy 329.869094 -152.466357) (xy 329.848185 -152.476524) (xy 329.84059 -152.485344) (xy 329.822416 -152.507841)
			(xy 329.780391 -152.547574) (xy 329.732852 -152.58051) (xy 329.680888 -152.605895) (xy 329.625688 -152.623149)
			(xy 329.568517 -152.631876) (xy 329.5396 -152.63241) (xy 329.512349 -152.63192) (xy 329.458401 -152.624164)
			(xy 329.406107 -152.608809) (xy 329.35653 -152.586168) (xy 329.31068 -152.556702) (xy 329.26949 -152.52101)
			(xy 329.233798 -152.47982) (xy 329.204332 -152.43397) (xy 329.181691 -152.384393) (xy 329.166336 -152.332099)
			(xy 329.15858 -152.278151) (xy 327.35774 -152.278151) (xy 327.35774 -155.7274) (xy 331.734177 -155.7274)
			(xy 331.737907 -155.674149) (xy 331.749022 -155.621938) (xy 331.767307 -155.571787) (xy 331.792405 -155.524673)
			(xy 331.823824 -155.481518) (xy 331.860952 -155.443164) (xy 331.881734 -155.42641) (xy 331.890532 -155.418795)
			(xy 331.900719 -155.3979) (xy 331.901292 -155.386278) (xy 331.901292 -155.306522) (xy 331.900729 -155.294893)
			(xy 331.890557 -155.273983) (xy 331.881734 -155.26639) (xy 331.860952 -155.249636) (xy 331.823824 -155.211282)
			(xy 331.792405 -155.168127) (xy 331.767307 -155.121013) (xy 331.749022 -155.070862) (xy 331.737907 -155.018651)
			(xy 331.734177 -154.9654) (xy 331.737907 -154.912149) (xy 331.749022 -154.859938) (xy 331.767307 -154.809787)
			(xy 331.792405 -154.762673) (xy 331.823824 -154.719518) (xy 331.860952 -154.681164) (xy 331.881734 -154.66441)
			(xy 331.890532 -154.656795) (xy 331.900719 -154.6359) (xy 331.901292 -154.624278) (xy 331.901292 -154.544522)
			(xy 331.900729 -154.532893) (xy 331.890557 -154.511983) (xy 331.881734 -154.50439) (xy 331.860952 -154.487636)
			(xy 331.823824 -154.449282) (xy 331.792405 -154.406127) (xy 331.767307 -154.359013) (xy 331.749022 -154.308862)
			(xy 331.737907 -154.256651) (xy 331.734177 -154.2034) (xy 331.737907 -154.150149) (xy 331.749022 -154.097938)
			(xy 331.767307 -154.047787) (xy 331.792405 -154.000673) (xy 331.823824 -153.957518) (xy 331.860952 -153.919164)
			(xy 331.881734 -153.90241) (xy 331.890532 -153.894795) (xy 331.900719 -153.8739) (xy 331.901292 -153.862278)
			(xy 331.901292 -153.782522) (xy 331.900729 -153.770893) (xy 331.890557 -153.749983) (xy 331.881734 -153.74239)
			(xy 331.859253 -153.724196) (xy 331.819516 -153.682178) (xy 331.786576 -153.634644) (xy 331.761187 -153.582683)
			(xy 331.74393 -153.527486) (xy 331.735202 -153.470316) (xy 331.734668 -153.4414) (xy 331.735141 -153.413574)
			(xy 331.743205 -153.358509) (xy 331.759192 -153.305202) (xy 331.782761 -153.254788) (xy 331.813411 -153.208336)
			(xy 331.85049 -153.166836) (xy 331.893211 -153.13117) (xy 331.940664 -153.102095) (xy 331.991842 -153.08023)
			(xy 332.045654 -153.066041) (xy 332.07325 -153.062432) (xy 332.073504 -153.062432) (xy 332.08422 -153.060592)
			(xy 332.102762 -153.049265) (xy 332.109318 -153.040588) (xy 332.159102 -152.967436) (xy 332.162658 -152.945592)
			(xy 332.159864 -152.934924) (xy 332.153701 -152.910559) (xy 332.147074 -152.860739) (xy 332.146656 -152.83561)
			(xy 332.146656 -152.835102) (xy 332.147142 -152.807127) (xy 332.155319 -152.751777) (xy 332.171498 -152.698217)
			(xy 332.195332 -152.647597) (xy 332.21041 -152.624028) (xy 332.215744 -152.616154) (xy 332.219554 -152.597866)
			(xy 332.206346 -152.511252) (xy 332.196948 -152.494742) (xy 332.189582 -152.4889) (xy 332.167824 -152.470683)
			(xy 332.129417 -152.428912) (xy 332.097623 -152.381911) (xy 332.073143 -152.330719) (xy 332.056518 -152.276465)
			(xy 332.048115 -152.220346) (xy 332.047596 -152.191974) (xy 332.048082 -152.164723) (xy 332.055838 -152.110775)
			(xy 332.071193 -152.05848) (xy 332.093835 -152.008903) (xy 332.123301 -151.963053) (xy 332.158992 -151.921862)
			(xy 332.200183 -151.886171) (xy 332.246033 -151.856705) (xy 332.29561 -151.834063) (xy 332.347905 -151.818708)
			(xy 332.401853 -151.810952) (xy 332.456355 -151.810952) (xy 332.510303 -151.818708) (xy 332.562598 -151.834063)
			(xy 332.612175 -151.856705) (xy 332.658025 -151.886171) (xy 332.699216 -151.921862) (xy 332.734907 -151.963053)
			(xy 332.764373 -152.008903) (xy 332.787015 -152.05848) (xy 332.80237 -152.110775) (xy 332.810126 -152.164723)
			(xy 332.810612 -152.191974) (xy 332.81012 -152.219949) (xy 332.801945 -152.275299) (xy 332.785768 -152.328859)
			(xy 332.761936 -152.379479) (xy 332.746858 -152.403048) (xy 332.741524 -152.410922) (xy 332.737714 -152.42921)
			(xy 332.74151 -152.454102) (xy 334.204056 -152.454102) (xy 334.204555 -152.425184) (xy 334.213285 -152.368011)
			(xy 334.230545 -152.312811) (xy 334.25594 -152.260849) (xy 334.288888 -152.213316) (xy 334.328634 -152.171301)
			(xy 334.351122 -152.153112) (xy 334.359918 -152.145494) (xy 334.370107 -152.124601) (xy 334.37068 -152.11298)
			(xy 334.37068 -152.033224) (xy 334.37012 -152.021595) (xy 334.359947 -152.000684) (xy 334.351122 -151.993092)
			(xy 334.328639 -151.9749) (xy 334.288903 -151.932881) (xy 334.255963 -151.885347) (xy 334.230575 -151.833385)
			(xy 334.213319 -151.778188) (xy 334.20459 -151.721018) (xy 334.204056 -151.692102) (xy 334.204542 -151.664851)
			(xy 334.212298 -151.610903) (xy 334.227653 -151.558608) (xy 334.250295 -151.509031) (xy 334.279761 -151.463181)
			(xy 334.315452 -151.42199) (xy 334.356643 -151.386299) (xy 334.402493 -151.356833) (xy 334.45207 -151.334191)
			(xy 334.504365 -151.318836) (xy 334.558313 -151.31108) (xy 334.612815 -151.31108) (xy 334.666763 -151.318836)
			(xy 334.719058 -151.334191) (xy 334.768635 -151.356833) (xy 334.814485 -151.386299) (xy 334.855676 -151.42199)
			(xy 334.891367 -151.463181) (xy 334.920833 -151.509031) (xy 334.943475 -151.558608) (xy 334.95883 -151.610903)
			(xy 334.966586 -151.664851) (xy 334.967072 -151.692102) (xy 334.966566 -151.721019) (xy 334.957836 -151.778192)
			(xy 334.940576 -151.833391) (xy 334.915182 -151.885353) (xy 334.882236 -151.932887) (xy 334.842493 -151.974903)
			(xy 334.820006 -151.993092) (xy 334.811213 -152.000713) (xy 334.801021 -152.021603) (xy 334.800448 -152.033224)
			(xy 334.800448 -152.11298) (xy 334.800996 -152.124611) (xy 334.811177 -152.145522) (xy 334.820006 -152.153112)
			(xy 334.842496 -152.171295) (xy 334.882231 -152.213316) (xy 334.915169 -152.260853) (xy 334.940556 -152.312816)
			(xy 334.957811 -152.368015) (xy 334.966538 -152.425186) (xy 334.967072 -152.454102) (xy 336.261456 -152.454102)
			(xy 336.261456 -151.692102) (xy 336.262048 -151.662125) (xy 336.271439 -151.60291) (xy 336.289973 -151.545891)
			(xy 336.317195 -151.492473) (xy 336.352436 -151.443968) (xy 336.373216 -151.422354) (xy 344.382598 -143.412972)
			(xy 344.40419 -143.392164) (xy 344.452692 -143.356908) (xy 344.506114 -143.329678) (xy 344.563141 -143.311145)
			(xy 344.622365 -143.301767) (xy 344.652346 -143.301212) (xy 350.92132 -143.301212) (xy 350.951297 -143.301803)
			(xy 351.010512 -143.311196) (xy 351.067529 -143.329731) (xy 351.120948 -143.356953) (xy 351.169453 -143.392192)
			(xy 351.191068 -143.412972) (xy 352.298081 -144.520158) (xy 371.53926 -144.520158) (xy 371.543331 -144.464536)
			(xy 371.555457 -144.410099) (xy 371.57538 -144.358008) (xy 371.602676 -144.309373) (xy 371.636762 -144.26523)
			(xy 371.676911 -144.226521) (xy 371.722269 -144.19407) (xy 371.771869 -144.168569) (xy 371.824653 -144.150562)
			(xy 371.879496 -144.140432) (xy 371.93523 -144.138395) (xy 371.990667 -144.144495) (xy 372.044624 -144.158601)
			(xy 372.095953 -144.180413) (xy 372.143559 -144.209467) (xy 372.186427 -144.245142) (xy 372.223644 -144.286679)
			(xy 372.254417 -144.333192) (xy 372.278089 -144.383689) (xy 372.294157 -144.437096) (xy 372.302277 -144.492272)
			(xy 372.302786 -144.520158) (xy 372.302277 -144.548044) (xy 372.294157 -144.60322) (xy 372.278089 -144.656627)
			(xy 372.254417 -144.707124) (xy 372.223644 -144.753637) (xy 372.186427 -144.795174) (xy 372.143559 -144.830849)
			(xy 372.095953 -144.859903) (xy 372.044624 -144.881715) (xy 371.990667 -144.895821) (xy 371.93523 -144.901921)
			(xy 371.879496 -144.899884) (xy 371.824653 -144.889754) (xy 371.771869 -144.871747) (xy 371.722269 -144.846246)
			(xy 371.676911 -144.813795) (xy 371.636762 -144.775086) (xy 371.602676 -144.730943) (xy 371.57538 -144.682308)
			(xy 371.555457 -144.630217) (xy 371.543331 -144.57578) (xy 371.53926 -144.520158) (xy 352.298081 -144.520158)
			(xy 352.815144 -145.037302) (xy 352.822535 -145.044154) (xy 352.841141 -145.051867) (xy 352.851212 -145.052288)
			(xy 366.60836 -145.052288) (xy 366.638278 -145.052897) (xy 366.697377 -145.06226) (xy 366.754286 -145.080747)
			(xy 366.807605 -145.107904) (xy 366.856023 -145.143061) (xy 366.8776 -145.163794) (xy 367.249933 -145.536158)
			(xy 371.53926 -145.536158) (xy 371.543331 -145.480536) (xy 371.555457 -145.426099) (xy 371.57538 -145.374008)
			(xy 371.602676 -145.325373) (xy 371.636762 -145.28123) (xy 371.676911 -145.242521) (xy 371.722269 -145.21007)
			(xy 371.771869 -145.184569) (xy 371.824653 -145.166562) (xy 371.879496 -145.156432) (xy 371.93523 -145.154395)
			(xy 371.990667 -145.160495) (xy 372.044624 -145.174601) (xy 372.095953 -145.196413) (xy 372.143559 -145.225467)
			(xy 372.186427 -145.261142) (xy 372.223644 -145.302679) (xy 372.254417 -145.349192) (xy 372.278089 -145.399689)
			(xy 372.294157 -145.453096) (xy 372.302277 -145.508272) (xy 372.302786 -145.536158) (xy 372.302277 -145.564044)
			(xy 372.294157 -145.61922) (xy 372.278089 -145.672627) (xy 372.254417 -145.723124) (xy 372.223644 -145.769637)
			(xy 372.186427 -145.811174) (xy 372.143559 -145.846849) (xy 372.095953 -145.875903) (xy 372.044624 -145.897715)
			(xy 371.990667 -145.911821) (xy 371.93523 -145.917921) (xy 371.879496 -145.915884) (xy 371.824653 -145.905754)
			(xy 371.771869 -145.887747) (xy 371.722269 -145.862246) (xy 371.676911 -145.829795) (xy 371.636762 -145.791086)
			(xy 371.602676 -145.746943) (xy 371.57538 -145.698308) (xy 371.555457 -145.646217) (xy 371.543331 -145.59178)
			(xy 371.53926 -145.536158) (xy 367.249933 -145.536158) (xy 368.265847 -146.552158) (xy 371.53926 -146.552158)
			(xy 371.543331 -146.496536) (xy 371.555457 -146.442099) (xy 371.57538 -146.390008) (xy 371.602676 -146.341373)
			(xy 371.636762 -146.29723) (xy 371.676911 -146.258521) (xy 371.722269 -146.22607) (xy 371.771869 -146.200569)
			(xy 371.824653 -146.182562) (xy 371.879496 -146.172432) (xy 371.93523 -146.170395) (xy 371.990667 -146.176495)
			(xy 372.044624 -146.190601) (xy 372.095953 -146.212413) (xy 372.143559 -146.241467) (xy 372.186427 -146.277142)
			(xy 372.223644 -146.318679) (xy 372.254417 -146.365192) (xy 372.278089 -146.415689) (xy 372.294157 -146.469096)
			(xy 372.302277 -146.524272) (xy 372.302786 -146.552158) (xy 372.302277 -146.580044) (xy 372.294157 -146.63522)
			(xy 372.278089 -146.688627) (xy 372.254417 -146.739124) (xy 372.223644 -146.785637) (xy 372.186427 -146.827174)
			(xy 372.143559 -146.862849) (xy 372.095953 -146.891903) (xy 372.044624 -146.913715) (xy 371.990667 -146.927821)
			(xy 371.93523 -146.933921) (xy 371.879496 -146.931884) (xy 371.824653 -146.921754) (xy 371.771869 -146.903747)
			(xy 371.722269 -146.878246) (xy 371.676911 -146.845795) (xy 371.636762 -146.807086) (xy 371.602676 -146.762943)
			(xy 371.57538 -146.714308) (xy 371.555457 -146.662217) (xy 371.543331 -146.60778) (xy 371.53926 -146.552158)
			(xy 368.265847 -146.552158) (xy 369.281762 -147.568158) (xy 371.53926 -147.568158) (xy 371.543331 -147.512536)
			(xy 371.555457 -147.458099) (xy 371.57538 -147.406008) (xy 371.602676 -147.357373) (xy 371.636762 -147.31323)
			(xy 371.676911 -147.274521) (xy 371.722269 -147.24207) (xy 371.771869 -147.216569) (xy 371.824653 -147.198562)
			(xy 371.879496 -147.188432) (xy 371.93523 -147.186395) (xy 371.990667 -147.192495) (xy 372.044624 -147.206601)
			(xy 372.095953 -147.228413) (xy 372.143559 -147.257467) (xy 372.186427 -147.293142) (xy 372.223644 -147.334679)
			(xy 372.254417 -147.381192) (xy 372.278089 -147.431689) (xy 372.294157 -147.485096) (xy 372.302277 -147.540272)
			(xy 372.302786 -147.568158) (xy 372.302277 -147.596044) (xy 372.294157 -147.65122) (xy 372.278089 -147.704627)
			(xy 372.254417 -147.755124) (xy 372.223644 -147.801637) (xy 372.186427 -147.843174) (xy 372.143559 -147.878849)
			(xy 372.095953 -147.907903) (xy 372.044624 -147.929715) (xy 371.990667 -147.943821) (xy 371.93523 -147.949921)
			(xy 371.879496 -147.947884) (xy 371.824653 -147.937754) (xy 371.771869 -147.919747) (xy 371.722269 -147.894246)
			(xy 371.676911 -147.861795) (xy 371.636762 -147.823086) (xy 371.602676 -147.778943) (xy 371.57538 -147.730308)
			(xy 371.555457 -147.678217) (xy 371.543331 -147.62378) (xy 371.53926 -147.568158) (xy 369.281762 -147.568158)
			(xy 369.893342 -148.17979) (xy 369.900735 -148.18664) (xy 369.919339 -148.194354) (xy 369.92941 -148.194776)
			(xy 372.5672 -148.194776) (xy 372.57727 -148.194357) (xy 372.595868 -148.186632) (xy 372.603268 -148.17979)
			(xy 374.50903 -146.274028) (xy 374.515855 -146.266616) (xy 374.523582 -146.248026) (xy 374.524016 -146.23796)
			(xy 374.524016 -143.565118) (xy 374.523604 -143.555047) (xy 374.515876 -143.536448) (xy 374.50903 -143.52905)
			(xy 374.50014 -143.52016) (xy 374.493316 -143.514005) (xy 374.476555 -143.506509) (xy 374.458229 -143.505386)
			(xy 374.44934 -143.507714) (xy 374.349518 -143.538702) (xy 374.330976 -143.55953) (xy 374.328436 -143.5735)
			(xy 374.323235 -143.599478) (xy 374.306482 -143.64974) (xy 374.282937 -143.697201) (xy 374.253052 -143.740948)
			(xy 374.217402 -143.780141) (xy 374.176673 -143.814024) (xy 374.131648 -143.841947) (xy 374.083193 -143.863372)
			(xy 374.03224 -143.877887) (xy 373.979768 -143.885214) (xy 373.953278 -143.885666) (xy 373.926023 -143.885265)
			(xy 373.872067 -143.877504) (xy 373.819766 -143.862143) (xy 373.770183 -143.839495) (xy 373.724327 -143.810021)
			(xy 373.683134 -143.774321) (xy 373.647441 -143.733121) (xy 373.617974 -143.687261) (xy 373.595334 -143.637674)
			(xy 373.579982 -143.58537) (xy 373.57223 -143.531413) (xy 373.57177 -143.504158) (xy 373.57229 -143.477672)
			(xy 373.579612 -143.425208) (xy 373.594122 -143.374262) (xy 373.615542 -143.325814) (xy 373.643459 -143.280795)
			(xy 373.677336 -143.240072) (xy 373.716523 -143.204428) (xy 373.760264 -143.174549) (xy 373.807719 -143.15101)
			(xy 373.857974 -143.134263) (xy 373.883936 -143.129) (xy 373.897906 -143.12646) (xy 373.918734 -143.107918)
			(xy 373.949722 -143.008096) (xy 373.951978 -142.999178) (xy 373.950784 -142.980838) (xy 373.943228 -142.964084)
			(xy 373.937022 -142.957296) (xy 373.81053 -142.830804) (xy 373.789829 -142.809199) (xy 373.754686 -142.760778)
			(xy 373.727531 -142.707465) (xy 373.70903 -142.650567) (xy 373.699635 -142.591479) (xy 373.699024 -142.561564)
			(xy 373.699024 -142.561056) (xy 373.699426 -142.534996) (xy 373.706531 -142.483363) (xy 373.720602 -142.433178)
			(xy 373.741378 -142.385378) (xy 373.76847 -142.340853) (xy 373.801375 -142.300433) (xy 373.839478 -142.264871)
			(xy 373.88207 -142.234831) (xy 373.905018 -142.222474) (xy 373.914721 -142.216752) (xy 373.928305 -142.198821)
			(xy 373.93118 -142.18793) (xy 373.949722 -142.099284) (xy 373.944388 -142.07744) (xy 373.937276 -142.06855)
			(xy 373.937276 -142.068296) (xy 373.921311 -142.047845) (xy 373.894452 -142.003457) (xy 373.87386 -141.955836)
			(xy 373.859917 -141.905863) (xy 373.852878 -141.854461) (xy 373.85244 -141.82852) (xy 373.852894 -141.800916)
			(xy 373.860837 -141.746283) (xy 373.876574 -141.693366) (xy 373.899777 -141.643271) (xy 373.929959 -141.597044)
			(xy 373.966492 -141.555653) (xy 374.008611 -141.519962) (xy 374.031764 -141.504924) (xy 374.042087 -141.497686)
			(xy 374.054605 -141.475834) (xy 374.05564 -141.463268) (xy 374.057926 -141.378686) (xy 374.057546 -141.365981)
			(xy 374.0461 -141.343326) (xy 374.036082 -141.335506) (xy 374.014869 -141.320146) (xy 373.976466 -141.284535)
			(xy 373.943296 -141.244005) (xy 373.91598 -141.199319) (xy 373.895034 -141.151317) (xy 373.88085 -141.100901)
			(xy 373.873696 -141.049019) (xy 373.873268 -141.022832) (xy 373.873754 -140.995581) (xy 373.88151 -140.941633)
			(xy 373.896865 -140.889338) (xy 373.919507 -140.839761) (xy 373.948973 -140.793911) (xy 373.984664 -140.75272)
			(xy 374.025855 -140.717029) (xy 374.071705 -140.687563) (xy 374.121282 -140.664921) (xy 374.173577 -140.649566)
			(xy 374.227525 -140.64181) (xy 374.282027 -140.64181) (xy 374.335975 -140.649566) (xy 374.38827 -140.664921)
			(xy 374.437847 -140.687563) (xy 374.483697 -140.717029) (xy 374.524888 -140.75272) (xy 374.560579 -140.793911)
			(xy 374.571232 -140.810488) (xy 382.559558 -140.810488) (xy 382.563629 -140.754866) (xy 382.575755 -140.700429)
			(xy 382.595678 -140.648338) (xy 382.622974 -140.599703) (xy 382.65706 -140.55556) (xy 382.697209 -140.516851)
			(xy 382.742567 -140.4844) (xy 382.792167 -140.458899) (xy 382.844951 -140.440892) (xy 382.899794 -140.430762)
			(xy 382.955528 -140.428725) (xy 383.010965 -140.434825) (xy 383.064922 -140.448931) (xy 383.116251 -140.470743)
			(xy 383.163857 -140.499797) (xy 383.206725 -140.535472) (xy 383.243942 -140.577009) (xy 383.274715 -140.623522)
			(xy 383.298387 -140.674019) (xy 383.314455 -140.727426) (xy 383.322575 -140.782602) (xy 383.323084 -140.810488)
			(xy 383.322575 -140.838374) (xy 383.314455 -140.89355) (xy 383.298387 -140.946957) (xy 383.274715 -140.997454)
			(xy 383.243942 -141.043967) (xy 383.206725 -141.085504) (xy 383.163857 -141.121179) (xy 383.116251 -141.150233)
			(xy 383.064922 -141.172045) (xy 383.010965 -141.186151) (xy 382.955528 -141.192251) (xy 382.899794 -141.190214)
			(xy 382.844951 -141.180084) (xy 382.792167 -141.162077) (xy 382.742567 -141.136576) (xy 382.697209 -141.104125)
			(xy 382.65706 -141.065416) (xy 382.622974 -141.021273) (xy 382.595678 -140.972638) (xy 382.575755 -140.920547)
			(xy 382.563629 -140.86611) (xy 382.559558 -140.810488) (xy 374.571232 -140.810488) (xy 374.590045 -140.839761)
			(xy 374.612687 -140.889338) (xy 374.628042 -140.941633) (xy 374.635798 -140.995581) (xy 374.636284 -141.022832)
			(xy 374.635828 -141.050436) (xy 374.62789 -141.105071) (xy 374.612156 -141.15799) (xy 374.588955 -141.208086)
			(xy 374.558771 -141.254313) (xy 374.522237 -141.295703) (xy 374.480115 -141.331392) (xy 374.45696 -141.346428)
			(xy 374.446643 -141.353672) (xy 374.434125 -141.37552) (xy 374.433084 -141.388084) (xy 374.430798 -141.472666)
			(xy 374.431137 -141.485376) (xy 374.442611 -141.508031) (xy 374.452642 -141.515846) (xy 374.473838 -141.531228)
			(xy 374.51224 -141.566837) (xy 374.545411 -141.607363) (xy 374.572728 -141.652045) (xy 374.593677 -141.700043)
			(xy 374.607865 -141.750456) (xy 374.615025 -141.802335) (xy 374.615456 -141.82852) (xy 374.614891 -141.856768)
			(xy 374.606544 -141.912644) (xy 374.59005 -141.966679) (xy 374.565769 -142.017692) (xy 374.534233 -142.064567)
			(xy 374.49613 -142.106281) (xy 374.452294 -142.141921) (xy 374.403682 -142.170708) (xy 374.377712 -142.181834)
			(xy 374.366326 -142.187095) (xy 374.35022 -142.206291) (xy 374.346978 -142.21841) (xy 374.334786 -142.277084)
			(xy 374.350026 -142.291308) (xy 375.175018 -143.1163) (xy 375.195711 -143.137912) (xy 375.230858 -143.18633)
			(xy 375.258015 -143.239641) (xy 375.276518 -143.296538) (xy 375.285913 -143.355626) (xy 375.286524 -143.38554)
			(xy 375.286524 -145.028158) (xy 381.31826 -145.028158) (xy 381.322331 -144.972536) (xy 381.334457 -144.918099)
			(xy 381.35438 -144.866008) (xy 381.381676 -144.817373) (xy 381.415762 -144.77323) (xy 381.455911 -144.734521)
			(xy 381.501269 -144.70207) (xy 381.550869 -144.676569) (xy 381.603653 -144.658562) (xy 381.658496 -144.648432)
			(xy 381.71423 -144.646395) (xy 381.769667 -144.652495) (xy 381.823624 -144.666601) (xy 381.874953 -144.688413)
			(xy 381.922559 -144.717467) (xy 381.965427 -144.753142) (xy 382.002644 -144.794679) (xy 382.033417 -144.841192)
			(xy 382.057089 -144.891689) (xy 382.073157 -144.945096) (xy 382.081277 -145.000272) (xy 382.081786 -145.028158)
			(xy 382.081277 -145.056044) (xy 382.073157 -145.11122) (xy 382.057089 -145.164627) (xy 382.033417 -145.215124)
			(xy 382.002644 -145.261637) (xy 381.965427 -145.303174) (xy 381.922559 -145.338849) (xy 381.874953 -145.367903)
			(xy 381.823624 -145.389715) (xy 381.769667 -145.403821) (xy 381.71423 -145.409921) (xy 381.658496 -145.407884)
			(xy 381.603653 -145.397754) (xy 381.550869 -145.379747) (xy 381.501269 -145.354246) (xy 381.455911 -145.321795)
			(xy 381.415762 -145.283086) (xy 381.381676 -145.238943) (xy 381.35438 -145.190308) (xy 381.334457 -145.138217)
			(xy 381.322331 -145.08378) (xy 381.31826 -145.028158) (xy 375.286524 -145.028158) (xy 375.286524 -146.417538)
			(xy 375.285898 -146.447455) (xy 375.284401 -146.456908) (xy 378.786388 -146.456908) (xy 378.790459 -146.401286)
			(xy 378.802585 -146.346849) (xy 378.822508 -146.294758) (xy 378.849804 -146.246123) (xy 378.88389 -146.20198)
			(xy 378.924039 -146.163271) (xy 378.969397 -146.13082) (xy 379.018997 -146.105319) (xy 379.071781 -146.087312)
			(xy 379.126624 -146.077182) (xy 379.182358 -146.075145) (xy 379.237795 -146.081245) (xy 379.291752 -146.095351)
			(xy 379.343081 -146.117163) (xy 379.390687 -146.146217) (xy 379.433555 -146.181892) (xy 379.470772 -146.223429)
			(xy 379.501545 -146.269942) (xy 379.525217 -146.320439) (xy 379.541285 -146.373846) (xy 379.549405 -146.429022)
			(xy 379.549914 -146.456908) (xy 379.549405 -146.484794) (xy 379.541285 -146.53997) (xy 379.525217 -146.593377)
			(xy 379.501545 -146.643874) (xy 379.470772 -146.690387) (xy 379.438275 -146.726656) (xy 381.080516 -146.726656)
			(xy 381.084587 -146.671034) (xy 381.096713 -146.616597) (xy 381.116636 -146.564506) (xy 381.143932 -146.515871)
			(xy 381.178018 -146.471728) (xy 381.218167 -146.433019) (xy 381.263525 -146.400568) (xy 381.313125 -146.375067)
			(xy 381.365909 -146.35706) (xy 381.420752 -146.34693) (xy 381.476486 -146.344893) (xy 381.531923 -146.350993)
			(xy 381.58588 -146.365099) (xy 381.637209 -146.386911) (xy 381.684815 -146.415965) (xy 381.727683 -146.45164)
			(xy 381.7649 -146.493177) (xy 381.795673 -146.53969) (xy 381.819345 -146.590187) (xy 381.835413 -146.643594)
			(xy 381.843533 -146.69877) (xy 381.844042 -146.726656) (xy 381.843533 -146.754542) (xy 381.835413 -146.809718)
			(xy 381.819345 -146.863125) (xy 381.795673 -146.913622) (xy 381.7649 -146.960135) (xy 381.727683 -147.001672)
			(xy 381.684815 -147.037347) (xy 381.637209 -147.066401) (xy 381.58588 -147.088213) (xy 381.531923 -147.102319)
			(xy 381.476486 -147.108419) (xy 381.420752 -147.106382) (xy 381.365909 -147.096252) (xy 381.313125 -147.078245)
			(xy 381.263525 -147.052744) (xy 381.218167 -147.020293) (xy 381.178018 -146.981584) (xy 381.143932 -146.937441)
			(xy 381.116636 -146.888806) (xy 381.096713 -146.836715) (xy 381.084587 -146.782278) (xy 381.080516 -146.726656)
			(xy 379.438275 -146.726656) (xy 379.433555 -146.731924) (xy 379.390687 -146.767599) (xy 379.343081 -146.796653)
			(xy 379.291752 -146.818465) (xy 379.237795 -146.832571) (xy 379.182358 -146.838671) (xy 379.126624 -146.836634)
			(xy 379.071781 -146.826504) (xy 379.018997 -146.808497) (xy 378.969397 -146.782996) (xy 378.924039 -146.750545)
			(xy 378.88389 -146.711836) (xy 378.849804 -146.667693) (xy 378.822508 -146.619058) (xy 378.802585 -146.566967)
			(xy 378.790459 -146.51253) (xy 378.786388 -146.456908) (xy 375.284401 -146.456908) (xy 375.276538 -146.506553)
			(xy 375.258055 -146.563462) (xy 375.230903 -146.616781) (xy 375.195749 -146.6652) (xy 375.175018 -146.686778)
			(xy 374.443244 -147.418552) (xy 376.64212 -147.418552) (xy 376.646191 -147.36293) (xy 376.658317 -147.308493)
			(xy 376.67824 -147.256402) (xy 376.705536 -147.207767) (xy 376.739622 -147.163624) (xy 376.779771 -147.124915)
			(xy 376.825129 -147.092464) (xy 376.874729 -147.066963) (xy 376.927513 -147.048956) (xy 376.982356 -147.038826)
			(xy 377.03809 -147.036789) (xy 377.093527 -147.042889) (xy 377.147484 -147.056995) (xy 377.198813 -147.078807)
			(xy 377.246419 -147.107861) (xy 377.289287 -147.143536) (xy 377.326504 -147.185073) (xy 377.357277 -147.231586)
			(xy 377.380949 -147.282083) (xy 377.397017 -147.33549) (xy 377.405137 -147.390666) (xy 377.405646 -147.418552)
			(xy 377.405137 -147.446438) (xy 377.398027 -147.494752) (xy 378.25045 -147.494752) (xy 378.250936 -147.467501)
			(xy 378.258692 -147.413553) (xy 378.274047 -147.361258) (xy 378.296689 -147.311681) (xy 378.326155 -147.265831)
			(xy 378.361846 -147.22464) (xy 378.403037 -147.188949) (xy 378.448887 -147.159483) (xy 378.498464 -147.136841)
			(xy 378.550759 -147.121486) (xy 378.604707 -147.11373) (xy 378.659209 -147.11373) (xy 378.713157 -147.121486)
			(xy 378.765452 -147.136841) (xy 378.815029 -147.159483) (xy 378.860879 -147.188949) (xy 378.90207 -147.22464)
			(xy 378.937761 -147.265831) (xy 378.967227 -147.311681) (xy 378.989869 -147.361258) (xy 379.005224 -147.413553)
			(xy 379.01298 -147.467501) (xy 379.013466 -147.494752) (xy 379.013466 -147.49526) (xy 379.012933 -147.524122)
			(xy 379.004207 -147.581184) (xy 378.98698 -147.636278) (xy 378.961644 -147.688146) (xy 378.945648 -147.712176)
			(xy 378.93821 -147.723591) (xy 378.929195 -147.749296) (xy 378.927304 -147.776469) (xy 378.932672 -147.803174)
			(xy 378.944916 -147.827507) (xy 378.963162 -147.847732) (xy 378.98611 -147.862406) (xy 378.998988 -147.866862)
			(xy 379.024571 -147.875301) (xy 379.073263 -147.898344) (xy 379.11823 -147.928006) (xy 379.158579 -147.963697)
			(xy 379.193506 -148.004709) (xy 379.222318 -148.050226) (xy 379.244442 -148.099343) (xy 379.259437 -148.151083)
			(xy 379.267007 -148.204417) (xy 379.267466 -148.231352) (xy 379.26698 -148.258603) (xy 379.259224 -148.312551)
			(xy 379.243869 -148.364846) (xy 379.221227 -148.414423) (xy 379.191761 -148.460273) (xy 379.15607 -148.501464)
			(xy 379.114879 -148.537155) (xy 379.069029 -148.566621) (xy 379.019452 -148.589263) (xy 378.967157 -148.604618)
			(xy 378.913209 -148.612374) (xy 378.858707 -148.612374) (xy 378.804759 -148.604618) (xy 378.752464 -148.589263)
			(xy 378.702887 -148.566621) (xy 378.657037 -148.537155) (xy 378.615846 -148.501464) (xy 378.580155 -148.460273)
			(xy 378.550689 -148.414423) (xy 378.528047 -148.364846) (xy 378.512692 -148.312551) (xy 378.504936 -148.258603)
			(xy 378.50445 -148.231352) (xy 378.50445 -148.230844) (xy 378.504982 -148.201982) (xy 378.513708 -148.14492)
			(xy 378.530936 -148.089826) (xy 378.556272 -148.037958) (xy 378.572268 -148.013928) (xy 378.579693 -148.002505)
			(xy 378.588706 -147.976804) (xy 378.590597 -147.949633) (xy 378.585231 -147.92293) (xy 378.57299 -147.8986)
			(xy 378.554747 -147.878375) (xy 378.531804 -147.863699) (xy 378.518928 -147.859242) (xy 378.49335 -147.85079)
			(xy 378.444657 -147.827749) (xy 378.39969 -147.79809) (xy 378.359341 -147.7624) (xy 378.324413 -147.721389)
			(xy 378.2956 -147.675874) (xy 378.273476 -147.626759) (xy 378.25848 -147.57502) (xy 378.25091 -147.521686)
			(xy 378.25045 -147.494752) (xy 377.398027 -147.494752) (xy 377.397017 -147.501614) (xy 377.380949 -147.555021)
			(xy 377.357277 -147.605518) (xy 377.326504 -147.652031) (xy 377.289287 -147.693568) (xy 377.246419 -147.729243)
			(xy 377.198813 -147.758297) (xy 377.147484 -147.780109) (xy 377.093527 -147.794215) (xy 377.03809 -147.800315)
			(xy 376.982356 -147.798278) (xy 376.927513 -147.788148) (xy 376.874729 -147.770141) (xy 376.825129 -147.74464)
			(xy 376.779771 -147.712189) (xy 376.739622 -147.67348) (xy 376.705536 -147.629337) (xy 376.67824 -147.580702)
			(xy 376.658317 -147.528611) (xy 376.646191 -147.474174) (xy 376.64212 -147.418552) (xy 374.443244 -147.418552)
			(xy 373.489728 -148.372068) (xy 375.095514 -148.372068) (xy 375.099585 -148.316446) (xy 375.111711 -148.262009)
			(xy 375.131634 -148.209918) (xy 375.15893 -148.161283) (xy 375.193016 -148.11714) (xy 375.233165 -148.078431)
			(xy 375.278523 -148.04598) (xy 375.328123 -148.020479) (xy 375.380907 -148.002472) (xy 375.43575 -147.992342)
			(xy 375.491484 -147.990305) (xy 375.546921 -147.996405) (xy 375.600878 -148.010511) (xy 375.652207 -148.032323)
			(xy 375.699813 -148.061377) (xy 375.742681 -148.097052) (xy 375.779898 -148.138589) (xy 375.810671 -148.185102)
			(xy 375.834343 -148.235599) (xy 375.850411 -148.289006) (xy 375.858531 -148.344182) (xy 375.85904 -148.372068)
			(xy 375.858531 -148.399954) (xy 375.850411 -148.45513) (xy 375.834343 -148.508537) (xy 375.810671 -148.559034)
			(xy 375.779898 -148.605547) (xy 375.742681 -148.647084) (xy 375.699813 -148.682759) (xy 375.653696 -148.710904)
			(xy 376.020074 -148.710904) (xy 376.024145 -148.655282) (xy 376.036271 -148.600845) (xy 376.056194 -148.548754)
			(xy 376.08349 -148.500119) (xy 376.117576 -148.455976) (xy 376.157725 -148.417267) (xy 376.203083 -148.384816)
			(xy 376.252683 -148.359315) (xy 376.305467 -148.341308) (xy 376.36031 -148.331178) (xy 376.416044 -148.329141)
			(xy 376.471481 -148.335241) (xy 376.525438 -148.349347) (xy 376.576767 -148.371159) (xy 376.624373 -148.400213)
			(xy 376.667241 -148.435888) (xy 376.704458 -148.477425) (xy 376.735231 -148.523938) (xy 376.758903 -148.574435)
			(xy 376.774971 -148.627842) (xy 376.783091 -148.683018) (xy 376.7836 -148.710904) (xy 376.783091 -148.73879)
			(xy 376.777027 -148.779992) (xy 377.483622 -148.779992) (xy 377.487693 -148.72437) (xy 377.499819 -148.669933)
			(xy 377.519742 -148.617842) (xy 377.547038 -148.569207) (xy 377.581124 -148.525064) (xy 377.621273 -148.486355)
			(xy 377.666631 -148.453904) (xy 377.716231 -148.428403) (xy 377.769015 -148.410396) (xy 377.823858 -148.400266)
			(xy 377.879592 -148.398229) (xy 377.935029 -148.404329) (xy 377.988986 -148.418435) (xy 378.040315 -148.440247)
			(xy 378.087921 -148.469301) (xy 378.130789 -148.504976) (xy 378.168006 -148.546513) (xy 378.198779 -148.593026)
			(xy 378.222451 -148.643523) (xy 378.238519 -148.69693) (xy 378.246639 -148.752106) (xy 378.247148 -148.779992)
			(xy 378.246639 -148.807878) (xy 378.238519 -148.863054) (xy 378.222451 -148.916461) (xy 378.198779 -148.966958)
			(xy 378.168006 -149.013471) (xy 378.130789 -149.055008) (xy 378.087921 -149.090683) (xy 378.040315 -149.119737)
			(xy 377.988986 -149.141549) (xy 377.935029 -149.155655) (xy 377.879592 -149.161755) (xy 377.823858 -149.159718)
			(xy 377.769015 -149.149588) (xy 377.716231 -149.131581) (xy 377.666631 -149.10608) (xy 377.621273 -149.073629)
			(xy 377.581124 -149.03492) (xy 377.547038 -148.990777) (xy 377.519742 -148.942142) (xy 377.499819 -148.890051)
			(xy 377.487693 -148.835614) (xy 377.483622 -148.779992) (xy 376.777027 -148.779992) (xy 376.774971 -148.793966)
			(xy 376.758903 -148.847373) (xy 376.735231 -148.89787) (xy 376.704458 -148.944383) (xy 376.667241 -148.98592)
			(xy 376.624373 -149.021595) (xy 376.576767 -149.050649) (xy 376.525438 -149.072461) (xy 376.471481 -149.086567)
			(xy 376.416044 -149.092667) (xy 376.36031 -149.09063) (xy 376.305467 -149.0805) (xy 376.252683 -149.062493)
			(xy 376.203083 -149.036992) (xy 376.157725 -149.004541) (xy 376.117576 -148.965832) (xy 376.08349 -148.921689)
			(xy 376.056194 -148.873054) (xy 376.036271 -148.820963) (xy 376.024145 -148.766526) (xy 376.020074 -148.710904)
			(xy 375.653696 -148.710904) (xy 375.652207 -148.711813) (xy 375.600878 -148.733625) (xy 375.546921 -148.747731)
			(xy 375.491484 -148.753831) (xy 375.43575 -148.751794) (xy 375.380907 -148.741664) (xy 375.328123 -148.723657)
			(xy 375.278523 -148.698156) (xy 375.233165 -148.665705) (xy 375.193016 -148.626996) (xy 375.15893 -148.582853)
			(xy 375.131634 -148.534218) (xy 375.111711 -148.482127) (xy 375.099585 -148.42769) (xy 375.095514 -148.372068)
			(xy 373.489728 -148.372068) (xy 373.016018 -148.845778) (xy 372.994452 -148.866521) (xy 372.94602 -148.901658)
			(xy 372.892697 -148.928805) (xy 372.835791 -148.947297) (xy 372.776695 -148.956679) (xy 372.746778 -148.957284)
			(xy 369.749832 -148.957284) (xy 369.719913 -148.956688) (xy 369.660813 -148.947323) (xy 369.603904 -148.928833)
			(xy 369.550586 -148.901674) (xy 369.502168 -148.866513) (xy 369.480592 -148.845778) (xy 366.46485 -145.829782)
			(xy 366.457429 -145.822969) (xy 366.438846 -145.815234) (xy 366.428782 -145.814796) (xy 352.671634 -145.814796)
			(xy 352.641716 -145.814195) (xy 352.582616 -145.804831) (xy 352.525707 -145.786342) (xy 352.472388 -145.759184)
			(xy 352.423971 -145.724024) (xy 352.402394 -145.70329) (xy 350.778318 -144.079214) (xy 350.770904 -144.072391)
			(xy 350.752316 -144.064661) (xy 350.74225 -144.064228) (xy 344.831416 -144.064228) (xy 344.821347 -144.064654)
			(xy 344.802748 -144.072373) (xy 344.795348 -144.079214) (xy 340.9696 -147.904962) (xy 344.785959 -147.904962)
			(xy 344.789955 -147.743437) (xy 344.801934 -147.582308) (xy 344.821868 -147.421968) (xy 344.849706 -147.26281)
			(xy 344.885381 -147.105224) (xy 344.928806 -146.949595) (xy 344.979874 -146.796304) (xy 345.038461 -146.645725)
			(xy 345.104422 -146.498229) (xy 345.177597 -146.354175) (xy 345.257807 -146.213915) (xy 345.344854 -146.077795)
			(xy 345.438527 -145.946145) (xy 345.538596 -145.819289) (xy 345.644816 -145.697537) (xy 345.756927 -145.581187)
			(xy 345.874654 -145.470524) (xy 345.997711 -145.365818) (xy 346.125794 -145.267326) (xy 346.258592 -145.175289)
			(xy 346.395779 -145.089931) (xy 346.53702 -145.011463) (xy 346.681968 -144.940075) (xy 346.830269 -144.875943)
			(xy 346.981561 -144.819223) (xy 347.135472 -144.770055) (xy 347.291626 -144.728558) (xy 347.449642 -144.694835)
			(xy 347.609132 -144.668967) (xy 347.769706 -144.651018) (xy 347.930971 -144.641033) (xy 348.092533 -144.639034)
			(xy 348.253995 -144.645028) (xy 348.414964 -144.659) (xy 348.575045 -144.680915) (xy 348.733847 -144.710719)
			(xy 348.89098 -144.748341) (xy 349.04606 -144.793687) (xy 349.198708 -144.846647) (xy 349.34855 -144.907092)
			(xy 349.49522 -144.974872) (xy 349.638358 -145.049823) (xy 349.777614 -145.131761) (xy 349.912648 -145.220486)
			(xy 350.043129 -145.31578) (xy 350.168737 -145.41741) (xy 350.289166 -145.525128) (xy 350.40412 -145.638669)
			(xy 350.513319 -145.757756) (xy 350.616495 -145.882098) (xy 350.713396 -146.01139) (xy 350.803783 -146.145317)
			(xy 350.887438 -146.283549) (xy 350.964153 -146.425749) (xy 350.997569 -146.49577) (xy 365.860584 -146.49577)
			(xy 365.86105 -146.468518) (xy 365.86881 -146.41457) (xy 365.884169 -146.362276) (xy 365.906813 -146.312699)
			(xy 365.936282 -146.266849) (xy 365.971975 -146.225659) (xy 366.013167 -146.189968) (xy 366.059018 -146.160502)
			(xy 366.108596 -146.137861) (xy 366.160892 -146.122506) (xy 366.21484 -146.114748) (xy 366.242092 -146.114262)
			(xy 366.270869 -146.114762) (xy 366.327773 -146.123393) (xy 366.382734 -146.140474) (xy 366.434505 -146.165618)
			(xy 366.481912 -146.198254) (xy 366.523877 -146.237642) (xy 366.559448 -146.282888) (xy 366.587819 -146.332964)
			(xy 366.608345 -146.386734) (xy 366.614964 -146.414744) (xy 366.616488 -146.42211) (xy 366.623346 -146.43481)
			(xy 369.567968 -149.379432) (xy 375.095514 -149.379432) (xy 375.099585 -149.32381) (xy 375.111711 -149.269373)
			(xy 375.131634 -149.217282) (xy 375.15893 -149.168647) (xy 375.193016 -149.124504) (xy 375.233165 -149.085795)
			(xy 375.278523 -149.053344) (xy 375.328123 -149.027843) (xy 375.380907 -149.009836) (xy 375.43575 -148.999706)
			(xy 375.491484 -148.997669) (xy 375.546921 -149.003769) (xy 375.600878 -149.017875) (xy 375.652207 -149.039687)
			(xy 375.699813 -149.068741) (xy 375.742681 -149.104416) (xy 375.779898 -149.145953) (xy 375.810671 -149.192466)
			(xy 375.834343 -149.242963) (xy 375.850411 -149.29637) (xy 375.858531 -149.351546) (xy 375.85904 -149.379432)
			(xy 375.858531 -149.407318) (xy 375.850411 -149.462494) (xy 375.834343 -149.515901) (xy 375.810671 -149.566398)
			(xy 375.779898 -149.612911) (xy 375.742681 -149.654448) (xy 375.699813 -149.690123) (xy 375.652207 -149.719177)
			(xy 375.600878 -149.740989) (xy 375.546921 -149.755095) (xy 375.491484 -149.761195) (xy 375.43575 -149.759158)
			(xy 375.380907 -149.749028) (xy 375.328123 -149.731021) (xy 375.278523 -149.70552) (xy 375.233165 -149.673069)
			(xy 375.193016 -149.63436) (xy 375.15893 -149.590217) (xy 375.131634 -149.541582) (xy 375.111711 -149.489491)
			(xy 375.099585 -149.435054) (xy 375.095514 -149.379432) (xy 369.567968 -149.379432) (xy 370.091462 -149.902926)
			(xy 370.098878 -149.909746) (xy 370.117465 -149.917477) (xy 370.12753 -149.917912) (xy 381.315976 -149.917912)
			(xy 381.326047 -149.917498) (xy 381.344646 -149.909772) (xy 381.352044 -149.902926) (xy 382.281938 -148.973032)
			(xy 382.288762 -148.965619) (xy 382.29649 -148.94703) (xy 382.296924 -148.936964) (xy 382.296924 -144.839182)
			(xy 382.296528 -144.829109) (xy 382.288789 -144.81051) (xy 382.281938 -144.803114) (xy 381.896366 -144.417796)
			(xy 381.879308 -144.400079) (xy 381.850388 -144.360302) (xy 381.828048 -144.316491) (xy 381.812839 -144.269723)
			(xy 381.805134 -144.221151) (xy 381.804672 -144.196562) (xy 381.804672 -143.157956) (xy 381.805105 -143.133364)
			(xy 381.812799 -143.084785) (xy 381.828008 -143.038011) (xy 381.850354 -142.994196) (xy 381.879287 -142.954422)
			(xy 381.896366 -142.936722) (xy 382.228344 -142.604998) (xy 382.235202 -142.592298) (xy 382.236726 -142.584932)
			(xy 382.243311 -142.55693) (xy 382.263843 -142.503196) (xy 382.292206 -142.453152) (xy 382.327759 -142.407931)
			(xy 382.369695 -142.368558) (xy 382.417065 -142.335924) (xy 382.468796 -142.310769) (xy 382.523717 -142.293662)
			(xy 382.580583 -142.284991) (xy 382.609344 -142.28445) (xy 382.609852 -142.28445) (xy 382.626108 -142.284704)
			(xy 382.637538 -142.285212) (xy 382.659382 -142.275814) (xy 382.718818 -142.205964) (xy 382.725932 -142.196694)
			(xy 382.731629 -142.174061) (xy 382.72974 -142.16253) (xy 382.726084 -142.143563) (xy 382.722137 -142.105136)
			(xy 382.721866 -142.085822) (xy 382.721866 -142.08506) (xy 382.722352 -142.057809) (xy 382.730108 -142.003861)
			(xy 382.745463 -141.951566) (xy 382.768105 -141.901989) (xy 382.797571 -141.856139) (xy 382.833262 -141.814948)
			(xy 382.874453 -141.779257) (xy 382.920303 -141.749791) (xy 382.96988 -141.727149) (xy 383.022175 -141.711794)
			(xy 383.076123 -141.704038) (xy 383.130625 -141.704038) (xy 383.184573 -141.711794) (xy 383.236868 -141.727149)
			(xy 383.286445 -141.749791) (xy 383.332295 -141.779257) (xy 383.373486 -141.814948) (xy 383.409177 -141.856139)
			(xy 383.438643 -141.901989) (xy 383.461285 -141.951566) (xy 383.47664 -142.003861) (xy 383.484396 -142.057809)
			(xy 383.484882 -142.08506) (xy 383.484385 -142.1123) (xy 383.47664 -142.166226) (xy 383.461302 -142.218502)
			(xy 383.438682 -142.268064) (xy 383.409241 -142.313903) (xy 383.373578 -142.355088) (xy 383.332418 -142.39078)
			(xy 383.286599 -142.420253) (xy 383.237053 -142.442908) (xy 383.184788 -142.458283) (xy 383.130868 -142.466066)
			(xy 383.103628 -142.466568) (xy 383.10312 -142.466568) (xy 383.086864 -142.466314) (xy 383.075434 -142.465806)
			(xy 383.05359 -142.475204) (xy 382.994154 -142.545054) (xy 382.987027 -142.554316) (xy 382.981339 -142.576956)
			(xy 382.983232 -142.588488) (xy 382.986892 -142.607454) (xy 382.990836 -142.645882) (xy 382.991106 -142.665196)
			(xy 382.991106 -142.665958) (xy 382.990505 -142.695943) (xy 382.983157 -142.742158) (xy 385.5245 -142.742158)
			(xy 385.528571 -142.686536) (xy 385.540697 -142.632099) (xy 385.56062 -142.580008) (xy 385.587916 -142.531373)
			(xy 385.622002 -142.48723) (xy 385.662151 -142.448521) (xy 385.707509 -142.41607) (xy 385.757109 -142.390569)
			(xy 385.809893 -142.372562) (xy 385.864736 -142.362432) (xy 385.92047 -142.360395) (xy 385.975907 -142.366495)
			(xy 386.029864 -142.380601) (xy 386.081193 -142.402413) (xy 386.128799 -142.431467) (xy 386.171667 -142.467142)
			(xy 386.208884 -142.508679) (xy 386.239657 -142.555192) (xy 386.263329 -142.605689) (xy 386.279397 -142.659096)
			(xy 386.287517 -142.714272) (xy 386.288026 -142.742158) (xy 386.287517 -142.770044) (xy 386.279397 -142.82522)
			(xy 386.263329 -142.878627) (xy 386.239657 -142.929124) (xy 386.208884 -142.975637) (xy 386.19687 -142.989046)
			(xy 388.931912 -142.989046) (xy 388.932398 -142.961795) (xy 388.940154 -142.907847) (xy 388.955509 -142.855552)
			(xy 388.978151 -142.805975) (xy 389.007617 -142.760125) (xy 389.043308 -142.718934) (xy 389.084499 -142.683243)
			(xy 389.130349 -142.653777) (xy 389.179926 -142.631135) (xy 389.232221 -142.61578) (xy 389.286169 -142.608024)
			(xy 389.340671 -142.608024) (xy 389.394619 -142.61578) (xy 389.446914 -142.631135) (xy 389.496491 -142.653777)
			(xy 389.542341 -142.683243) (xy 389.583532 -142.718934) (xy 389.611358 -142.751048) (xy 392.29868 -142.751048)
			(xy 392.302751 -142.695426) (xy 392.314877 -142.640989) (xy 392.3348 -142.588898) (xy 392.362096 -142.540263)
			(xy 392.396182 -142.49612) (xy 392.436331 -142.457411) (xy 392.481689 -142.42496) (xy 392.531289 -142.399459)
			(xy 392.584073 -142.381452) (xy 392.638916 -142.371322) (xy 392.69465 -142.369285) (xy 392.750087 -142.375385)
			(xy 392.804044 -142.389491) (xy 392.855373 -142.411303) (xy 392.902979 -142.440357) (xy 392.945847 -142.476032)
			(xy 392.983064 -142.517569) (xy 393.013837 -142.564082) (xy 393.037509 -142.614579) (xy 393.053577 -142.667986)
			(xy 393.061697 -142.723162) (xy 393.062206 -142.751048) (xy 393.061697 -142.778934) (xy 393.053577 -142.83411)
			(xy 393.037509 -142.887517) (xy 393.013837 -142.938014) (xy 392.983064 -142.984527) (xy 392.945847 -143.026064)
			(xy 392.902979 -143.061739) (xy 392.855373 -143.090793) (xy 392.804044 -143.112605) (xy 392.750087 -143.126711)
			(xy 392.69465 -143.132811) (xy 392.638916 -143.130774) (xy 392.584073 -143.120644) (xy 392.531289 -143.102637)
			(xy 392.481689 -143.077136) (xy 392.436331 -143.044685) (xy 392.396182 -143.005976) (xy 392.362096 -142.961833)
			(xy 392.3348 -142.913198) (xy 392.314877 -142.861107) (xy 392.302751 -142.80667) (xy 392.29868 -142.751048)
			(xy 389.611358 -142.751048) (xy 389.619223 -142.760125) (xy 389.648689 -142.805975) (xy 389.671331 -142.855552)
			(xy 389.686686 -142.907847) (xy 389.694442 -142.961795) (xy 389.694928 -142.989046) (xy 389.69442 -143.008096)
			(xy 389.694231 -143.021559) (xy 389.699969 -143.047851) (xy 389.71237 -143.071735) (xy 389.730574 -143.091555)
			(xy 389.75332 -143.105937) (xy 389.779032 -143.113884) (xy 389.792464 -143.114776) (xy 389.819095 -143.116143)
			(xy 389.871619 -143.125347) (xy 389.922349 -143.141777) (xy 389.970296 -143.165112) (xy 390.014525 -143.194899)
			(xy 390.054174 -143.230556) (xy 390.08847 -143.271388) (xy 390.116745 -143.316598) (xy 390.138446 -143.365307)
			(xy 390.153152 -143.416563) (xy 390.160575 -143.469368) (xy 390.161018 -143.49603) (xy 390.160532 -143.523281)
			(xy 390.152776 -143.577229) (xy 390.137421 -143.629524) (xy 390.114779 -143.679101) (xy 390.085313 -143.724951)
			(xy 390.049622 -143.766142) (xy 390.008431 -143.801833) (xy 389.962581 -143.831299) (xy 389.913004 -143.853941)
			(xy 389.860709 -143.869296) (xy 389.806761 -143.877052) (xy 389.752259 -143.877052) (xy 389.698311 -143.869296)
			(xy 389.646016 -143.853941) (xy 389.596439 -143.831299) (xy 389.550589 -143.801833) (xy 389.509398 -143.766142)
			(xy 389.473707 -143.724951) (xy 389.444241 -143.679101) (xy 389.421599 -143.629524) (xy 389.406244 -143.577229)
			(xy 389.398488 -143.523281) (xy 389.398002 -143.49603) (xy 389.39851 -143.47698) (xy 389.398788 -143.463515)
			(xy 389.39304 -143.43721) (xy 389.380624 -143.413318) (xy 389.362401 -143.393496) (xy 389.339635 -143.379119)
			(xy 389.313906 -143.371183) (xy 389.300466 -143.3703) (xy 389.273829 -143.36902) (xy 389.221302 -143.359806)
			(xy 389.170569 -143.343366) (xy 389.122621 -143.32002) (xy 389.078391 -143.290224) (xy 389.038743 -143.254559)
			(xy 389.004448 -143.213719) (xy 388.976175 -143.1685) (xy 388.954476 -143.119785) (xy 388.939773 -143.068522)
			(xy 388.932353 -143.015711) (xy 388.931912 -142.989046) (xy 386.19687 -142.989046) (xy 386.171667 -143.017174)
			(xy 386.128799 -143.052849) (xy 386.081193 -143.081903) (xy 386.029864 -143.103715) (xy 385.975907 -143.117821)
			(xy 385.92047 -143.123921) (xy 385.864736 -143.121884) (xy 385.809893 -143.111754) (xy 385.757109 -143.093747)
			(xy 385.707509 -143.068246) (xy 385.662151 -143.035795) (xy 385.622002 -142.997086) (xy 385.587916 -142.952943)
			(xy 385.56062 -142.904308) (xy 385.540697 -142.852217) (xy 385.528571 -142.79778) (xy 385.5245 -142.742158)
			(xy 382.983157 -142.742158) (xy 382.981088 -142.755171) (xy 382.962541 -142.812202) (xy 382.94945 -142.839186)
			(xy 382.944869 -142.849292) (xy 382.944096 -142.871443) (xy 382.947926 -142.881858) (xy 382.98247 -142.9639)
			(xy 382.999234 -142.978886) (xy 383.009902 -142.982188) (xy 383.035496 -142.990596) (xy 383.084189 -143.013642)
			(xy 383.129157 -143.043308) (xy 383.169505 -143.079004) (xy 383.204431 -143.12002) (xy 383.233242 -143.165541)
			(xy 383.255363 -143.214661) (xy 383.270356 -143.266404) (xy 383.277922 -143.319742) (xy 383.27838 -143.346678)
			(xy 383.277924 -143.373932) (xy 383.270169 -143.427884) (xy 383.254815 -143.480184) (xy 383.232173 -143.529766)
			(xy 383.202704 -143.57562) (xy 383.16701 -143.616814) (xy 383.125816 -143.652508) (xy 383.079961 -143.681976)
			(xy 383.030378 -143.704617) (xy 382.978078 -143.719971) (xy 382.924126 -143.727725) (xy 382.896872 -143.728186)
			(xy 382.869647 -143.727714) (xy 382.815753 -143.71995) (xy 382.763512 -143.704598) (xy 382.713986 -143.681972)
			(xy 382.668182 -143.652529) (xy 382.627032 -143.616871) (xy 382.608836 -143.596614) (xy 382.601723 -143.58921)
			(xy 382.583239 -143.580308) (xy 382.562748 -143.579299) (xy 382.552956 -143.58239) (xy 382.463548 -143.615664)
			(xy 382.454016 -143.619723) (xy 382.439041 -143.634011) (xy 382.430956 -143.653064) (xy 382.430528 -143.663416)
			(xy 382.430528 -144.04594) (xy 382.430925 -144.056013) (xy 382.438665 -144.074611) (xy 382.445514 -144.082008)
			(xy 382.830832 -144.467326) (xy 382.847833 -144.485011) (xy 382.876648 -144.524712) (xy 382.898911 -144.568425)
			(xy 382.914077 -144.615077) (xy 382.921774 -144.663525) (xy 382.922272 -144.688052) (xy 382.922272 -146.171158)
			(xy 383.09626 -146.171158) (xy 383.100331 -146.115536) (xy 383.112457 -146.061099) (xy 383.13238 -146.009008)
			(xy 383.159676 -145.960373) (xy 383.193762 -145.91623) (xy 383.233911 -145.877521) (xy 383.279269 -145.84507)
			(xy 383.328869 -145.819569) (xy 383.381653 -145.801562) (xy 383.436496 -145.791432) (xy 383.49223 -145.789395)
			(xy 383.547667 -145.795495) (xy 383.570973 -145.801588) (xy 399.016726 -145.801588) (xy 399.020797 -145.745966)
			(xy 399.032923 -145.691529) (xy 399.052846 -145.639438) (xy 399.080142 -145.590803) (xy 399.114228 -145.54666)
			(xy 399.154377 -145.507951) (xy 399.199735 -145.4755) (xy 399.249335 -145.449999) (xy 399.302119 -145.431992)
			(xy 399.356962 -145.421862) (xy 399.412696 -145.419825) (xy 399.468133 -145.425925) (xy 399.52209 -145.440031)
			(xy 399.573419 -145.461843) (xy 399.621025 -145.490897) (xy 399.663893 -145.526572) (xy 399.70111 -145.568109)
			(xy 399.731883 -145.614622) (xy 399.755555 -145.665119) (xy 399.771623 -145.718526) (xy 399.779743 -145.773702)
			(xy 399.780252 -145.801588) (xy 399.779743 -145.829474) (xy 399.771623 -145.88465) (xy 399.755555 -145.938057)
			(xy 399.731883 -145.988554) (xy 399.70111 -146.035067) (xy 399.663893 -146.076604) (xy 399.621025 -146.112279)
			(xy 399.573419 -146.141333) (xy 399.52209 -146.163145) (xy 399.468133 -146.177251) (xy 399.412696 -146.183351)
			(xy 399.356962 -146.181314) (xy 399.302119 -146.171184) (xy 399.249335 -146.153177) (xy 399.199735 -146.127676)
			(xy 399.154377 -146.095225) (xy 399.114228 -146.056516) (xy 399.080142 -146.012373) (xy 399.052846 -145.963738)
			(xy 399.032923 -145.911647) (xy 399.020797 -145.85721) (xy 399.016726 -145.801588) (xy 383.570973 -145.801588)
			(xy 383.601624 -145.809601) (xy 383.652953 -145.831413) (xy 383.700559 -145.860467) (xy 383.743427 -145.896142)
			(xy 383.780644 -145.937679) (xy 383.811417 -145.984192) (xy 383.835089 -146.034689) (xy 383.851157 -146.088096)
			(xy 383.859277 -146.143272) (xy 383.859786 -146.171158) (xy 383.859277 -146.199044) (xy 383.851157 -146.25422)
			(xy 383.835089 -146.307627) (xy 383.811417 -146.358124) (xy 383.780644 -146.404637) (xy 383.743427 -146.446174)
			(xy 383.700559 -146.481849) (xy 383.652953 -146.510903) (xy 383.601624 -146.532715) (xy 383.547667 -146.546821)
			(xy 383.49223 -146.552921) (xy 383.436496 -146.550884) (xy 383.381653 -146.540754) (xy 383.328869 -146.522747)
			(xy 383.279269 -146.497246) (xy 383.233911 -146.464795) (xy 383.193762 -146.426086) (xy 383.159676 -146.381943)
			(xy 383.13238 -146.333308) (xy 383.112457 -146.281217) (xy 383.100331 -146.22678) (xy 383.09626 -146.171158)
			(xy 382.922272 -146.171158) (xy 382.922272 -147.663662) (xy 387.813054 -147.663662) (xy 387.81702 -147.579131)
			(xy 387.828885 -147.495344) (xy 387.848543 -147.413035) (xy 387.875823 -147.332929) (xy 387.910484 -147.25573)
			(xy 387.952222 -147.182115) (xy 388.000669 -147.112732) (xy 388.055401 -147.048191) (xy 388.115937 -146.989059)
			(xy 388.181743 -146.935855) (xy 388.252243 -146.889047) (xy 388.326815 -146.849046) (xy 388.404806 -146.816204)
			(xy 388.48553 -146.79081) (xy 388.568277 -146.773087) (xy 388.652319 -146.763189) (xy 388.73692 -146.761206)
			(xy 388.821334 -146.767153) (xy 388.904821 -146.780978) (xy 388.986646 -146.802561) (xy 389.06609 -146.831711)
			(xy 389.142456 -146.868172) (xy 389.215072 -146.911624) (xy 389.2833 -146.961685) (xy 389.34654 -147.017915)
			(xy 389.404237 -147.07982) (xy 389.455884 -147.146856) (xy 389.501026 -147.218433) (xy 389.539268 -147.293923)
			(xy 389.570272 -147.372662) (xy 389.593767 -147.453959) (xy 389.609546 -147.537098) (xy 389.61747 -147.62135)
			(xy 389.617966 -147.663662) (xy 390.353054 -147.663662) (xy 390.35702 -147.579131) (xy 390.368885 -147.495344)
			(xy 390.388543 -147.413035) (xy 390.415823 -147.332929) (xy 390.450484 -147.25573) (xy 390.492222 -147.182115)
			(xy 390.540669 -147.112732) (xy 390.595401 -147.048191) (xy 390.655937 -146.989059) (xy 390.721743 -146.935855)
			(xy 390.792243 -146.889047) (xy 390.866815 -146.849046) (xy 390.944806 -146.816204) (xy 391.02553 -146.79081)
			(xy 391.108277 -146.773087) (xy 391.192319 -146.763189) (xy 391.27692 -146.761206) (xy 391.361334 -146.767153)
			(xy 391.444821 -146.780978) (xy 391.526646 -146.802561) (xy 391.60609 -146.831711) (xy 391.682456 -146.868172)
			(xy 391.755072 -146.911624) (xy 391.8233 -146.961685) (xy 391.88654 -147.017915) (xy 391.944237 -147.07982)
			(xy 391.995884 -147.146856) (xy 392.041026 -147.218433) (xy 392.079268 -147.293923) (xy 392.110272 -147.372662)
			(xy 392.123901 -147.419822) (xy 396.174466 -147.419822) (xy 396.178537 -147.3642) (xy 396.190663 -147.309763)
			(xy 396.210586 -147.257672) (xy 396.237882 -147.209037) (xy 396.271968 -147.164894) (xy 396.312117 -147.126185)
			(xy 396.357475 -147.093734) (xy 396.407075 -147.068233) (xy 396.459859 -147.050226) (xy 396.514702 -147.040096)
			(xy 396.570436 -147.038059) (xy 396.625873 -147.044159) (xy 396.644322 -147.048982) (xy 399.016726 -147.048982)
			(xy 399.020797 -146.99336) (xy 399.032923 -146.938923) (xy 399.052846 -146.886832) (xy 399.080142 -146.838197)
			(xy 399.114228 -146.794054) (xy 399.154377 -146.755345) (xy 399.199735 -146.722894) (xy 399.249335 -146.697393)
			(xy 399.302119 -146.679386) (xy 399.356962 -146.669256) (xy 399.412696 -146.667219) (xy 399.468133 -146.673319)
			(xy 399.52209 -146.687425) (xy 399.573419 -146.709237) (xy 399.621025 -146.738291) (xy 399.663893 -146.773966)
			(xy 399.70111 -146.815503) (xy 399.731883 -146.862016) (xy 399.755555 -146.912513) (xy 399.771623 -146.96592)
			(xy 399.779743 -147.021096) (xy 399.780252 -147.048982) (xy 399.779743 -147.076868) (xy 399.771623 -147.132044)
			(xy 399.755555 -147.185451) (xy 399.731883 -147.235948) (xy 399.70111 -147.282461) (xy 399.663893 -147.323998)
			(xy 399.621025 -147.359673) (xy 399.573419 -147.388727) (xy 399.52209 -147.410539) (xy 399.468133 -147.424645)
			(xy 399.412696 -147.430745) (xy 399.356962 -147.428708) (xy 399.302119 -147.418578) (xy 399.249335 -147.400571)
			(xy 399.199735 -147.37507) (xy 399.154377 -147.342619) (xy 399.114228 -147.30391) (xy 399.080142 -147.259767)
			(xy 399.052846 -147.211132) (xy 399.032923 -147.159041) (xy 399.020797 -147.104604) (xy 399.016726 -147.048982)
			(xy 396.644322 -147.048982) (xy 396.67983 -147.058265) (xy 396.731159 -147.080077) (xy 396.778765 -147.109131)
			(xy 396.821633 -147.144806) (xy 396.85885 -147.186343) (xy 396.889623 -147.232856) (xy 396.913295 -147.283353)
			(xy 396.929363 -147.33676) (xy 396.937483 -147.391936) (xy 396.937992 -147.419822) (xy 396.937483 -147.447708)
			(xy 396.929363 -147.502884) (xy 396.913295 -147.556291) (xy 396.889623 -147.606788) (xy 396.85885 -147.653301)
			(xy 396.821633 -147.694838) (xy 396.778765 -147.730513) (xy 396.731159 -147.759567) (xy 396.67983 -147.781379)
			(xy 396.625873 -147.795485) (xy 396.570436 -147.801585) (xy 396.514702 -147.799548) (xy 396.459859 -147.789418)
			(xy 396.407075 -147.771411) (xy 396.357475 -147.74591) (xy 396.312117 -147.713459) (xy 396.271968 -147.67475)
			(xy 396.237882 -147.630607) (xy 396.210586 -147.581972) (xy 396.190663 -147.529881) (xy 396.178537 -147.475444)
			(xy 396.174466 -147.419822) (xy 392.123901 -147.419822) (xy 392.133767 -147.453959) (xy 392.149546 -147.537098)
			(xy 392.15747 -147.62135) (xy 392.157966 -147.663662) (xy 392.15747 -147.705974) (xy 392.149546 -147.790226)
			(xy 392.133767 -147.873365) (xy 392.110272 -147.954662) (xy 392.079268 -148.033401) (xy 392.041026 -148.108891)
			(xy 391.995884 -148.180468) (xy 391.944237 -148.247504) (xy 391.88654 -148.309409) (xy 391.8233 -148.365639)
			(xy 391.755072 -148.4157) (xy 391.722566 -148.435151) (xy 396.37106 -148.435151) (xy 396.37106 -148.380649)
			(xy 396.378816 -148.326702) (xy 396.39417 -148.274408) (xy 396.416809 -148.22483) (xy 396.446274 -148.17898)
			(xy 396.481963 -148.137788) (xy 396.523151 -148.102095) (xy 396.568999 -148.072627) (xy 396.618574 -148.049982)
			(xy 396.670867 -148.034623) (xy 396.724813 -148.026862) (xy 396.752064 -148.026374) (xy 396.779321 -148.026858)
			(xy 396.833275 -148.034645) (xy 396.885571 -148.050035) (xy 396.935143 -148.072716) (xy 396.958312 -148.08708)
			(xy 396.958566 -148.087334) (xy 396.96629 -148.091888) (xy 396.983796 -148.09573) (xy 397.001549 -148.093276)
			(xy 397.00962 -148.089366) (xy 397.088106 -148.04771) (xy 397.095775 -148.043174) (xy 397.107666 -148.029923)
			(xy 397.114329 -148.013413) (xy 397.11503 -148.00453) (xy 397.11503 -148.004022) (xy 397.116159 -147.977253)
			(xy 397.125045 -147.924417) (xy 397.141239 -147.873345) (xy 397.164422 -147.825043) (xy 397.194139 -147.780461)
			(xy 397.229803 -147.740478) (xy 397.270714 -147.705881) (xy 397.316064 -147.677352) (xy 397.364961 -147.655451)
			(xy 397.416443 -147.64061) (xy 397.469495 -147.633122) (xy 397.496284 -147.632674) (xy 397.523534 -147.633193)
			(xy 397.57748 -147.640947) (xy 397.629773 -147.656299) (xy 397.679348 -147.678937) (xy 397.725198 -147.7084)
			(xy 397.766388 -147.744088) (xy 397.80208 -147.785275) (xy 397.831547 -147.831122) (xy 397.854189 -147.880696)
			(xy 397.869546 -147.932987) (xy 397.877304 -147.986932) (xy 397.877792 -148.014182) (xy 398.003776 -148.014182)
			(xy 398.004262 -147.986931) (xy 398.012018 -147.932983) (xy 398.027373 -147.880688) (xy 398.050015 -147.831111)
			(xy 398.079481 -147.785261) (xy 398.115172 -147.74407) (xy 398.156363 -147.708379) (xy 398.202213 -147.678913)
			(xy 398.25179 -147.656271) (xy 398.304085 -147.640916) (xy 398.358033 -147.63316) (xy 398.412535 -147.63316)
			(xy 398.466483 -147.640916) (xy 398.518778 -147.656271) (xy 398.568355 -147.678913) (xy 398.614205 -147.708379)
			(xy 398.655396 -147.74407) (xy 398.691087 -147.785261) (xy 398.720553 -147.831111) (xy 398.743195 -147.880688)
			(xy 398.75855 -147.932983) (xy 398.759269 -147.937982) (xy 399.016726 -147.937982) (xy 399.020797 -147.88236)
			(xy 399.032923 -147.827923) (xy 399.052846 -147.775832) (xy 399.080142 -147.727197) (xy 399.114228 -147.683054)
			(xy 399.154377 -147.644345) (xy 399.199735 -147.611894) (xy 399.249335 -147.586393) (xy 399.302119 -147.568386)
			(xy 399.356962 -147.558256) (xy 399.412696 -147.556219) (xy 399.468133 -147.562319) (xy 399.52209 -147.576425)
			(xy 399.573419 -147.598237) (xy 399.621025 -147.627291) (xy 399.663893 -147.662966) (xy 399.70111 -147.704503)
			(xy 399.731883 -147.751016) (xy 399.755555 -147.801513) (xy 399.771623 -147.85492) (xy 399.779743 -147.910096)
			(xy 399.780252 -147.937982) (xy 399.779743 -147.965868) (xy 399.771623 -148.021044) (xy 399.755555 -148.074451)
			(xy 399.731883 -148.124948) (xy 399.70111 -148.171461) (xy 399.663893 -148.212998) (xy 399.621025 -148.248673)
			(xy 399.573419 -148.277727) (xy 399.52209 -148.299539) (xy 399.468133 -148.313645) (xy 399.412696 -148.319745)
			(xy 399.356962 -148.317708) (xy 399.302119 -148.307578) (xy 399.249335 -148.289571) (xy 399.199735 -148.26407)
			(xy 399.154377 -148.231619) (xy 399.114228 -148.19291) (xy 399.080142 -148.148767) (xy 399.052846 -148.100132)
			(xy 399.032923 -148.048041) (xy 399.020797 -147.993604) (xy 399.016726 -147.937982) (xy 398.759269 -147.937982)
			(xy 398.766306 -147.986931) (xy 398.766792 -148.014182) (xy 398.766326 -148.041728) (xy 398.75841 -148.096247)
			(xy 398.742727 -148.149059) (xy 398.719603 -148.199062) (xy 398.68952 -148.245215) (xy 398.653105 -148.286555)
			(xy 398.632426 -148.304758) (xy 398.621425 -148.314681) (xy 398.605327 -148.339543) (xy 398.59703 -148.367976)
			(xy 398.597231 -148.397594) (xy 398.605912 -148.425912) (xy 398.622345 -148.450554) (xy 398.645152 -148.469452)
			(xy 398.658588 -148.4757) (xy 398.684099 -148.487036) (xy 398.731775 -148.516077) (xy 398.774711 -148.551755)
			(xy 398.811989 -148.593309) (xy 398.842815 -148.639851) (xy 398.86653 -148.690388) (xy 398.882628 -148.743841)
			(xy 398.890765 -148.79907) (xy 398.891252 -148.826982) (xy 399.016726 -148.826982) (xy 399.020797 -148.77136)
			(xy 399.032923 -148.716923) (xy 399.052846 -148.664832) (xy 399.080142 -148.616197) (xy 399.114228 -148.572054)
			(xy 399.154377 -148.533345) (xy 399.199735 -148.500894) (xy 399.249335 -148.475393) (xy 399.302119 -148.457386)
			(xy 399.356962 -148.447256) (xy 399.412696 -148.445219) (xy 399.468133 -148.451319) (xy 399.52209 -148.465425)
			(xy 399.573419 -148.487237) (xy 399.621025 -148.516291) (xy 399.663893 -148.551966) (xy 399.70111 -148.593503)
			(xy 399.731883 -148.640016) (xy 399.755555 -148.690513) (xy 399.771623 -148.74392) (xy 399.779743 -148.799096)
			(xy 399.780252 -148.826982) (xy 399.779743 -148.854868) (xy 399.771623 -148.910044) (xy 399.755555 -148.963451)
			(xy 399.731883 -149.013948) (xy 399.70111 -149.060461) (xy 399.663893 -149.101998) (xy 399.621025 -149.137673)
			(xy 399.573419 -149.166727) (xy 399.52209 -149.188539) (xy 399.468133 -149.202645) (xy 399.412696 -149.208745)
			(xy 399.356962 -149.206708) (xy 399.302119 -149.196578) (xy 399.249335 -149.178571) (xy 399.199735 -149.15307)
			(xy 399.154377 -149.120619) (xy 399.114228 -149.08191) (xy 399.080142 -149.037767) (xy 399.052846 -148.989132)
			(xy 399.032923 -148.937041) (xy 399.020797 -148.882604) (xy 399.016726 -148.826982) (xy 398.891252 -148.826982)
			(xy 398.890766 -148.854233) (xy 398.88301 -148.908181) (xy 398.867655 -148.960476) (xy 398.845013 -149.010053)
			(xy 398.815547 -149.055903) (xy 398.779856 -149.097094) (xy 398.738665 -149.132785) (xy 398.692815 -149.162251)
			(xy 398.643238 -149.184893) (xy 398.590943 -149.200248) (xy 398.536995 -149.208004) (xy 398.482493 -149.208004)
			(xy 398.428545 -149.200248) (xy 398.37625 -149.184893) (xy 398.326673 -149.162251) (xy 398.280823 -149.132785)
			(xy 398.239632 -149.097094) (xy 398.203941 -149.055903) (xy 398.174475 -149.010053) (xy 398.151833 -148.960476)
			(xy 398.136478 -148.908181) (xy 398.128722 -148.854233) (xy 398.128236 -148.826982) (xy 398.128737 -148.799437)
			(xy 398.136644 -148.744919) (xy 398.15232 -148.692108) (xy 398.175437 -148.642104) (xy 398.205514 -148.595951)
			(xy 398.241925 -148.55461) (xy 398.262602 -148.536406) (xy 398.273524 -148.526404) (xy 398.289618 -148.501561)
			(xy 398.297918 -148.473148) (xy 398.297727 -148.443548) (xy 398.289062 -148.415245) (xy 398.272649 -148.390611)
			(xy 398.249865 -148.371715) (xy 398.23644 -148.365464) (xy 398.210921 -148.354143) (xy 398.163243 -148.325102)
			(xy 398.120306 -148.289422) (xy 398.083027 -148.247867) (xy 398.052202 -148.201322) (xy 398.028489 -148.150782)
			(xy 398.012394 -148.097326) (xy 398.004261 -148.042095) (xy 398.003776 -148.014182) (xy 397.877792 -148.014182)
			(xy 397.877326 -148.041728) (xy 397.86941 -148.096247) (xy 397.853727 -148.149059) (xy 397.830603 -148.199062)
			(xy 397.80052 -148.245215) (xy 397.764105 -148.286555) (xy 397.743426 -148.304758) (xy 397.733266 -148.313394)
			(xy 397.724122 -148.337778) (xy 397.74114 -148.449792) (xy 397.757396 -148.47062) (xy 397.769588 -148.4757)
			(xy 397.795099 -148.487036) (xy 397.842775 -148.516077) (xy 397.885711 -148.551755) (xy 397.922989 -148.593309)
			(xy 397.953815 -148.639851) (xy 397.97753 -148.690388) (xy 397.993628 -148.743841) (xy 398.001765 -148.79907)
			(xy 398.002252 -148.826982) (xy 398.001766 -148.854233) (xy 397.99401 -148.908181) (xy 397.978655 -148.960476)
			(xy 397.956013 -149.010053) (xy 397.926547 -149.055903) (xy 397.890856 -149.097094) (xy 397.849665 -149.132785)
			(xy 397.803815 -149.162251) (xy 397.754238 -149.184893) (xy 397.701943 -149.200248) (xy 397.647995 -149.208004)
			(xy 397.593493 -149.208004) (xy 397.539545 -149.200248) (xy 397.48725 -149.184893) (xy 397.437673 -149.162251)
			(xy 397.391823 -149.132785) (xy 397.350632 -149.097094) (xy 397.314941 -149.055903) (xy 397.285475 -149.010053)
			(xy 397.262833 -148.960476) (xy 397.247478 -148.908181) (xy 397.239722 -148.854233) (xy 397.239236 -148.826982)
			(xy 397.239737 -148.799437) (xy 397.247644 -148.744919) (xy 397.26332 -148.692108) (xy 397.286437 -148.642104)
			(xy 397.316514 -148.595951) (xy 397.352925 -148.55461) (xy 397.373602 -148.536406) (xy 397.383762 -148.52777)
			(xy 397.392906 -148.503386) (xy 397.375888 -148.391372) (xy 397.359632 -148.370544) (xy 397.34744 -148.365464)
			(xy 397.332538 -148.35893) (xy 397.303797 -148.343668) (xy 397.290036 -148.334984) (xy 397.289782 -148.33473)
			(xy 397.282039 -148.330214) (xy 397.264545 -148.326362) (xy 397.246799 -148.328799) (xy 397.238728 -148.332698)
			(xy 397.160242 -148.374354) (xy 397.152577 -148.378895) (xy 397.14069 -148.392146) (xy 397.134023 -148.408653)
			(xy 397.133318 -148.417534) (xy 397.133318 -148.418042) (xy 397.132108 -148.444806) (xy 397.123229 -148.497636)
			(xy 397.107042 -148.548704) (xy 397.083867 -148.597004) (xy 397.054158 -148.641584) (xy 397.018502 -148.681566)
			(xy 396.9776 -148.716164) (xy 396.932258 -148.744696) (xy 396.883369 -148.7666) (xy 396.831895 -148.781445)
			(xy 396.77885 -148.788939) (xy 396.752064 -148.78939) (xy 396.724813 -148.788938) (xy 396.670867 -148.781177)
			(xy 396.618574 -148.765818) (xy 396.568999 -148.743173) (xy 396.523151 -148.713705) (xy 396.481963 -148.678012)
			(xy 396.446274 -148.63682) (xy 396.416809 -148.59097) (xy 396.39417 -148.541392) (xy 396.378816 -148.489098)
			(xy 396.37106 -148.435151) (xy 391.722566 -148.435151) (xy 391.682456 -148.459152) (xy 391.60609 -148.495613)
			(xy 391.526646 -148.524763) (xy 391.444821 -148.546346) (xy 391.361334 -148.560171) (xy 391.27692 -148.566118)
			(xy 391.192319 -148.564135) (xy 391.108277 -148.554237) (xy 391.02553 -148.536514) (xy 390.944806 -148.51112)
			(xy 390.866815 -148.478278) (xy 390.792243 -148.438277) (xy 390.721743 -148.391469) (xy 390.655937 -148.338265)
			(xy 390.595401 -148.279133) (xy 390.540669 -148.214592) (xy 390.492222 -148.145209) (xy 390.450484 -148.071594)
			(xy 390.415823 -147.994395) (xy 390.388543 -147.914289) (xy 390.368885 -147.83198) (xy 390.35702 -147.748193)
			(xy 390.353054 -147.663662) (xy 389.617966 -147.663662) (xy 389.61747 -147.705974) (xy 389.609546 -147.790226)
			(xy 389.593767 -147.873365) (xy 389.570272 -147.954662) (xy 389.539268 -148.033401) (xy 389.501026 -148.108891)
			(xy 389.455884 -148.180468) (xy 389.404237 -148.247504) (xy 389.34654 -148.309409) (xy 389.2833 -148.365639)
			(xy 389.215072 -148.4157) (xy 389.142456 -148.459152) (xy 389.06609 -148.495613) (xy 388.986646 -148.524763)
			(xy 388.904821 -148.546346) (xy 388.821334 -148.560171) (xy 388.73692 -148.566118) (xy 388.652319 -148.564135)
			(xy 388.568277 -148.554237) (xy 388.48553 -148.536514) (xy 388.404806 -148.51112) (xy 388.326815 -148.478278)
			(xy 388.252243 -148.438277) (xy 388.181743 -148.391469) (xy 388.115937 -148.338265) (xy 388.055401 -148.279133)
			(xy 388.000669 -148.214592) (xy 387.952222 -148.145209) (xy 387.910484 -148.071594) (xy 387.875823 -147.994395)
			(xy 387.848543 -147.914289) (xy 387.828885 -147.83198) (xy 387.81702 -147.748193) (xy 387.813054 -147.663662)
			(xy 382.922272 -147.663662) (xy 382.922272 -149.088094) (xy 382.921784 -149.112622) (xy 382.91409 -149.161071)
			(xy 382.898923 -149.207724) (xy 382.876653 -149.251434) (xy 382.847829 -149.291129) (xy 382.842302 -149.296882)
			(xy 396.370046 -149.296882) (xy 396.374117 -149.24126) (xy 396.386243 -149.186823) (xy 396.406166 -149.134732)
			(xy 396.433462 -149.086097) (xy 396.467548 -149.041954) (xy 396.507697 -149.003245) (xy 396.553055 -148.970794)
			(xy 396.602655 -148.945293) (xy 396.655439 -148.927286) (xy 396.710282 -148.917156) (xy 396.766016 -148.915119)
			(xy 396.821453 -148.921219) (xy 396.87541 -148.935325) (xy 396.926739 -148.957137) (xy 396.974345 -148.986191)
			(xy 397.017213 -149.021866) (xy 397.05443 -149.063403) (xy 397.085203 -149.109916) (xy 397.108875 -149.160413)
			(xy 397.124943 -149.21382) (xy 397.133063 -149.268996) (xy 397.133572 -149.296882) (xy 397.133063 -149.324768)
			(xy 397.124943 -149.379944) (xy 397.108875 -149.433351) (xy 397.085203 -149.483848) (xy 397.05443 -149.530361)
			(xy 397.017213 -149.571898) (xy 396.974345 -149.607573) (xy 396.926739 -149.636627) (xy 396.87541 -149.658439)
			(xy 396.821453 -149.672545) (xy 396.766016 -149.678645) (xy 396.710282 -149.676608) (xy 396.655439 -149.666478)
			(xy 396.602655 -149.648471) (xy 396.553055 -149.62297) (xy 396.507697 -149.590519) (xy 396.467548 -149.55181)
			(xy 396.433462 -149.507667) (xy 396.406166 -149.459032) (xy 396.386243 -149.406941) (xy 396.374117 -149.352504)
			(xy 396.370046 -149.296882) (xy 382.842302 -149.296882) (xy 382.830832 -149.30882) (xy 382.42367 -149.715982)
			(xy 397.238726 -149.715982) (xy 397.242797 -149.66036) (xy 397.254923 -149.605923) (xy 397.274846 -149.553832)
			(xy 397.302142 -149.505197) (xy 397.336228 -149.461054) (xy 397.376377 -149.422345) (xy 397.421735 -149.389894)
			(xy 397.471335 -149.364393) (xy 397.524119 -149.346386) (xy 397.578962 -149.336256) (xy 397.634696 -149.334219)
			(xy 397.690133 -149.340319) (xy 397.74409 -149.354425) (xy 397.795419 -149.376237) (xy 397.843025 -149.405291)
			(xy 397.885893 -149.440966) (xy 397.92311 -149.482503) (xy 397.953883 -149.529016) (xy 397.977555 -149.579513)
			(xy 397.993623 -149.63292) (xy 398.001743 -149.688096) (xy 398.002252 -149.715982) (xy 398.127726 -149.715982)
			(xy 398.131797 -149.66036) (xy 398.143923 -149.605923) (xy 398.163846 -149.553832) (xy 398.191142 -149.505197)
			(xy 398.225228 -149.461054) (xy 398.265377 -149.422345) (xy 398.310735 -149.389894) (xy 398.360335 -149.364393)
			(xy 398.413119 -149.346386) (xy 398.467962 -149.336256) (xy 398.523696 -149.334219) (xy 398.579133 -149.340319)
			(xy 398.63309 -149.354425) (xy 398.684419 -149.376237) (xy 398.732025 -149.405291) (xy 398.774893 -149.440966)
			(xy 398.81211 -149.482503) (xy 398.842883 -149.529016) (xy 398.866555 -149.579513) (xy 398.882623 -149.63292)
			(xy 398.890743 -149.688096) (xy 398.891252 -149.715982) (xy 399.016726 -149.715982) (xy 399.020797 -149.66036)
			(xy 399.032923 -149.605923) (xy 399.052846 -149.553832) (xy 399.080142 -149.505197) (xy 399.114228 -149.461054)
			(xy 399.154377 -149.422345) (xy 399.199735 -149.389894) (xy 399.249335 -149.364393) (xy 399.302119 -149.346386)
			(xy 399.356962 -149.336256) (xy 399.412696 -149.334219) (xy 399.468133 -149.340319) (xy 399.52209 -149.354425)
			(xy 399.573419 -149.376237) (xy 399.621025 -149.405291) (xy 399.663893 -149.440966) (xy 399.70111 -149.482503)
			(xy 399.731883 -149.529016) (xy 399.755555 -149.579513) (xy 399.771623 -149.63292) (xy 399.779743 -149.688096)
			(xy 399.780252 -149.715982) (xy 399.779743 -149.743868) (xy 399.771623 -149.799044) (xy 399.755555 -149.852451)
			(xy 399.731883 -149.902948) (xy 399.70111 -149.949461) (xy 399.663893 -149.990998) (xy 399.621025 -150.026673)
			(xy 399.573419 -150.055727) (xy 399.52209 -150.077539) (xy 399.468133 -150.091645) (xy 399.412696 -150.097745)
			(xy 399.356962 -150.095708) (xy 399.302119 -150.085578) (xy 399.249335 -150.067571) (xy 399.199735 -150.04207)
			(xy 399.154377 -150.009619) (xy 399.114228 -149.97091) (xy 399.080142 -149.926767) (xy 399.052846 -149.878132)
			(xy 399.032923 -149.826041) (xy 399.020797 -149.771604) (xy 399.016726 -149.715982) (xy 398.891252 -149.715982)
			(xy 398.890743 -149.743868) (xy 398.882623 -149.799044) (xy 398.866555 -149.852451) (xy 398.842883 -149.902948)
			(xy 398.81211 -149.949461) (xy 398.774893 -149.990998) (xy 398.732025 -150.026673) (xy 398.684419 -150.055727)
			(xy 398.63309 -150.077539) (xy 398.579133 -150.091645) (xy 398.523696 -150.097745) (xy 398.467962 -150.095708)
			(xy 398.413119 -150.085578) (xy 398.360335 -150.067571) (xy 398.310735 -150.04207) (xy 398.265377 -150.009619)
			(xy 398.225228 -149.97091) (xy 398.191142 -149.926767) (xy 398.163846 -149.878132) (xy 398.143923 -149.826041)
			(xy 398.131797 -149.771604) (xy 398.127726 -149.715982) (xy 398.002252 -149.715982) (xy 398.001743 -149.743868)
			(xy 397.993623 -149.799044) (xy 397.977555 -149.852451) (xy 397.953883 -149.902948) (xy 397.92311 -149.949461)
			(xy 397.885893 -149.990998) (xy 397.843025 -150.026673) (xy 397.795419 -150.055727) (xy 397.74409 -150.077539)
			(xy 397.690133 -150.091645) (xy 397.634696 -150.097745) (xy 397.578962 -150.095708) (xy 397.524119 -150.085578)
			(xy 397.471335 -150.067571) (xy 397.421735 -150.04207) (xy 397.376377 -150.009619) (xy 397.336228 -149.97091)
			(xy 397.302142 -149.926767) (xy 397.274846 -149.878132) (xy 397.254923 -149.826041) (xy 397.242797 -149.771604)
			(xy 397.238726 -149.715982) (xy 382.42367 -149.715982) (xy 381.687832 -150.45182) (xy 381.670119 -150.468792)
			(xy 381.630426 -150.497611) (xy 381.586721 -150.51988) (xy 381.540074 -150.535053) (xy 381.491631 -150.542758)
			(xy 381.467106 -150.54326) (xy 369.9764 -150.54326) (xy 369.951872 -150.542779) (xy 369.903422 -150.535084)
			(xy 369.856769 -150.519915) (xy 369.813059 -150.497644) (xy 369.773364 -150.468818) (xy 369.755674 -150.45182)
			(xy 366.181132 -146.877024) (xy 366.168432 -146.870166) (xy 366.161066 -146.868642) (xy 366.133073 -146.861966)
			(xy 366.079319 -146.84143) (xy 366.029257 -146.813056) (xy 365.984022 -146.777487) (xy 365.944641 -146.73553)
			(xy 365.912006 -146.688135) (xy 365.886856 -146.636378) (xy 365.869762 -146.581432) (xy 365.861112 -146.524542)
			(xy 365.860584 -146.49577) (xy 350.997569 -146.49577) (xy 351.033743 -146.571569) (xy 351.096036 -146.720652)
			(xy 351.15088 -146.872633) (xy 351.198141 -147.027141) (xy 351.237703 -147.183797) (xy 351.269469 -147.342217)
			(xy 351.293362 -147.502015) (xy 351.309324 -147.662799) (xy 351.317314 -147.824175) (xy 351.317814 -147.904962)
			(xy 351.317314 -147.985749) (xy 351.309324 -148.147125) (xy 351.293362 -148.307909) (xy 351.269469 -148.467707)
			(xy 351.237703 -148.626127) (xy 351.198141 -148.782783) (xy 351.15088 -148.937291) (xy 351.096036 -149.089272)
			(xy 351.033743 -149.238355) (xy 350.964153 -149.384175) (xy 350.887438 -149.526375) (xy 350.803783 -149.664607)
			(xy 350.713396 -149.798534) (xy 350.616495 -149.927826) (xy 350.513319 -150.052168) (xy 350.40412 -150.171255)
			(xy 350.289166 -150.284796) (xy 350.168737 -150.392514) (xy 350.043129 -150.494144) (xy 349.912648 -150.589438)
			(xy 349.777614 -150.678163) (xy 349.638358 -150.760101) (xy 349.49522 -150.835052) (xy 349.34855 -150.902832)
			(xy 349.198708 -150.963277) (xy 349.04606 -151.016237) (xy 348.89098 -151.061583) (xy 348.733847 -151.099205)
			(xy 348.575045 -151.129009) (xy 348.414964 -151.150924) (xy 348.253995 -151.164896) (xy 348.092533 -151.17089)
			(xy 347.930971 -151.168891) (xy 347.769706 -151.158906) (xy 347.609132 -151.140957) (xy 347.449642 -151.115089)
			(xy 347.291626 -151.081366) (xy 347.135472 -151.039869) (xy 346.981561 -150.990701) (xy 346.830269 -150.933981)
			(xy 346.681968 -150.869849) (xy 346.53702 -150.798461) (xy 346.395779 -150.719993) (xy 346.258592 -150.634635)
			(xy 346.125794 -150.542598) (xy 345.997711 -150.444106) (xy 345.874654 -150.3394) (xy 345.756927 -150.228737)
			(xy 345.644816 -150.112387) (xy 345.538596 -149.990635) (xy 345.438527 -149.863779) (xy 345.344854 -149.732129)
			(xy 345.257807 -149.596009) (xy 345.177597 -149.455749) (xy 345.104422 -149.311695) (xy 345.038461 -149.164199)
			(xy 344.979874 -149.01362) (xy 344.928806 -148.860329) (xy 344.885381 -148.7047) (xy 344.849706 -148.547114)
			(xy 344.821868 -148.387956) (xy 344.801934 -148.227616) (xy 344.789955 -148.066487) (xy 344.785959 -147.904962)
			(xy 340.9696 -147.904962) (xy 337.039458 -151.835104) (xy 337.032618 -151.842504) (xy 337.024899 -151.861103)
			(xy 337.024472 -151.871172) (xy 337.024472 -152.454102) (xy 337.023986 -152.481353) (xy 337.01623 -152.535301)
			(xy 337.000875 -152.587596) (xy 336.978233 -152.637173) (xy 336.948767 -152.683023) (xy 336.913076 -152.724214)
			(xy 336.871885 -152.759905) (xy 336.826035 -152.789371) (xy 336.776458 -152.812013) (xy 336.724163 -152.827368)
			(xy 336.670215 -152.835124) (xy 336.615713 -152.835124) (xy 336.561765 -152.827368) (xy 336.50947 -152.812013)
			(xy 336.459893 -152.789371) (xy 336.414043 -152.759905) (xy 336.372852 -152.724214) (xy 336.337161 -152.683023)
			(xy 336.307695 -152.637173) (xy 336.285053 -152.587596) (xy 336.269698 -152.535301) (xy 336.261942 -152.481353)
			(xy 336.261456 -152.454102) (xy 334.967072 -152.454102) (xy 334.966586 -152.481353) (xy 334.95883 -152.535301)
			(xy 334.943475 -152.587596) (xy 334.920833 -152.637173) (xy 334.891367 -152.683023) (xy 334.855676 -152.724214)
			(xy 334.814485 -152.759905) (xy 334.768635 -152.789371) (xy 334.719058 -152.812013) (xy 334.666763 -152.827368)
			(xy 334.612815 -152.835124) (xy 334.558313 -152.835124) (xy 334.504365 -152.827368) (xy 334.45207 -152.812013)
			(xy 334.402493 -152.789371) (xy 334.356643 -152.759905) (xy 334.315452 -152.724214) (xy 334.279761 -152.683023)
			(xy 334.250295 -152.637173) (xy 334.227653 -152.587596) (xy 334.212298 -152.535301) (xy 334.204542 -152.481353)
			(xy 334.204056 -152.454102) (xy 332.74151 -152.454102) (xy 332.750922 -152.515824) (xy 332.76032 -152.532334)
			(xy 332.767686 -152.538176) (xy 332.789446 -152.556389) (xy 332.82785 -152.598163) (xy 332.859642 -152.645165)
			(xy 332.884121 -152.696358) (xy 332.900747 -152.750612) (xy 332.909152 -152.80673) (xy 332.909672 -152.835102)
			(xy 332.909672 -152.835864) (xy 332.909159 -152.863043) (xy 332.901387 -152.916842) (xy 332.894178 -152.943052)
			(xy 332.89113 -152.952958) (xy 332.89367 -152.973786) (xy 332.940914 -153.055828) (xy 332.957424 -153.06802)
			(xy 332.967584 -153.07056) (xy 332.992446 -153.076951) (xy 333.040293 -153.095547) (xy 333.08521 -153.120398)
			(xy 333.126384 -153.151054) (xy 333.163069 -153.186962) (xy 333.179166 -153.206958) (xy 333.186788 -153.21575)
			(xy 333.207678 -153.225939) (xy 333.219298 -153.226516) (xy 333.299054 -153.226516) (xy 333.310687 -153.225988)
			(xy 333.331596 -153.215791) (xy 333.339186 -153.206958) (xy 333.357374 -153.184472) (xy 333.399396 -153.144739)
			(xy 333.446932 -153.111802) (xy 333.498893 -153.086414) (xy 333.554091 -153.069158) (xy 333.61126 -153.060428)
			(xy 333.640176 -153.059892) (xy 333.667428 -153.060378) (xy 333.721378 -153.068131) (xy 333.773676 -153.083484)
			(xy 333.823256 -153.106124) (xy 333.869109 -153.13559) (xy 333.910302 -153.171281) (xy 333.945996 -153.212472)
			(xy 333.975464 -153.258323) (xy 333.998107 -153.307902) (xy 334.013464 -153.360198) (xy 334.021221 -153.414148)
			(xy 334.021684 -153.4414) (xy 334.021172 -153.470317) (xy 334.012442 -153.527489) (xy 333.995183 -153.582688)
			(xy 333.969791 -153.63465) (xy 333.936846 -153.682184) (xy 333.897104 -153.7242) (xy 333.874618 -153.74239)
			(xy 333.865811 -153.749997) (xy 333.855631 -153.770898) (xy 333.85506 -153.782522) (xy 333.85506 -153.862278)
			(xy 333.855605 -153.87391) (xy 333.865788 -153.894821) (xy 333.874618 -153.90241) (xy 333.895402 -153.919163)
			(xy 333.932535 -153.957515) (xy 333.963958 -154.000669) (xy 333.989059 -154.047783) (xy 334.007346 -154.097935)
			(xy 334.018463 -154.150148) (xy 334.022193 -154.2034) (xy 334.018463 -154.256652) (xy 334.007346 -154.308865)
			(xy 333.989059 -154.359017) (xy 333.963958 -154.406131) (xy 333.932535 -154.449285) (xy 333.895402 -154.487637)
			(xy 333.874618 -154.50439) (xy 333.865811 -154.511997) (xy 333.855631 -154.532898) (xy 333.85506 -154.544522)
			(xy 333.85506 -154.624278) (xy 333.855605 -154.63591) (xy 333.865788 -154.656821) (xy 333.874618 -154.66441)
			(xy 333.895402 -154.681163) (xy 333.932535 -154.719515) (xy 333.963958 -154.762669) (xy 333.989059 -154.809783)
			(xy 334.007346 -154.859935) (xy 334.018463 -154.912148) (xy 334.022193 -154.9654) (xy 334.018463 -155.018652)
			(xy 334.007346 -155.070865) (xy 333.989059 -155.121017) (xy 333.963958 -155.168131) (xy 333.932535 -155.211285)
			(xy 333.895402 -155.249637) (xy 333.874618 -155.26639) (xy 333.865811 -155.273997) (xy 333.855631 -155.294898)
			(xy 333.85506 -155.306522) (xy 333.85506 -155.386278) (xy 333.855605 -155.39791) (xy 333.865788 -155.418821)
			(xy 333.874618 -155.42641) (xy 333.895402 -155.443163) (xy 333.932535 -155.481515) (xy 333.963958 -155.524669)
			(xy 333.989059 -155.571783) (xy 334.007346 -155.621935) (xy 334.018463 -155.674148) (xy 334.022193 -155.7274)
			(xy 334.018463 -155.780652) (xy 334.007346 -155.832865) (xy 333.989059 -155.883017) (xy 333.963958 -155.930131)
			(xy 333.932535 -155.973285) (xy 333.895402 -156.011637) (xy 333.874618 -156.02839) (xy 333.865811 -156.035997)
			(xy 333.855631 -156.056898) (xy 333.85506 -156.068522) (xy 333.85506 -156.148278) (xy 333.855605 -156.15991)
			(xy 333.865788 -156.180821) (xy 333.874618 -156.18841) (xy 333.89711 -156.206591) (xy 333.936844 -156.248613)
			(xy 333.969781 -156.29615) (xy 333.995168 -156.348114) (xy 334.012423 -156.403313) (xy 334.02115 -156.460483)
			(xy 334.021684 -156.4894) (xy 334.021245 -156.516654) (xy 334.013487 -156.570607) (xy 333.99813 -156.622907)
			(xy 333.975486 -156.672488) (xy 333.946015 -156.718343) (xy 333.910319 -156.759536) (xy 333.869123 -156.79523)
			(xy 333.823267 -156.824697) (xy 333.773684 -156.847338) (xy 333.721383 -156.862692) (xy 333.66743 -156.870446)
			(xy 333.640176 -156.870908) (xy 333.611259 -156.87037) (xy 333.554088 -156.86165) (xy 333.498888 -156.844398)
			(xy 333.446925 -156.81901) (xy 333.399391 -156.786068) (xy 333.357375 -156.746328) (xy 333.339186 -156.723842)
			(xy 333.331585 -156.715029) (xy 333.310679 -156.704851) (xy 333.299054 -156.704284) (xy 333.219298 -156.704284)
			(xy 333.207669 -156.704842) (xy 333.186759 -156.715018) (xy 333.179166 -156.723842) (xy 333.162413 -156.744625)
			(xy 333.124059 -156.781755) (xy 333.080905 -156.813177) (xy 333.033791 -156.838276) (xy 332.983639 -156.856562)
			(xy 332.931428 -156.867679) (xy 332.878176 -156.871409) (xy 332.824924 -156.867679) (xy 332.772713 -156.856562)
			(xy 332.722561 -156.838276) (xy 332.675447 -156.813177) (xy 332.632293 -156.781755) (xy 332.593939 -156.744625)
			(xy 332.577186 -156.723842) (xy 332.569585 -156.715029) (xy 332.548679 -156.704851) (xy 332.537054 -156.704284)
			(xy 332.457044 -156.704284) (xy 332.44548 -156.704885) (xy 332.424709 -156.715059) (xy 332.417166 -156.723842)
			(xy 332.410562 -156.73197) (xy 332.401672 -156.742892) (xy 332.397354 -156.770324) (xy 332.44155 -156.87929)
			(xy 332.463902 -156.896054) (xy 332.477618 -156.897578) (xy 332.505239 -156.901191) (xy 332.559102 -156.91539)
			(xy 332.610329 -156.937267) (xy 332.657832 -156.966357) (xy 332.700602 -157.002043) (xy 332.737732 -157.043567)
			(xy 332.768432 -157.090046) (xy 332.79205 -157.140494) (xy 332.808084 -157.193839) (xy 332.816195 -157.248949)
			(xy 332.816708 -157.2768) (xy 332.816225 -157.305719) (xy 332.807493 -157.362893) (xy 332.790231 -157.418094)
			(xy 332.764833 -157.470056) (xy 332.731881 -157.517589) (xy 332.692132 -157.559603) (xy 332.669642 -157.57779)
			(xy 332.66084 -157.585401) (xy 332.650656 -157.606299) (xy 332.650084 -157.617922) (xy 332.650084 -157.697678)
			(xy 332.650656 -157.709306) (xy 332.660822 -157.730215) (xy 332.669642 -157.73781) (xy 332.690425 -157.754563)
			(xy 332.727555 -157.792917) (xy 332.758977 -157.836071) (xy 332.784076 -157.883185) (xy 332.802362 -157.933337)
			(xy 332.813478 -157.985549) (xy 332.817208 -158.0388) (xy 334.466192 -158.0388) (xy 334.469922 -157.985549)
			(xy 334.481038 -157.933337) (xy 334.499324 -157.883185) (xy 334.524423 -157.836071) (xy 334.555845 -157.792917)
			(xy 334.592975 -157.754563) (xy 334.613758 -157.73781) (xy 334.62256 -157.730199) (xy 334.632744 -157.709301)
			(xy 334.633316 -157.697678) (xy 334.633316 -157.617922) (xy 334.632744 -157.606294) (xy 334.622578 -157.585385)
			(xy 334.613758 -157.57779) (xy 334.591261 -157.559615) (xy 334.551529 -157.517591) (xy 334.518592 -157.470052)
			(xy 334.493207 -157.418088) (xy 334.475953 -157.362888) (xy 334.467226 -157.305717) (xy 334.466692 -157.2768)
			(xy 334.467178 -157.249549) (xy 334.474934 -157.195601) (xy 334.490289 -157.143306) (xy 334.512931 -157.093729)
			(xy 334.542397 -157.047879) (xy 334.578088 -157.006688) (xy 334.619279 -156.970997) (xy 334.665129 -156.941531)
			(xy 334.714706 -156.918889) (xy 334.767001 -156.903534) (xy 334.820949 -156.895778) (xy 334.8482 -156.895292)
			(xy 334.877119 -156.895775) (xy 334.934293 -156.904507) (xy 334.989494 -156.921769) (xy 335.041456 -156.947167)
			(xy 335.088989 -156.980119) (xy 335.131003 -157.019868) (xy 335.14919 -157.042358) (xy 335.156801 -157.05116)
			(xy 335.177699 -157.061344) (xy 335.189322 -157.061916) (xy 335.269078 -157.061916) (xy 335.280706 -157.061344)
			(xy 335.301615 -157.051178) (xy 335.30921 -157.042358) (xy 335.327385 -157.019861) (xy 335.369409 -156.980129)
			(xy 335.416948 -156.947192) (xy 335.468912 -156.921807) (xy 335.524112 -156.904553) (xy 335.581283 -156.895826)
			(xy 335.6102 -156.895292) (xy 335.637451 -156.895778) (xy 335.691399 -156.903534) (xy 335.743694 -156.918889)
			(xy 335.793271 -156.941531) (xy 335.839121 -156.970997) (xy 335.880312 -157.006688) (xy 335.916003 -157.047879)
			(xy 335.945469 -157.093729) (xy 335.968111 -157.143306) (xy 335.983466 -157.195601) (xy 335.991222 -157.249549)
			(xy 335.991708 -157.2768) (xy 335.991225 -157.305719) (xy 335.982493 -157.362893) (xy 335.965231 -157.418094)
			(xy 335.939833 -157.470056) (xy 335.906881 -157.517589) (xy 335.867132 -157.559603) (xy 335.844642 -157.57779)
			(xy 335.83584 -157.585401) (xy 335.825656 -157.606299) (xy 335.825084 -157.617922) (xy 335.825084 -157.697678)
			(xy 335.825656 -157.709306) (xy 335.835822 -157.730215) (xy 335.844642 -157.73781) (xy 335.865425 -157.754563)
			(xy 335.902555 -157.792917) (xy 335.933977 -157.836071) (xy 335.959076 -157.883185) (xy 335.977362 -157.933337)
			(xy 335.988478 -157.985549) (xy 335.992208 -158.0388) (xy 335.988478 -158.092051) (xy 335.977362 -158.144263)
			(xy 335.959076 -158.194415) (xy 335.933977 -158.241529) (xy 335.902555 -158.284683) (xy 335.865425 -158.323037)
			(xy 335.844642 -158.33979) (xy 335.83584 -158.347401) (xy 335.825656 -158.368299) (xy 335.825084 -158.379922)
			(xy 335.825084 -158.459678) (xy 335.825656 -158.471306) (xy 335.835822 -158.492215) (xy 335.844642 -158.49981)
			(xy 335.867139 -158.517985) (xy 335.906871 -158.560009) (xy 335.939808 -158.607548) (xy 335.965193 -158.659512)
			(xy 335.982447 -158.714712) (xy 335.991174 -158.771883) (xy 335.991708 -158.8008) (xy 335.991222 -158.828051)
			(xy 335.983466 -158.881999) (xy 335.968111 -158.934294) (xy 335.945469 -158.983871) (xy 335.916003 -159.029721)
			(xy 335.880312 -159.070912) (xy 335.839121 -159.106603) (xy 335.793271 -159.136069) (xy 335.743694 -159.158711)
			(xy 335.691399 -159.174066) (xy 335.637451 -159.181822) (xy 335.6102 -159.182308) (xy 335.581281 -159.181825)
			(xy 335.524107 -159.173093) (xy 335.468906 -159.155831) (xy 335.416944 -159.130433) (xy 335.369411 -159.097481)
			(xy 335.327397 -159.057732) (xy 335.30921 -159.035242) (xy 335.301599 -159.02644) (xy 335.280701 -159.016256)
			(xy 335.269078 -159.015684) (xy 335.189322 -159.015684) (xy 335.177694 -159.016256) (xy 335.156785 -159.026422)
			(xy 335.14919 -159.035242) (xy 335.131015 -159.057739) (xy 335.088991 -159.097471) (xy 335.041452 -159.130408)
			(xy 334.989488 -159.155793) (xy 334.934288 -159.173047) (xy 334.877117 -159.181774) (xy 334.8482 -159.182308)
			(xy 334.820949 -159.181822) (xy 334.767001 -159.174066) (xy 334.714706 -159.158711) (xy 334.665129 -159.136069)
			(xy 334.619279 -159.106603) (xy 334.578088 -159.070912) (xy 334.542397 -159.029721) (xy 334.512931 -158.983871)
			(xy 334.490289 -158.934294) (xy 334.474934 -158.881999) (xy 334.467178 -158.828051) (xy 334.466692 -158.8008)
			(xy 334.467175 -158.771881) (xy 334.475907 -158.714707) (xy 334.493169 -158.659506) (xy 334.518567 -158.607544)
			(xy 334.551519 -158.560011) (xy 334.591268 -158.517997) (xy 334.613758 -158.49981) (xy 334.62256 -158.492199)
			(xy 334.632744 -158.471301) (xy 334.633316 -158.459678) (xy 334.633316 -158.379922) (xy 334.632744 -158.368294)
			(xy 334.622578 -158.347385) (xy 334.613758 -158.33979) (xy 334.592975 -158.323037) (xy 334.555845 -158.284683)
			(xy 334.524423 -158.241529) (xy 334.499324 -158.194415) (xy 334.481038 -158.144263) (xy 334.469922 -158.092051)
			(xy 334.466192 -158.0388) (xy 332.817208 -158.0388) (xy 332.813478 -158.092051) (xy 332.802362 -158.144263)
			(xy 332.784076 -158.194415) (xy 332.758977 -158.241529) (xy 332.727555 -158.284683) (xy 332.690425 -158.323037)
			(xy 332.669642 -158.33979) (xy 332.66084 -158.347401) (xy 332.650656 -158.368299) (xy 332.650084 -158.379922)
			(xy 332.650084 -158.459678) (xy 332.650656 -158.471306) (xy 332.660822 -158.492215) (xy 332.669642 -158.49981)
			(xy 332.692139 -158.517985) (xy 332.731871 -158.560009) (xy 332.764808 -158.607548) (xy 332.790193 -158.659512)
			(xy 332.807447 -158.714712) (xy 332.816174 -158.771883) (xy 332.816708 -158.8008) (xy 332.816222 -158.828051)
			(xy 332.808466 -158.881999) (xy 332.793111 -158.934294) (xy 332.770469 -158.983871) (xy 332.741003 -159.029721)
			(xy 332.705312 -159.070912) (xy 332.664121 -159.106603) (xy 332.618271 -159.136069) (xy 332.568694 -159.158711)
			(xy 332.516399 -159.174066) (xy 332.462451 -159.181822) (xy 332.407949 -159.181822) (xy 332.354001 -159.174066)
			(xy 332.301706 -159.158711) (xy 332.252129 -159.136069) (xy 332.206279 -159.106603) (xy 332.165088 -159.070912)
			(xy 332.129397 -159.029721) (xy 332.099931 -158.983871) (xy 332.077289 -158.934294) (xy 332.061934 -158.881999)
			(xy 332.054178 -158.828051) (xy 332.053692 -158.8008) (xy 332.054175 -158.771881) (xy 332.062907 -158.714707)
			(xy 332.080169 -158.659506) (xy 332.105567 -158.607544) (xy 332.138519 -158.560011) (xy 332.178268 -158.517997)
			(xy 332.200758 -158.49981) (xy 332.20956 -158.492199) (xy 332.219744 -158.471301) (xy 332.220316 -158.459678)
			(xy 332.220316 -158.379922) (xy 332.219744 -158.368294) (xy 332.209578 -158.347385) (xy 332.200758 -158.33979)
			(xy 332.179975 -158.323037) (xy 332.142845 -158.284683) (xy 332.111423 -158.241529) (xy 332.086324 -158.194415)
			(xy 332.068038 -158.144263) (xy 332.056922 -158.092051) (xy 332.053192 -158.0388) (xy 332.056922 -157.985549)
			(xy 332.068038 -157.933337) (xy 332.086324 -157.883185) (xy 332.111423 -157.836071) (xy 332.142845 -157.792917)
			(xy 332.179975 -157.754563) (xy 332.200758 -157.73781) (xy 332.20956 -157.730199) (xy 332.219744 -157.709301)
			(xy 332.220316 -157.697678) (xy 332.220316 -157.617922) (xy 332.219744 -157.606294) (xy 332.209578 -157.585385)
			(xy 332.200758 -157.57779) (xy 332.178261 -157.559615) (xy 332.138529 -157.517591) (xy 332.105592 -157.470052)
			(xy 332.080207 -157.418088) (xy 332.062953 -157.362888) (xy 332.054226 -157.305717) (xy 332.053692 -157.2768)
			(xy 332.054147 -157.250497) (xy 332.061379 -157.198391) (xy 332.075705 -157.147774) (xy 332.096853 -157.099607)
			(xy 332.124422 -157.054805) (xy 332.140814 -157.03423) (xy 332.149704 -157.023308) (xy 332.154022 -156.995876)
			(xy 332.109826 -156.88691) (xy 332.087474 -156.870146) (xy 332.073758 -156.868622) (xy 332.046146 -156.864948)
			(xy 331.992284 -156.850759) (xy 331.941057 -156.828892) (xy 331.893552 -156.79981) (xy 331.85078 -156.764131)
			(xy 331.813649 -156.722614) (xy 331.782948 -156.67614) (xy 331.759328 -156.625696) (xy 331.743292 -156.572355)
			(xy 331.735181 -156.51725) (xy 331.734668 -156.4894) (xy 331.735161 -156.460482) (xy 331.743891 -156.403308)
			(xy 331.761153 -156.348108) (xy 331.786549 -156.296146) (xy 331.819498 -156.248613) (xy 331.859245 -156.206598)
			(xy 331.881734 -156.18841) (xy 331.890532 -156.180795) (xy 331.900719 -156.1599) (xy 331.901292 -156.148278)
			(xy 331.901292 -156.068522) (xy 331.900729 -156.056893) (xy 331.890557 -156.035983) (xy 331.881734 -156.02839)
			(xy 331.860952 -156.011636) (xy 331.823824 -155.973282) (xy 331.792405 -155.930127) (xy 331.767307 -155.883013)
			(xy 331.749022 -155.832862) (xy 331.737907 -155.780651) (xy 331.734177 -155.7274) (xy 327.35774 -155.7274)
			(xy 327.35774 -157.664658) (xy 327.358756 -157.675072) (xy 327.365614 -157.698948) (xy 327.369424 -157.705044)
			(xy 327.424778 -157.794528) (xy 327.529162 -157.977252) (xy 327.62617 -158.163998) (xy 327.715647 -158.354466)
			(xy 327.797451 -158.548354) (xy 327.87145 -158.745353) (xy 327.937528 -158.945148) (xy 327.995578 -159.147422)
			(xy 328.045508 -159.351851) (xy 328.08724 -159.558111) (xy 328.120705 -159.765871) (xy 328.145851 -159.974802)
			(xy 328.162638 -160.18457) (xy 328.171039 -160.394841) (xy 328.171556 -160.50006) (xy 328.170973 -160.610858)
			(xy 328.169948 -160.635188) (xy 340.000336 -160.635188) (xy 340.000336 -151.839422) (xy 340.000764 -151.829353)
			(xy 340.008482 -151.810755) (xy 340.015322 -151.803354) (xy 340.52256 -151.29637) (xy 340.529976 -151.289551)
			(xy 340.548563 -151.28182) (xy 340.558628 -151.281384) (xy 350.19996 -151.281384) (xy 350.210027 -151.280942)
			(xy 350.228626 -151.273233) (xy 350.236028 -151.266398) (xy 352.702622 -148.79955) (xy 352.710026 -148.792715)
			(xy 352.728622 -148.784991) (xy 352.73869 -148.784564) (xy 363.615986 -148.784564) (xy 363.626057 -148.78498)
			(xy 363.644655 -148.792705) (xy 363.652054 -148.79955) (xy 364.774226 -149.921976) (xy 364.781052 -149.929387)
			(xy 364.788779 -149.947978) (xy 364.789212 -149.958044) (xy 364.789212 -157.46831) (xy 365.557825 -157.46831)
			(xy 365.561553 -157.415059) (xy 365.572669 -157.362848) (xy 365.590955 -157.312696) (xy 365.616054 -157.265584)
			(xy 365.647476 -157.22243) (xy 365.684607 -157.184079) (xy 365.70539 -157.167326) (xy 365.714174 -157.159696)
			(xy 365.724371 -157.138813) (xy 365.724948 -157.127194) (xy 365.724948 -157.047438) (xy 365.724448 -157.035801)
			(xy 365.714233 -157.01489) (xy 365.70539 -157.007306) (xy 365.684622 -156.990534) (xy 365.647489 -156.952185)
			(xy 365.616065 -156.909033) (xy 365.590963 -156.861922) (xy 365.572675 -156.811771) (xy 365.561556 -156.75956)
			(xy 365.557825 -156.70631) (xy 365.561553 -156.653059) (xy 365.572669 -156.600848) (xy 365.590955 -156.550696)
			(xy 365.616054 -156.503584) (xy 365.647476 -156.46043) (xy 365.684607 -156.422079) (xy 365.70539 -156.405326)
			(xy 365.714174 -156.397696) (xy 365.724371 -156.376813) (xy 365.724948 -156.365194) (xy 365.724948 -156.285438)
			(xy 365.724448 -156.273801) (xy 365.714233 -156.25289) (xy 365.70539 -156.245306) (xy 365.684622 -156.228534)
			(xy 365.647489 -156.190185) (xy 365.616065 -156.147033) (xy 365.590963 -156.099922) (xy 365.572675 -156.049771)
			(xy 365.561556 -155.99756) (xy 365.557825 -155.94431) (xy 365.561553 -155.891059) (xy 365.572669 -155.838848)
			(xy 365.590955 -155.788696) (xy 365.616054 -155.741584) (xy 365.647476 -155.69843) (xy 365.684607 -155.660079)
			(xy 365.70539 -155.643326) (xy 365.714174 -155.635696) (xy 365.724371 -155.614813) (xy 365.724948 -155.603194)
			(xy 365.724948 -155.523438) (xy 365.724448 -155.511801) (xy 365.714233 -155.49089) (xy 365.70539 -155.483306)
			(xy 365.684622 -155.466534) (xy 365.647489 -155.428185) (xy 365.616065 -155.385033) (xy 365.590963 -155.337922)
			(xy 365.572675 -155.287771) (xy 365.561556 -155.23556) (xy 365.557825 -155.18231) (xy 365.561553 -155.129059)
			(xy 365.572669 -155.076848) (xy 365.590955 -155.026696) (xy 365.616054 -154.979584) (xy 365.647476 -154.93643)
			(xy 365.684607 -154.898079) (xy 365.70539 -154.881326) (xy 365.714174 -154.873696) (xy 365.724371 -154.852813)
			(xy 365.724948 -154.841194) (xy 365.724948 -154.761438) (xy 365.724448 -154.749801) (xy 365.714233 -154.72889)
			(xy 365.70539 -154.721306) (xy 365.682907 -154.703114) (xy 365.643173 -154.661094) (xy 365.610234 -154.613559)
			(xy 365.584845 -154.561598) (xy 365.567589 -154.506401) (xy 365.558859 -154.449232) (xy 365.558324 -154.420316)
			(xy 365.55877 -154.393062) (xy 365.566526 -154.339109) (xy 365.581882 -154.286809) (xy 365.604525 -154.237227)
			(xy 365.633994 -154.191372) (xy 365.669689 -154.150178) (xy 365.710885 -154.114484) (xy 365.756741 -154.085017)
			(xy 365.806324 -154.062376) (xy 365.858625 -154.047023) (xy 365.912578 -154.039269) (xy 365.939832 -154.038808)
			(xy 365.968747 -154.039372) (xy 366.025916 -154.048091) (xy 366.081115 -154.06534) (xy 366.133077 -154.090723)
			(xy 366.180612 -154.123658) (xy 366.222631 -154.163392) (xy 366.240822 -154.185874) (xy 366.248417 -154.194693)
			(xy 366.269327 -154.204867) (xy 366.280954 -154.205432) (xy 366.36071 -154.205432) (xy 366.372344 -154.204908)
			(xy 366.393255 -154.194711) (xy 366.400842 -154.185874) (xy 366.417595 -154.165091) (xy 366.455949 -154.127961)
			(xy 366.499103 -154.096539) (xy 366.546217 -154.07144) (xy 366.596369 -154.053154) (xy 366.64858 -154.042037)
			(xy 366.701832 -154.038307) (xy 366.755084 -154.042037) (xy 366.807295 -154.053154) (xy 366.857447 -154.07144)
			(xy 366.904561 -154.096539) (xy 366.947715 -154.127961) (xy 366.986069 -154.165091) (xy 367.002822 -154.185874)
			(xy 367.010417 -154.194693) (xy 367.031327 -154.204867) (xy 367.042954 -154.205432) (xy 367.12271 -154.205432)
			(xy 367.134344 -154.204908) (xy 367.155255 -154.194711) (xy 367.162842 -154.185874) (xy 367.179595 -154.165091)
			(xy 367.217949 -154.127961) (xy 367.261103 -154.096539) (xy 367.308217 -154.07144) (xy 367.358369 -154.053154)
			(xy 367.41058 -154.042037) (xy 367.463832 -154.038307) (xy 367.517084 -154.042037) (xy 367.569295 -154.053154)
			(xy 367.619447 -154.07144) (xy 367.666561 -154.096539) (xy 367.709715 -154.127961) (xy 367.748069 -154.165091)
			(xy 367.764822 -154.185874) (xy 367.772417 -154.194693) (xy 367.793327 -154.204867) (xy 367.804954 -154.205432)
			(xy 367.88471 -154.205432) (xy 367.896344 -154.204908) (xy 367.917255 -154.194711) (xy 367.924842 -154.185874)
			(xy 367.941595 -154.165091) (xy 367.979949 -154.127961) (xy 368.023103 -154.096539) (xy 368.070217 -154.07144)
			(xy 368.120369 -154.053154) (xy 368.17258 -154.042037) (xy 368.225832 -154.038307) (xy 368.279084 -154.042037)
			(xy 368.331295 -154.053154) (xy 368.381447 -154.07144) (xy 368.428561 -154.096539) (xy 368.471715 -154.127961)
			(xy 368.510069 -154.165091) (xy 368.526822 -154.185874) (xy 368.534417 -154.194693) (xy 368.555327 -154.204867)
			(xy 368.566954 -154.205432) (xy 368.64671 -154.205432) (xy 368.658344 -154.204908) (xy 368.679255 -154.194711)
			(xy 368.686842 -154.185874) (xy 368.703595 -154.165091) (xy 368.741949 -154.127961) (xy 368.785103 -154.096539)
			(xy 368.832217 -154.07144) (xy 368.882369 -154.053154) (xy 368.93458 -154.042037) (xy 368.987832 -154.038307)
			(xy 369.041084 -154.042037) (xy 369.093295 -154.053154) (xy 369.143447 -154.07144) (xy 369.190561 -154.096539)
			(xy 369.233715 -154.127961) (xy 369.272069 -154.165091) (xy 369.288822 -154.185874) (xy 369.296417 -154.194693)
			(xy 369.317327 -154.204867) (xy 369.328954 -154.205432) (xy 369.40871 -154.205432) (xy 369.420344 -154.204908)
			(xy 369.441255 -154.194711) (xy 369.448842 -154.185874) (xy 369.465595 -154.165091) (xy 369.503949 -154.127961)
			(xy 369.547103 -154.096539) (xy 369.594217 -154.07144) (xy 369.644369 -154.053154) (xy 369.69658 -154.042037)
			(xy 369.749832 -154.038307) (xy 369.803084 -154.042037) (xy 369.855295 -154.053154) (xy 369.905447 -154.07144)
			(xy 369.952561 -154.096539) (xy 369.995715 -154.127961) (xy 370.034069 -154.165091) (xy 370.050822 -154.185874)
			(xy 370.058417 -154.194693) (xy 370.079327 -154.204867) (xy 370.090954 -154.205432) (xy 370.17071 -154.205432)
			(xy 370.182344 -154.204908) (xy 370.203255 -154.194711) (xy 370.210842 -154.185874) (xy 370.227595 -154.165091)
			(xy 370.265949 -154.127961) (xy 370.309103 -154.096539) (xy 370.356217 -154.07144) (xy 370.406369 -154.053154)
			(xy 370.45858 -154.042037) (xy 370.511832 -154.038307) (xy 370.565084 -154.042037) (xy 370.617295 -154.053154)
			(xy 370.667447 -154.07144) (xy 370.714561 -154.096539) (xy 370.757715 -154.127961) (xy 370.796069 -154.165091)
			(xy 370.812822 -154.185874) (xy 370.820417 -154.194693) (xy 370.841327 -154.204867) (xy 370.852954 -154.205432)
			(xy 370.93271 -154.205432) (xy 370.944344 -154.204908) (xy 370.965255 -154.194711) (xy 370.972842 -154.185874)
			(xy 370.989595 -154.165091) (xy 371.027949 -154.127961) (xy 371.071103 -154.096539) (xy 371.118217 -154.07144)
			(xy 371.168369 -154.053154) (xy 371.22058 -154.042037) (xy 371.273832 -154.038307) (xy 371.327084 -154.042037)
			(xy 371.379295 -154.053154) (xy 371.429447 -154.07144) (xy 371.476561 -154.096539) (xy 371.519715 -154.127961)
			(xy 371.558069 -154.165091) (xy 371.574822 -154.185874) (xy 371.582417 -154.194693) (xy 371.603327 -154.204867)
			(xy 371.614954 -154.205432) (xy 371.69471 -154.205432) (xy 371.706344 -154.204908) (xy 371.727255 -154.194711)
			(xy 371.734842 -154.185874) (xy 371.751595 -154.165091) (xy 371.789949 -154.127961) (xy 371.833103 -154.096539)
			(xy 371.880217 -154.07144) (xy 371.930369 -154.053154) (xy 371.98258 -154.042037) (xy 372.035832 -154.038307)
			(xy 372.089084 -154.042037) (xy 372.141295 -154.053154) (xy 372.191447 -154.07144) (xy 372.238561 -154.096539)
			(xy 372.281715 -154.127961) (xy 372.320069 -154.165091) (xy 372.336822 -154.185874) (xy 372.344417 -154.194693)
			(xy 372.365327 -154.204867) (xy 372.376954 -154.205432) (xy 372.45671 -154.205432) (xy 372.468344 -154.204908)
			(xy 372.489255 -154.194711) (xy 372.496842 -154.185874) (xy 372.515003 -154.163365) (xy 372.55703 -154.123633)
			(xy 372.604571 -154.090697) (xy 372.656538 -154.065314) (xy 372.711741 -154.048063) (xy 372.768914 -154.03934)
			(xy 372.797832 -154.038808) (xy 372.825085 -154.039248) (xy 372.879035 -154.047009) (xy 372.931332 -154.062369)
			(xy 372.98091 -154.085015) (xy 373.026761 -154.114487) (xy 373.067951 -154.150183) (xy 373.103642 -154.191378)
			(xy 373.133108 -154.237232) (xy 373.155747 -154.286813) (xy 373.171101 -154.339112) (xy 373.178855 -154.393063)
			(xy 373.17934 -154.420316) (xy 373.178784 -154.449232) (xy 373.170066 -154.506402) (xy 373.152817 -154.561601)
			(xy 373.127432 -154.613564) (xy 373.094494 -154.661098) (xy 373.054758 -154.703116) (xy 373.032274 -154.721306)
			(xy 373.02347 -154.728916) (xy 373.013285 -154.749815) (xy 373.012716 -154.761438) (xy 373.012716 -154.841194)
			(xy 373.013267 -154.852824) (xy 373.023447 -154.873734) (xy 373.032274 -154.881326) (xy 373.053071 -154.898062)
			(xy 373.090199 -154.936418) (xy 373.121617 -154.979576) (xy 373.146714 -155.026691) (xy 373.164998 -155.076845)
			(xy 373.176112 -155.129058) (xy 373.17984 -155.18231) (xy 373.17611 -155.235562) (xy 373.164992 -155.287774)
			(xy 373.146706 -155.337927) (xy 373.121607 -155.385041) (xy 373.090186 -155.428197) (xy 373.053057 -155.466552)
			(xy 373.032274 -155.483306) (xy 373.02347 -155.490916) (xy 373.013285 -155.511815) (xy 373.012716 -155.523438)
			(xy 373.012716 -155.603194) (xy 373.013267 -155.614824) (xy 373.023447 -155.635734) (xy 373.029025 -155.640532)
			(xy 378.748036 -155.640532) (xy 378.748512 -155.613162) (xy 378.756326 -155.558983) (xy 378.771812 -155.50648)
			(xy 378.794652 -155.456733) (xy 378.824375 -155.410766) (xy 378.842016 -155.389834) (xy 378.84227 -155.38958)
			(xy 378.847879 -155.382509) (xy 378.85411 -155.36558) (xy 378.854462 -155.35656) (xy 378.854462 -155.289504)
			(xy 378.854111 -155.280486) (xy 378.84786 -155.263569) (xy 378.84227 -155.256484) (xy 378.842016 -155.256484)
			(xy 378.842016 -155.25623) (xy 378.824407 -155.235272) (xy 378.794682 -155.189308) (xy 378.771835 -155.139566)
			(xy 378.756337 -155.087068) (xy 378.748506 -155.032893) (xy 378.748502 -154.978155) (xy 378.756327 -154.923979)
			(xy 378.771818 -154.871479) (xy 378.794659 -154.821734) (xy 378.824378 -154.775767) (xy 378.842016 -154.754834)
			(xy 378.84227 -154.75458) (xy 378.847879 -154.747509) (xy 378.85411 -154.73058) (xy 378.854462 -154.72156)
			(xy 378.854462 -154.654504) (xy 378.854111 -154.645486) (xy 378.84786 -154.628569) (xy 378.84227 -154.621484)
			(xy 378.842016 -154.621484) (xy 378.842016 -154.62123) (xy 378.824407 -154.600272) (xy 378.794682 -154.554308)
			(xy 378.771835 -154.504566) (xy 378.756337 -154.452068) (xy 378.748506 -154.397893) (xy 378.748502 -154.343155)
			(xy 378.756327 -154.288979) (xy 378.771818 -154.236479) (xy 378.794659 -154.186734) (xy 378.824378 -154.140767)
			(xy 378.842016 -154.119834) (xy 378.84227 -154.11958) (xy 378.847879 -154.112509) (xy 378.85411 -154.09558)
			(xy 378.854462 -154.08656) (xy 378.854462 -154.019504) (xy 378.854111 -154.010486) (xy 378.84786 -153.993569)
			(xy 378.84227 -153.986484) (xy 378.842016 -153.986484) (xy 378.842016 -153.98623) (xy 378.82438 -153.965295)
			(xy 378.794667 -153.919324) (xy 378.77183 -153.869577) (xy 378.756339 -153.817076) (xy 378.74851 -153.762901)
			(xy 378.748036 -153.735532) (xy 378.748485 -153.708278) (xy 378.756239 -153.654324) (xy 378.771593 -153.602023)
			(xy 378.794235 -153.55244) (xy 378.823704 -153.506585) (xy 378.859399 -153.465391) (xy 378.900595 -153.429697)
			(xy 378.946451 -153.400229) (xy 378.996035 -153.377589) (xy 379.048336 -153.362236) (xy 379.10229 -153.354484)
			(xy 379.129544 -153.354024) (xy 379.15945 -153.35459) (xy 379.218528 -153.363942) (xy 379.275423 -153.382394)
			(xy 379.328744 -153.409495) (xy 379.377186 -153.444582) (xy 379.398784 -153.465276) (xy 379.405642 -153.472134)
			(xy 379.423422 -153.479754) (xy 379.512576 -153.482548) (xy 379.530356 -153.476198) (xy 379.537722 -153.469594)
			(xy 379.545539 -153.462796) (xy 379.561805 -153.449962) (xy 379.570234 -153.44394) (xy 379.570488 -153.44394)
			(xy 379.579143 -153.437041) (xy 379.590074 -153.417822) (xy 379.59157 -153.406856) (xy 379.598428 -153.329386)
			(xy 379.598866 -153.318223) (xy 379.591216 -153.297262) (xy 379.583696 -153.289) (xy 379.562873 -153.267422)
			(xy 379.527622 -153.218915) (xy 379.500396 -153.165488) (xy 379.481867 -153.10846) (xy 379.47249 -153.049234)
			(xy 379.471936 -153.019252) (xy 379.472424 -152.991882) (xy 379.480235 -152.937704) (xy 379.495719 -152.885201)
			(xy 379.518556 -152.835453) (xy 379.548276 -152.789486) (xy 379.565916 -152.768554) (xy 379.56617 -152.7683)
			(xy 379.571771 -152.761224) (xy 379.578007 -152.744299) (xy 379.578362 -152.73528) (xy 379.578362 -152.668224)
			(xy 379.578002 -152.659207) (xy 379.571757 -152.64229) (xy 379.56617 -152.635204) (xy 379.565916 -152.635204)
			(xy 379.565916 -152.63495) (xy 379.548289 -152.614008) (xy 379.518575 -152.568038) (xy 379.495737 -152.518293)
			(xy 379.480243 -152.465795) (xy 379.472411 -152.411621) (xy 379.471936 -152.384252) (xy 379.472333 -152.356998)
			(xy 379.480097 -152.303044) (xy 379.495461 -152.250745) (xy 379.518111 -152.201165) (xy 379.547586 -152.155313)
			(xy 379.583287 -152.114122) (xy 379.624486 -152.078431) (xy 379.670346 -152.048967) (xy 379.719932 -152.026329)
			(xy 379.772234 -152.010978) (xy 379.826189 -152.003227) (xy 379.853444 -152.002744) (xy 379.880814 -152.003232)
			(xy 379.934992 -152.011043) (xy 379.987495 -152.026526) (xy 380.037243 -152.049363) (xy 380.08321 -152.079084)
			(xy 380.104142 -152.096724) (xy 380.104396 -152.096978) (xy 380.111473 -152.102578) (xy 380.128397 -152.108815)
			(xy 380.137416 -152.10917) (xy 380.204472 -152.10917) (xy 380.213488 -152.108806) (xy 380.230406 -152.102564)
			(xy 380.237492 -152.096978) (xy 380.237492 -152.096724) (xy 380.237746 -152.096724) (xy 380.258679 -152.079083)
			(xy 380.304647 -152.049359) (xy 380.354393 -152.026513) (xy 380.406895 -152.011017) (xy 380.461073 -152.003188)
			(xy 380.515815 -152.003188) (xy 380.569993 -152.011017) (xy 380.622495 -152.026513) (xy 380.672241 -152.049359)
			(xy 380.718209 -152.079083) (xy 380.739142 -152.096724) (xy 380.739396 -152.096978) (xy 380.746473 -152.102578)
			(xy 380.763397 -152.108815) (xy 380.772416 -152.10917) (xy 380.839472 -152.10917) (xy 380.848488 -152.108806)
			(xy 380.865406 -152.102564) (xy 380.872492 -152.096978) (xy 380.872492 -152.096724) (xy 380.872746 -152.096724)
			(xy 380.893679 -152.079083) (xy 380.939647 -152.049359) (xy 380.989393 -152.026513) (xy 381.041895 -152.011017)
			(xy 381.096073 -152.003188) (xy 381.150815 -152.003188) (xy 381.204993 -152.011017) (xy 381.257495 -152.026513)
			(xy 381.307241 -152.049359) (xy 381.353209 -152.079083) (xy 381.374142 -152.096724) (xy 381.374396 -152.096978)
			(xy 381.381473 -152.102578) (xy 381.398397 -152.108815) (xy 381.407416 -152.10917) (xy 381.474472 -152.10917)
			(xy 381.483488 -152.108806) (xy 381.500406 -152.102564) (xy 381.507492 -152.096978) (xy 381.507492 -152.096724)
			(xy 381.507746 -152.096724) (xy 381.528691 -152.0791) (xy 381.57466 -152.049385) (xy 381.624404 -152.026546)
			(xy 381.676902 -152.011052) (xy 381.731076 -152.00322) (xy 381.758444 -152.002744) (xy 381.785694 -152.003237)
			(xy 381.839639 -152.010998) (xy 381.891931 -152.026356) (xy 381.941505 -152.048999) (xy 381.987353 -152.078465)
			(xy 382.028541 -152.114156) (xy 382.064232 -152.155344) (xy 382.093699 -152.201191) (xy 382.116342 -152.250765)
			(xy 382.131701 -152.303057) (xy 382.139463 -152.357002) (xy 382.139952 -152.384252) (xy 382.139469 -152.411622)
			(xy 382.131657 -152.465801) (xy 382.116173 -152.518304) (xy 382.093334 -152.568051) (xy 382.063612 -152.614018)
			(xy 382.045972 -152.63495) (xy 382.045718 -152.635204) (xy 382.040126 -152.642287) (xy 382.033882 -152.659206)
			(xy 382.033526 -152.668224) (xy 382.033526 -152.73528) (xy 382.033887 -152.744297) (xy 382.040131 -152.761214)
			(xy 382.045718 -152.7683) (xy 382.045972 -152.7683) (xy 382.045972 -152.768554) (xy 382.063599 -152.789496)
			(xy 382.093313 -152.835466) (xy 382.116152 -152.885211) (xy 382.131646 -152.937709) (xy 382.139477 -152.991883)
			(xy 382.139952 -153.019252) (xy 382.139434 -153.048033) (xy 382.13078 -153.104939) (xy 382.113677 -153.159901)
			(xy 382.088512 -153.21167) (xy 382.055856 -153.259071) (xy 382.016451 -153.30103) (xy 381.97119 -153.336593)
			(xy 381.946404 -153.35123) (xy 381.936752 -153.356818) (xy 381.92329 -153.37536) (xy 381.90805 -153.46426)
			(xy 381.90673 -153.475491) (xy 381.912791 -153.497245) (xy 381.919734 -153.50617) (xy 381.937187 -153.527084)
			(xy 381.96664 -153.572906) (xy 381.989282 -153.622449) (xy 382.004654 -153.674706) (xy 382.012443 -153.728617)
			(xy 382.012952 -153.755852) (xy 382.012469 -153.783222) (xy 382.004657 -153.837401) (xy 381.989173 -153.889904)
			(xy 381.966334 -153.939651) (xy 381.936612 -153.985618) (xy 381.918972 -154.00655) (xy 381.918718 -154.006804)
			(xy 381.913126 -154.013887) (xy 381.906882 -154.030806) (xy 381.906526 -154.039824) (xy 381.906526 -154.10688)
			(xy 381.906887 -154.115897) (xy 381.913131 -154.132814) (xy 381.918718 -154.1399) (xy 381.918972 -154.1399)
			(xy 381.918972 -154.140154) (xy 381.936566 -154.161125) (xy 381.966293 -154.207086) (xy 381.989141 -154.256826)
			(xy 382.004641 -154.309322) (xy 382.012474 -154.363496) (xy 382.012479 -154.418232) (xy 382.004656 -154.472407)
			(xy 381.989166 -154.524906) (xy 381.966327 -154.574651) (xy 381.936609 -154.620617) (xy 381.918972 -154.64155)
			(xy 381.918718 -154.641804) (xy 381.913126 -154.648887) (xy 381.906882 -154.665806) (xy 381.906526 -154.674824)
			(xy 381.906526 -154.74188) (xy 381.906887 -154.750897) (xy 381.913131 -154.767814) (xy 381.918718 -154.7749)
			(xy 381.918972 -154.7749) (xy 381.918972 -154.775154) (xy 381.936566 -154.796125) (xy 381.966293 -154.842086)
			(xy 381.989141 -154.891826) (xy 382.004641 -154.944322) (xy 382.012474 -154.998496) (xy 382.012479 -155.053232)
			(xy 382.004656 -155.107407) (xy 381.989166 -155.159906) (xy 381.966327 -155.209651) (xy 381.936609 -155.255617)
			(xy 381.918972 -155.27655) (xy 381.918718 -155.276804) (xy 381.913126 -155.283887) (xy 381.906882 -155.300806)
			(xy 381.906526 -155.309824) (xy 381.906526 -155.37688) (xy 381.906887 -155.385897) (xy 381.913131 -155.402814)
			(xy 381.918718 -155.4099) (xy 381.918972 -155.4099) (xy 381.918972 -155.410154) (xy 381.936599 -155.431096)
			(xy 381.966313 -155.477066) (xy 381.989152 -155.526811) (xy 382.004646 -155.579309) (xy 382.012477 -155.633483)
			(xy 382.012952 -155.660852) (xy 382.012435 -155.688653) (xy 382.004382 -155.743668) (xy 381.988424 -155.79693)
			(xy 381.9649 -155.84731) (xy 381.934309 -155.89374) (xy 381.897299 -155.935234) (xy 381.8763 -155.95346)
			(xy 381.86815 -155.961065) (xy 381.858649 -155.981196) (xy 381.858012 -155.992322) (xy 381.858012 -156.071824)
			(xy 381.876046 -156.097732) (xy 381.891286 -156.10332) (xy 381.918266 -156.113936) (xy 381.968932 -156.142116)
			(xy 382.014751 -156.177637) (xy 382.054669 -156.21968) (xy 382.087768 -156.267279) (xy 382.113284 -156.319338)
			(xy 382.130631 -156.374657) (xy 382.139409 -156.431964) (xy 382.139952 -156.460952) (xy 382.139469 -156.488322)
			(xy 382.131657 -156.542501) (xy 382.116173 -156.595004) (xy 382.093334 -156.644751) (xy 382.063612 -156.690718)
			(xy 382.045972 -156.71165) (xy 382.045718 -156.711904) (xy 382.040126 -156.718987) (xy 382.033882 -156.735906)
			(xy 382.033526 -156.744924) (xy 382.033526 -156.81198) (xy 382.033887 -156.820997) (xy 382.040131 -156.837914)
			(xy 382.045718 -156.845) (xy 382.045972 -156.845) (xy 382.045972 -156.845254) (xy 382.063599 -156.866196)
			(xy 382.093313 -156.912166) (xy 382.116152 -156.961911) (xy 382.131646 -157.014409) (xy 382.139477 -157.068583)
			(xy 382.139952 -157.095952) (xy 382.1394 -157.123202) (xy 382.131651 -157.177147) (xy 382.116303 -157.229441)
			(xy 382.093669 -157.279018) (xy 382.064211 -157.324869) (xy 382.028526 -157.366061) (xy 381.987343 -157.401755)
			(xy 381.941499 -157.431225) (xy 381.891927 -157.453871) (xy 381.839637 -157.469231) (xy 381.785694 -157.476994)
			(xy 381.758444 -157.47746) (xy 381.731074 -157.476978) (xy 381.676895 -157.469165) (xy 381.624392 -157.453681)
			(xy 381.574645 -157.430842) (xy 381.528678 -157.40112) (xy 381.507746 -157.38348) (xy 381.507492 -157.383226)
			(xy 381.500418 -157.377621) (xy 381.483491 -157.371387) (xy 381.474472 -157.371034) (xy 381.407416 -157.371034)
			(xy 381.398399 -157.371391) (xy 381.381482 -157.377638) (xy 381.374396 -157.383226) (xy 381.374396 -157.38348)
			(xy 381.374142 -157.38348) (xy 381.353209 -157.401121) (xy 381.307241 -157.430845) (xy 381.257495 -157.453691)
			(xy 381.204993 -157.469187) (xy 381.150815 -157.477016) (xy 381.096073 -157.477016) (xy 381.041895 -157.469187)
			(xy 380.989393 -157.453691) (xy 380.939647 -157.430845) (xy 380.893679 -157.401121) (xy 380.872746 -157.38348)
			(xy 380.872492 -157.383226) (xy 380.865418 -157.377621) (xy 380.848491 -157.371387) (xy 380.839472 -157.371034)
			(xy 380.772416 -157.371034) (xy 380.763399 -157.371391) (xy 380.746482 -157.377638) (xy 380.739396 -157.383226)
			(xy 380.739396 -157.38348) (xy 380.739142 -157.38348) (xy 380.718209 -157.401121) (xy 380.672241 -157.430845)
			(xy 380.622495 -157.453691) (xy 380.569993 -157.469187) (xy 380.515815 -157.477016) (xy 380.461073 -157.477016)
			(xy 380.406895 -157.469187) (xy 380.354393 -157.453691) (xy 380.304647 -157.430845) (xy 380.258679 -157.401121)
			(xy 380.237746 -157.38348) (xy 380.237492 -157.383226) (xy 380.230418 -157.377621) (xy 380.213491 -157.371387)
			(xy 380.204472 -157.371034) (xy 380.137416 -157.371034) (xy 380.128399 -157.371391) (xy 380.111482 -157.377638)
			(xy 380.104396 -157.383226) (xy 380.104396 -157.38348) (xy 380.104142 -157.38348) (xy 380.083202 -157.40111)
			(xy 380.037232 -157.430824) (xy 379.987486 -157.453662) (xy 379.934987 -157.469155) (xy 379.880813 -157.476985)
			(xy 379.853444 -157.47746) (xy 379.82354 -157.476843) (xy 379.764464 -157.467504) (xy 379.707569 -157.449064)
			(xy 379.654247 -157.421974) (xy 379.605804 -157.386898) (xy 379.584204 -157.366208) (xy 379.577346 -157.35935)
			(xy 379.559566 -157.35173) (xy 379.470412 -157.348936) (xy 379.452632 -157.355286) (xy 379.445266 -157.36189)
			(xy 379.424251 -157.37974) (xy 379.378064 -157.409851) (xy 379.328024 -157.433002) (xy 379.275173 -157.448711)
			(xy 379.220612 -157.456652) (xy 379.193044 -157.45714) (xy 379.165794 -157.456604) (xy 379.111847 -157.448854)
			(xy 379.059552 -157.433505) (xy 379.009975 -157.41087) (xy 378.964123 -157.381409) (xy 378.92293 -157.345723)
			(xy 378.887236 -157.304538) (xy 378.857767 -157.258692) (xy 378.835122 -157.209119) (xy 378.819762 -157.156827)
			(xy 378.812002 -157.102882) (xy 378.811536 -157.075632) (xy 378.812012 -157.048262) (xy 378.819826 -156.994083)
			(xy 378.835312 -156.94158) (xy 378.858152 -156.891833) (xy 378.887875 -156.845866) (xy 378.905516 -156.824934)
			(xy 378.90577 -156.82468) (xy 378.911379 -156.817609) (xy 378.91761 -156.80068) (xy 378.917962 -156.79166)
			(xy 378.917962 -156.724604) (xy 378.917611 -156.715586) (xy 378.91136 -156.698669) (xy 378.90577 -156.691584)
			(xy 378.905516 -156.691584) (xy 378.905516 -156.69133) (xy 378.88788 -156.670395) (xy 378.858167 -156.624424)
			(xy 378.83533 -156.574677) (xy 378.819839 -156.522176) (xy 378.81201 -156.468001) (xy 378.811536 -156.440632)
			(xy 378.812066 -156.411956) (xy 378.820635 -156.355248) (xy 378.837599 -156.300463) (xy 378.862576 -156.248836)
			(xy 378.895002 -156.201531) (xy 378.934147 -156.159616) (xy 378.956316 -156.14142) (xy 378.966222 -156.133546)
			(xy 378.976382 -156.110432) (xy 378.967492 -156.000704) (xy 378.95403 -155.979622) (xy 378.942854 -155.973272)
			(xy 378.917936 -155.958648) (xy 378.872393 -155.923103) (xy 378.832729 -155.881098) (xy 378.79985 -155.833593)
			(xy 378.774509 -155.781675) (xy 378.757285 -155.72653) (xy 378.74857 -155.669418) (xy 378.748036 -155.640532)
			(xy 373.029025 -155.640532) (xy 373.032274 -155.643326) (xy 373.053071 -155.660062) (xy 373.090199 -155.698418)
			(xy 373.121617 -155.741576) (xy 373.146714 -155.788691) (xy 373.164998 -155.838845) (xy 373.176112 -155.891058)
			(xy 373.17984 -155.94431) (xy 373.17611 -155.997562) (xy 373.164992 -156.049774) (xy 373.146706 -156.099927)
			(xy 373.121607 -156.147041) (xy 373.090186 -156.190197) (xy 373.053057 -156.228552) (xy 373.032274 -156.245306)
			(xy 373.02347 -156.252916) (xy 373.013285 -156.273815) (xy 373.012716 -156.285438) (xy 373.012716 -156.365194)
			(xy 373.013267 -156.376824) (xy 373.023447 -156.397734) (xy 373.032274 -156.405326) (xy 373.053071 -156.422062)
			(xy 373.090199 -156.460418) (xy 373.121617 -156.503576) (xy 373.146714 -156.550691) (xy 373.164998 -156.600845)
			(xy 373.176112 -156.653058) (xy 373.17984 -156.70631) (xy 373.17611 -156.759562) (xy 373.164992 -156.811774)
			(xy 373.146706 -156.861927) (xy 373.121607 -156.909041) (xy 373.090186 -156.952197) (xy 373.053057 -156.990552)
			(xy 373.032274 -157.007306) (xy 373.02347 -157.014916) (xy 373.013285 -157.035815) (xy 373.012716 -157.047438)
			(xy 373.012716 -157.127194) (xy 373.013267 -157.138824) (xy 373.023447 -157.159734) (xy 373.032274 -157.167326)
			(xy 373.053071 -157.184062) (xy 373.090199 -157.222418) (xy 373.121617 -157.265576) (xy 373.146714 -157.312691)
			(xy 373.164998 -157.362845) (xy 373.176112 -157.415058) (xy 373.17984 -157.46831) (xy 373.17611 -157.521562)
			(xy 373.164992 -157.573774) (xy 373.146706 -157.623927) (xy 373.121607 -157.671041) (xy 373.090186 -157.714197)
			(xy 373.053057 -157.752552) (xy 373.032274 -157.769306) (xy 373.02347 -157.776916) (xy 373.013285 -157.797815)
			(xy 373.012716 -157.809438) (xy 373.012716 -157.889194) (xy 373.013267 -157.900824) (xy 373.023447 -157.921734)
			(xy 373.032274 -157.929326) (xy 373.054765 -157.947509) (xy 373.0945 -157.98953) (xy 373.127439 -158.037066)
			(xy 373.152827 -158.089029) (xy 373.170081 -158.144228) (xy 373.178807 -158.201399) (xy 373.17934 -158.230316)
			(xy 373.178837 -158.257566) (xy 373.171079 -158.311512) (xy 373.155724 -158.363804) (xy 373.133083 -158.413379)
			(xy 373.103618 -158.459228) (xy 373.067929 -158.500417) (xy 373.026741 -158.536109) (xy 372.980893 -158.565575)
			(xy 372.931319 -158.588218) (xy 372.879027 -158.603576) (xy 372.825082 -158.611336) (xy 372.797832 -158.611824)
			(xy 372.768915 -158.611312) (xy 372.711742 -158.602585) (xy 372.656542 -158.585328) (xy 372.604579 -158.559936)
			(xy 372.557046 -158.52699) (xy 372.515031 -158.487245) (xy 372.496842 -158.464758) (xy 372.489214 -158.455973)
			(xy 372.468329 -158.445779) (xy 372.45671 -158.4452) (xy 372.376954 -158.4452) (xy 372.365321 -158.445727)
			(xy 372.344411 -158.455924) (xy 372.336822 -158.464758) (xy 372.320069 -158.485541) (xy 372.281715 -158.522671)
			(xy 372.238561 -158.554093) (xy 372.191447 -158.579192) (xy 372.141295 -158.597478) (xy 372.089084 -158.608595)
			(xy 372.035832 -158.612325) (xy 371.98258 -158.608595) (xy 371.930369 -158.597478) (xy 371.880217 -158.579192)
			(xy 371.833103 -158.554093) (xy 371.789949 -158.522671) (xy 371.751595 -158.485541) (xy 371.734842 -158.464758)
			(xy 371.727214 -158.455973) (xy 371.706329 -158.445779) (xy 371.69471 -158.4452) (xy 371.614954 -158.4452)
			(xy 371.603321 -158.445727) (xy 371.582411 -158.455924) (xy 371.574822 -158.464758) (xy 371.556608 -158.487222)
			(xy 371.514594 -158.526961) (xy 371.467065 -158.559903) (xy 371.415108 -158.585295) (xy 371.359914 -158.602555)
			(xy 371.302747 -158.611287) (xy 371.273832 -158.611824) (xy 371.246985 -158.611383) (xy 371.19382 -158.603872)
			(xy 371.142233 -158.588978) (xy 371.093246 -158.566998) (xy 371.047824 -158.538364) (xy 371.006867 -158.503644)
			(xy 370.971184 -158.463523) (xy 370.941481 -158.418794) (xy 370.918343 -158.370342) (xy 370.90985 -158.34487)
			(xy 370.90985 -158.344616) (xy 370.906145 -158.334478) (xy 370.891796 -158.318377) (xy 370.872119 -158.309548)
			(xy 370.861336 -158.309056) (xy 370.430298 -158.309056) (xy 370.422678 -158.311596) (xy 370.394291 -158.320136)
			(xy 370.335731 -158.329324) (xy 370.306092 -158.329884) (xy 370.276456 -158.329298) (xy 370.217897 -158.320116)
			(xy 370.189506 -158.311596) (xy 370.181886 -158.309056) (xy 369.795298 -158.309056) (xy 369.787678 -158.311596)
			(xy 369.759291 -158.320136) (xy 369.700731 -158.329324) (xy 369.671092 -158.329884) (xy 369.641456 -158.329298)
			(xy 369.582897 -158.320116) (xy 369.554506 -158.311596) (xy 369.546886 -158.309056) (xy 369.160298 -158.309056)
			(xy 369.152678 -158.311596) (xy 369.124291 -158.320136) (xy 369.065731 -158.329324) (xy 369.036092 -158.329884)
			(xy 369.006456 -158.329298) (xy 368.947897 -158.320116) (xy 368.919506 -158.311596) (xy 368.911886 -158.309056)
			(xy 368.525298 -158.309056) (xy 368.517678 -158.311596) (xy 368.489291 -158.320136) (xy 368.430731 -158.329324)
			(xy 368.401092 -158.329884) (xy 368.371456 -158.329298) (xy 368.312897 -158.320116) (xy 368.284506 -158.311596)
			(xy 368.276886 -158.309056) (xy 367.876328 -158.309056) (xy 367.865542 -158.309553) (xy 367.845852 -158.31836)
			(xy 367.831513 -158.334474) (xy 367.827814 -158.344616) (xy 367.827814 -158.34487) (xy 367.81935 -158.370349)
			(xy 367.79619 -158.418787) (xy 367.766471 -158.463501) (xy 367.730779 -158.50361) (xy 367.689819 -158.538322)
			(xy 367.6444 -158.566952) (xy 367.595417 -158.588935) (xy 367.543837 -158.603838) (xy 367.490677 -158.611365)
			(xy 367.463832 -158.611824) (xy 367.434915 -158.611312) (xy 367.377742 -158.602585) (xy 367.322542 -158.585328)
			(xy 367.270579 -158.559936) (xy 367.223046 -158.52699) (xy 367.181031 -158.487245) (xy 367.162842 -158.464758)
			(xy 367.155214 -158.455973) (xy 367.134329 -158.445779) (xy 367.12271 -158.4452) (xy 367.042954 -158.4452)
			(xy 367.031321 -158.445727) (xy 367.010411 -158.455924) (xy 367.002822 -158.464758) (xy 366.986069 -158.485541)
			(xy 366.947715 -158.522671) (xy 366.904561 -158.554093) (xy 366.857447 -158.579192) (xy 366.807295 -158.597478)
			(xy 366.755084 -158.608595) (xy 366.701832 -158.612325) (xy 366.64858 -158.608595) (xy 366.596369 -158.597478)
			(xy 366.546217 -158.579192) (xy 366.499103 -158.554093) (xy 366.455949 -158.522671) (xy 366.417595 -158.485541)
			(xy 366.400842 -158.464758) (xy 366.393214 -158.455973) (xy 366.372329 -158.445779) (xy 366.36071 -158.4452)
			(xy 366.280954 -158.4452) (xy 366.269321 -158.445727) (xy 366.248411 -158.455924) (xy 366.240822 -158.464758)
			(xy 366.222608 -158.487222) (xy 366.180594 -158.526961) (xy 366.133065 -158.559903) (xy 366.081108 -158.585295)
			(xy 366.025914 -158.602555) (xy 365.968747 -158.611287) (xy 365.939832 -158.611824) (xy 365.912581 -158.611315)
			(xy 365.858632 -158.603563) (xy 365.806336 -158.588212) (xy 365.756757 -158.565574) (xy 365.710905 -158.536111)
			(xy 365.669712 -158.500422) (xy 365.634018 -158.459234) (xy 365.604549 -158.413385) (xy 365.581905 -158.363809)
			(xy 365.566547 -158.311515) (xy 365.558788 -158.257567) (xy 365.558324 -158.230316) (xy 365.558845 -158.201399)
			(xy 365.567572 -158.144228) (xy 365.584829 -158.089028) (xy 365.61022 -158.037067) (xy 365.643164 -157.989533)
			(xy 365.682904 -157.947516) (xy 365.70539 -157.929326) (xy 365.714174 -157.921696) (xy 365.724371 -157.900813)
			(xy 365.724948 -157.889194) (xy 365.724948 -157.809438) (xy 365.724448 -157.797801) (xy 365.714233 -157.77689)
			(xy 365.70539 -157.769306) (xy 365.684622 -157.752534) (xy 365.647489 -157.714185) (xy 365.616065 -157.671033)
			(xy 365.590963 -157.623922) (xy 365.572675 -157.573771) (xy 365.561556 -157.52156) (xy 365.557825 -157.46831)
			(xy 364.789212 -157.46831) (xy 364.789212 -158.623) (xy 364.789634 -158.63307) (xy 364.797357 -158.651668)
			(xy 364.804198 -158.659068) (xy 365.511842 -159.366458) (xy 365.519238 -159.373303) (xy 365.53784 -159.381021)
			(xy 365.54791 -159.381444) (xy 383.796286 -159.381444) (xy 383.806356 -159.381865) (xy 383.824954 -159.389588)
			(xy 383.832354 -159.39643) (xy 384.332226 -159.896556) (xy 384.339043 -159.903974) (xy 384.346776 -159.92256)
			(xy 384.347212 -159.932624) (xy 384.347212 -167.872664) (xy 385.265676 -167.872664) (xy 385.265676 -151.917908)
			(xy 385.266085 -151.907837) (xy 385.273815 -151.889238) (xy 385.280662 -151.88184) (xy 385.859528 -151.302974)
			(xy 385.866921 -151.296125) (xy 385.885526 -151.288411) (xy 385.895596 -151.287988) (xy 392.805158 -151.287988)
			(xy 392.815228 -151.288412) (xy 392.833827 -151.296131) (xy 392.841226 -151.302974) (xy 394.188696 -152.650444)
			(xy 408.315158 -152.650444) (xy 408.319229 -152.594822) (xy 408.331355 -152.540385) (xy 408.351278 -152.488294)
			(xy 408.378574 -152.439659) (xy 408.41266 -152.395516) (xy 408.452809 -152.356807) (xy 408.498167 -152.324356)
			(xy 408.547767 -152.298855) (xy 408.600551 -152.280848) (xy 408.655394 -152.270718) (xy 408.711128 -152.268681)
			(xy 408.766565 -152.274781) (xy 408.820522 -152.288887) (xy 408.871851 -152.310699) (xy 408.919457 -152.339753)
			(xy 408.962325 -152.375428) (xy 408.999542 -152.416965) (xy 409.030315 -152.463478) (xy 409.053987 -152.513975)
			(xy 409.070055 -152.567382) (xy 409.078175 -152.622558) (xy 409.078684 -152.650444) (xy 409.078175 -152.67833)
			(xy 409.070055 -152.733506) (xy 409.053987 -152.786913) (xy 409.030315 -152.83741) (xy 408.999542 -152.883923)
			(xy 408.962325 -152.92546) (xy 408.919457 -152.961135) (xy 408.871851 -152.990189) (xy 408.820522 -153.012001)
			(xy 408.766565 -153.026107) (xy 408.711128 -153.032207) (xy 408.655394 -153.03017) (xy 408.600551 -153.02004)
			(xy 408.547767 -153.002033) (xy 408.498167 -152.976532) (xy 408.452809 -152.944081) (xy 408.41266 -152.905372)
			(xy 408.378574 -152.861229) (xy 408.351278 -152.812594) (xy 408.331355 -152.760503) (xy 408.319229 -152.706066)
			(xy 408.315158 -152.650444) (xy 394.188696 -152.650444) (xy 397.778986 -156.240734) (xy 397.786393 -156.247565)
			(xy 397.804987 -156.255289) (xy 397.815054 -156.25572) (xy 409.283408 -156.25572) (xy 409.293478 -156.256136)
			(xy 409.312076 -156.263863) (xy 409.319476 -156.270706) (xy 412.476696 -159.427926) (xy 414.223454 -159.427926)
			(xy 414.22394 -159.400675) (xy 414.231696 -159.346727) (xy 414.247051 -159.294432) (xy 414.269693 -159.244855)
			(xy 414.299159 -159.199005) (xy 414.33485 -159.157814) (xy 414.376041 -159.122123) (xy 414.421891 -159.092657)
			(xy 414.471468 -159.070015) (xy 414.523763 -159.05466) (xy 414.577711 -159.046904) (xy 414.632213 -159.046904)
			(xy 414.686161 -159.05466) (xy 414.738456 -159.070015) (xy 414.788033 -159.092657) (xy 414.833883 -159.122123)
			(xy 414.875074 -159.157814) (xy 414.910765 -159.199005) (xy 414.940231 -159.244855) (xy 414.962873 -159.294432)
			(xy 414.978228 -159.346727) (xy 414.985984 -159.400675) (xy 414.98647 -159.427926) (xy 414.985809 -159.459489)
			(xy 414.975423 -159.521754) (xy 414.954937 -159.581463) (xy 414.940496 -159.609536) (xy 414.93567 -159.618426)
			(xy 414.933638 -159.637984) (xy 414.956498 -159.71647) (xy 414.959759 -159.725885) (xy 414.97216 -159.741449)
			(xy 414.980628 -159.746696) (xy 414.987994 -159.75076) (xy 414.9979 -159.756602) (xy 415.019744 -159.758634)
			(xy 415.114486 -159.725106) (xy 415.130234 -159.709612) (xy 415.134298 -159.699198) (xy 415.144978 -159.672415)
			(xy 415.173267 -159.622172) (xy 415.208799 -159.576762) (xy 415.250763 -159.537219) (xy 415.298203 -159.504446)
			(xy 415.350036 -159.479189) (xy 415.405082 -159.462026) (xy 415.462084 -159.453346) (xy 415.490914 -159.452818)
			(xy 415.518166 -159.453253) (xy 415.572116 -159.461011) (xy 415.624413 -159.476369) (xy 415.673992 -159.499012)
			(xy 415.719844 -159.528481) (xy 415.761035 -159.564175) (xy 415.796727 -159.605368) (xy 415.826194 -159.65122)
			(xy 415.848836 -159.7008) (xy 415.864192 -159.753097) (xy 415.871948 -159.807048) (xy 415.871948 -159.861552)
			(xy 415.864192 -159.915503) (xy 415.854839 -159.947356) (xy 416.113722 -159.947356) (xy 416.114177 -159.91988)
			(xy 416.122076 -159.865499) (xy 416.137703 -159.812816) (xy 416.160735 -159.762924) (xy 416.190693 -159.716857)
			(xy 416.208464 -159.695896) (xy 416.208718 -159.695642) (xy 416.214295 -159.688549) (xy 416.220547 -159.671637)
			(xy 416.22091 -159.662622) (xy 416.22091 -159.595058) (xy 416.220523 -159.586044) (xy 416.214296 -159.569127)
			(xy 416.208718 -159.562038) (xy 416.20821 -159.56153) (xy 416.190496 -159.540568) (xy 416.16061 -159.49454)
			(xy 416.13764 -159.444699) (xy 416.122061 -159.392077) (xy 416.114195 -159.337764) (xy 416.113722 -159.310324)
			(xy 416.114208 -159.283073) (xy 416.121964 -159.229125) (xy 416.137319 -159.17683) (xy 416.159961 -159.127253)
			(xy 416.189427 -159.081403) (xy 416.225118 -159.040212) (xy 416.266309 -159.004521) (xy 416.312159 -158.975055)
			(xy 416.361736 -158.952413) (xy 416.414031 -158.937058) (xy 416.467979 -158.929302) (xy 416.522481 -158.929302)
			(xy 416.576429 -158.937058) (xy 416.628724 -158.952413) (xy 416.678301 -158.975055) (xy 416.724151 -159.004521)
			(xy 416.765342 -159.040212) (xy 416.801033 -159.081403) (xy 416.830499 -159.127253) (xy 416.853141 -159.17683)
			(xy 416.868496 -159.229125) (xy 416.876252 -159.283073) (xy 416.876738 -159.310324) (xy 416.876256 -159.337799)
			(xy 416.868362 -159.392178) (xy 416.85274 -159.44486) (xy 416.829715 -159.494753) (xy 416.799763 -159.540822)
			(xy 416.781996 -159.561784) (xy 416.781742 -159.562038) (xy 416.776168 -159.569133) (xy 416.769915 -159.586044)
			(xy 416.76955 -159.595058) (xy 416.76955 -159.662622) (xy 416.769885 -159.671641) (xy 416.776147 -159.688559)
			(xy 416.781742 -159.695642) (xy 416.78225 -159.69615) (xy 416.799995 -159.717087) (xy 416.829878 -159.763122)
			(xy 416.852842 -159.812969) (xy 416.868414 -159.865596) (xy 416.87627 -159.919914) (xy 416.876738 -159.947356)
			(xy 416.876252 -159.974607) (xy 416.874619 -159.985964) (xy 417.451538 -159.985964) (xy 417.455609 -159.930342)
			(xy 417.467735 -159.875905) (xy 417.487658 -159.823814) (xy 417.514954 -159.775179) (xy 417.54904 -159.731036)
			(xy 417.589189 -159.692327) (xy 417.634547 -159.659876) (xy 417.684147 -159.634375) (xy 417.736931 -159.616368)
			(xy 417.791774 -159.606238) (xy 417.847508 -159.604201) (xy 417.902945 -159.610301) (xy 417.956902 -159.624407)
			(xy 418.008231 -159.646219) (xy 418.055837 -159.675273) (xy 418.098705 -159.710948) (xy 418.135922 -159.752485)
			(xy 418.166695 -159.798998) (xy 418.190367 -159.849495) (xy 418.206435 -159.902902) (xy 418.214555 -159.958078)
			(xy 418.215064 -159.985964) (xy 418.214555 -160.01385) (xy 418.206435 -160.069026) (xy 418.190367 -160.122433)
			(xy 418.166695 -160.17293) (xy 418.135922 -160.219443) (xy 418.098705 -160.26098) (xy 418.055837 -160.296655)
			(xy 418.008231 -160.325709) (xy 417.956902 -160.347521) (xy 417.902945 -160.361627) (xy 417.847508 -160.367727)
			(xy 417.791774 -160.36569) (xy 417.736931 -160.35556) (xy 417.684147 -160.337553) (xy 417.634547 -160.312052)
			(xy 417.589189 -160.279601) (xy 417.54904 -160.240892) (xy 417.514954 -160.196749) (xy 417.487658 -160.148114)
			(xy 417.467735 -160.096023) (xy 417.455609 -160.041586) (xy 417.451538 -159.985964) (xy 416.874619 -159.985964)
			(xy 416.868496 -160.028555) (xy 416.853141 -160.08085) (xy 416.830499 -160.130427) (xy 416.801033 -160.176277)
			(xy 416.765342 -160.217468) (xy 416.724151 -160.253159) (xy 416.678301 -160.282625) (xy 416.628724 -160.305267)
			(xy 416.576429 -160.320622) (xy 416.522481 -160.328378) (xy 416.467979 -160.328378) (xy 416.414031 -160.320622)
			(xy 416.361736 -160.305267) (xy 416.312159 -160.282625) (xy 416.266309 -160.253159) (xy 416.225118 -160.217468)
			(xy 416.189427 -160.176277) (xy 416.159961 -160.130427) (xy 416.137319 -160.08085) (xy 416.121964 -160.028555)
			(xy 416.114208 -159.974607) (xy 416.113722 -159.947356) (xy 415.854839 -159.947356) (xy 415.848836 -159.9678)
			(xy 415.826194 -160.01738) (xy 415.796727 -160.063232) (xy 415.761035 -160.104425) (xy 415.719844 -160.140119)
			(xy 415.673992 -160.169588) (xy 415.624413 -160.192231) (xy 415.572116 -160.207589) (xy 415.518166 -160.215347)
			(xy 415.490914 -160.215834) (xy 415.49066 -160.215834) (xy 415.465456 -160.215456) (xy 415.415487 -160.20881)
			(xy 415.366832 -160.195628) (xy 415.320343 -160.176139) (xy 415.298382 -160.163764) (xy 415.288476 -160.157922)
			(xy 415.266632 -160.15589) (xy 415.17189 -160.189418) (xy 415.156142 -160.204912) (xy 415.152078 -160.215326)
			(xy 415.141347 -160.242087) (xy 415.113063 -160.292327) (xy 415.077537 -160.337735) (xy 415.03558 -160.377277)
			(xy 414.988148 -160.410052) (xy 414.936322 -160.435313) (xy 414.881285 -160.452484) (xy 414.824289 -160.461173)
			(xy 414.795462 -160.461706) (xy 414.76821 -160.461258) (xy 414.714261 -160.453496) (xy 414.661965 -160.438136)
			(xy 414.612388 -160.41549) (xy 414.566537 -160.38602) (xy 414.525347 -160.350324) (xy 414.489656 -160.309131)
			(xy 414.460191 -160.263277) (xy 414.43755 -160.213697) (xy 414.422196 -160.1614) (xy 414.41444 -160.10745)
			(xy 414.413954 -160.080198) (xy 414.414622 -160.048636) (xy 414.425005 -159.98637) (xy 414.445487 -159.926661)
			(xy 414.459928 -159.898588) (xy 414.464754 -159.889698) (xy 414.466786 -159.87014) (xy 414.443926 -159.791654)
			(xy 414.440723 -159.782215) (xy 414.428281 -159.766662) (xy 414.419796 -159.761428) (xy 414.394678 -159.746907)
			(xy 414.348796 -159.711399) (xy 414.308822 -159.66935) (xy 414.275679 -159.621732) (xy 414.250131 -159.569642)
			(xy 414.232768 -159.514284) (xy 414.223991 -159.456935) (xy 414.223454 -159.427926) (xy 412.476696 -159.427926)
			(xy 413.930084 -160.881314) (xy 416.872418 -160.881314) (xy 416.876489 -160.825692) (xy 416.888615 -160.771255)
			(xy 416.908538 -160.719164) (xy 416.935834 -160.670529) (xy 416.96992 -160.626386) (xy 417.010069 -160.587677)
			(xy 417.055427 -160.555226) (xy 417.105027 -160.529725) (xy 417.157811 -160.511718) (xy 417.212654 -160.501588)
			(xy 417.268388 -160.499551) (xy 417.323825 -160.505651) (xy 417.377782 -160.519757) (xy 417.429111 -160.541569)
			(xy 417.476717 -160.570623) (xy 417.519585 -160.606298) (xy 417.556802 -160.647835) (xy 417.587575 -160.694348)
			(xy 417.611247 -160.744845) (xy 417.627315 -160.798252) (xy 417.635435 -160.853428) (xy 417.635944 -160.881314)
			(xy 417.635435 -160.9092) (xy 417.627315 -160.964376) (xy 417.611247 -161.017783) (xy 417.587575 -161.06828)
			(xy 417.556802 -161.114793) (xy 417.519585 -161.15633) (xy 417.476717 -161.192005) (xy 417.429111 -161.221059)
			(xy 417.377782 -161.242871) (xy 417.323825 -161.256977) (xy 417.268388 -161.263077) (xy 417.212654 -161.26104)
			(xy 417.157811 -161.25091) (xy 417.105027 -161.232903) (xy 417.055427 -161.207402) (xy 417.010069 -161.174951)
			(xy 416.96992 -161.136242) (xy 416.935834 -161.092099) (xy 416.908538 -161.043464) (xy 416.888615 -160.991373)
			(xy 416.876489 -160.936936) (xy 416.872418 -160.881314) (xy 413.930084 -160.881314) (xy 414.404302 -161.355532)
			(xy 414.411149 -161.362927) (xy 414.418865 -161.38153) (xy 414.419288 -161.3916) (xy 414.419288 -162.758374)
			(xy 417.83127 -162.758374) (xy 417.831752 -162.730463) (xy 417.83989 -162.675237) (xy 417.855988 -162.621786)
			(xy 417.879703 -162.571252) (xy 417.910529 -162.524712) (xy 417.928806 -162.503612) (xy 417.934699 -162.496432)
			(xy 417.941352 -162.479109) (xy 417.94176 -162.46983) (xy 417.94176 -162.392106) (xy 417.935156 -162.374834)
			(xy 417.928806 -162.367722) (xy 417.910518 -162.346631) (xy 417.879692 -162.30009) (xy 417.855978 -162.249554)
			(xy 417.839884 -162.1961) (xy 417.831753 -162.140872) (xy 417.83127 -162.11296) (xy 417.831756 -162.085709)
			(xy 417.839512 -162.031761) (xy 417.854867 -161.979466) (xy 417.877509 -161.929889) (xy 417.906975 -161.884039)
			(xy 417.942666 -161.842848) (xy 417.983857 -161.807157) (xy 418.029707 -161.777691) (xy 418.079284 -161.755049)
			(xy 418.131579 -161.739694) (xy 418.185527 -161.731938) (xy 418.240029 -161.731938) (xy 418.293977 -161.739694)
			(xy 418.346272 -161.755049) (xy 418.395849 -161.777691) (xy 418.441699 -161.807157) (xy 418.48289 -161.842848)
			(xy 418.518581 -161.884039) (xy 418.548047 -161.929889) (xy 418.570689 -161.979466) (xy 418.586044 -162.031761)
			(xy 418.5938 -162.085709) (xy 418.594286 -162.11296) (xy 418.59381 -162.140871) (xy 418.585669 -162.196097)
			(xy 418.569568 -162.249547) (xy 418.545852 -162.300082) (xy 418.515027 -162.346621) (xy 418.49675 -162.367722)
			(xy 418.490838 -162.374888) (xy 418.484197 -162.392222) (xy 418.483796 -162.401504) (xy 418.483796 -162.479228)
			(xy 418.4904 -162.4965) (xy 418.49675 -162.503612) (xy 418.515016 -162.524721) (xy 418.545843 -162.571258)
			(xy 418.56956 -162.62179) (xy 418.58566 -162.675239) (xy 418.593798 -162.730464) (xy 418.594286 -162.758374)
			(xy 418.5938 -162.785625) (xy 418.586044 -162.839573) (xy 418.570689 -162.891868) (xy 418.548047 -162.941445)
			(xy 418.518581 -162.987295) (xy 418.48289 -163.028486) (xy 418.441699 -163.064177) (xy 418.395849 -163.093643)
			(xy 418.346272 -163.116285) (xy 418.293977 -163.13164) (xy 418.240029 -163.139396) (xy 418.185527 -163.139396)
			(xy 418.131579 -163.13164) (xy 418.079284 -163.116285) (xy 418.029707 -163.093643) (xy 417.983857 -163.064177)
			(xy 417.942666 -163.028486) (xy 417.906975 -162.987295) (xy 417.877509 -162.941445) (xy 417.854867 -162.891868)
			(xy 417.839512 -162.839573) (xy 417.831756 -162.785625) (xy 417.83127 -162.758374) (xy 414.419288 -162.758374)
			(xy 414.419288 -163.56203) (xy 414.419145 -163.56692) (xy 414.417231 -163.576513) (xy 414.415478 -163.58108)
			(xy 414.37433 -163.682934) (xy 414.372192 -163.687838) (xy 414.366176 -163.696679) (xy 414.362392 -163.70046)
			(xy 414.323276 -163.738052) (xy 414.320736 -163.740592) (xy 414.283144 -163.779708) (xy 414.279331 -163.783454)
			(xy 414.270504 -163.789478) (xy 414.265618 -163.791646) (xy 414.163764 -163.832794) (xy 414.159201 -163.83456)
			(xy 414.149605 -163.836471) (xy 414.144714 -163.836604) (xy 409.610306 -163.836604) (xy 409.585034 -163.836041)
			(xy 409.53512 -163.828066) (xy 409.487066 -163.812389) (xy 409.442052 -163.789395) (xy 409.401184 -163.75965)
			(xy 409.382976 -163.742116) (xy 409.335986 -163.695126) (xy 409.335478 -163.694618) (xy 409.296616 -163.65728)
			(xy 409.29286 -163.653476) (xy 409.286842 -163.644642) (xy 409.284678 -163.639754) (xy 409.24353 -163.5379)
			(xy 409.241775 -163.533333) (xy 409.239857 -163.523741) (xy 409.23972 -163.51885) (xy 409.23972 -162.730434)
			(xy 409.239298 -162.720364) (xy 409.231577 -162.701765) (xy 409.224734 -162.694366) (xy 409.019756 -162.489134)
			(xy 409.012361 -162.482287) (xy 408.993758 -162.47457) (xy 408.983688 -162.474148) (xy 405.538686 -162.474148)
			(xy 405.528614 -162.474553) (xy 405.510016 -162.482287) (xy 405.502618 -162.489134) (xy 405.267922 -162.724084)
			(xy 405.261099 -162.731498) (xy 405.253369 -162.750086) (xy 405.252936 -162.760152) (xy 405.252936 -164.253926)
			(xy 405.841454 -164.253926) (xy 405.84194 -164.226675) (xy 405.849696 -164.172727) (xy 405.865051 -164.120432)
			(xy 405.887693 -164.070855) (xy 405.917159 -164.025005) (xy 405.95285 -163.983814) (xy 405.994041 -163.948123)
			(xy 406.039891 -163.918657) (xy 406.089468 -163.896015) (xy 406.141763 -163.88066) (xy 406.195711 -163.872904)
			(xy 406.250213 -163.872904) (xy 406.304161 -163.88066) (xy 406.356456 -163.896015) (xy 406.406033 -163.918657)
			(xy 406.451883 -163.948123) (xy 406.493074 -163.983814) (xy 406.528765 -164.025005) (xy 406.558231 -164.070855)
			(xy 406.580873 -164.120432) (xy 406.596228 -164.172727) (xy 406.603984 -164.226675) (xy 406.60447 -164.253926)
			(xy 406.603809 -164.285489) (xy 406.593423 -164.347754) (xy 406.572937 -164.407463) (xy 406.558496 -164.435536)
			(xy 406.55367 -164.444426) (xy 406.551638 -164.463984) (xy 406.574498 -164.54247) (xy 406.577759 -164.551885)
			(xy 406.59016 -164.567449) (xy 406.598628 -164.572696) (xy 406.605994 -164.57676) (xy 406.6159 -164.582602)
			(xy 406.637744 -164.584634) (xy 406.732486 -164.551106) (xy 406.748234 -164.535612) (xy 406.752298 -164.525198)
			(xy 406.762978 -164.498415) (xy 406.791267 -164.448172) (xy 406.826799 -164.402762) (xy 406.868763 -164.363219)
			(xy 406.916203 -164.330446) (xy 406.968036 -164.305189) (xy 407.023082 -164.288026) (xy 407.080084 -164.279346)
			(xy 407.108914 -164.278818) (xy 407.136166 -164.279253) (xy 407.190116 -164.287011) (xy 407.242413 -164.302369)
			(xy 407.291992 -164.325012) (xy 407.337844 -164.354481) (xy 407.379035 -164.390175) (xy 407.414727 -164.431368)
			(xy 407.444194 -164.47722) (xy 407.466836 -164.5268) (xy 407.482192 -164.579097) (xy 407.489948 -164.633048)
			(xy 407.489948 -164.687552) (xy 407.482192 -164.741503) (xy 407.472839 -164.773356) (xy 407.731722 -164.773356)
			(xy 407.732177 -164.74588) (xy 407.740076 -164.691499) (xy 407.755703 -164.638816) (xy 407.778735 -164.588924)
			(xy 407.808693 -164.542857) (xy 407.826464 -164.521896) (xy 407.826718 -164.521642) (xy 407.832295 -164.514549)
			(xy 407.838547 -164.497637) (xy 407.83891 -164.488622) (xy 407.83891 -164.421058) (xy 407.838523 -164.412044)
			(xy 407.832296 -164.395127) (xy 407.826718 -164.388038) (xy 407.82621 -164.38753) (xy 407.808496 -164.366568)
			(xy 407.77861 -164.32054) (xy 407.75564 -164.270699) (xy 407.740061 -164.218077) (xy 407.732195 -164.163764)
			(xy 407.731722 -164.136324) (xy 407.732208 -164.109073) (xy 407.739964 -164.055125) (xy 407.755319 -164.00283)
			(xy 407.777961 -163.953253) (xy 407.807427 -163.907403) (xy 407.843118 -163.866212) (xy 407.884309 -163.830521)
			(xy 407.930159 -163.801055) (xy 407.979736 -163.778413) (xy 408.032031 -163.763058) (xy 408.085979 -163.755302)
			(xy 408.140481 -163.755302) (xy 408.194429 -163.763058) (xy 408.246724 -163.778413) (xy 408.296301 -163.801055)
			(xy 408.342151 -163.830521) (xy 408.383342 -163.866212) (xy 408.419033 -163.907403) (xy 408.448499 -163.953253)
			(xy 408.471141 -164.00283) (xy 408.486496 -164.055125) (xy 408.494252 -164.109073) (xy 408.494738 -164.136324)
			(xy 408.494256 -164.163799) (xy 408.486362 -164.218178) (xy 408.47074 -164.27086) (xy 408.447715 -164.320753)
			(xy 408.417763 -164.366822) (xy 408.399996 -164.387784) (xy 408.399742 -164.388038) (xy 408.394168 -164.395133)
			(xy 408.387915 -164.412044) (xy 408.38755 -164.421058) (xy 408.38755 -164.488622) (xy 408.387885 -164.497641)
			(xy 408.394147 -164.514559) (xy 408.399742 -164.521642) (xy 408.40025 -164.52215) (xy 408.417995 -164.543087)
			(xy 408.447878 -164.589122) (xy 408.470842 -164.638969) (xy 408.486414 -164.691596) (xy 408.49427 -164.745914)
			(xy 408.494738 -164.773356) (xy 408.494252 -164.800607) (xy 408.492619 -164.811964) (xy 409.069538 -164.811964)
			(xy 409.073609 -164.756342) (xy 409.085735 -164.701905) (xy 409.105658 -164.649814) (xy 409.132954 -164.601179)
			(xy 409.16704 -164.557036) (xy 409.207189 -164.518327) (xy 409.252547 -164.485876) (xy 409.302147 -164.460375)
			(xy 409.354931 -164.442368) (xy 409.409774 -164.432238) (xy 409.465508 -164.430201) (xy 409.520945 -164.436301)
			(xy 409.574902 -164.450407) (xy 409.626231 -164.472219) (xy 409.673837 -164.501273) (xy 409.716705 -164.536948)
			(xy 409.753922 -164.578485) (xy 409.784695 -164.624998) (xy 409.808367 -164.675495) (xy 409.824435 -164.728902)
			(xy 409.832555 -164.784078) (xy 409.833064 -164.811964) (xy 409.832555 -164.83985) (xy 409.824435 -164.895026)
			(xy 409.808367 -164.948433) (xy 409.784695 -164.99893) (xy 409.753922 -165.045443) (xy 409.716705 -165.08698)
			(xy 409.673837 -165.122655) (xy 409.626231 -165.151709) (xy 409.574902 -165.173521) (xy 409.520945 -165.187627)
			(xy 409.465508 -165.193727) (xy 409.409774 -165.19169) (xy 409.354931 -165.18156) (xy 409.302147 -165.163553)
			(xy 409.252547 -165.138052) (xy 409.207189 -165.105601) (xy 409.16704 -165.066892) (xy 409.132954 -165.022749)
			(xy 409.105658 -164.974114) (xy 409.085735 -164.922023) (xy 409.073609 -164.867586) (xy 409.069538 -164.811964)
			(xy 408.492619 -164.811964) (xy 408.486496 -164.854555) (xy 408.471141 -164.90685) (xy 408.448499 -164.956427)
			(xy 408.419033 -165.002277) (xy 408.383342 -165.043468) (xy 408.342151 -165.079159) (xy 408.296301 -165.108625)
			(xy 408.246724 -165.131267) (xy 408.194429 -165.146622) (xy 408.140481 -165.154378) (xy 408.085979 -165.154378)
			(xy 408.032031 -165.146622) (xy 407.979736 -165.131267) (xy 407.930159 -165.108625) (xy 407.884309 -165.079159)
			(xy 407.843118 -165.043468) (xy 407.807427 -165.002277) (xy 407.777961 -164.956427) (xy 407.755319 -164.90685)
			(xy 407.739964 -164.854555) (xy 407.732208 -164.800607) (xy 407.731722 -164.773356) (xy 407.472839 -164.773356)
			(xy 407.466836 -164.7938) (xy 407.444194 -164.84338) (xy 407.414727 -164.889232) (xy 407.379035 -164.930425)
			(xy 407.337844 -164.966119) (xy 407.291992 -164.995588) (xy 407.242413 -165.018231) (xy 407.190116 -165.033589)
			(xy 407.136166 -165.041347) (xy 407.108914 -165.041834) (xy 407.10866 -165.041834) (xy 407.083456 -165.041456)
			(xy 407.033487 -165.03481) (xy 406.984832 -165.021628) (xy 406.938343 -165.002139) (xy 406.916382 -164.989764)
			(xy 406.906476 -164.983922) (xy 406.884632 -164.98189) (xy 406.78989 -165.015418) (xy 406.774142 -165.030912)
			(xy 406.770078 -165.041326) (xy 406.759347 -165.068087) (xy 406.731063 -165.118327) (xy 406.695537 -165.163735)
			(xy 406.65358 -165.203277) (xy 406.606148 -165.236052) (xy 406.554322 -165.261313) (xy 406.499285 -165.278484)
			(xy 406.442289 -165.287173) (xy 406.413462 -165.287706) (xy 406.38621 -165.287258) (xy 406.332261 -165.279496)
			(xy 406.279965 -165.264136) (xy 406.230388 -165.24149) (xy 406.184537 -165.21202) (xy 406.143347 -165.176324)
			(xy 406.107656 -165.135131) (xy 406.078191 -165.089277) (xy 406.05555 -165.039697) (xy 406.040196 -164.9874)
			(xy 406.03244 -164.93345) (xy 406.031954 -164.906198) (xy 406.032622 -164.874636) (xy 406.043005 -164.81237)
			(xy 406.063487 -164.752661) (xy 406.077928 -164.724588) (xy 406.082754 -164.715698) (xy 406.084786 -164.69614)
			(xy 406.061926 -164.617654) (xy 406.058723 -164.608215) (xy 406.046281 -164.592662) (xy 406.037796 -164.587428)
			(xy 406.012678 -164.572907) (xy 405.966796 -164.537399) (xy 405.926822 -164.49535) (xy 405.893679 -164.447732)
			(xy 405.868131 -164.395642) (xy 405.850768 -164.340284) (xy 405.841991 -164.282935) (xy 405.841454 -164.253926)
			(xy 405.252936 -164.253926) (xy 405.252936 -165.466776) (xy 405.253365 -165.476845) (xy 405.261082 -165.495443)
			(xy 405.267922 -165.502844) (xy 405.472392 -165.707314) (xy 408.490418 -165.707314) (xy 408.494489 -165.651692)
			(xy 408.506615 -165.597255) (xy 408.526538 -165.545164) (xy 408.553834 -165.496529) (xy 408.58792 -165.452386)
			(xy 408.628069 -165.413677) (xy 408.673427 -165.381226) (xy 408.723027 -165.355725) (xy 408.775811 -165.337718)
			(xy 408.830654 -165.327588) (xy 408.886388 -165.325551) (xy 408.941825 -165.331651) (xy 408.995782 -165.345757)
			(xy 409.047111 -165.367569) (xy 409.094717 -165.396623) (xy 409.137585 -165.432298) (xy 409.174802 -165.473835)
			(xy 409.205575 -165.520348) (xy 409.229247 -165.570845) (xy 409.245315 -165.624252) (xy 409.253435 -165.679428)
			(xy 409.253944 -165.707314) (xy 409.253435 -165.7352) (xy 409.245315 -165.790376) (xy 409.229247 -165.843783)
			(xy 409.205575 -165.89428) (xy 409.174802 -165.940793) (xy 409.137585 -165.98233) (xy 409.094717 -166.018005)
			(xy 409.047111 -166.047059) (xy 408.995782 -166.068871) (xy 408.941825 -166.082977) (xy 408.886388 -166.089077)
			(xy 408.830654 -166.08704) (xy 408.775811 -166.07691) (xy 408.723027 -166.058903) (xy 408.673427 -166.033402)
			(xy 408.628069 -166.000951) (xy 408.58792 -165.962242) (xy 408.553834 -165.918099) (xy 408.526538 -165.869464)
			(xy 408.506615 -165.817373) (xy 408.494489 -165.762936) (xy 408.490418 -165.707314) (xy 405.472392 -165.707314)
			(xy 406.022302 -166.257224) (xy 406.029145 -166.264622) (xy 406.036863 -166.283223) (xy 406.037288 -166.293292)
			(xy 406.037288 -167.584374) (xy 409.44927 -167.584374) (xy 409.449752 -167.556463) (xy 409.45789 -167.501237)
			(xy 409.473988 -167.447786) (xy 409.497703 -167.397252) (xy 409.528529 -167.350712) (xy 409.546806 -167.329612)
			(xy 409.552699 -167.322432) (xy 409.559352 -167.305109) (xy 409.55976 -167.29583) (xy 409.55976 -167.218106)
			(xy 409.553156 -167.200834) (xy 409.546806 -167.193722) (xy 409.528518 -167.172631) (xy 409.497692 -167.12609)
			(xy 409.473978 -167.075554) (xy 409.457884 -167.0221) (xy 409.449753 -166.966872) (xy 409.44927 -166.93896)
			(xy 409.449756 -166.911709) (xy 409.457512 -166.857761) (xy 409.472867 -166.805466) (xy 409.495509 -166.755889)
			(xy 409.524975 -166.710039) (xy 409.560666 -166.668848) (xy 409.601857 -166.633157) (xy 409.647707 -166.603691)
			(xy 409.697284 -166.581049) (xy 409.749579 -166.565694) (xy 409.803527 -166.557938) (xy 409.858029 -166.557938)
			(xy 409.911977 -166.565694) (xy 409.964272 -166.581049) (xy 410.013849 -166.603691) (xy 410.059699 -166.633157)
			(xy 410.10089 -166.668848) (xy 410.136581 -166.710039) (xy 410.166047 -166.755889) (xy 410.188689 -166.805466)
			(xy 410.204044 -166.857761) (xy 410.2118 -166.911709) (xy 410.212286 -166.93896) (xy 410.21181 -166.966871)
			(xy 410.203669 -167.022097) (xy 410.187568 -167.075547) (xy 410.163852 -167.126082) (xy 410.133027 -167.172621)
			(xy 410.11475 -167.193722) (xy 410.108838 -167.200888) (xy 410.102197 -167.218222) (xy 410.101796 -167.227504)
			(xy 410.101796 -167.305228) (xy 410.1084 -167.3225) (xy 410.11475 -167.329612) (xy 410.133016 -167.350721)
			(xy 410.163843 -167.397258) (xy 410.18756 -167.44779) (xy 410.20366 -167.501239) (xy 410.211798 -167.556464)
			(xy 410.212286 -167.584374) (xy 410.2118 -167.611625) (xy 410.204044 -167.665573) (xy 410.188689 -167.717868)
			(xy 410.166047 -167.767445) (xy 410.136581 -167.813295) (xy 410.10089 -167.854486) (xy 410.059699 -167.890177)
			(xy 410.013849 -167.919643) (xy 409.964272 -167.942285) (xy 409.911977 -167.95764) (xy 409.858029 -167.965396)
			(xy 409.803527 -167.965396) (xy 409.749579 -167.95764) (xy 409.697284 -167.942285) (xy 409.647707 -167.919643)
			(xy 409.601857 -167.890177) (xy 409.560666 -167.854486) (xy 409.524975 -167.813295) (xy 409.495509 -167.767445)
			(xy 409.472867 -167.717868) (xy 409.457512 -167.665573) (xy 409.449756 -167.611625) (xy 409.44927 -167.584374)
			(xy 406.037288 -167.584374) (xy 406.037288 -168.263316) (xy 406.036783 -168.288584) (xy 406.028876 -168.338497)
			(xy 406.013258 -168.386559) (xy 405.990315 -168.431586) (xy 405.960611 -168.472471) (xy 405.924877 -168.508205)
			(xy 405.883993 -168.537911) (xy 405.838966 -168.560855) (xy 405.790905 -168.576474) (xy 405.740992 -168.584382)
			(xy 405.715724 -168.58488) (xy 404.17623 -168.58488) (xy 404.169506 -168.58511) (xy 404.156513 -168.588575)
			(xy 404.150576 -168.591738) (xy 404.125806 -168.605503) (xy 404.072633 -168.625083) (xy 404.016855 -168.635055)
			(xy 403.988524 -168.63568) (xy 403.929088 -168.63568) (xy 403.929088 -168.637204) (xy 400.841464 -168.637204)
			(xy 400.836574 -168.637346) (xy 400.826981 -168.639261) (xy 400.822414 -168.641014) (xy 400.804634 -168.648126)
			(xy 400.800065 -168.649874) (xy 400.790474 -168.651796) (xy 400.785584 -168.651936) (xy 399.12925 -168.651936)
			(xy 399.119182 -168.652378) (xy 399.100584 -168.660086) (xy 399.093182 -168.666922) (xy 396.75943 -171.000928)
			(xy 396.75259 -171.008328) (xy 396.744869 -171.026927) (xy 396.744444 -171.036996) (xy 396.744444 -172.831252)
			(xy 397.517874 -172.831252) (xy 397.51836 -172.804001) (xy 397.526116 -172.750053) (xy 397.541471 -172.697758)
			(xy 397.564113 -172.648181) (xy 397.593579 -172.602331) (xy 397.62927 -172.56114) (xy 397.670461 -172.525449)
			(xy 397.716311 -172.495983) (xy 397.765888 -172.473341) (xy 397.818183 -172.457986) (xy 397.872131 -172.45023)
			(xy 397.926633 -172.45023) (xy 397.980581 -172.457986) (xy 398.032876 -172.473341) (xy 398.082453 -172.495983)
			(xy 398.128303 -172.525449) (xy 398.169494 -172.56114) (xy 398.205185 -172.602331) (xy 398.234651 -172.648181)
			(xy 398.257293 -172.697758) (xy 398.272648 -172.750053) (xy 398.280404 -172.804001) (xy 398.28089 -172.831252)
			(xy 398.280237 -172.862815) (xy 398.269847 -172.925081) (xy 398.249359 -172.98479) (xy 398.234916 -173.012862)
			(xy 398.23009 -173.021752) (xy 398.228058 -173.04131) (xy 398.250918 -173.119796) (xy 398.254161 -173.129218)
			(xy 398.266575 -173.144779) (xy 398.275048 -173.150022) (xy 398.282414 -173.154086) (xy 398.29232 -173.159928)
			(xy 398.314164 -173.16196) (xy 398.408906 -173.128432) (xy 398.424654 -173.112938) (xy 398.428718 -173.102524)
			(xy 398.439395 -173.075739) (xy 398.467683 -173.025495) (xy 398.503214 -172.980083) (xy 398.545179 -172.94054)
			(xy 398.592619 -172.907766) (xy 398.644454 -172.88251) (xy 398.6995 -172.865348) (xy 398.756504 -172.85667)
			(xy 398.785334 -172.856144) (xy 398.81258 -172.856728) (xy 398.866517 -172.864488) (xy 398.918801 -172.879844)
			(xy 398.968368 -172.902484) (xy 399.014208 -172.931948) (xy 399.055389 -172.967635) (xy 399.091073 -173.008819)
			(xy 399.120532 -173.054662) (xy 399.143168 -173.10423) (xy 399.158519 -173.156516) (xy 399.166274 -173.210454)
			(xy 399.166274 -173.264946) (xy 399.158519 -173.318884) (xy 399.149183 -173.350682) (xy 399.408142 -173.350682)
			(xy 399.408607 -173.323206) (xy 399.416503 -173.268826) (xy 399.432127 -173.216143) (xy 399.455157 -173.16625)
			(xy 399.485114 -173.120183) (xy 399.502884 -173.099222) (xy 399.503138 -173.098968) (xy 399.508706 -173.091869)
			(xy 399.514963 -173.074962) (xy 399.51533 -173.065948) (xy 399.51533 -172.998384) (xy 399.514974 -172.989367)
			(xy 399.508725 -172.97245) (xy 399.503138 -172.965364) (xy 399.50263 -172.964856) (xy 399.484884 -172.943919)
			(xy 399.455003 -172.897884) (xy 399.432038 -172.848037) (xy 399.416467 -172.795409) (xy 399.40861 -172.741092)
			(xy 399.408142 -172.71365) (xy 399.408628 -172.686399) (xy 399.416384 -172.632451) (xy 399.431739 -172.580156)
			(xy 399.454381 -172.530579) (xy 399.483847 -172.484729) (xy 399.519538 -172.443538) (xy 399.560729 -172.407847)
			(xy 399.606579 -172.378381) (xy 399.656156 -172.355739) (xy 399.708451 -172.340384) (xy 399.762399 -172.332628)
			(xy 399.816901 -172.332628) (xy 399.870849 -172.340384) (xy 399.923144 -172.355739) (xy 399.972721 -172.378381)
			(xy 400.018571 -172.407847) (xy 400.059762 -172.443538) (xy 400.095453 -172.484729) (xy 400.124919 -172.530579)
			(xy 400.147561 -172.580156) (xy 400.162916 -172.632451) (xy 400.170672 -172.686399) (xy 400.171158 -172.71365)
			(xy 400.170711 -172.741126) (xy 400.162811 -172.795508) (xy 400.147183 -172.848191) (xy 400.124149 -172.898083)
			(xy 400.094188 -172.94415) (xy 400.076416 -172.96511) (xy 400.076162 -172.965364) (xy 400.07058 -172.972454)
			(xy 400.064332 -172.989368) (xy 400.06397 -172.998384) (xy 400.06397 -173.065948) (xy 400.064358 -173.074962)
			(xy 400.070585 -173.091878) (xy 400.076162 -173.098968) (xy 400.07667 -173.099476) (xy 400.094384 -173.120438)
			(xy 400.12427 -173.166466) (xy 400.147241 -173.216307) (xy 400.16282 -173.268929) (xy 400.170685 -173.323242)
			(xy 400.171158 -173.350682) (xy 400.170672 -173.377933) (xy 400.169039 -173.38929) (xy 400.745958 -173.38929)
			(xy 400.750029 -173.333668) (xy 400.762155 -173.279231) (xy 400.782078 -173.22714) (xy 400.809374 -173.178505)
			(xy 400.84346 -173.134362) (xy 400.883609 -173.095653) (xy 400.928967 -173.063202) (xy 400.978567 -173.037701)
			(xy 401.031351 -173.019694) (xy 401.086194 -173.009564) (xy 401.141928 -173.007527) (xy 401.197365 -173.013627)
			(xy 401.251322 -173.027733) (xy 401.302651 -173.049545) (xy 401.350257 -173.078599) (xy 401.393125 -173.114274)
			(xy 401.430342 -173.155811) (xy 401.461115 -173.202324) (xy 401.484787 -173.252821) (xy 401.500855 -173.306228)
			(xy 401.508975 -173.361404) (xy 401.509484 -173.38929) (xy 401.508975 -173.417176) (xy 401.500855 -173.472352)
			(xy 401.484787 -173.525759) (xy 401.461115 -173.576256) (xy 401.430342 -173.622769) (xy 401.393125 -173.664306)
			(xy 401.350257 -173.699981) (xy 401.302651 -173.729035) (xy 401.251322 -173.750847) (xy 401.197365 -173.764953)
			(xy 401.141928 -173.771053) (xy 401.086194 -173.769016) (xy 401.031351 -173.758886) (xy 400.978567 -173.740879)
			(xy 400.928967 -173.715378) (xy 400.883609 -173.682927) (xy 400.84346 -173.644218) (xy 400.809374 -173.600075)
			(xy 400.782078 -173.55144) (xy 400.762155 -173.499349) (xy 400.750029 -173.444912) (xy 400.745958 -173.38929)
			(xy 400.169039 -173.38929) (xy 400.162916 -173.431881) (xy 400.147561 -173.484176) (xy 400.124919 -173.533753)
			(xy 400.095453 -173.579603) (xy 400.059762 -173.620794) (xy 400.018571 -173.656485) (xy 399.972721 -173.685951)
			(xy 399.923144 -173.708593) (xy 399.870849 -173.723948) (xy 399.816901 -173.731704) (xy 399.762399 -173.731704)
			(xy 399.708451 -173.723948) (xy 399.656156 -173.708593) (xy 399.606579 -173.685951) (xy 399.560729 -173.656485)
			(xy 399.519538 -173.620794) (xy 399.483847 -173.579603) (xy 399.454381 -173.533753) (xy 399.431739 -173.484176)
			(xy 399.416384 -173.431881) (xy 399.408628 -173.377933) (xy 399.408142 -173.350682) (xy 399.149183 -173.350682)
			(xy 399.143168 -173.37117) (xy 399.120532 -173.420738) (xy 399.091073 -173.466581) (xy 399.055389 -173.507765)
			(xy 399.014208 -173.543452) (xy 398.968368 -173.572916) (xy 398.918801 -173.595556) (xy 398.866517 -173.610912)
			(xy 398.81258 -173.618672) (xy 398.785334 -173.61916) (xy 398.78508 -173.61916) (xy 398.759876 -173.618769)
			(xy 398.709908 -173.612127) (xy 398.661253 -173.598948) (xy 398.614764 -173.579463) (xy 398.592802 -173.56709)
			(xy 398.582896 -173.561248) (xy 398.561052 -173.559216) (xy 398.46631 -173.592744) (xy 398.450562 -173.608238)
			(xy 398.446498 -173.618652) (xy 398.435848 -173.645448) (xy 398.407552 -173.695689) (xy 398.372015 -173.741098)
			(xy 398.330046 -173.780638) (xy 398.282602 -173.813409) (xy 398.230765 -173.838664) (xy 398.175717 -173.855826)
			(xy 398.118713 -173.864505) (xy 398.089882 -173.865032) (xy 398.062631 -173.864539) (xy 398.008685 -173.856781)
			(xy 397.956392 -173.841424) (xy 397.906816 -173.818783) (xy 397.860967 -173.789317) (xy 397.819778 -173.753626)
			(xy 397.784087 -173.712438) (xy 397.75462 -173.666589) (xy 397.731978 -173.617014) (xy 397.716621 -173.564721)
			(xy 397.708861 -173.510775) (xy 397.708374 -173.483524) (xy 397.709022 -173.451961) (xy 397.719415 -173.389695)
			(xy 397.739905 -173.329986) (xy 397.754348 -173.301914) (xy 397.759174 -173.293024) (xy 397.761206 -173.273466)
			(xy 397.738346 -173.19498) (xy 397.735125 -173.185548) (xy 397.722696 -173.169992) (xy 397.714216 -173.164754)
			(xy 397.689114 -173.150207) (xy 397.643231 -173.114704) (xy 397.603256 -173.07266) (xy 397.57011 -173.025046)
			(xy 397.544559 -172.972961) (xy 397.527193 -172.917606) (xy 397.518413 -172.860259) (xy 397.517874 -172.831252)
			(xy 396.744444 -172.831252) (xy 396.744444 -173.790864) (xy 396.744877 -173.800933) (xy 396.752591 -173.819531)
			(xy 396.75943 -173.826932) (xy 397.217138 -174.28464) (xy 400.166838 -174.28464) (xy 400.170909 -174.229018)
			(xy 400.183035 -174.174581) (xy 400.202958 -174.12249) (xy 400.230254 -174.073855) (xy 400.26434 -174.029712)
			(xy 400.304489 -173.991003) (xy 400.349847 -173.958552) (xy 400.399447 -173.933051) (xy 400.452231 -173.915044)
			(xy 400.507074 -173.904914) (xy 400.562808 -173.902877) (xy 400.618245 -173.908977) (xy 400.672202 -173.923083)
			(xy 400.723531 -173.944895) (xy 400.771137 -173.973949) (xy 400.814005 -174.009624) (xy 400.851222 -174.051161)
			(xy 400.881995 -174.097674) (xy 400.905667 -174.148171) (xy 400.921735 -174.201578) (xy 400.929855 -174.256754)
			(xy 400.930364 -174.28464) (xy 400.929855 -174.312526) (xy 400.921735 -174.367702) (xy 400.905667 -174.421109)
			(xy 400.881995 -174.471606) (xy 400.851222 -174.518119) (xy 400.814005 -174.559656) (xy 400.771137 -174.595331)
			(xy 400.723531 -174.624385) (xy 400.672202 -174.646197) (xy 400.618245 -174.660303) (xy 400.562808 -174.666403)
			(xy 400.507074 -174.664366) (xy 400.452231 -174.654236) (xy 400.399447 -174.636229) (xy 400.349847 -174.610728)
			(xy 400.304489 -174.578277) (xy 400.26434 -174.539568) (xy 400.230254 -174.495425) (xy 400.202958 -174.44679)
			(xy 400.183035 -174.394699) (xy 400.170909 -174.340262) (xy 400.166838 -174.28464) (xy 397.217138 -174.28464)
			(xy 397.698722 -174.766224) (xy 397.705568 -174.773619) (xy 397.713284 -174.792222) (xy 397.713708 -174.802292)
			(xy 397.713708 -176.1617) (xy 401.12569 -176.1617) (xy 401.126182 -176.133789) (xy 401.134317 -176.078563)
			(xy 401.150413 -176.025113) (xy 401.174125 -175.974578) (xy 401.204949 -175.928038) (xy 401.223226 -175.906938)
			(xy 401.229153 -175.899782) (xy 401.235785 -175.882441) (xy 401.23618 -175.873156) (xy 401.23618 -175.795432)
			(xy 401.229576 -175.77816) (xy 401.223226 -175.771048) (xy 401.204938 -175.749957) (xy 401.174114 -175.703415)
			(xy 401.150402 -175.652878) (xy 401.134308 -175.599425) (xy 401.126175 -175.544198) (xy 401.12569 -175.516286)
			(xy 401.126176 -175.489035) (xy 401.133932 -175.435087) (xy 401.149287 -175.382792) (xy 401.171929 -175.333215)
			(xy 401.201395 -175.287365) (xy 401.237086 -175.246174) (xy 401.278277 -175.210483) (xy 401.324127 -175.181017)
			(xy 401.373704 -175.158375) (xy 401.425999 -175.14302) (xy 401.479947 -175.135264) (xy 401.534449 -175.135264)
			(xy 401.588397 -175.14302) (xy 401.640692 -175.158375) (xy 401.690269 -175.181017) (xy 401.736119 -175.210483)
			(xy 401.77731 -175.246174) (xy 401.813001 -175.287365) (xy 401.842467 -175.333215) (xy 401.865109 -175.382792)
			(xy 401.880464 -175.435087) (xy 401.88822 -175.489035) (xy 401.888706 -175.516286) (xy 401.888206 -175.544197)
			(xy 401.880074 -175.599422) (xy 401.86398 -175.652873) (xy 401.840269 -175.703408) (xy 401.809446 -175.749948)
			(xy 401.79117 -175.771048) (xy 401.785249 -175.778208) (xy 401.778613 -175.795546) (xy 401.778216 -175.80483)
			(xy 401.778216 -175.882554) (xy 401.78482 -175.899826) (xy 401.79117 -175.906938) (xy 401.809451 -175.928035)
			(xy 401.840276 -175.974575) (xy 401.863989 -176.02511) (xy 401.880085 -176.078562) (xy 401.88822 -176.133789)
			(xy 401.888706 -176.1617) (xy 401.88822 -176.188951) (xy 401.880464 -176.242899) (xy 401.865109 -176.295194)
			(xy 401.842467 -176.344771) (xy 401.813001 -176.390621) (xy 401.77731 -176.431812) (xy 401.736119 -176.467503)
			(xy 401.690269 -176.496969) (xy 401.640692 -176.519611) (xy 401.588397 -176.534966) (xy 401.534449 -176.542722)
			(xy 401.479947 -176.542722) (xy 401.425999 -176.534966) (xy 401.373704 -176.519611) (xy 401.324127 -176.496969)
			(xy 401.278277 -176.467503) (xy 401.237086 -176.431812) (xy 401.201395 -176.390621) (xy 401.171929 -176.344771)
			(xy 401.149287 -176.295194) (xy 401.133932 -176.242899) (xy 401.126176 -176.188951) (xy 401.12569 -176.1617)
			(xy 397.713708 -176.1617) (xy 397.713708 -176.840642) (xy 397.713255 -176.865879) (xy 397.705357 -176.915732)
			(xy 397.689762 -176.963737) (xy 397.666853 -177.008714) (xy 397.637195 -177.049555) (xy 397.601515 -177.085258)
			(xy 397.560693 -177.114943) (xy 397.515731 -177.137881) (xy 397.467737 -177.153508) (xy 397.417889 -177.161438)
			(xy 397.392652 -177.161952) (xy 395.85265 -177.161952) (xy 395.845924 -177.162156) (xy 395.832932 -177.165639)
			(xy 395.826996 -177.16881) (xy 395.802221 -177.182565) (xy 395.749051 -177.202149) (xy 395.693274 -177.212125)
			(xy 395.664944 -177.212752) (xy 395.605508 -177.212752) (xy 395.605508 -177.216816) (xy 392.841226 -177.216816)
			(xy 392.831155 -177.216399) (xy 392.812556 -177.208675) (xy 392.805158 -177.20183) (xy 392.600434 -176.997106)
			(xy 392.593609 -176.989694) (xy 392.585879 -176.971104) (xy 392.585448 -176.961038) (xy 392.585448 -171.707048)
			(xy 392.585011 -171.69698) (xy 392.5773 -171.678381) (xy 392.570462 -171.67098) (xy 390.72693 -169.827702)
			(xy 390.719513 -169.820883) (xy 390.700927 -169.813151) (xy 390.690862 -169.812716) (xy 387.205728 -169.812716)
			(xy 387.195657 -169.812298) (xy 387.177058 -169.804575) (xy 387.16966 -169.79773) (xy 385.280662 -167.908732)
			(xy 385.273838 -167.901319) (xy 385.26611 -167.88273) (xy 385.265676 -167.872664) (xy 384.347212 -167.872664)
			(xy 384.347212 -167.89146) (xy 384.347655 -167.901527) (xy 384.355363 -167.920126) (xy 384.362198 -167.927528)
			(xy 386.394706 -169.960036) (xy 386.401555 -169.967429) (xy 386.409269 -169.986034) (xy 386.409692 -169.996104)
			(xy 386.409692 -174.64532) (xy 386.410083 -174.655394) (xy 386.417825 -174.673993) (xy 386.424678 -174.681388)
			(xy 388.397242 -176.653698) (xy 388.40408 -176.6611) (xy 388.411799 -176.679698) (xy 388.412228 -176.689766)
			(xy 388.412228 -178.404012) (xy 389.102854 -178.404012) (xy 389.10334 -178.376761) (xy 389.111096 -178.322813)
			(xy 389.126451 -178.270518) (xy 389.149093 -178.220941) (xy 389.178559 -178.175091) (xy 389.21425 -178.1339)
			(xy 389.255441 -178.098209) (xy 389.301291 -178.068743) (xy 389.350868 -178.046101) (xy 389.403163 -178.030746)
			(xy 389.457111 -178.02299) (xy 389.511613 -178.02299) (xy 389.565561 -178.030746) (xy 389.617856 -178.046101)
			(xy 389.667433 -178.068743) (xy 389.713283 -178.098209) (xy 389.754474 -178.1339) (xy 389.790165 -178.175091)
			(xy 389.819631 -178.220941) (xy 389.842273 -178.270518) (xy 389.857628 -178.322813) (xy 389.865384 -178.376761)
			(xy 389.86587 -178.404012) (xy 389.865203 -178.435575) (xy 389.854819 -178.49784) (xy 389.834336 -178.557549)
			(xy 389.819896 -178.585622) (xy 389.81507 -178.594512) (xy 389.813038 -178.61407) (xy 389.835898 -178.692556)
			(xy 389.839125 -178.701985) (xy 389.851551 -178.717541) (xy 389.860028 -178.722782) (xy 389.867394 -178.726846)
			(xy 389.8773 -178.732688) (xy 389.899144 -178.73472) (xy 389.993886 -178.701192) (xy 390.009634 -178.685698)
			(xy 390.013698 -178.675284) (xy 390.024371 -178.648498) (xy 390.052662 -178.598255) (xy 390.088195 -178.552845)
			(xy 390.13016 -178.513303) (xy 390.177601 -178.480531) (xy 390.229435 -178.455275) (xy 390.284481 -178.438111)
			(xy 390.341484 -178.429432) (xy 390.370314 -178.428904) (xy 390.397565 -178.429367) (xy 390.451513 -178.437125)
			(xy 390.503808 -178.452482) (xy 390.553385 -178.475125) (xy 390.599235 -178.504592) (xy 390.640425 -178.540285)
			(xy 390.676116 -178.581476) (xy 390.705582 -178.627327) (xy 390.728223 -178.676905) (xy 390.743578 -178.7292)
			(xy 390.751334 -178.783149) (xy 390.751334 -178.837651) (xy 390.743578 -178.8916) (xy 390.734228 -178.923442)
			(xy 390.993122 -178.923442) (xy 390.993628 -178.895968) (xy 391.001514 -178.841589) (xy 391.017129 -178.788907)
			(xy 391.04015 -178.739014) (xy 391.070098 -178.692944) (xy 391.087864 -178.671982) (xy 391.088118 -178.671728)
			(xy 391.093701 -178.664639) (xy 391.099949 -178.647724) (xy 391.10031 -178.638708) (xy 391.10031 -178.571144)
			(xy 391.09993 -178.562129) (xy 391.093698 -178.545212) (xy 391.088118 -178.538124) (xy 391.08761 -178.537616)
			(xy 391.06989 -178.516659) (xy 391.040005 -178.470629) (xy 391.017036 -178.420787) (xy 391.001458 -178.368164)
			(xy 390.993594 -178.31385) (xy 390.993122 -178.28641) (xy 390.993608 -178.259159) (xy 391.001364 -178.205211)
			(xy 391.016719 -178.152916) (xy 391.039361 -178.103339) (xy 391.068827 -178.057489) (xy 391.104518 -178.016298)
			(xy 391.145709 -177.980607) (xy 391.191559 -177.951141) (xy 391.241136 -177.928499) (xy 391.293431 -177.913144)
			(xy 391.347379 -177.905388) (xy 391.401881 -177.905388) (xy 391.455829 -177.913144) (xy 391.508124 -177.928499)
			(xy 391.557701 -177.951141) (xy 391.603551 -177.980607) (xy 391.644742 -178.016298) (xy 391.680433 -178.057489)
			(xy 391.709899 -178.103339) (xy 391.732541 -178.152916) (xy 391.747896 -178.205211) (xy 391.755652 -178.259159)
			(xy 391.756138 -178.28641) (xy 391.755648 -178.313884) (xy 391.747756 -178.368263) (xy 391.732136 -178.420945)
			(xy 391.709112 -178.470838) (xy 391.679162 -178.516907) (xy 391.661396 -178.53787) (xy 391.661142 -178.538124)
			(xy 391.655532 -178.545195) (xy 391.649301 -178.562124) (xy 391.64895 -178.571144) (xy 391.64895 -178.638708)
			(xy 391.649293 -178.647727) (xy 391.655549 -178.664644) (xy 391.661142 -178.671728) (xy 391.66165 -178.672236)
			(xy 391.679389 -178.693178) (xy 391.709272 -178.739211) (xy 391.732238 -178.789057) (xy 391.747811 -178.841684)
			(xy 391.755669 -178.896001) (xy 391.756138 -178.923442) (xy 391.755652 -178.950693) (xy 391.754019 -178.96205)
			(xy 392.330938 -178.96205) (xy 392.335009 -178.906428) (xy 392.347135 -178.851991) (xy 392.367058 -178.7999)
			(xy 392.394354 -178.751265) (xy 392.42844 -178.707122) (xy 392.468589 -178.668413) (xy 392.513947 -178.635962)
			(xy 392.563547 -178.610461) (xy 392.616331 -178.592454) (xy 392.671174 -178.582324) (xy 392.726908 -178.580287)
			(xy 392.782345 -178.586387) (xy 392.836302 -178.600493) (xy 392.887631 -178.622305) (xy 392.935237 -178.651359)
			(xy 392.978105 -178.687034) (xy 393.015322 -178.728571) (xy 393.046095 -178.775084) (xy 393.069767 -178.825581)
			(xy 393.085835 -178.878988) (xy 393.093955 -178.934164) (xy 393.094464 -178.96205) (xy 393.093955 -178.989936)
			(xy 393.085835 -179.045112) (xy 393.069767 -179.098519) (xy 393.046095 -179.149016) (xy 393.015322 -179.195529)
			(xy 392.978105 -179.237066) (xy 392.935237 -179.272741) (xy 392.887631 -179.301795) (xy 392.836302 -179.323607)
			(xy 392.782345 -179.337713) (xy 392.726908 -179.343813) (xy 392.671174 -179.341776) (xy 392.616331 -179.331646)
			(xy 392.563547 -179.313639) (xy 392.513947 -179.288138) (xy 392.468589 -179.255687) (xy 392.42844 -179.216978)
			(xy 392.394354 -179.172835) (xy 392.367058 -179.1242) (xy 392.347135 -179.072109) (xy 392.335009 -179.017672)
			(xy 392.330938 -178.96205) (xy 391.754019 -178.96205) (xy 391.747896 -179.004641) (xy 391.732541 -179.056936)
			(xy 391.709899 -179.106513) (xy 391.680433 -179.152363) (xy 391.644742 -179.193554) (xy 391.603551 -179.229245)
			(xy 391.557701 -179.258711) (xy 391.508124 -179.281353) (xy 391.455829 -179.296708) (xy 391.401881 -179.304464)
			(xy 391.347379 -179.304464) (xy 391.293431 -179.296708) (xy 391.241136 -179.281353) (xy 391.191559 -179.258711)
			(xy 391.145709 -179.229245) (xy 391.104518 -179.193554) (xy 391.068827 -179.152363) (xy 391.039361 -179.106513)
			(xy 391.016719 -179.056936) (xy 391.001364 -179.004641) (xy 390.993608 -178.950693) (xy 390.993122 -178.923442)
			(xy 390.734228 -178.923442) (xy 390.728223 -178.943895) (xy 390.705582 -178.993473) (xy 390.676116 -179.039324)
			(xy 390.640425 -179.080515) (xy 390.599235 -179.116208) (xy 390.553385 -179.145675) (xy 390.503808 -179.168318)
			(xy 390.451513 -179.183675) (xy 390.397565 -179.191433) (xy 390.370314 -179.19192) (xy 390.37006 -179.19192)
			(xy 390.344855 -179.191543) (xy 390.294887 -179.184898) (xy 390.246232 -179.171715) (xy 390.199743 -179.152225)
			(xy 390.177782 -179.13985) (xy 390.167876 -179.134008) (xy 390.146032 -179.131976) (xy 390.05129 -179.165504)
			(xy 390.035542 -179.180998) (xy 390.031478 -179.191412) (xy 390.02074 -179.21817) (xy 389.992457 -179.26841)
			(xy 389.956933 -179.313819) (xy 389.914977 -179.353362) (xy 389.867546 -179.386137) (xy 389.815721 -179.411399)
			(xy 389.760684 -179.428569) (xy 389.703689 -179.437259) (xy 389.674862 -179.437792) (xy 389.647609 -179.437357)
			(xy 389.593659 -179.429595) (xy 389.541362 -179.414235) (xy 389.491784 -179.391588) (xy 389.445933 -179.362116)
			(xy 389.404742 -179.326419) (xy 389.369051 -179.285224) (xy 389.339586 -179.239369) (xy 389.316946 -179.189787)
			(xy 389.301593 -179.137488) (xy 389.293839 -179.083537) (xy 389.293354 -179.056284) (xy 389.294016 -179.024721)
			(xy 389.304401 -178.962456) (xy 389.324886 -178.902747) (xy 389.339328 -178.874674) (xy 389.344154 -178.865784)
			(xy 389.346186 -178.846226) (xy 389.323326 -178.76774) (xy 389.320128 -178.758299) (xy 389.307683 -178.742748)
			(xy 389.299196 -178.737514) (xy 389.274072 -178.723003) (xy 389.22819 -178.687493) (xy 389.188216 -178.645443)
			(xy 389.155073 -178.597823) (xy 389.129526 -178.545732) (xy 389.112165 -178.490372) (xy 389.10339 -178.433021)
			(xy 389.102854 -178.404012) (xy 388.412228 -178.404012) (xy 388.412228 -179.529486) (xy 388.412653 -179.539555)
			(xy 388.420373 -179.558154) (xy 388.427214 -179.565554) (xy 388.71906 -179.8574) (xy 391.751818 -179.8574)
			(xy 391.755889 -179.801778) (xy 391.768015 -179.747341) (xy 391.787938 -179.69525) (xy 391.815234 -179.646615)
			(xy 391.84932 -179.602472) (xy 391.889469 -179.563763) (xy 391.934827 -179.531312) (xy 391.984427 -179.505811)
			(xy 392.037211 -179.487804) (xy 392.092054 -179.477674) (xy 392.147788 -179.475637) (xy 392.203225 -179.481737)
			(xy 392.257182 -179.495843) (xy 392.308511 -179.517655) (xy 392.356117 -179.546709) (xy 392.398985 -179.582384)
			(xy 392.436202 -179.623921) (xy 392.466975 -179.670434) (xy 392.490647 -179.720931) (xy 392.506715 -179.774338)
			(xy 392.514835 -179.829514) (xy 392.515344 -179.8574) (xy 392.514835 -179.885286) (xy 392.506715 -179.940462)
			(xy 392.490647 -179.993869) (xy 392.466975 -180.044366) (xy 392.436202 -180.090879) (xy 392.398985 -180.132416)
			(xy 392.356117 -180.168091) (xy 392.308511 -180.197145) (xy 392.257182 -180.218957) (xy 392.203225 -180.233063)
			(xy 392.147788 -180.239163) (xy 392.092054 -180.237126) (xy 392.037211 -180.226996) (xy 391.984427 -180.208989)
			(xy 391.934827 -180.183488) (xy 391.889469 -180.151037) (xy 391.84932 -180.112328) (xy 391.815234 -180.068185)
			(xy 391.787938 -180.01955) (xy 391.768015 -179.967459) (xy 391.755889 -179.913022) (xy 391.751818 -179.8574)
			(xy 388.71906 -179.8574) (xy 389.267446 -180.405786) (xy 389.274279 -180.413191) (xy 389.282001 -180.431787)
			(xy 389.282432 -180.441854) (xy 389.282432 -181.73446) (xy 392.71067 -181.73446) (xy 392.711144 -181.706549)
			(xy 392.719284 -181.651322) (xy 392.735384 -181.597871) (xy 392.759101 -181.547337) (xy 392.789928 -181.500798)
			(xy 392.808206 -181.479698) (xy 392.814105 -181.472522) (xy 392.820755 -181.455196) (xy 392.82116 -181.445916)
			(xy 392.82116 -181.368192) (xy 392.814556 -181.35092) (xy 392.808206 -181.343808) (xy 392.789911 -181.322722)
			(xy 392.759086 -181.27618) (xy 392.735374 -181.225642) (xy 392.719281 -181.172188) (xy 392.711152 -181.116958)
			(xy 392.71067 -181.089046) (xy 392.711156 -181.061795) (xy 392.718912 -181.007847) (xy 392.734267 -180.955552)
			(xy 392.756909 -180.905975) (xy 392.786375 -180.860125) (xy 392.822066 -180.818934) (xy 392.863257 -180.783243)
			(xy 392.909107 -180.753777) (xy 392.958684 -180.731135) (xy 393.010979 -180.71578) (xy 393.064927 -180.708024)
			(xy 393.119429 -180.708024) (xy 393.173377 -180.71578) (xy 393.225672 -180.731135) (xy 393.275249 -180.753777)
			(xy 393.321099 -180.783243) (xy 393.36229 -180.818934) (xy 393.397981 -180.860125) (xy 393.427447 -180.905975)
			(xy 393.450089 -180.955552) (xy 393.465444 -181.007847) (xy 393.4732 -181.061795) (xy 393.473686 -181.089046)
			(xy 393.473202 -181.116957) (xy 393.465062 -181.172182) (xy 393.448964 -181.225632) (xy 393.42525 -181.276167)
			(xy 393.394426 -181.322707) (xy 393.37615 -181.343808) (xy 393.370244 -181.350978) (xy 393.3636 -181.368309)
			(xy 393.363196 -181.37759) (xy 393.363196 -181.455314) (xy 393.3698 -181.472586) (xy 393.37615 -181.479698)
			(xy 393.394409 -181.500813) (xy 393.425238 -181.547348) (xy 393.448956 -181.597879) (xy 393.465057 -181.651326)
			(xy 393.473197 -181.70655) (xy 393.473686 -181.73446) (xy 393.4732 -181.761711) (xy 393.465444 -181.815659)
			(xy 393.450089 -181.867954) (xy 393.427447 -181.917531) (xy 393.397981 -181.963381) (xy 393.36229 -182.004572)
			(xy 393.321099 -182.040263) (xy 393.275249 -182.069729) (xy 393.225672 -182.092371) (xy 393.173377 -182.107726)
			(xy 393.119429 -182.115482) (xy 393.064927 -182.115482) (xy 393.010979 -182.107726) (xy 392.958684 -182.092371)
			(xy 392.909107 -182.069729) (xy 392.863257 -182.040263) (xy 392.822066 -182.004572) (xy 392.786375 -181.963381)
			(xy 392.756909 -181.917531) (xy 392.734267 -181.867954) (xy 392.718912 -181.815659) (xy 392.711156 -181.761711)
			(xy 392.71067 -181.73446) (xy 389.282432 -181.73446) (xy 389.282432 -182.563262) (xy 389.282005 -182.573331)
			(xy 389.274287 -182.59193) (xy 389.267446 -182.59933) (xy 389.13689 -182.729886) (xy 389.129486 -182.736721)
			(xy 389.11089 -182.744444) (xy 389.100822 -182.744872) (xy 386.013452 -182.744872) (xy 386.003385 -182.744427)
			(xy 385.984786 -182.736721) (xy 385.977384 -182.729886) (xy 385.705858 -182.45836) (xy 385.699002 -182.450973)
			(xy 385.691293 -182.432363) (xy 385.690872 -182.422292) (xy 385.690872 -181.317392) (xy 385.690458 -181.307321)
			(xy 385.68273 -181.288723) (xy 385.675886 -181.281324) (xy 385.068826 -180.67401) (xy 385.062002 -180.666597)
			(xy 385.054272 -180.648008) (xy 385.05384 -180.637942) (xy 385.05384 -177.720752) (xy 385.053403 -177.710684)
			(xy 385.045692 -177.692085) (xy 385.038854 -177.684684) (xy 384.432556 -177.078894) (xy 384.425166 -177.072041)
			(xy 384.406559 -177.064329) (xy 384.396488 -177.063908) (xy 380.346712 -177.063908) (xy 380.336643 -177.064338)
			(xy 380.318045 -177.072055) (xy 380.310644 -177.078894) (xy 380.073154 -177.316384) (xy 380.066322 -177.32379)
			(xy 380.058599 -177.342385) (xy 380.058168 -177.352452) (xy 380.058168 -178.404012) (xy 380.771654 -178.404012)
			(xy 380.77214 -178.376761) (xy 380.779896 -178.322813) (xy 380.795251 -178.270518) (xy 380.817893 -178.220941)
			(xy 380.847359 -178.175091) (xy 380.88305 -178.1339) (xy 380.924241 -178.098209) (xy 380.970091 -178.068743)
			(xy 381.019668 -178.046101) (xy 381.071963 -178.030746) (xy 381.125911 -178.02299) (xy 381.180413 -178.02299)
			(xy 381.234361 -178.030746) (xy 381.286656 -178.046101) (xy 381.336233 -178.068743) (xy 381.382083 -178.098209)
			(xy 381.423274 -178.1339) (xy 381.458965 -178.175091) (xy 381.488431 -178.220941) (xy 381.511073 -178.270518)
			(xy 381.526428 -178.322813) (xy 381.534184 -178.376761) (xy 381.53467 -178.404012) (xy 381.534003 -178.435575)
			(xy 381.523619 -178.49784) (xy 381.503136 -178.557549) (xy 381.488696 -178.585622) (xy 381.48387 -178.594512)
			(xy 381.481838 -178.61407) (xy 381.504698 -178.692556) (xy 381.507925 -178.701985) (xy 381.520351 -178.717541)
			(xy 381.528828 -178.722782) (xy 381.536194 -178.726846) (xy 381.5461 -178.732688) (xy 381.567944 -178.73472)
			(xy 381.662686 -178.701192) (xy 381.678434 -178.685698) (xy 381.682498 -178.675284) (xy 381.693171 -178.648498)
			(xy 381.721462 -178.598255) (xy 381.756995 -178.552845) (xy 381.79896 -178.513303) (xy 381.846401 -178.480531)
			(xy 381.898235 -178.455275) (xy 381.953281 -178.438111) (xy 382.010284 -178.429432) (xy 382.039114 -178.428904)
			(xy 382.066365 -178.429367) (xy 382.120313 -178.437125) (xy 382.172608 -178.452482) (xy 382.222185 -178.475125)
			(xy 382.268035 -178.504592) (xy 382.309225 -178.540285) (xy 382.344916 -178.581476) (xy 382.374382 -178.627327)
			(xy 382.397023 -178.676905) (xy 382.412378 -178.7292) (xy 382.420134 -178.783149) (xy 382.420134 -178.837651)
			(xy 382.412378 -178.8916) (xy 382.403028 -178.923442) (xy 382.661922 -178.923442) (xy 382.662428 -178.895968)
			(xy 382.670314 -178.841589) (xy 382.685929 -178.788907) (xy 382.70895 -178.739014) (xy 382.738898 -178.692944)
			(xy 382.756664 -178.671982) (xy 382.756918 -178.671728) (xy 382.762501 -178.664639) (xy 382.768749 -178.647724)
			(xy 382.76911 -178.638708) (xy 382.76911 -178.571144) (xy 382.76873 -178.562129) (xy 382.762498 -178.545212)
			(xy 382.756918 -178.538124) (xy 382.75641 -178.537616) (xy 382.73869 -178.516659) (xy 382.708805 -178.470629)
			(xy 382.685836 -178.420787) (xy 382.670258 -178.368164) (xy 382.662394 -178.31385) (xy 382.661922 -178.28641)
			(xy 382.662408 -178.259159) (xy 382.670164 -178.205211) (xy 382.685519 -178.152916) (xy 382.708161 -178.103339)
			(xy 382.737627 -178.057489) (xy 382.773318 -178.016298) (xy 382.814509 -177.980607) (xy 382.860359 -177.951141)
			(xy 382.909936 -177.928499) (xy 382.962231 -177.913144) (xy 383.016179 -177.905388) (xy 383.070681 -177.905388)
			(xy 383.124629 -177.913144) (xy 383.176924 -177.928499) (xy 383.226501 -177.951141) (xy 383.272351 -177.980607)
			(xy 383.313542 -178.016298) (xy 383.349233 -178.057489) (xy 383.378699 -178.103339) (xy 383.401341 -178.152916)
			(xy 383.416696 -178.205211) (xy 383.424452 -178.259159) (xy 383.424938 -178.28641) (xy 383.424448 -178.313884)
			(xy 383.416556 -178.368263) (xy 383.400936 -178.420945) (xy 383.377912 -178.470838) (xy 383.347962 -178.516907)
			(xy 383.330196 -178.53787) (xy 383.329942 -178.538124) (xy 383.324332 -178.545195) (xy 383.318101 -178.562124)
			(xy 383.31775 -178.571144) (xy 383.31775 -178.638708) (xy 383.318093 -178.647727) (xy 383.324349 -178.664644)
			(xy 383.329942 -178.671728) (xy 383.33045 -178.672236) (xy 383.348189 -178.693178) (xy 383.378072 -178.739211)
			(xy 383.401038 -178.789057) (xy 383.416611 -178.841684) (xy 383.424469 -178.896001) (xy 383.424938 -178.923442)
			(xy 383.424452 -178.950693) (xy 383.422819 -178.96205) (xy 383.999738 -178.96205) (xy 384.003809 -178.906428)
			(xy 384.015935 -178.851991) (xy 384.035858 -178.7999) (xy 384.063154 -178.751265) (xy 384.09724 -178.707122)
			(xy 384.137389 -178.668413) (xy 384.182747 -178.635962) (xy 384.232347 -178.610461) (xy 384.285131 -178.592454)
			(xy 384.339974 -178.582324) (xy 384.395708 -178.580287) (xy 384.451145 -178.586387) (xy 384.505102 -178.600493)
			(xy 384.556431 -178.622305) (xy 384.604037 -178.651359) (xy 384.646905 -178.687034) (xy 384.684122 -178.728571)
			(xy 384.714895 -178.775084) (xy 384.738567 -178.825581) (xy 384.754635 -178.878988) (xy 384.762755 -178.934164)
			(xy 384.763264 -178.96205) (xy 384.762755 -178.989936) (xy 384.754635 -179.045112) (xy 384.738567 -179.098519)
			(xy 384.714895 -179.149016) (xy 384.684122 -179.195529) (xy 384.646905 -179.237066) (xy 384.604037 -179.272741)
			(xy 384.556431 -179.301795) (xy 384.505102 -179.323607) (xy 384.451145 -179.337713) (xy 384.395708 -179.343813)
			(xy 384.339974 -179.341776) (xy 384.285131 -179.331646) (xy 384.232347 -179.313639) (xy 384.182747 -179.288138)
			(xy 384.137389 -179.255687) (xy 384.09724 -179.216978) (xy 384.063154 -179.172835) (xy 384.035858 -179.1242)
			(xy 384.015935 -179.072109) (xy 384.003809 -179.017672) (xy 383.999738 -178.96205) (xy 383.422819 -178.96205)
			(xy 383.416696 -179.004641) (xy 383.401341 -179.056936) (xy 383.378699 -179.106513) (xy 383.349233 -179.152363)
			(xy 383.313542 -179.193554) (xy 383.272351 -179.229245) (xy 383.226501 -179.258711) (xy 383.176924 -179.281353)
			(xy 383.124629 -179.296708) (xy 383.070681 -179.304464) (xy 383.016179 -179.304464) (xy 382.962231 -179.296708)
			(xy 382.909936 -179.281353) (xy 382.860359 -179.258711) (xy 382.814509 -179.229245) (xy 382.773318 -179.193554)
			(xy 382.737627 -179.152363) (xy 382.708161 -179.106513) (xy 382.685519 -179.056936) (xy 382.670164 -179.004641)
			(xy 382.662408 -178.950693) (xy 382.661922 -178.923442) (xy 382.403028 -178.923442) (xy 382.397023 -178.943895)
			(xy 382.374382 -178.993473) (xy 382.344916 -179.039324) (xy 382.309225 -179.080515) (xy 382.268035 -179.116208)
			(xy 382.222185 -179.145675) (xy 382.172608 -179.168318) (xy 382.120313 -179.183675) (xy 382.066365 -179.191433)
			(xy 382.039114 -179.19192) (xy 382.03886 -179.19192) (xy 382.013655 -179.191543) (xy 381.963687 -179.184898)
			(xy 381.915032 -179.171715) (xy 381.868543 -179.152225) (xy 381.846582 -179.13985) (xy 381.836676 -179.134008)
			(xy 381.814832 -179.131976) (xy 381.72009 -179.165504) (xy 381.704342 -179.180998) (xy 381.700278 -179.191412)
			(xy 381.68954 -179.21817) (xy 381.661257 -179.26841) (xy 381.625733 -179.313819) (xy 381.583777 -179.353362)
			(xy 381.536346 -179.386137) (xy 381.484521 -179.411399) (xy 381.429484 -179.428569) (xy 381.372489 -179.437259)
			(xy 381.343662 -179.437792) (xy 381.316409 -179.437357) (xy 381.262459 -179.429595) (xy 381.210162 -179.414235)
			(xy 381.160584 -179.391588) (xy 381.114733 -179.362116) (xy 381.073542 -179.326419) (xy 381.037851 -179.285224)
			(xy 381.008386 -179.239369) (xy 380.985746 -179.189787) (xy 380.970393 -179.137488) (xy 380.962639 -179.083537)
			(xy 380.962154 -179.056284) (xy 380.962816 -179.024721) (xy 380.973201 -178.962456) (xy 380.993686 -178.902747)
			(xy 381.008128 -178.874674) (xy 381.012954 -178.865784) (xy 381.014986 -178.846226) (xy 380.992126 -178.76774)
			(xy 380.988928 -178.758299) (xy 380.976483 -178.742748) (xy 380.967996 -178.737514) (xy 380.942872 -178.723003)
			(xy 380.89699 -178.687493) (xy 380.857016 -178.645443) (xy 380.823873 -178.597823) (xy 380.798326 -178.545732)
			(xy 380.780965 -178.490372) (xy 380.77219 -178.433021) (xy 380.771654 -178.404012) (xy 380.058168 -178.404012)
			(xy 380.058168 -179.506626) (xy 380.058562 -179.516699) (xy 380.066303 -179.535298) (xy 380.073154 -179.542694)
			(xy 380.38786 -179.8574) (xy 383.420618 -179.8574) (xy 383.424689 -179.801778) (xy 383.436815 -179.747341)
			(xy 383.456738 -179.69525) (xy 383.484034 -179.646615) (xy 383.51812 -179.602472) (xy 383.558269 -179.563763)
			(xy 383.603627 -179.531312) (xy 383.653227 -179.505811) (xy 383.706011 -179.487804) (xy 383.760854 -179.477674)
			(xy 383.816588 -179.475637) (xy 383.872025 -179.481737) (xy 383.925982 -179.495843) (xy 383.977311 -179.517655)
			(xy 384.024917 -179.546709) (xy 384.067785 -179.582384) (xy 384.105002 -179.623921) (xy 384.135775 -179.670434)
			(xy 384.159447 -179.720931) (xy 384.175515 -179.774338) (xy 384.183635 -179.829514) (xy 384.184144 -179.8574)
			(xy 384.183635 -179.885286) (xy 384.175515 -179.940462) (xy 384.159447 -179.993869) (xy 384.135775 -180.044366)
			(xy 384.105002 -180.090879) (xy 384.067785 -180.132416) (xy 384.024917 -180.168091) (xy 383.977311 -180.197145)
			(xy 383.925982 -180.218957) (xy 383.872025 -180.233063) (xy 383.816588 -180.239163) (xy 383.760854 -180.237126)
			(xy 383.706011 -180.226996) (xy 383.653227 -180.208989) (xy 383.603627 -180.183488) (xy 383.558269 -180.151037)
			(xy 383.51812 -180.112328) (xy 383.484034 -180.068185) (xy 383.456738 -180.01955) (xy 383.436815 -179.967459)
			(xy 383.424689 -179.913022) (xy 383.420618 -179.8574) (xy 380.38786 -179.8574) (xy 380.936246 -180.405786)
			(xy 380.943079 -180.413191) (xy 380.950801 -180.431787) (xy 380.951232 -180.441854) (xy 380.951232 -181.73446)
			(xy 384.37947 -181.73446) (xy 384.379944 -181.706549) (xy 384.388084 -181.651322) (xy 384.404184 -181.597871)
			(xy 384.427901 -181.547337) (xy 384.458728 -181.500798) (xy 384.477006 -181.479698) (xy 384.482905 -181.472522)
			(xy 384.489555 -181.455196) (xy 384.48996 -181.445916) (xy 384.48996 -181.368192) (xy 384.483356 -181.35092)
			(xy 384.477006 -181.343808) (xy 384.458711 -181.322722) (xy 384.427886 -181.27618) (xy 384.404174 -181.225642)
			(xy 384.388081 -181.172188) (xy 384.379952 -181.116958) (xy 384.37947 -181.089046) (xy 384.379956 -181.061795)
			(xy 384.387712 -181.007847) (xy 384.403067 -180.955552) (xy 384.425709 -180.905975) (xy 384.455175 -180.860125)
			(xy 384.490866 -180.818934) (xy 384.532057 -180.783243) (xy 384.577907 -180.753777) (xy 384.627484 -180.731135)
			(xy 384.679779 -180.71578) (xy 384.733727 -180.708024) (xy 384.788229 -180.708024) (xy 384.842177 -180.71578)
			(xy 384.894472 -180.731135) (xy 384.944049 -180.753777) (xy 384.989899 -180.783243) (xy 385.03109 -180.818934)
			(xy 385.066781 -180.860125) (xy 385.096247 -180.905975) (xy 385.118889 -180.955552) (xy 385.134244 -181.007847)
			(xy 385.142 -181.061795) (xy 385.142486 -181.089046) (xy 385.142002 -181.116957) (xy 385.133862 -181.172182)
			(xy 385.117764 -181.225632) (xy 385.09405 -181.276167) (xy 385.063226 -181.322707) (xy 385.04495 -181.343808)
			(xy 385.039044 -181.350978) (xy 385.0324 -181.368309) (xy 385.031996 -181.37759) (xy 385.031996 -181.455314)
			(xy 385.0386 -181.472586) (xy 385.04495 -181.479698) (xy 385.063209 -181.500813) (xy 385.094038 -181.547348)
			(xy 385.117756 -181.597879) (xy 385.133857 -181.651326) (xy 385.141997 -181.70655) (xy 385.142486 -181.73446)
			(xy 385.142 -181.761711) (xy 385.134244 -181.815659) (xy 385.118889 -181.867954) (xy 385.096247 -181.917531)
			(xy 385.066781 -181.963381) (xy 385.03109 -182.004572) (xy 384.989899 -182.040263) (xy 384.944049 -182.069729)
			(xy 384.894472 -182.092371) (xy 384.842177 -182.107726) (xy 384.788229 -182.115482) (xy 384.733727 -182.115482)
			(xy 384.679779 -182.107726) (xy 384.627484 -182.092371) (xy 384.577907 -182.069729) (xy 384.532057 -182.040263)
			(xy 384.490866 -182.004572) (xy 384.455175 -181.963381) (xy 384.425709 -181.917531) (xy 384.403067 -181.867954)
			(xy 384.387712 -181.815659) (xy 384.379956 -181.761711) (xy 384.37947 -181.73446) (xy 380.951232 -181.73446)
			(xy 380.951232 -182.694072) (xy 380.95069 -182.704074) (xy 380.943046 -182.722559) (xy 380.928909 -182.736712)
			(xy 380.910433 -182.744378) (xy 380.900432 -182.744872) (xy 377.627896 -182.744872) (xy 377.617826 -182.744456)
			(xy 377.599227 -182.73673) (xy 377.591828 -182.729886) (xy 377.290838 -182.428896) (xy 377.284009 -182.421487)
			(xy 377.276282 -182.402895) (xy 377.275852 -182.392828) (xy 377.275852 -181.243478) (xy 377.275451 -181.233406)
			(xy 377.267715 -181.214807) (xy 377.260866 -181.20741) (xy 376.775726 -180.722016) (xy 376.768904 -180.714601)
			(xy 376.761173 -180.696013) (xy 376.76074 -180.685948) (xy 376.76074 -177.448718) (xy 376.760321 -177.438648)
			(xy 376.752598 -177.420049) (xy 376.745754 -177.41265) (xy 375.691654 -176.35855) (xy 375.684224 -176.351748)
			(xy 375.665648 -176.344005) (xy 375.655586 -176.343564) (xy 372.55577 -176.343564) (xy 372.545697 -176.343957)
			(xy 372.527098 -176.351698) (xy 372.519702 -176.35855) (xy 371.683534 -177.194718) (xy 371.676698 -177.202122)
			(xy 371.668975 -177.220718) (xy 371.668548 -177.230786) (xy 371.668548 -178.404012) (xy 372.368826 -178.404012)
			(xy 372.369312 -178.376761) (xy 372.377068 -178.322813) (xy 372.392423 -178.270518) (xy 372.415065 -178.220941)
			(xy 372.444531 -178.175091) (xy 372.480222 -178.1339) (xy 372.521413 -178.098209) (xy 372.567263 -178.068743)
			(xy 372.61684 -178.046101) (xy 372.669135 -178.030746) (xy 372.723083 -178.02299) (xy 372.777585 -178.02299)
			(xy 372.831533 -178.030746) (xy 372.883828 -178.046101) (xy 372.933405 -178.068743) (xy 372.979255 -178.098209)
			(xy 373.020446 -178.1339) (xy 373.056137 -178.175091) (xy 373.085603 -178.220941) (xy 373.108245 -178.270518)
			(xy 373.112911 -178.28641) (xy 374.259094 -178.28641) (xy 374.25958 -178.259159) (xy 374.267336 -178.205211)
			(xy 374.282691 -178.152916) (xy 374.305333 -178.103339) (xy 374.334799 -178.057489) (xy 374.37049 -178.016298)
			(xy 374.411681 -177.980607) (xy 374.457531 -177.951141) (xy 374.507108 -177.928499) (xy 374.559403 -177.913144)
			(xy 374.613351 -177.905388) (xy 374.667853 -177.905388) (xy 374.721801 -177.913144) (xy 374.774096 -177.928499)
			(xy 374.823673 -177.951141) (xy 374.869523 -177.980607) (xy 374.910714 -178.016298) (xy 374.946405 -178.057489)
			(xy 374.975871 -178.103339) (xy 374.998513 -178.152916) (xy 375.013868 -178.205211) (xy 375.021624 -178.259159)
			(xy 375.02211 -178.28641) (xy 375.021586 -178.314084) (xy 375.013594 -178.36885) (xy 374.997766 -178.421886)
			(xy 374.974434 -178.472074) (xy 374.944088 -178.51836) (xy 374.926098 -178.539394) (xy 374.919748 -178.546506)
			(xy 374.913144 -178.564286) (xy 374.914668 -178.652424) (xy 374.922034 -178.66995) (xy 374.928638 -178.676808)
			(xy 374.948251 -178.698239) (xy 374.981448 -178.745911) (xy 375.007042 -178.798061) (xy 375.024442 -178.853486)
			(xy 375.033248 -178.910906) (xy 375.033794 -178.939952) (xy 375.0334 -178.96205) (xy 375.59691 -178.96205)
			(xy 375.600981 -178.906428) (xy 375.613107 -178.851991) (xy 375.63303 -178.7999) (xy 375.660326 -178.751265)
			(xy 375.694412 -178.707122) (xy 375.734561 -178.668413) (xy 375.779919 -178.635962) (xy 375.829519 -178.610461)
			(xy 375.882303 -178.592454) (xy 375.937146 -178.582324) (xy 375.99288 -178.580287) (xy 376.048317 -178.586387)
			(xy 376.102274 -178.600493) (xy 376.153603 -178.622305) (xy 376.201209 -178.651359) (xy 376.244077 -178.687034)
			(xy 376.281294 -178.728571) (xy 376.312067 -178.775084) (xy 376.335739 -178.825581) (xy 376.351807 -178.878988)
			(xy 376.359927 -178.934164) (xy 376.360436 -178.96205) (xy 376.359927 -178.989936) (xy 376.351807 -179.045112)
			(xy 376.335739 -179.098519) (xy 376.312067 -179.149016) (xy 376.281294 -179.195529) (xy 376.244077 -179.237066)
			(xy 376.201209 -179.272741) (xy 376.153603 -179.301795) (xy 376.102274 -179.323607) (xy 376.048317 -179.337713)
			(xy 375.99288 -179.343813) (xy 375.937146 -179.341776) (xy 375.882303 -179.331646) (xy 375.829519 -179.313639)
			(xy 375.779919 -179.288138) (xy 375.734561 -179.255687) (xy 375.694412 -179.216978) (xy 375.660326 -179.172835)
			(xy 375.63303 -179.1242) (xy 375.613107 -179.072109) (xy 375.600981 -179.017672) (xy 375.59691 -178.96205)
			(xy 375.0334 -178.96205) (xy 375.033308 -178.967203) (xy 375.025552 -179.021151) (xy 375.010197 -179.073446)
			(xy 374.987555 -179.123023) (xy 374.958089 -179.168873) (xy 374.922398 -179.210064) (xy 374.881207 -179.245755)
			(xy 374.835357 -179.275221) (xy 374.78578 -179.297863) (xy 374.733485 -179.313218) (xy 374.679537 -179.320974)
			(xy 374.625035 -179.320974) (xy 374.571087 -179.313218) (xy 374.518792 -179.297863) (xy 374.469215 -179.275221)
			(xy 374.423365 -179.245755) (xy 374.382174 -179.210064) (xy 374.346483 -179.168873) (xy 374.317017 -179.123023)
			(xy 374.294375 -179.073446) (xy 374.27902 -179.021151) (xy 374.271264 -178.967203) (xy 374.270778 -178.939952)
			(xy 374.271259 -178.912277) (xy 374.279258 -178.857507) (xy 374.295095 -178.804471) (xy 374.318438 -178.754283)
			(xy 374.348794 -178.707999) (xy 374.36679 -178.686968) (xy 374.37314 -178.679856) (xy 374.379744 -178.662076)
			(xy 374.37822 -178.573938) (xy 374.370854 -178.556412) (xy 374.36425 -178.549554) (xy 374.344616 -178.528141)
			(xy 374.311423 -178.480464) (xy 374.285833 -178.428309) (xy 374.268437 -178.372881) (xy 374.259637 -178.315457)
			(xy 374.259094 -178.28641) (xy 373.112911 -178.28641) (xy 373.1236 -178.322813) (xy 373.131356 -178.376761)
			(xy 373.131842 -178.404012) (xy 373.131179 -178.435575) (xy 373.120794 -178.49784) (xy 373.100309 -178.557549)
			(xy 373.085868 -178.585622) (xy 373.081042 -178.594512) (xy 373.07901 -178.61407) (xy 373.10187 -178.692556)
			(xy 373.105071 -178.701996) (xy 373.117514 -178.717548) (xy 373.126 -178.722782) (xy 373.133366 -178.726846)
			(xy 373.143272 -178.732688) (xy 373.165116 -178.73472) (xy 373.259858 -178.701192) (xy 373.275606 -178.685698)
			(xy 373.27967 -178.675284) (xy 373.290366 -178.648508) (xy 373.318654 -178.598266) (xy 373.354184 -178.552857)
			(xy 373.396146 -178.513315) (xy 373.443583 -178.480541) (xy 373.495414 -178.455283) (xy 373.550457 -178.438117)
			(xy 373.607457 -178.429434) (xy 373.636286 -178.428904) (xy 373.66354 -178.429342) (xy 373.717495 -178.437098)
			(xy 373.769796 -178.452453) (xy 373.819379 -178.475095) (xy 373.865236 -178.504564) (xy 373.906431 -178.540259)
			(xy 373.942128 -178.581453) (xy 373.971598 -178.627308) (xy 373.994242 -178.676891) (xy 374.009599 -178.729192)
			(xy 374.017357 -178.783146) (xy 374.017357 -178.837654) (xy 374.009599 -178.891608) (xy 373.994242 -178.943909)
			(xy 373.971598 -178.993492) (xy 373.942128 -179.039347) (xy 373.906431 -179.080541) (xy 373.865236 -179.116236)
			(xy 373.819379 -179.145705) (xy 373.769796 -179.168347) (xy 373.717495 -179.183702) (xy 373.66354 -179.191458)
			(xy 373.636286 -179.19192) (xy 373.636032 -179.19192) (xy 373.610829 -179.191512) (xy 373.560861 -179.184876)
			(xy 373.512206 -179.171702) (xy 373.465716 -179.152221) (xy 373.443754 -179.13985) (xy 373.433848 -179.134008)
			(xy 373.412004 -179.131976) (xy 373.317262 -179.165504) (xy 373.301514 -179.180998) (xy 373.29745 -179.191412)
			(xy 373.286735 -179.21818) (xy 373.25845 -179.268421) (xy 373.222922 -179.31383) (xy 373.180963 -179.353373)
			(xy 373.133528 -179.386147) (xy 373.0817 -179.411407) (xy 373.02666 -179.428575) (xy 372.969662 -179.437261)
			(xy 372.940834 -179.437792) (xy 372.913581 -179.437313) (xy 372.85963 -179.42956) (xy 372.807332 -179.414208)
			(xy 372.75775 -179.391568) (xy 372.711896 -179.362102) (xy 372.670703 -179.32641) (xy 372.635009 -179.285218)
			(xy 372.605541 -179.239365) (xy 372.582899 -179.189785) (xy 372.567544 -179.137488) (xy 372.559788 -179.083537)
			(xy 372.559326 -179.056284) (xy 372.559992 -179.024721) (xy 372.570376 -178.962456) (xy 372.590859 -178.902747)
			(xy 372.6053 -178.874674) (xy 372.610126 -178.865784) (xy 372.612158 -178.846226) (xy 372.589298 -178.76774)
			(xy 372.586074 -178.75831) (xy 372.573646 -178.742755) (xy 372.565168 -178.737514) (xy 372.540061 -178.722975)
			(xy 372.494175 -178.687473) (xy 372.454197 -178.645429) (xy 372.421051 -178.597814) (xy 372.395502 -178.545726)
			(xy 372.378138 -178.490369) (xy 372.369362 -178.43302) (xy 372.368826 -178.404012) (xy 371.668548 -178.404012)
			(xy 371.668548 -179.477416) (xy 371.668952 -179.487488) (xy 371.676686 -179.506086) (xy 371.683534 -179.513484)
			(xy 372.027553 -179.8574) (xy 375.01779 -179.8574) (xy 375.021861 -179.801778) (xy 375.033987 -179.747341)
			(xy 375.05391 -179.69525) (xy 375.081206 -179.646615) (xy 375.115292 -179.602472) (xy 375.155441 -179.563763)
			(xy 375.200799 -179.531312) (xy 375.250399 -179.505811) (xy 375.303183 -179.487804) (xy 375.358026 -179.477674)
			(xy 375.41376 -179.475637) (xy 375.469197 -179.481737) (xy 375.523154 -179.495843) (xy 375.574483 -179.517655)
			(xy 375.622089 -179.546709) (xy 375.664957 -179.582384) (xy 375.702174 -179.623921) (xy 375.732947 -179.670434)
			(xy 375.756619 -179.720931) (xy 375.772687 -179.774338) (xy 375.780807 -179.829514) (xy 375.781316 -179.8574)
			(xy 375.780807 -179.885286) (xy 375.772687 -179.940462) (xy 375.756619 -179.993869) (xy 375.732947 -180.044366)
			(xy 375.702174 -180.090879) (xy 375.664957 -180.132416) (xy 375.622089 -180.168091) (xy 375.574483 -180.197145)
			(xy 375.523154 -180.218957) (xy 375.469197 -180.233063) (xy 375.41376 -180.239163) (xy 375.358026 -180.237126)
			(xy 375.303183 -180.226996) (xy 375.250399 -180.208989) (xy 375.200799 -180.183488) (xy 375.155441 -180.151037)
			(xy 375.115292 -180.112328) (xy 375.081206 -180.068185) (xy 375.05391 -180.01955) (xy 375.033987 -179.967459)
			(xy 375.021861 -179.913022) (xy 375.01779 -179.8574) (xy 372.027553 -179.8574) (xy 372.533418 -180.363114)
			(xy 372.540259 -180.370513) (xy 372.547977 -180.389113) (xy 372.548404 -180.399182) (xy 372.548404 -181.73446)
			(xy 375.976642 -181.73446) (xy 375.977123 -181.706549) (xy 375.985262 -181.651323) (xy 376.001361 -181.597873)
			(xy 376.025076 -181.547338) (xy 376.055901 -181.500798) (xy 376.074178 -181.479698) (xy 376.080073 -181.472519)
			(xy 376.086726 -181.455195) (xy 376.087132 -181.445916) (xy 376.087132 -181.368192) (xy 376.080528 -181.35092)
			(xy 376.074178 -181.343808) (xy 376.055879 -181.322726) (xy 376.025055 -181.276182) (xy 376.001344 -181.225643)
			(xy 375.985253 -181.172188) (xy 375.977124 -181.116958) (xy 375.976642 -181.089046) (xy 375.977128 -181.061795)
			(xy 375.984884 -181.007847) (xy 376.000239 -180.955552) (xy 376.022881 -180.905975) (xy 376.052347 -180.860125)
			(xy 376.088038 -180.818934) (xy 376.129229 -180.783243) (xy 376.175079 -180.753777) (xy 376.224656 -180.731135)
			(xy 376.276951 -180.71578) (xy 376.330899 -180.708024) (xy 376.385401 -180.708024) (xy 376.439349 -180.71578)
			(xy 376.491644 -180.731135) (xy 376.541221 -180.753777) (xy 376.587071 -180.783243) (xy 376.628262 -180.818934)
			(xy 376.663953 -180.860125) (xy 376.693419 -180.905975) (xy 376.716061 -180.955552) (xy 376.731416 -181.007847)
			(xy 376.739172 -181.061795) (xy 376.739658 -181.089046) (xy 376.739181 -181.116957) (xy 376.731041 -181.172183)
			(xy 376.714941 -181.225634) (xy 376.691225 -181.276168) (xy 376.660399 -181.322708) (xy 376.642122 -181.343808)
			(xy 376.636225 -181.350985) (xy 376.629573 -181.36831) (xy 376.629168 -181.37759) (xy 376.629168 -181.455314)
			(xy 376.635772 -181.472586) (xy 376.642122 -181.479698) (xy 376.660377 -181.500817) (xy 376.691207 -181.54735)
			(xy 376.714926 -181.59788) (xy 376.731028 -181.651327) (xy 376.739169 -181.70655) (xy 376.739658 -181.73446)
			(xy 376.739172 -181.761711) (xy 376.731416 -181.815659) (xy 376.716061 -181.867954) (xy 376.693419 -181.917531)
			(xy 376.663953 -181.963381) (xy 376.628262 -182.004572) (xy 376.587071 -182.040263) (xy 376.541221 -182.069729)
			(xy 376.491644 -182.092371) (xy 376.439349 -182.107726) (xy 376.385401 -182.115482) (xy 376.330899 -182.115482)
			(xy 376.276951 -182.107726) (xy 376.224656 -182.092371) (xy 376.175079 -182.069729) (xy 376.129229 -182.040263)
			(xy 376.088038 -182.004572) (xy 376.052347 -181.963381) (xy 376.022881 -181.917531) (xy 376.000239 -181.867954)
			(xy 375.984884 -181.815659) (xy 375.977128 -181.761711) (xy 375.976642 -181.73446) (xy 372.548404 -181.73446)
			(xy 372.548404 -182.667656) (xy 372.547945 -182.677674) (xy 372.54029 -182.696189) (xy 372.526129 -182.710363)
			(xy 372.507622 -182.718035) (xy 372.497604 -182.718456) (xy 370.821204 -182.718456) (xy 370.821204 -182.724044)
			(xy 368.764566 -182.724044) (xy 368.754493 -182.723651) (xy 368.735894 -182.715909) (xy 368.728498 -182.709058)
			(xy 368.330226 -182.310786) (xy 368.323391 -182.303382) (xy 368.315668 -182.284786) (xy 368.31524 -182.274718)
			(xy 368.31524 -177.583592) (xy 368.315651 -177.573521) (xy 368.32338 -177.554923) (xy 368.330226 -177.547524)
			(xy 368.759486 -177.11801) (xy 368.766312 -177.110599) (xy 368.774041 -177.092008) (xy 368.774472 -177.081942)
			(xy 368.774472 -175.647858) (xy 368.774076 -175.637785) (xy 368.766336 -175.619187) (xy 368.759486 -175.61179)
			(xy 368.330226 -175.182276) (xy 368.323387 -175.174875) (xy 368.315666 -175.156277) (xy 368.31524 -175.146208)
			(xy 368.31524 -172.414438) (xy 368.314811 -172.404369) (xy 368.307094 -172.38577) (xy 368.300254 -172.37837)
			(xy 367.327434 -171.40555) (xy 367.32001 -171.398739) (xy 367.301429 -171.391001) (xy 367.291366 -171.390564)
			(xy 364.666022 -171.390564) (xy 364.655952 -171.390984) (xy 364.637353 -171.398707) (xy 364.629954 -171.40555)
			(xy 363.304074 -172.731684) (xy 363.297245 -172.739092) (xy 363.289519 -172.757685) (xy 363.289088 -172.767752)
			(xy 363.289088 -173.431454) (xy 364.007654 -173.431454) (xy 364.00814 -173.404203) (xy 364.015896 -173.350255)
			(xy 364.031251 -173.29796) (xy 364.053893 -173.248383) (xy 364.083359 -173.202533) (xy 364.11905 -173.161342)
			(xy 364.160241 -173.125651) (xy 364.206091 -173.096185) (xy 364.255668 -173.073543) (xy 364.307963 -173.058188)
			(xy 364.361911 -173.050432) (xy 364.416413 -173.050432) (xy 364.470361 -173.058188) (xy 364.522656 -173.073543)
			(xy 364.572233 -173.096185) (xy 364.618083 -173.125651) (xy 364.659274 -173.161342) (xy 364.694965 -173.202533)
			(xy 364.724431 -173.248383) (xy 364.747073 -173.29796) (xy 364.751739 -173.313852) (xy 365.897922 -173.313852)
			(xy 365.898408 -173.286601) (xy 365.906164 -173.232653) (xy 365.921519 -173.180358) (xy 365.944161 -173.130781)
			(xy 365.973627 -173.084931) (xy 366.009318 -173.04374) (xy 366.050509 -173.008049) (xy 366.096359 -172.978583)
			(xy 366.145936 -172.955941) (xy 366.198231 -172.940586) (xy 366.252179 -172.93283) (xy 366.306681 -172.93283)
			(xy 366.360629 -172.940586) (xy 366.412924 -172.955941) (xy 366.462501 -172.978583) (xy 366.508351 -173.008049)
			(xy 366.549542 -173.04374) (xy 366.585233 -173.084931) (xy 366.614699 -173.130781) (xy 366.637341 -173.180358)
			(xy 366.652696 -173.232653) (xy 366.660452 -173.286601) (xy 366.660938 -173.313852) (xy 366.66048 -173.340646)
			(xy 366.65298 -173.393706) (xy 366.638135 -173.445197) (xy 366.616237 -173.494106) (xy 366.587715 -173.539473)
			(xy 366.570768 -173.560232) (xy 366.564672 -173.567344) (xy 366.55883 -173.584362) (xy 366.5601 -173.660816)
			(xy 366.560627 -173.669989) (xy 366.567403 -173.687051) (xy 366.573308 -173.69409) (xy 366.591915 -173.715263)
			(xy 366.623297 -173.762086) (xy 366.647447 -173.813016) (xy 366.663841 -173.866946) (xy 366.672122 -173.922701)
			(xy 366.672622 -173.950884) (xy 366.672136 -173.978135) (xy 366.670503 -173.989492) (xy 367.235738 -173.989492)
			(xy 367.239809 -173.93387) (xy 367.251935 -173.879433) (xy 367.271858 -173.827342) (xy 367.299154 -173.778707)
			(xy 367.33324 -173.734564) (xy 367.373389 -173.695855) (xy 367.418747 -173.663404) (xy 367.468347 -173.637903)
			(xy 367.521131 -173.619896) (xy 367.575974 -173.609766) (xy 367.631708 -173.607729) (xy 367.687145 -173.613829)
			(xy 367.741102 -173.627935) (xy 367.792431 -173.649747) (xy 367.840037 -173.678801) (xy 367.882905 -173.714476)
			(xy 367.920122 -173.756013) (xy 367.950895 -173.802526) (xy 367.974567 -173.853023) (xy 367.990635 -173.90643)
			(xy 367.998755 -173.961606) (xy 367.999264 -173.989492) (xy 367.998755 -174.017378) (xy 367.990635 -174.072554)
			(xy 367.974567 -174.125961) (xy 367.950895 -174.176458) (xy 367.920122 -174.222971) (xy 367.882905 -174.264508)
			(xy 367.840037 -174.300183) (xy 367.792431 -174.329237) (xy 367.741102 -174.351049) (xy 367.687145 -174.365155)
			(xy 367.631708 -174.371255) (xy 367.575974 -174.369218) (xy 367.521131 -174.359088) (xy 367.468347 -174.341081)
			(xy 367.418747 -174.31558) (xy 367.373389 -174.283129) (xy 367.33324 -174.24442) (xy 367.299154 -174.200277)
			(xy 367.271858 -174.151642) (xy 367.251935 -174.099551) (xy 367.239809 -174.045114) (xy 367.235738 -173.989492)
			(xy 366.670503 -173.989492) (xy 366.66438 -174.032083) (xy 366.649025 -174.084378) (xy 366.626383 -174.133955)
			(xy 366.596917 -174.179805) (xy 366.561226 -174.220996) (xy 366.520035 -174.256687) (xy 366.474185 -174.286153)
			(xy 366.424608 -174.308795) (xy 366.372313 -174.32415) (xy 366.318365 -174.331906) (xy 366.263863 -174.331906)
			(xy 366.209915 -174.32415) (xy 366.15762 -174.308795) (xy 366.108043 -174.286153) (xy 366.062193 -174.256687)
			(xy 366.021002 -174.220996) (xy 365.985311 -174.179805) (xy 365.955845 -174.133955) (xy 365.933203 -174.084378)
			(xy 365.917848 -174.032083) (xy 365.910092 -173.978135) (xy 365.909606 -173.950884) (xy 365.91004 -173.924089)
			(xy 365.917547 -173.871028) (xy 365.932399 -173.819538) (xy 365.954302 -173.770629) (xy 365.982828 -173.725262)
			(xy 365.999776 -173.704504) (xy 366.005872 -173.697392) (xy 366.011714 -173.680374) (xy 366.010444 -173.60392)
			(xy 366.00989 -173.594751) (xy 366.003132 -173.577688) (xy 365.997236 -173.570646) (xy 365.978637 -173.549467)
			(xy 365.947256 -173.502644) (xy 365.923105 -173.451715) (xy 365.906709 -173.397788) (xy 365.898424 -173.342035)
			(xy 365.897922 -173.313852) (xy 364.751739 -173.313852) (xy 364.762428 -173.350255) (xy 364.770184 -173.404203)
			(xy 364.77067 -173.431454) (xy 364.77002 -173.463017) (xy 364.759629 -173.525283) (xy 364.73914 -173.584992)
			(xy 364.724696 -173.613064) (xy 364.71987 -173.621954) (xy 364.717838 -173.641512) (xy 364.740698 -173.719998)
			(xy 364.743948 -173.729418) (xy 364.756357 -173.744979) (xy 364.764828 -173.750224) (xy 364.772194 -173.754288)
			(xy 364.7821 -173.76013) (xy 364.803944 -173.762162) (xy 364.898686 -173.728634) (xy 364.914434 -173.71314)
			(xy 364.918498 -173.702726) (xy 364.929193 -173.675949) (xy 364.957479 -173.625705) (xy 364.993008 -173.580294)
			(xy 365.034969 -173.54075) (xy 365.082407 -173.507976) (xy 365.134239 -173.482718) (xy 365.189283 -173.465554)
			(xy 365.246285 -173.456874) (xy 365.275114 -173.456346) (xy 365.302361 -173.456925) (xy 365.356301 -173.464682)
			(xy 365.408588 -173.480037) (xy 365.458157 -173.502676) (xy 365.504 -173.532139) (xy 365.545184 -173.567826)
			(xy 365.580869 -173.609011) (xy 365.610331 -173.654855) (xy 365.632968 -173.704425) (xy 365.648321 -173.756713)
			(xy 365.656076 -173.810653) (xy 365.656076 -173.865147) (xy 365.648321 -173.919087) (xy 365.632968 -173.971375)
			(xy 365.610331 -174.020945) (xy 365.580869 -174.066789) (xy 365.545184 -174.107974) (xy 365.504 -174.143661)
			(xy 365.458157 -174.173124) (xy 365.408588 -174.195763) (xy 365.356301 -174.211118) (xy 365.302361 -174.218875)
			(xy 365.275114 -174.219362) (xy 365.27486 -174.219362) (xy 365.249656 -174.21898) (xy 365.199687 -174.212335)
			(xy 365.151033 -174.199153) (xy 365.104543 -174.179666) (xy 365.082582 -174.167292) (xy 365.072676 -174.16145)
			(xy 365.050832 -174.159418) (xy 364.95609 -174.192946) (xy 364.940342 -174.20844) (xy 364.936278 -174.218854)
			(xy 364.925562 -174.245622) (xy 364.897274 -174.29586) (xy 364.861745 -174.341267) (xy 364.819786 -174.380808)
			(xy 364.772352 -174.413582) (xy 364.720525 -174.438842) (xy 364.665486 -174.456012) (xy 364.608489 -174.464701)
			(xy 364.579662 -174.465234) (xy 364.552411 -174.464758) (xy 364.498464 -174.456997) (xy 364.446171 -174.441638)
			(xy 364.396595 -174.418994) (xy 364.350746 -174.389526) (xy 364.309557 -174.353834) (xy 364.273866 -174.312644)
			(xy 364.2444 -174.266794) (xy 364.221758 -174.217218) (xy 364.206401 -174.164924) (xy 364.198642 -174.110977)
			(xy 364.198154 -174.083726) (xy 364.198793 -174.052162) (xy 364.209188 -173.989896) (xy 364.229682 -173.930188)
			(xy 364.244128 -173.902116) (xy 364.248954 -173.893226) (xy 364.250986 -173.873668) (xy 364.228126 -173.795182)
			(xy 364.224912 -173.785747) (xy 364.212478 -173.770193) (xy 364.203996 -173.764956) (xy 364.17889 -173.750415)
			(xy 364.133008 -173.71491) (xy 364.093034 -173.672865) (xy 364.059889 -173.62525) (xy 364.034339 -173.573164)
			(xy 364.016973 -173.517809) (xy 364.008193 -173.460462) (xy 364.007654 -173.431454) (xy 363.289088 -173.431454)
			(xy 363.289088 -174.49038) (xy 363.2895 -174.500451) (xy 363.297228 -174.51905) (xy 363.304074 -174.526448)
			(xy 363.662468 -174.884842) (xy 366.656618 -174.884842) (xy 366.660689 -174.82922) (xy 366.672815 -174.774783)
			(xy 366.692738 -174.722692) (xy 366.720034 -174.674057) (xy 366.75412 -174.629914) (xy 366.794269 -174.591205)
			(xy 366.839627 -174.558754) (xy 366.889227 -174.533253) (xy 366.942011 -174.515246) (xy 366.996854 -174.505116)
			(xy 367.052588 -174.503079) (xy 367.108025 -174.509179) (xy 367.161982 -174.523285) (xy 367.213311 -174.545097)
			(xy 367.260917 -174.574151) (xy 367.303785 -174.609826) (xy 367.341002 -174.651363) (xy 367.371775 -174.697876)
			(xy 367.395447 -174.748373) (xy 367.411515 -174.80178) (xy 367.419635 -174.856956) (xy 367.420144 -174.884842)
			(xy 367.419635 -174.912728) (xy 367.411515 -174.967904) (xy 367.395447 -175.021311) (xy 367.371775 -175.071808)
			(xy 367.341002 -175.118321) (xy 367.303785 -175.159858) (xy 367.260917 -175.195533) (xy 367.213311 -175.224587)
			(xy 367.161982 -175.246399) (xy 367.108025 -175.260505) (xy 367.052588 -175.266605) (xy 366.996854 -175.264568)
			(xy 366.942011 -175.254438) (xy 366.889227 -175.236431) (xy 366.839627 -175.21093) (xy 366.794269 -175.178479)
			(xy 366.75412 -175.13977) (xy 366.720034 -175.095627) (xy 366.692738 -175.046992) (xy 366.672815 -174.994901)
			(xy 366.660689 -174.940464) (xy 366.656618 -174.884842) (xy 363.662468 -174.884842) (xy 364.019084 -175.241458)
			(xy 364.0265 -175.248278) (xy 364.045087 -175.256011) (xy 364.055152 -175.256444) (xy 364.136432 -175.256444)
			(xy 364.146461 -175.256794) (xy 364.164987 -175.264483) (xy 364.17916 -175.278677) (xy 364.186821 -175.297215)
			(xy 364.187232 -175.307244) (xy 364.187232 -176.761902) (xy 367.61547 -176.761902) (xy 367.615969 -176.733991)
			(xy 367.624103 -176.678766) (xy 367.640197 -176.625316) (xy 367.663908 -176.574781) (xy 367.69473 -176.528241)
			(xy 367.713006 -176.50714) (xy 367.718929 -176.499982) (xy 367.725565 -176.482642) (xy 367.72596 -176.473358)
			(xy 367.72596 -176.395634) (xy 367.719356 -176.378362) (xy 367.713006 -176.37125) (xy 367.694731 -176.350148)
			(xy 367.663903 -176.30361) (xy 367.640187 -176.253076) (xy 367.62409 -176.199625) (xy 367.615955 -176.144399)
			(xy 367.61547 -176.116488) (xy 367.615956 -176.089237) (xy 367.623712 -176.035289) (xy 367.639067 -175.982994)
			(xy 367.661709 -175.933417) (xy 367.691175 -175.887567) (xy 367.726866 -175.846376) (xy 367.768057 -175.810685)
			(xy 367.813907 -175.781219) (xy 367.863484 -175.758577) (xy 367.915779 -175.743222) (xy 367.969727 -175.735466)
			(xy 368.024229 -175.735466) (xy 368.078177 -175.743222) (xy 368.130472 -175.758577) (xy 368.180049 -175.781219)
			(xy 368.225899 -175.810685) (xy 368.26709 -175.846376) (xy 368.302781 -175.887567) (xy 368.332247 -175.933417)
			(xy 368.354889 -175.982994) (xy 368.370244 -176.035289) (xy 368.378 -176.089237) (xy 368.378486 -176.116488)
			(xy 368.377967 -176.144398) (xy 368.369836 -176.199621) (xy 368.353746 -176.253071) (xy 368.330039 -176.303606)
			(xy 368.299223 -176.350148) (xy 368.28095 -176.37125) (xy 368.275026 -176.378407) (xy 368.268393 -176.395748)
			(xy 368.267996 -176.405032) (xy 368.267996 -176.482756) (xy 368.2746 -176.500028) (xy 368.28095 -176.50714)
			(xy 368.299229 -176.528239) (xy 368.330055 -176.574778) (xy 368.353769 -176.625313) (xy 368.369865 -176.678764)
			(xy 368.378 -176.733991) (xy 368.378486 -176.761902) (xy 368.378 -176.789153) (xy 368.370244 -176.843101)
			(xy 368.354889 -176.895396) (xy 368.332247 -176.944973) (xy 368.302781 -176.990823) (xy 368.26709 -177.032014)
			(xy 368.225899 -177.067705) (xy 368.180049 -177.097171) (xy 368.130472 -177.119813) (xy 368.078177 -177.135168)
			(xy 368.024229 -177.142924) (xy 367.969727 -177.142924) (xy 367.915779 -177.135168) (xy 367.863484 -177.119813)
			(xy 367.813907 -177.097171) (xy 367.768057 -177.067705) (xy 367.726866 -177.032014) (xy 367.691175 -176.990823)
			(xy 367.661709 -176.944973) (xy 367.639067 -176.895396) (xy 367.623712 -176.843101) (xy 367.615956 -176.789153)
			(xy 367.61547 -176.761902) (xy 364.187232 -176.761902) (xy 364.187232 -177.695352) (xy 364.186742 -177.705366)
			(xy 364.179094 -177.723876) (xy 364.164943 -177.738049) (xy 364.146446 -177.745726) (xy 364.136432 -177.746152)
			(xy 362.475526 -177.746152) (xy 362.430314 -177.791364) (xy 360.45775 -177.791364) (xy 360.447682 -177.790922)
			(xy 360.429084 -177.783214) (xy 360.421682 -177.776378) (xy 360.12501 -177.479706) (xy 360.118181 -177.472297)
			(xy 360.110455 -177.453705) (xy 360.110024 -177.443638) (xy 360.110024 -169.313352) (xy 360.11047 -169.303285)
			(xy 360.118176 -169.284687) (xy 360.12501 -169.277284) (xy 360.613706 -168.788334) (xy 360.620524 -168.780917)
			(xy 360.628257 -168.762331) (xy 360.628692 -168.752266) (xy 360.628692 -167.462454) (xy 360.62824 -167.452388)
			(xy 360.620538 -167.43379) (xy 360.613706 -167.426386) (xy 360.12501 -166.937436) (xy 360.118195 -166.930016)
			(xy 360.11046 -166.911432) (xy 360.110024 -166.901368) (xy 360.110024 -164.323522) (xy 360.109607 -164.313451)
			(xy 360.101883 -164.294852) (xy 360.095038 -164.287454) (xy 358.760776 -162.953446) (xy 358.753373 -162.946609)
			(xy 358.734776 -162.938886) (xy 358.724708 -162.93846) (xy 356.077012 -162.93846) (xy 356.066941 -162.938876)
			(xy 356.048343 -162.946602) (xy 356.040944 -162.953446) (xy 355.013006 -163.98113) (xy 355.006161 -163.988526)
			(xy 354.998444 -164.007128) (xy 354.99802 -164.017198) (xy 354.99802 -165.156134) (xy 355.727254 -165.156134)
			(xy 355.72774 -165.128883) (xy 355.735496 -165.074935) (xy 355.750851 -165.02264) (xy 355.773493 -164.973063)
			(xy 355.802959 -164.927213) (xy 355.83865 -164.886022) (xy 355.879841 -164.850331) (xy 355.925691 -164.820865)
			(xy 355.975268 -164.798223) (xy 356.027563 -164.782868) (xy 356.081511 -164.775112) (xy 356.136013 -164.775112)
			(xy 356.189961 -164.782868) (xy 356.242256 -164.798223) (xy 356.291833 -164.820865) (xy 356.337683 -164.850331)
			(xy 356.378874 -164.886022) (xy 356.414565 -164.927213) (xy 356.444031 -164.973063) (xy 356.466673 -165.02264)
			(xy 356.482028 -165.074935) (xy 356.489784 -165.128883) (xy 356.49027 -165.156134) (xy 356.489612 -165.187697)
			(xy 356.479225 -165.249962) (xy 356.458738 -165.309671) (xy 356.444296 -165.337744) (xy 356.43947 -165.346634)
			(xy 356.437438 -165.366192) (xy 356.460298 -165.444678) (xy 356.463556 -165.454094) (xy 356.475959 -165.469657)
			(xy 356.484428 -165.474904) (xy 356.491794 -165.478968) (xy 356.5017 -165.48481) (xy 356.523544 -165.486842)
			(xy 356.618286 -165.453314) (xy 356.634034 -165.43782) (xy 356.638098 -165.427406) (xy 356.648782 -165.400624)
			(xy 356.677071 -165.350381) (xy 356.712601 -165.304971) (xy 356.754565 -165.265428) (xy 356.802004 -165.232654)
			(xy 356.853837 -165.207398) (xy 356.908882 -165.190234) (xy 356.965884 -165.181554) (xy 356.994714 -165.181026)
			(xy 357.021967 -165.181445) (xy 357.075918 -165.189204) (xy 357.128216 -165.204561) (xy 357.177796 -165.227205)
			(xy 357.223648 -165.256675) (xy 357.264841 -165.292369) (xy 357.300534 -165.333563) (xy 357.330001 -165.379417)
			(xy 357.352644 -165.428997) (xy 357.367999 -165.481296) (xy 357.375756 -165.535247) (xy 357.375756 -165.589753)
			(xy 357.367999 -165.643704) (xy 357.358645 -165.675564) (xy 357.617522 -165.675564) (xy 357.617982 -165.648088)
			(xy 357.625879 -165.593707) (xy 357.641505 -165.541025) (xy 357.664536 -165.491132) (xy 357.694494 -165.445065)
			(xy 357.712264 -165.424104) (xy 357.712518 -165.42385) (xy 357.718092 -165.416755) (xy 357.724346 -165.399845)
			(xy 357.72471 -165.39083) (xy 357.72471 -165.323266) (xy 357.724367 -165.314248) (xy 357.71811 -165.297331)
			(xy 357.712518 -165.290246) (xy 357.71201 -165.289738) (xy 357.6943 -165.268773) (xy 357.664414 -165.222745)
			(xy 357.641443 -165.172905) (xy 357.625863 -165.120284) (xy 357.617996 -165.065972) (xy 357.617522 -165.038532)
			(xy 357.618008 -165.011281) (xy 357.625764 -164.957333) (xy 357.641119 -164.905038) (xy 357.663761 -164.855461)
			(xy 357.693227 -164.809611) (xy 357.728918 -164.76842) (xy 357.770109 -164.732729) (xy 357.815959 -164.703263)
			(xy 357.865536 -164.680621) (xy 357.917831 -164.665266) (xy 357.971779 -164.65751) (xy 358.026281 -164.65751)
			(xy 358.080229 -164.665266) (xy 358.132524 -164.680621) (xy 358.182101 -164.703263) (xy 358.227951 -164.732729)
			(xy 358.269142 -164.76842) (xy 358.304833 -164.809611) (xy 358.334299 -164.855461) (xy 358.356941 -164.905038)
			(xy 358.372296 -164.957333) (xy 358.380052 -165.011281) (xy 358.380538 -165.038532) (xy 358.380062 -165.066007)
			(xy 358.372166 -165.120387) (xy 358.356543 -165.173069) (xy 358.333517 -165.222961) (xy 358.303564 -165.26903)
			(xy 358.285796 -165.289992) (xy 358.285542 -165.290246) (xy 358.279965 -165.297339) (xy 358.273714 -165.314251)
			(xy 358.27335 -165.323266) (xy 358.27335 -165.39083) (xy 358.273682 -165.39985) (xy 358.279946 -165.416767)
			(xy 358.285542 -165.42385) (xy 358.28605 -165.424358) (xy 358.303799 -165.445292) (xy 358.333681 -165.491327)
			(xy 358.356645 -165.541175) (xy 358.372216 -165.593804) (xy 358.380071 -165.648122) (xy 358.380538 -165.675564)
			(xy 358.380052 -165.702815) (xy 358.372296 -165.756763) (xy 358.356941 -165.809058) (xy 358.334299 -165.858635)
			(xy 358.330831 -165.864032) (xy 358.955338 -165.864032) (xy 358.959409 -165.80841) (xy 358.971535 -165.753973)
			(xy 358.991458 -165.701882) (xy 359.018754 -165.653247) (xy 359.05284 -165.609104) (xy 359.092989 -165.570395)
			(xy 359.138347 -165.537944) (xy 359.187947 -165.512443) (xy 359.240731 -165.494436) (xy 359.295574 -165.484306)
			(xy 359.351308 -165.482269) (xy 359.406745 -165.488369) (xy 359.460702 -165.502475) (xy 359.512031 -165.524287)
			(xy 359.559637 -165.553341) (xy 359.602505 -165.589016) (xy 359.639722 -165.630553) (xy 359.670495 -165.677066)
			(xy 359.694167 -165.727563) (xy 359.710235 -165.78097) (xy 359.718355 -165.836146) (xy 359.718864 -165.864032)
			(xy 359.718355 -165.891918) (xy 359.710235 -165.947094) (xy 359.694167 -166.000501) (xy 359.670495 -166.050998)
			(xy 359.639722 -166.097511) (xy 359.602505 -166.139048) (xy 359.559637 -166.174723) (xy 359.512031 -166.203777)
			(xy 359.460702 -166.225589) (xy 359.406745 -166.239695) (xy 359.351308 -166.245795) (xy 359.295574 -166.243758)
			(xy 359.240731 -166.233628) (xy 359.187947 -166.215621) (xy 359.138347 -166.19012) (xy 359.092989 -166.157669)
			(xy 359.05284 -166.11896) (xy 359.018754 -166.074817) (xy 358.991458 -166.026182) (xy 358.971535 -165.974091)
			(xy 358.959409 -165.919654) (xy 358.955338 -165.864032) (xy 358.330831 -165.864032) (xy 358.304833 -165.904485)
			(xy 358.269142 -165.945676) (xy 358.227951 -165.981367) (xy 358.182101 -166.010833) (xy 358.132524 -166.033475)
			(xy 358.080229 -166.04883) (xy 358.026281 -166.056586) (xy 357.971779 -166.056586) (xy 357.917831 -166.04883)
			(xy 357.865536 -166.033475) (xy 357.815959 -166.010833) (xy 357.770109 -165.981367) (xy 357.728918 -165.945676)
			(xy 357.693227 -165.904485) (xy 357.663761 -165.858635) (xy 357.641119 -165.809058) (xy 357.625764 -165.756763)
			(xy 357.618008 -165.702815) (xy 357.617522 -165.675564) (xy 357.358645 -165.675564) (xy 357.352644 -165.696003)
			(xy 357.330001 -165.745583) (xy 357.300534 -165.791437) (xy 357.264841 -165.832631) (xy 357.223648 -165.868325)
			(xy 357.177796 -165.897795) (xy 357.128216 -165.920439) (xy 357.075918 -165.935796) (xy 357.021967 -165.943555)
			(xy 356.994714 -165.944042) (xy 356.99446 -165.944042) (xy 356.969256 -165.943663) (xy 356.919287 -165.937017)
			(xy 356.870632 -165.923835) (xy 356.824143 -165.904346) (xy 356.802182 -165.891972) (xy 356.792276 -165.88613)
			(xy 356.770432 -165.884098) (xy 356.67569 -165.917626) (xy 356.659942 -165.93312) (xy 356.655878 -165.943534)
			(xy 356.645152 -165.970297) (xy 356.616866 -166.020536) (xy 356.581339 -166.065944) (xy 356.539382 -166.105486)
			(xy 356.491949 -166.138261) (xy 356.440123 -166.163521) (xy 356.385085 -166.180692) (xy 356.328089 -166.189381)
			(xy 356.299262 -166.189914) (xy 356.27201 -166.189458) (xy 356.218062 -166.181696) (xy 356.165767 -166.166336)
			(xy 356.11619 -166.143691) (xy 356.07034 -166.114222) (xy 356.02915 -166.078527) (xy 355.993459 -166.037335)
			(xy 355.963993 -165.991482) (xy 355.941352 -165.941903) (xy 355.925997 -165.889607) (xy 355.91824 -165.835658)
			(xy 355.917754 -165.808406) (xy 355.918386 -165.776842) (xy 355.928784 -165.714576) (xy 355.949281 -165.654867)
			(xy 355.963728 -165.626796) (xy 355.968554 -165.617906) (xy 355.970586 -165.598348) (xy 355.947726 -165.519862)
			(xy 355.94452 -165.510424) (xy 355.93208 -165.494871) (xy 355.923596 -165.489636) (xy 355.898482 -165.475109)
			(xy 355.8526 -165.439602) (xy 355.812625 -165.397554) (xy 355.779482 -165.349937) (xy 355.753933 -165.297849)
			(xy 355.736569 -165.242491) (xy 355.727791 -165.185142) (xy 355.727254 -165.156134) (xy 354.99802 -165.156134)
			(xy 354.99802 -166.200582) (xy 354.99845 -166.210651) (xy 355.006167 -166.229249) (xy 355.013006 -166.23665)
			(xy 355.385986 -166.609522) (xy 358.376218 -166.609522) (xy 358.380289 -166.5539) (xy 358.392415 -166.499463)
			(xy 358.412338 -166.447372) (xy 358.439634 -166.398737) (xy 358.47372 -166.354594) (xy 358.513869 -166.315885)
			(xy 358.559227 -166.283434) (xy 358.608827 -166.257933) (xy 358.661611 -166.239926) (xy 358.716454 -166.229796)
			(xy 358.772188 -166.227759) (xy 358.827625 -166.233859) (xy 358.881582 -166.247965) (xy 358.932911 -166.269777)
			(xy 358.980517 -166.298831) (xy 359.023385 -166.334506) (xy 359.060602 -166.376043) (xy 359.091375 -166.422556)
			(xy 359.115047 -166.473053) (xy 359.131115 -166.52646) (xy 359.139235 -166.581636) (xy 359.139744 -166.609522)
			(xy 359.139235 -166.637408) (xy 359.131115 -166.692584) (xy 359.115047 -166.745991) (xy 359.091375 -166.796488)
			(xy 359.060602 -166.843001) (xy 359.023385 -166.884538) (xy 358.980517 -166.920213) (xy 358.932911 -166.949267)
			(xy 358.881582 -166.971079) (xy 358.827625 -166.985185) (xy 358.772188 -166.991285) (xy 358.716454 -166.989248)
			(xy 358.661611 -166.979118) (xy 358.608827 -166.961111) (xy 358.559227 -166.93561) (xy 358.513869 -166.903159)
			(xy 358.47372 -166.86445) (xy 358.439634 -166.820307) (xy 358.412338 -166.771672) (xy 358.392415 -166.719581)
			(xy 358.380289 -166.665144) (xy 358.376218 -166.609522) (xy 355.385986 -166.609522) (xy 355.891846 -167.115236)
			(xy 355.898701 -167.122624) (xy 355.90641 -167.141233) (xy 355.906832 -167.151304) (xy 355.906832 -168.486582)
			(xy 359.33507 -168.486582) (xy 359.335557 -168.458671) (xy 359.343694 -168.403445) (xy 359.359791 -168.349994)
			(xy 359.383505 -168.29946) (xy 359.414329 -168.25292) (xy 359.432606 -168.23182) (xy 359.438495 -168.224637)
			(xy 359.445151 -168.207316) (xy 359.44556 -168.198038) (xy 359.44556 -168.120314) (xy 359.438956 -168.103042)
			(xy 359.432606 -168.09593) (xy 359.414322 -168.074836) (xy 359.383495 -168.028296) (xy 359.359781 -167.97776)
			(xy 359.343686 -167.924307) (xy 359.335554 -167.86908) (xy 359.33507 -167.841168) (xy 359.335556 -167.813917)
			(xy 359.343312 -167.759969) (xy 359.358667 -167.707674) (xy 359.381309 -167.658097) (xy 359.410775 -167.612247)
			(xy 359.446466 -167.571056) (xy 359.487657 -167.535365) (xy 359.533507 -167.505899) (xy 359.583084 -167.483257)
			(xy 359.635379 -167.467902) (xy 359.689327 -167.460146) (xy 359.743829 -167.460146) (xy 359.797777 -167.467902)
			(xy 359.850072 -167.483257) (xy 359.899649 -167.505899) (xy 359.945499 -167.535365) (xy 359.98669 -167.571056)
			(xy 360.022381 -167.612247) (xy 360.051847 -167.658097) (xy 360.074489 -167.707674) (xy 360.089844 -167.759969)
			(xy 360.0976 -167.813917) (xy 360.098086 -167.841168) (xy 360.097615 -167.869079) (xy 360.089472 -167.924305)
			(xy 360.073371 -167.977756) (xy 360.049654 -168.02829) (xy 360.018827 -168.07483) (xy 360.00055 -168.09593)
			(xy 359.994634 -168.103094) (xy 359.987996 -168.120429) (xy 359.987596 -168.129712) (xy 359.987596 -168.207436)
			(xy 359.9942 -168.224708) (xy 360.00055 -168.23182) (xy 360.01882 -168.252926) (xy 360.049647 -168.299464)
			(xy 360.073363 -168.349997) (xy 360.089461 -168.403446) (xy 360.097599 -168.458671) (xy 360.098086 -168.486582)
			(xy 360.0976 -168.513833) (xy 360.089844 -168.567781) (xy 360.074489 -168.620076) (xy 360.051847 -168.669653)
			(xy 360.022381 -168.715503) (xy 359.98669 -168.756694) (xy 359.945499 -168.792385) (xy 359.899649 -168.821851)
			(xy 359.850072 -168.844493) (xy 359.797777 -168.859848) (xy 359.743829 -168.867604) (xy 359.689327 -168.867604)
			(xy 359.635379 -168.859848) (xy 359.583084 -168.844493) (xy 359.533507 -168.821851) (xy 359.487657 -168.792385)
			(xy 359.446466 -168.756694) (xy 359.410775 -168.715503) (xy 359.381309 -168.669653) (xy 359.358667 -168.620076)
			(xy 359.343312 -168.567781) (xy 359.335556 -168.513833) (xy 359.33507 -168.486582) (xy 355.906832 -168.486582)
			(xy 355.906832 -169.420032) (xy 355.906339 -169.430038) (xy 355.898675 -169.448524) (xy 355.884524 -169.462675)
			(xy 355.866038 -169.470339) (xy 355.856032 -169.470832) (xy 354.051616 -169.470832) (xy 354.041547 -169.471257)
			(xy 354.022948 -169.478977) (xy 354.015548 -169.485818) (xy 353.99472 -169.506646) (xy 353.987312 -169.513476)
			(xy 353.968719 -169.5212) (xy 353.958652 -169.521632) (xy 352.06813 -169.521632) (xy 352.05806 -169.521209)
			(xy 352.039461 -169.513489) (xy 352.032062 -169.506646) (xy 351.794826 -169.269156) (xy 351.787978 -169.261762)
			(xy 351.780262 -169.243158) (xy 351.77984 -169.233088) (xy 351.77984 -161.142172) (xy 351.78024 -161.1321)
			(xy 351.787977 -161.113502) (xy 351.794826 -161.106104) (xy 352.381566 -160.51911) (xy 352.388389 -160.511697)
			(xy 352.39612 -160.493108) (xy 352.396552 -160.483042) (xy 352.396552 -159.336232) (xy 352.396122 -159.326163)
			(xy 352.388406 -159.307564) (xy 352.381566 -159.300164) (xy 351.794826 -158.71317) (xy 351.787984 -158.705771)
			(xy 351.780265 -158.687171) (xy 351.77984 -158.677102) (xy 351.77984 -155.49118) (xy 351.779441 -155.481107)
			(xy 351.771704 -155.462509) (xy 351.764854 -155.455112) (xy 351.457006 -155.147518) (xy 351.449596 -155.14069)
			(xy 351.431004 -155.132963) (xy 351.420938 -155.132532) (xy 347.199712 -155.132532) (xy 347.189642 -155.132955)
			(xy 347.171044 -155.140676) (xy 347.163644 -155.147518) (xy 346.743274 -155.567888) (xy 346.736443 -155.575295)
			(xy 346.728719 -155.593889) (xy 346.728288 -155.603956) (xy 346.728288 -156.799534) (xy 347.421454 -156.799534)
			(xy 347.42194 -156.772283) (xy 347.429696 -156.718335) (xy 347.445051 -156.66604) (xy 347.467693 -156.616463)
			(xy 347.497159 -156.570613) (xy 347.53285 -156.529422) (xy 347.574041 -156.493731) (xy 347.619891 -156.464265)
			(xy 347.669468 -156.441623) (xy 347.721763 -156.426268) (xy 347.775711 -156.418512) (xy 347.830213 -156.418512)
			(xy 347.884161 -156.426268) (xy 347.936456 -156.441623) (xy 347.986033 -156.464265) (xy 348.031883 -156.493731)
			(xy 348.073074 -156.529422) (xy 348.108765 -156.570613) (xy 348.138231 -156.616463) (xy 348.160873 -156.66604)
			(xy 348.165539 -156.681932) (xy 349.311722 -156.681932) (xy 349.312208 -156.654681) (xy 349.319964 -156.600733)
			(xy 349.335319 -156.548438) (xy 349.357961 -156.498861) (xy 349.387427 -156.453011) (xy 349.423118 -156.41182)
			(xy 349.464309 -156.376129) (xy 349.510159 -156.346663) (xy 349.559736 -156.324021) (xy 349.612031 -156.308666)
			(xy 349.665979 -156.30091) (xy 349.720481 -156.30091) (xy 349.774429 -156.308666) (xy 349.826724 -156.324021)
			(xy 349.876301 -156.346663) (xy 349.922151 -156.376129) (xy 349.963342 -156.41182) (xy 349.999033 -156.453011)
			(xy 350.028499 -156.498861) (xy 350.051141 -156.548438) (xy 350.066496 -156.600733) (xy 350.074252 -156.654681)
			(xy 350.074738 -156.681932) (xy 350.074171 -156.711027) (xy 350.065334 -156.768541) (xy 350.047854 -156.824042)
			(xy 350.022138 -156.876241) (xy 349.988784 -156.923922) (xy 349.969074 -156.94533) (xy 349.962216 -156.952442)
			(xy 349.955104 -156.970476) (xy 349.955612 -157.051248) (xy 349.956057 -157.060976) (xy 349.963384 -157.079004)
			(xy 349.969836 -157.0863) (xy 349.989942 -157.107813) (xy 350.024011 -157.155835) (xy 350.050299 -157.20852)
			(xy 350.068182 -157.264619) (xy 350.077236 -157.322798) (xy 350.077786 -157.352238) (xy 350.077691 -157.357572)
			(xy 350.649538 -157.357572) (xy 350.653609 -157.30195) (xy 350.665735 -157.247513) (xy 350.685658 -157.195422)
			(xy 350.712954 -157.146787) (xy 350.74704 -157.102644) (xy 350.787189 -157.063935) (xy 350.832547 -157.031484)
			(xy 350.882147 -157.005983) (xy 350.934931 -156.987976) (xy 350.989774 -156.977846) (xy 351.045508 -156.975809)
			(xy 351.100945 -156.981909) (xy 351.154902 -156.996015) (xy 351.206231 -157.017827) (xy 351.253837 -157.046881)
			(xy 351.296705 -157.082556) (xy 351.333922 -157.124093) (xy 351.364695 -157.170606) (xy 351.388367 -157.221103)
			(xy 351.404435 -157.27451) (xy 351.412555 -157.329686) (xy 351.413064 -157.357572) (xy 351.412555 -157.385458)
			(xy 351.404435 -157.440634) (xy 351.388367 -157.494041) (xy 351.364695 -157.544538) (xy 351.333922 -157.591051)
			(xy 351.296705 -157.632588) (xy 351.253837 -157.668263) (xy 351.206231 -157.697317) (xy 351.154902 -157.719129)
			(xy 351.100945 -157.733235) (xy 351.045508 -157.739335) (xy 350.989774 -157.737298) (xy 350.934931 -157.727168)
			(xy 350.882147 -157.709161) (xy 350.832547 -157.68366) (xy 350.787189 -157.651209) (xy 350.74704 -157.6125)
			(xy 350.712954 -157.568357) (xy 350.685658 -157.519722) (xy 350.665735 -157.467631) (xy 350.653609 -157.413194)
			(xy 350.649538 -157.357572) (xy 350.077691 -157.357572) (xy 350.0773 -157.379489) (xy 350.069544 -157.433437)
			(xy 350.054189 -157.485732) (xy 350.031547 -157.535309) (xy 350.002081 -157.581159) (xy 349.96639 -157.62235)
			(xy 349.925199 -157.658041) (xy 349.879349 -157.687507) (xy 349.829772 -157.710149) (xy 349.777477 -157.725504)
			(xy 349.723529 -157.73326) (xy 349.669027 -157.73326) (xy 349.615079 -157.725504) (xy 349.562784 -157.710149)
			(xy 349.513207 -157.687507) (xy 349.467357 -157.658041) (xy 349.426166 -157.62235) (xy 349.390475 -157.581159)
			(xy 349.361009 -157.535309) (xy 349.338367 -157.485732) (xy 349.323012 -157.433437) (xy 349.315256 -157.379489)
			(xy 349.31477 -157.352238) (xy 349.315343 -157.323144) (xy 349.324183 -157.265631) (xy 349.341663 -157.210131)
			(xy 349.367376 -157.157932) (xy 349.400726 -157.110249) (xy 349.420434 -157.08884) (xy 349.427292 -157.081728)
			(xy 349.434404 -157.063694) (xy 349.433896 -156.982922) (xy 349.433413 -156.973198) (xy 349.426112 -156.95517)
			(xy 349.419672 -156.94787) (xy 349.399553 -156.926369) (xy 349.365486 -156.878344) (xy 349.3392 -156.825655)
			(xy 349.32132 -156.769554) (xy 349.31227 -156.711373) (xy 349.311722 -156.681932) (xy 348.165539 -156.681932)
			(xy 348.176228 -156.718335) (xy 348.183984 -156.772283) (xy 348.18447 -156.799534) (xy 348.183812 -156.831097)
			(xy 348.173425 -156.893362) (xy 348.152938 -156.953071) (xy 348.138496 -156.981144) (xy 348.13367 -156.990034)
			(xy 348.131638 -157.009592) (xy 348.154498 -157.088078) (xy 348.157756 -157.097494) (xy 348.170159 -157.113057)
			(xy 348.178628 -157.118304) (xy 348.185994 -157.122368) (xy 348.1959 -157.12821) (xy 348.217744 -157.130242)
			(xy 348.312486 -157.096714) (xy 348.328234 -157.08122) (xy 348.332298 -157.070806) (xy 348.342982 -157.044024)
			(xy 348.371271 -156.993781) (xy 348.406801 -156.948371) (xy 348.448765 -156.908828) (xy 348.496204 -156.876054)
			(xy 348.548037 -156.850798) (xy 348.603082 -156.833634) (xy 348.660084 -156.824954) (xy 348.688914 -156.824426)
			(xy 348.716167 -156.824845) (xy 348.770118 -156.832604) (xy 348.822416 -156.847961) (xy 348.871996 -156.870605)
			(xy 348.917848 -156.900075) (xy 348.959041 -156.935769) (xy 348.994734 -156.976963) (xy 349.024201 -157.022817)
			(xy 349.046844 -157.072397) (xy 349.062199 -157.124696) (xy 349.069956 -157.178647) (xy 349.069956 -157.233153)
			(xy 349.062199 -157.287104) (xy 349.046844 -157.339403) (xy 349.024201 -157.388983) (xy 348.994734 -157.434837)
			(xy 348.959041 -157.476031) (xy 348.917848 -157.511725) (xy 348.871996 -157.541195) (xy 348.822416 -157.563839)
			(xy 348.770118 -157.579196) (xy 348.716167 -157.586955) (xy 348.688914 -157.587442) (xy 348.68866 -157.587442)
			(xy 348.663456 -157.587063) (xy 348.613487 -157.580417) (xy 348.564832 -157.567235) (xy 348.518343 -157.547746)
			(xy 348.496382 -157.535372) (xy 348.486476 -157.52953) (xy 348.464632 -157.527498) (xy 348.36989 -157.561026)
			(xy 348.354142 -157.57652) (xy 348.350078 -157.586934) (xy 348.339352 -157.613697) (xy 348.311066 -157.663936)
			(xy 348.275539 -157.709344) (xy 348.233582 -157.748886) (xy 348.186149 -157.781661) (xy 348.134323 -157.806921)
			(xy 348.079285 -157.824092) (xy 348.022289 -157.832781) (xy 347.993462 -157.833314) (xy 347.96621 -157.832858)
			(xy 347.912262 -157.825096) (xy 347.859967 -157.809736) (xy 347.81039 -157.787091) (xy 347.76454 -157.757622)
			(xy 347.72335 -157.721927) (xy 347.687659 -157.680735) (xy 347.658193 -157.634882) (xy 347.635552 -157.585303)
			(xy 347.620197 -157.533007) (xy 347.61244 -157.479058) (xy 347.611954 -157.451806) (xy 347.612586 -157.420242)
			(xy 347.622984 -157.357976) (xy 347.643481 -157.298267) (xy 347.657928 -157.270196) (xy 347.662754 -157.261306)
			(xy 347.664786 -157.241748) (xy 347.641926 -157.163262) (xy 347.63872 -157.153824) (xy 347.62628 -157.138271)
			(xy 347.617796 -157.133036) (xy 347.592682 -157.118509) (xy 347.5468 -157.083002) (xy 347.506825 -157.040954)
			(xy 347.473682 -156.993337) (xy 347.448133 -156.941249) (xy 347.430769 -156.885891) (xy 347.421991 -156.828542)
			(xy 347.421454 -156.799534) (xy 346.728288 -156.799534) (xy 346.728288 -157.831028) (xy 346.728676 -157.841102)
			(xy 346.73642 -157.859701) (xy 346.743274 -157.867096) (xy 347.1291 -158.252922) (xy 350.070418 -158.252922)
			(xy 350.074489 -158.1973) (xy 350.086615 -158.142863) (xy 350.106538 -158.090772) (xy 350.133834 -158.042137)
			(xy 350.16792 -157.997994) (xy 350.208069 -157.959285) (xy 350.253427 -157.926834) (xy 350.303027 -157.901333)
			(xy 350.355811 -157.883326) (xy 350.410654 -157.873196) (xy 350.466388 -157.871159) (xy 350.521825 -157.877259)
			(xy 350.575782 -157.891365) (xy 350.627111 -157.913177) (xy 350.674717 -157.942231) (xy 350.717585 -157.977906)
			(xy 350.754802 -158.019443) (xy 350.785575 -158.065956) (xy 350.809247 -158.116453) (xy 350.825315 -158.16986)
			(xy 350.833435 -158.225036) (xy 350.833944 -158.252922) (xy 350.833435 -158.280808) (xy 350.825315 -158.335984)
			(xy 350.809247 -158.389391) (xy 350.785575 -158.439888) (xy 350.754802 -158.486401) (xy 350.717585 -158.527938)
			(xy 350.674717 -158.563613) (xy 350.627111 -158.592667) (xy 350.575782 -158.614479) (xy 350.521825 -158.628585)
			(xy 350.466388 -158.634685) (xy 350.410654 -158.632648) (xy 350.355811 -158.622518) (xy 350.303027 -158.604511)
			(xy 350.253427 -158.57901) (xy 350.208069 -158.546559) (xy 350.16792 -158.50785) (xy 350.133834 -158.463707)
			(xy 350.106538 -158.415072) (xy 350.086615 -158.362981) (xy 350.074489 -158.308544) (xy 350.070418 -158.252922)
			(xy 347.1291 -158.252922) (xy 347.586046 -158.709868) (xy 347.592813 -158.717319) (xy 347.600529 -158.735884)
			(xy 347.601032 -158.745936) (xy 347.601032 -160.129982) (xy 351.02927 -160.129982) (xy 351.029757 -160.102071)
			(xy 351.037894 -160.046845) (xy 351.053991 -159.993394) (xy 351.077705 -159.94286) (xy 351.108529 -159.89632)
			(xy 351.126806 -159.87522) (xy 351.132695 -159.868037) (xy 351.139351 -159.850716) (xy 351.13976 -159.841438)
			(xy 351.13976 -159.763714) (xy 351.133156 -159.746442) (xy 351.126806 -159.73933) (xy 351.108522 -159.718236)
			(xy 351.077695 -159.671696) (xy 351.053981 -159.62116) (xy 351.037886 -159.567707) (xy 351.029754 -159.51248)
			(xy 351.02927 -159.484568) (xy 351.029756 -159.457317) (xy 351.037512 -159.403369) (xy 351.052867 -159.351074)
			(xy 351.075509 -159.301497) (xy 351.104975 -159.255647) (xy 351.140666 -159.214456) (xy 351.181857 -159.178765)
			(xy 351.227707 -159.149299) (xy 351.277284 -159.126657) (xy 351.329579 -159.111302) (xy 351.383527 -159.103546)
			(xy 351.438029 -159.103546) (xy 351.491977 -159.111302) (xy 351.544272 -159.126657) (xy 351.593849 -159.149299)
			(xy 351.639699 -159.178765) (xy 351.68089 -159.214456) (xy 351.716581 -159.255647) (xy 351.746047 -159.301497)
			(xy 351.768689 -159.351074) (xy 351.784044 -159.403369) (xy 351.7918 -159.457317) (xy 351.792286 -159.484568)
			(xy 351.791815 -159.512479) (xy 351.783672 -159.567705) (xy 351.767571 -159.621156) (xy 351.743854 -159.67169)
			(xy 351.713027 -159.71823) (xy 351.69475 -159.73933) (xy 351.688834 -159.746494) (xy 351.682196 -159.763829)
			(xy 351.681796 -159.773112) (xy 351.681796 -159.850836) (xy 351.6884 -159.868108) (xy 351.69475 -159.87522)
			(xy 351.71302 -159.896326) (xy 351.743847 -159.942864) (xy 351.767563 -159.993397) (xy 351.783661 -160.046846)
			(xy 351.791799 -160.102071) (xy 351.792286 -160.129982) (xy 351.7918 -160.157233) (xy 351.784044 -160.211181)
			(xy 351.768689 -160.263476) (xy 351.746047 -160.313053) (xy 351.716581 -160.358903) (xy 351.68089 -160.400094)
			(xy 351.639699 -160.435785) (xy 351.593849 -160.465251) (xy 351.544272 -160.487893) (xy 351.491977 -160.503248)
			(xy 351.438029 -160.511004) (xy 351.383527 -160.511004) (xy 351.329579 -160.503248) (xy 351.277284 -160.487893)
			(xy 351.227707 -160.465251) (xy 351.181857 -160.435785) (xy 351.140666 -160.400094) (xy 351.104975 -160.358903)
			(xy 351.075509 -160.313053) (xy 351.052867 -160.263476) (xy 351.037512 -160.211181) (xy 351.029756 -160.157233)
			(xy 351.02927 -160.129982) (xy 347.601032 -160.129982) (xy 347.601032 -161.063432) (xy 347.600539 -161.073438)
			(xy 347.592875 -161.091924) (xy 347.578724 -161.106075) (xy 347.560238 -161.113739) (xy 347.550232 -161.114232)
			(xy 345.745816 -161.114232) (xy 345.735747 -161.114657) (xy 345.717148 -161.122377) (xy 345.709748 -161.129218)
			(xy 345.68892 -161.150046) (xy 345.681512 -161.156876) (xy 345.662919 -161.1646) (xy 345.652852 -161.165032)
			(xy 340.53018 -161.165032) (xy 340.520107 -161.164635) (xy 340.501508 -161.156897) (xy 340.494112 -161.150046)
			(xy 340.015322 -160.671256) (xy 340.008473 -160.663863) (xy 340.000758 -160.645258) (xy 340.000336 -160.635188)
			(xy 328.169948 -160.635188) (xy 328.16165 -160.832259) (xy 328.143028 -161.053072) (xy 328.115139 -161.272907)
			(xy 328.078032 -161.491375) (xy 328.031774 -161.70809) (xy 328.004678 -161.815526) (xy 328.002838 -161.824129)
			(xy 328.004475 -161.841632) (xy 328.011955 -161.85754) (xy 328.017886 -161.86404) (xy 332.998064 -166.844218)
			(xy 335.512662 -166.844218) (xy 335.516733 -166.788596) (xy 335.528859 -166.734159) (xy 335.548782 -166.682068)
			(xy 335.576078 -166.633433) (xy 335.610164 -166.58929) (xy 335.650313 -166.550581) (xy 335.695671 -166.51813)
			(xy 335.745271 -166.492629) (xy 335.798055 -166.474622) (xy 335.852898 -166.464492) (xy 335.908632 -166.462455)
			(xy 335.964069 -166.468555) (xy 336.018026 -166.482661) (xy 336.069355 -166.504473) (xy 336.116961 -166.533527)
			(xy 336.159829 -166.569202) (xy 336.197046 -166.610739) (xy 336.227819 -166.657252) (xy 336.251491 -166.707749)
			(xy 336.267559 -166.761156) (xy 336.275679 -166.816332) (xy 336.275877 -166.8272) (xy 336.583526 -166.8272)
			(xy 336.587597 -166.771578) (xy 336.599723 -166.717141) (xy 336.619646 -166.66505) (xy 336.646942 -166.616415)
			(xy 336.681028 -166.572272) (xy 336.721177 -166.533563) (xy 336.766535 -166.501112) (xy 336.816135 -166.475611)
			(xy 336.868919 -166.457604) (xy 336.923762 -166.447474) (xy 336.979496 -166.445437) (xy 337.034933 -166.451537)
			(xy 337.08889 -166.465643) (xy 337.140219 -166.487455) (xy 337.187825 -166.516509) (xy 337.230693 -166.552184)
			(xy 337.26791 -166.593721) (xy 337.298683 -166.640234) (xy 337.322355 -166.690731) (xy 337.338423 -166.744138)
			(xy 337.346543 -166.799314) (xy 337.347052 -166.8272) (xy 337.346543 -166.855086) (xy 337.338423 -166.910262)
			(xy 337.322355 -166.963669) (xy 337.298683 -167.014166) (xy 337.26791 -167.060679) (xy 337.230693 -167.102216)
			(xy 337.187825 -167.137891) (xy 337.140219 -167.166945) (xy 337.08889 -167.188757) (xy 337.034933 -167.202863)
			(xy 336.979496 -167.208963) (xy 336.923762 -167.206926) (xy 336.868919 -167.196796) (xy 336.816135 -167.178789)
			(xy 336.766535 -167.153288) (xy 336.721177 -167.120837) (xy 336.681028 -167.082128) (xy 336.646942 -167.037985)
			(xy 336.619646 -166.98935) (xy 336.599723 -166.937259) (xy 336.587597 -166.882822) (xy 336.583526 -166.8272)
			(xy 336.275877 -166.8272) (xy 336.276188 -166.844218) (xy 336.275679 -166.872104) (xy 336.267559 -166.92728)
			(xy 336.251491 -166.980687) (xy 336.227819 -167.031184) (xy 336.197046 -167.077697) (xy 336.159829 -167.119234)
			(xy 336.116961 -167.154909) (xy 336.069355 -167.183963) (xy 336.018026 -167.205775) (xy 335.964069 -167.219881)
			(xy 335.908632 -167.225981) (xy 335.852898 -167.223944) (xy 335.798055 -167.213814) (xy 335.745271 -167.195807)
			(xy 335.695671 -167.170306) (xy 335.650313 -167.137855) (xy 335.610164 -167.099146) (xy 335.576078 -167.055003)
			(xy 335.548782 -167.006368) (xy 335.528859 -166.954277) (xy 335.516733 -166.89984) (xy 335.512662 -166.844218)
			(xy 332.998064 -166.844218) (xy 335.85404 -169.700194) (xy 335.860894 -169.707589) (xy 335.86864 -169.726188)
			(xy 335.869026 -169.736262) (xy 335.869026 -169.873422) (xy 335.869375 -169.882112) (xy 335.875224 -169.898478)
			(xy 335.880456 -169.905426) (xy 335.883758 -169.909236) (xy 338.126832 -172.15231) (xy 340.04377 -172.15231)
			(xy 340.044297 -172.122832) (xy 340.053366 -172.064577) (xy 340.071291 -172.008411) (xy 340.097643 -171.955672)
			(xy 340.131797 -171.907616) (xy 340.151974 -171.886118) (xy 340.159086 -171.879006) (xy 340.166452 -171.860718)
			(xy 340.166452 -171.769786) (xy 340.159086 -171.751498) (xy 340.151974 -171.744386) (xy 340.131798 -171.722888)
			(xy 340.097653 -171.674829) (xy 340.071306 -171.622089) (xy 340.053386 -171.565924) (xy 340.044318 -171.507671)
			(xy 340.04377 -171.478194) (xy 340.044256 -171.450943) (xy 340.052012 -171.396995) (xy 340.067367 -171.3447)
			(xy 340.090009 -171.295123) (xy 340.119475 -171.249273) (xy 340.155166 -171.208082) (xy 340.196357 -171.172391)
			(xy 340.242207 -171.142925) (xy 340.291784 -171.120283) (xy 340.344079 -171.104928) (xy 340.398027 -171.097172)
			(xy 340.452529 -171.097172) (xy 340.506477 -171.104928) (xy 340.558772 -171.120283) (xy 340.608349 -171.142925)
			(xy 340.654199 -171.172391) (xy 340.69539 -171.208082) (xy 340.731081 -171.249273) (xy 340.760547 -171.295123)
			(xy 340.783189 -171.3447) (xy 340.798544 -171.396995) (xy 340.8063 -171.450943) (xy 340.806786 -171.478194)
			(xy 340.806246 -171.507672) (xy 340.797177 -171.565925) (xy 340.779255 -171.62209) (xy 340.752906 -171.674829)
			(xy 340.718757 -171.722887) (xy 340.698582 -171.744386) (xy 340.69147 -171.751498) (xy 340.684104 -171.769786)
			(xy 340.684104 -171.860718) (xy 340.69147 -171.879006) (xy 340.698582 -171.886118) (xy 340.718769 -171.907605)
			(xy 340.752911 -171.955668) (xy 340.779254 -172.008411) (xy 340.797172 -172.064578) (xy 340.806238 -172.122832)
			(xy 340.806786 -172.15231) (xy 340.8063 -172.179561) (xy 340.798544 -172.233509) (xy 340.783189 -172.285804)
			(xy 340.760547 -172.335381) (xy 340.731081 -172.381231) (xy 340.69539 -172.422422) (xy 340.654199 -172.458113)
			(xy 340.608349 -172.487579) (xy 340.558772 -172.510221) (xy 340.506477 -172.525576) (xy 340.452529 -172.533332)
			(xy 340.398027 -172.533332) (xy 340.344079 -172.525576) (xy 340.291784 -172.510221) (xy 340.242207 -172.487579)
			(xy 340.196357 -172.458113) (xy 340.155166 -172.422422) (xy 340.119475 -172.381231) (xy 340.090009 -172.335381)
			(xy 340.067367 -172.285804) (xy 340.052012 -172.233509) (xy 340.044256 -172.179561) (xy 340.04377 -172.15231)
			(xy 338.126832 -172.15231) (xy 339.094064 -173.119542) (xy 344.660982 -173.119542) (xy 344.661494 -173.092291)
			(xy 344.669245 -173.038342) (xy 344.684596 -172.986046) (xy 344.707232 -172.936466) (xy 344.736695 -172.890613)
			(xy 344.772384 -172.849421) (xy 344.813572 -172.813726) (xy 344.859421 -172.784257) (xy 344.908997 -172.761614)
			(xy 344.961291 -172.746256) (xy 345.015239 -172.738498) (xy 345.04249 -172.738034) (xy 345.06986 -172.738498)
			(xy 345.12404 -172.746315) (xy 345.176543 -172.761804) (xy 345.22629 -172.784646) (xy 345.272257 -172.814372)
			(xy 345.293188 -172.832014) (xy 345.293442 -172.832268) (xy 345.300535 -172.837844) (xy 345.317447 -172.844095)
			(xy 345.326462 -172.84446) (xy 345.393518 -172.84446) (xy 345.402537 -172.84412) (xy 345.419454 -172.837862)
			(xy 345.426538 -172.832268) (xy 345.426538 -172.832014) (xy 345.426792 -172.832014) (xy 345.447725 -172.814373)
			(xy 345.493693 -172.784649) (xy 345.543439 -172.761803) (xy 345.595941 -172.746307) (xy 345.650119 -172.738478)
			(xy 345.704861 -172.738478) (xy 345.759039 -172.746307) (xy 345.811541 -172.761803) (xy 345.861287 -172.784649)
			(xy 345.907255 -172.814373) (xy 345.928188 -172.832014) (xy 345.928442 -172.832268) (xy 345.935535 -172.837844)
			(xy 345.952447 -172.844095) (xy 345.961462 -172.84446) (xy 346.028518 -172.84446) (xy 346.037537 -172.84412)
			(xy 346.054454 -172.837862) (xy 346.061538 -172.832268) (xy 346.061538 -172.832014) (xy 346.061792 -172.832014)
			(xy 346.082718 -172.814367) (xy 346.128692 -172.784656) (xy 346.178441 -172.761821) (xy 346.230943 -172.746332)
			(xy 346.28512 -172.738507) (xy 346.31249 -172.738034) (xy 346.339745 -172.738465) (xy 346.393699 -172.746221)
			(xy 346.446 -172.761578) (xy 346.495583 -172.784223) (xy 346.541438 -172.813694) (xy 346.582632 -172.849391)
			(xy 346.618326 -172.890588) (xy 346.647793 -172.936445) (xy 346.670433 -172.98603) (xy 346.685785 -173.038333)
			(xy 346.693538 -173.092287) (xy 346.693998 -173.119542) (xy 348.676722 -173.119542) (xy 348.677194 -173.092289)
			(xy 348.684946 -173.038337) (xy 348.700299 -172.986037) (xy 348.722939 -172.936455) (xy 348.752405 -172.8906)
			(xy 348.788098 -172.849406) (xy 348.829291 -172.813712) (xy 348.875145 -172.784244) (xy 348.924726 -172.761603)
			(xy 348.977025 -172.746249) (xy 349.030977 -172.738495) (xy 349.05823 -172.738034) (xy 349.085601 -172.738474)
			(xy 349.139782 -172.746297) (xy 349.192286 -172.761792) (xy 349.242032 -172.784639) (xy 349.287997 -172.81437)
			(xy 349.308928 -172.832014) (xy 349.309182 -172.832268) (xy 349.316264 -172.837861) (xy 349.333184 -172.844102)
			(xy 349.342202 -172.84446) (xy 349.409258 -172.84446) (xy 349.418274 -172.844092) (xy 349.435191 -172.837853)
			(xy 349.442278 -172.832268) (xy 349.442278 -172.832014) (xy 349.442532 -172.832014) (xy 349.463481 -172.814396)
			(xy 349.509449 -172.78468) (xy 349.559192 -172.76184) (xy 349.611689 -172.746344) (xy 349.665862 -172.738511)
			(xy 349.69323 -172.738034) (xy 349.720486 -172.738427) (xy 349.774441 -172.746189) (xy 349.826743 -172.761551)
			(xy 349.876326 -172.7842) (xy 349.922181 -172.813675) (xy 349.963375 -172.849376) (xy 349.999068 -172.890577)
			(xy 350.028534 -172.936437) (xy 350.051174 -172.986025) (xy 350.066526 -173.038329) (xy 350.074278 -173.092286)
			(xy 350.074738 -173.119542) (xy 350.074268 -173.146676) (xy 350.066578 -173.200397) (xy 350.051347 -173.252484)
			(xy 350.028882 -173.301884) (xy 349.999636 -173.347598) (xy 349.982282 -173.368462) (xy 349.976636 -173.375663)
			(xy 349.970384 -173.392845) (xy 349.97009 -173.40199) (xy 349.970344 -173.468792) (xy 349.970845 -173.477846)
			(xy 349.977341 -173.494762) (xy 349.983044 -173.501812) (xy 349.983298 -173.502066) (xy 350.001209 -173.523076)
			(xy 350.031401 -173.569298) (xy 350.054614 -173.61939) (xy 350.070362 -173.672305) (xy 350.078316 -173.726938)
			(xy 350.078802 -173.754542) (xy 350.078301 -173.781911) (xy 350.070492 -173.836089) (xy 350.055011 -173.888591)
			(xy 350.032177 -173.938339) (xy 350.00246 -173.984307) (xy 349.984822 -174.00524) (xy 349.984568 -174.005494)
			(xy 349.978974 -174.012575) (xy 349.972733 -174.029496) (xy 349.972376 -174.038514) (xy 349.972376 -174.10557)
			(xy 349.972753 -174.114585) (xy 349.978987 -174.131502) (xy 349.984568 -174.13859) (xy 349.984822 -174.13859)
			(xy 349.984822 -174.138844) (xy 350.002502 -174.159744) (xy 350.032221 -174.205719) (xy 350.055061 -174.255471)
			(xy 350.070552 -174.307977) (xy 350.078376 -174.36216) (xy 350.078371 -174.416904) (xy 350.070538 -174.471084)
			(xy 350.055039 -174.523588) (xy 350.032191 -174.573337) (xy 350.002464 -174.619306) (xy 349.984822 -174.64024)
			(xy 349.984568 -174.640494) (xy 349.978974 -174.647575) (xy 349.972733 -174.664496) (xy 349.972376 -174.673514)
			(xy 349.972376 -174.74057) (xy 349.972753 -174.749585) (xy 349.978987 -174.766502) (xy 349.984568 -174.77359)
			(xy 349.984822 -174.77359) (xy 349.984822 -174.773844) (xy 350.002502 -174.794744) (xy 350.032221 -174.840719)
			(xy 350.055061 -174.890471) (xy 350.070552 -174.942977) (xy 350.078376 -174.99716) (xy 350.078371 -175.051904)
			(xy 350.070538 -175.106084) (xy 350.055039 -175.158588) (xy 350.032191 -175.208337) (xy 350.002464 -175.254306)
			(xy 349.984822 -175.27524) (xy 349.984568 -175.275494) (xy 349.978974 -175.282575) (xy 349.972733 -175.299496)
			(xy 349.972376 -175.308514) (xy 349.972376 -175.37557) (xy 349.972753 -175.384585) (xy 349.978987 -175.401502)
			(xy 349.984568 -175.40859) (xy 349.984822 -175.40859) (xy 349.984822 -175.408844) (xy 350.002452 -175.429784)
			(xy 350.032164 -175.475755) (xy 350.055002 -175.5255) (xy 350.070495 -175.577999) (xy 350.078326 -175.632173)
			(xy 350.078802 -175.659542) (xy 350.078284 -175.687972) (xy 350.069834 -175.744201) (xy 350.053128 -175.798551)
			(xy 350.028537 -175.849818) (xy 349.996606 -175.896866) (xy 349.97771 -175.918114) (xy 349.97136 -175.924972)
			(xy 349.964502 -175.942752) (xy 349.964502 -176.031144) (xy 349.97136 -176.048924) (xy 349.97771 -176.055782)
			(xy 349.996627 -176.077012) (xy 350.028557 -176.124063) (xy 350.053144 -176.175335) (xy 350.069842 -176.22969)
			(xy 350.07828 -176.285923) (xy 350.078802 -176.314354) (xy 350.078308 -176.341723) (xy 350.070497 -176.395901)
			(xy 350.055015 -176.448404) (xy 350.032179 -176.498151) (xy 350.00246 -176.544119) (xy 349.984822 -176.565052)
			(xy 349.984568 -176.565306) (xy 349.978969 -176.572384) (xy 349.972731 -176.589308) (xy 349.972376 -176.598326)
			(xy 349.972376 -176.665382) (xy 349.972747 -176.674397) (xy 349.978985 -176.691314) (xy 349.984568 -176.698402)
			(xy 349.984822 -176.698402) (xy 349.984822 -176.698656) (xy 350.002416 -176.719626) (xy 350.032139 -176.765589)
			(xy 350.054984 -176.815329) (xy 350.070481 -176.867825) (xy 350.078313 -176.921998) (xy 350.078318 -176.976733)
			(xy 350.070496 -177.030907) (xy 350.055008 -177.083406) (xy 350.032172 -177.13315) (xy 350.002457 -177.179118)
			(xy 349.984822 -177.200052) (xy 349.984568 -177.200306) (xy 349.978969 -177.207384) (xy 349.972731 -177.224308)
			(xy 349.972376 -177.233326) (xy 349.972376 -177.300382) (xy 349.972747 -177.309397) (xy 349.978985 -177.326314)
			(xy 349.984568 -177.333402) (xy 349.984822 -177.333402) (xy 349.984822 -177.333656) (xy 350.002416 -177.354626)
			(xy 350.032139 -177.400589) (xy 350.054984 -177.450329) (xy 350.070481 -177.502825) (xy 350.078313 -177.556998)
			(xy 350.078318 -177.611733) (xy 350.070496 -177.665907) (xy 350.055008 -177.718406) (xy 350.032172 -177.76815)
			(xy 350.002457 -177.814118) (xy 349.984822 -177.835052) (xy 349.984568 -177.835306) (xy 349.978969 -177.842384)
			(xy 349.972731 -177.859308) (xy 349.972376 -177.868326) (xy 349.972376 -177.935382) (xy 349.972747 -177.944397)
			(xy 349.978985 -177.961314) (xy 349.984568 -177.968402) (xy 349.984822 -177.968402) (xy 349.984822 -177.968656)
			(xy 350.002416 -177.989626) (xy 350.032139 -178.035589) (xy 350.054984 -178.085329) (xy 350.070481 -178.137825)
			(xy 350.078313 -178.191998) (xy 350.078318 -178.246733) (xy 350.070496 -178.300907) (xy 350.055008 -178.353406)
			(xy 350.032172 -178.40315) (xy 350.002457 -178.449118) (xy 349.984822 -178.470052) (xy 349.984568 -178.470306)
			(xy 349.978969 -178.477384) (xy 349.972731 -178.494308) (xy 349.972376 -178.503326) (xy 349.972376 -178.570382)
			(xy 349.972747 -178.579397) (xy 349.978985 -178.596314) (xy 349.984568 -178.603402) (xy 349.984822 -178.603402)
			(xy 349.984822 -178.603656) (xy 350.002416 -178.624626) (xy 350.032139 -178.670589) (xy 350.054984 -178.720329)
			(xy 350.070481 -178.772825) (xy 350.078313 -178.826998) (xy 350.078318 -178.881733) (xy 350.070496 -178.935907)
			(xy 350.055008 -178.988406) (xy 350.032172 -179.03815) (xy 350.002457 -179.084118) (xy 349.984822 -179.105052)
			(xy 349.984568 -179.105306) (xy 349.978969 -179.112384) (xy 349.972731 -179.129308) (xy 349.972376 -179.138326)
			(xy 349.972376 -179.205382) (xy 349.972747 -179.214397) (xy 349.978985 -179.231314) (xy 349.984568 -179.238402)
			(xy 349.984822 -179.238402) (xy 349.984822 -179.238656) (xy 350.002457 -179.259591) (xy 350.032169 -179.305563)
			(xy 350.055005 -179.35531) (xy 350.070497 -179.40781) (xy 350.078327 -179.461985) (xy 350.078802 -179.489354)
			(xy 350.078302 -179.516606) (xy 350.070551 -179.570556) (xy 350.055201 -179.622853) (xy 350.032563 -179.672434)
			(xy 350.003099 -179.718287) (xy 349.967409 -179.759481) (xy 349.92622 -179.795175) (xy 349.880369 -179.824644)
			(xy 349.830791 -179.847287) (xy 349.778495 -179.862643) (xy 349.724546 -179.870399) (xy 349.697294 -179.870862)
			(xy 349.669923 -179.870409) (xy 349.615743 -179.862589) (xy 349.56324 -179.847098) (xy 349.513493 -179.824253)
			(xy 349.467527 -179.794525) (xy 349.446596 -179.776882) (xy 349.446342 -179.776628) (xy 349.439254 -179.771044)
			(xy 349.422338 -179.764798) (xy 349.413322 -179.764436) (xy 349.346266 -179.764436) (xy 349.337247 -179.764769)
			(xy 349.320329 -179.771032) (xy 349.313246 -179.776628) (xy 349.313246 -179.776882) (xy 349.312992 -179.776882)
			(xy 349.292071 -179.794536) (xy 349.246096 -179.824246) (xy 349.196345 -179.847079) (xy 349.143842 -179.862567)
			(xy 349.089664 -179.870391) (xy 349.062294 -179.870862) (xy 349.035039 -179.87045) (xy 348.981084 -179.862691)
			(xy 348.928782 -179.847332) (xy 348.879199 -179.824685) (xy 348.833344 -179.795213) (xy 348.79215 -179.759513)
			(xy 348.756456 -179.718315) (xy 348.72699 -179.672455) (xy 348.70435 -179.622869) (xy 348.688998 -179.570565)
			(xy 348.681246 -179.516609) (xy 348.680786 -179.489354) (xy 348.681287 -179.461985) (xy 348.689097 -179.407808)
			(xy 348.704578 -179.355305) (xy 348.727412 -179.305558) (xy 348.757129 -179.259589) (xy 348.774766 -179.238656)
			(xy 348.77502 -179.238402) (xy 348.780614 -179.231321) (xy 348.786856 -179.2144) (xy 348.787212 -179.205382)
			(xy 348.787212 -179.138326) (xy 348.78684 -179.129311) (xy 348.780603 -179.112394) (xy 348.77502 -179.105306)
			(xy 348.774766 -179.105306) (xy 348.774766 -179.105052) (xy 348.757079 -179.084157) (xy 348.727353 -179.038183)
			(xy 348.704508 -178.988431) (xy 348.689013 -178.935923) (xy 348.681188 -178.881739) (xy 348.681193 -178.826992)
			(xy 348.689028 -178.772809) (xy 348.704532 -178.720304) (xy 348.727386 -178.670556) (xy 348.75712 -178.624588)
			(xy 348.774766 -178.603656) (xy 348.77502 -178.603402) (xy 348.780614 -178.596321) (xy 348.786856 -178.5794)
			(xy 348.787212 -178.570382) (xy 348.787212 -178.503326) (xy 348.78684 -178.494311) (xy 348.780603 -178.477394)
			(xy 348.77502 -178.470306) (xy 348.774766 -178.470306) (xy 348.774766 -178.470052) (xy 348.757079 -178.449157)
			(xy 348.727353 -178.403183) (xy 348.704508 -178.353431) (xy 348.689013 -178.300923) (xy 348.681188 -178.246739)
			(xy 348.681193 -178.191992) (xy 348.689028 -178.137809) (xy 348.704532 -178.085304) (xy 348.727386 -178.035556)
			(xy 348.75712 -177.989588) (xy 348.774766 -177.968656) (xy 348.77502 -177.968402) (xy 348.780614 -177.961321)
			(xy 348.786856 -177.9444) (xy 348.787212 -177.935382) (xy 348.787212 -177.868326) (xy 348.78684 -177.859311)
			(xy 348.780603 -177.842394) (xy 348.77502 -177.835306) (xy 348.774766 -177.835306) (xy 348.774766 -177.835052)
			(xy 348.757079 -177.814157) (xy 348.727353 -177.768183) (xy 348.704508 -177.718431) (xy 348.689013 -177.665923)
			(xy 348.681188 -177.611739) (xy 348.681193 -177.556992) (xy 348.689028 -177.502809) (xy 348.704532 -177.450304)
			(xy 348.727386 -177.400556) (xy 348.75712 -177.354588) (xy 348.774766 -177.333656) (xy 348.77502 -177.333402)
			(xy 348.780614 -177.326321) (xy 348.786856 -177.3094) (xy 348.787212 -177.300382) (xy 348.787212 -177.233326)
			(xy 348.78684 -177.224311) (xy 348.780603 -177.207394) (xy 348.77502 -177.200306) (xy 348.774766 -177.200306)
			(xy 348.774766 -177.200052) (xy 348.757079 -177.179157) (xy 348.727353 -177.133183) (xy 348.704508 -177.083431)
			(xy 348.689013 -177.030923) (xy 348.681188 -176.976739) (xy 348.681193 -176.921992) (xy 348.689028 -176.867809)
			(xy 348.704532 -176.815304) (xy 348.727386 -176.765556) (xy 348.75712 -176.719588) (xy 348.774766 -176.698656)
			(xy 348.77502 -176.698402) (xy 348.780614 -176.691321) (xy 348.786856 -176.6744) (xy 348.787212 -176.665382)
			(xy 348.787212 -176.598326) (xy 348.78684 -176.589311) (xy 348.780603 -176.572394) (xy 348.77502 -176.565306)
			(xy 348.774766 -176.565306) (xy 348.774766 -176.565052) (xy 348.757133 -176.544116) (xy 348.727421 -176.498143)
			(xy 348.704585 -176.448397) (xy 348.689092 -176.395897) (xy 348.681262 -176.341723) (xy 348.680786 -176.314354)
			(xy 348.681305 -176.285924) (xy 348.689755 -176.229696) (xy 348.706461 -176.175345) (xy 348.731052 -176.124078)
			(xy 348.762983 -176.07703) (xy 348.781878 -176.055782) (xy 348.788228 -176.048924) (xy 348.795086 -176.031144)
			(xy 348.795086 -175.942752) (xy 348.788228 -175.924972) (xy 348.781878 -175.918114) (xy 348.762957 -175.896887)
			(xy 348.731028 -175.849835) (xy 348.706442 -175.798562) (xy 348.689745 -175.744206) (xy 348.681307 -175.687973)
			(xy 348.680786 -175.659542) (xy 348.68128 -175.632173) (xy 348.689092 -175.577995) (xy 348.704574 -175.525492)
			(xy 348.72741 -175.475745) (xy 348.757128 -175.429777) (xy 348.774766 -175.408844) (xy 348.77502 -175.40859)
			(xy 348.780619 -175.401512) (xy 348.786858 -175.384589) (xy 348.787212 -175.37557) (xy 348.787212 -175.308514)
			(xy 348.786846 -175.299498) (xy 348.780604 -175.282581) (xy 348.77502 -175.275494) (xy 348.774766 -175.275494)
			(xy 348.774766 -175.27524) (xy 348.757165 -175.254275) (xy 348.727435 -175.208314) (xy 348.704585 -175.158573)
			(xy 348.689084 -175.106075) (xy 348.681251 -175.051901) (xy 348.681246 -174.997163) (xy 348.68907 -174.942986)
			(xy 348.704563 -174.890486) (xy 348.727405 -174.840742) (xy 348.757127 -174.794776) (xy 348.774766 -174.773844)
			(xy 348.77502 -174.77359) (xy 348.780619 -174.766512) (xy 348.786858 -174.749589) (xy 348.787212 -174.74057)
			(xy 348.787212 -174.673514) (xy 348.786846 -174.664498) (xy 348.780604 -174.647581) (xy 348.77502 -174.640494)
			(xy 348.774766 -174.640494) (xy 348.774766 -174.64024) (xy 348.757165 -174.619275) (xy 348.727435 -174.573314)
			(xy 348.704585 -174.523573) (xy 348.689084 -174.471075) (xy 348.681251 -174.416901) (xy 348.681246 -174.362163)
			(xy 348.68907 -174.307986) (xy 348.704563 -174.255486) (xy 348.727405 -174.205742) (xy 348.757127 -174.159776)
			(xy 348.774766 -174.138844) (xy 348.77502 -174.13859) (xy 348.780619 -174.131512) (xy 348.786858 -174.114589)
			(xy 348.787212 -174.10557) (xy 348.787212 -174.038514) (xy 348.786846 -174.029498) (xy 348.780604 -174.012581)
			(xy 348.77502 -174.005494) (xy 348.774766 -174.005494) (xy 348.774766 -174.00524) (xy 348.757127 -173.984308)
			(xy 348.727416 -173.938335) (xy 348.704581 -173.888587) (xy 348.68909 -173.836087) (xy 348.681261 -173.781911)
			(xy 348.680786 -173.754542) (xy 348.681241 -173.727407) (xy 348.688933 -173.673686) (xy 348.704168 -173.621598)
			(xy 348.726637 -173.572199) (xy 348.755886 -173.526486) (xy 348.773242 -173.505622) (xy 348.778897 -173.498428)
			(xy 348.785144 -173.481241) (xy 348.785434 -173.472094) (xy 348.78518 -173.405292) (xy 348.784681 -173.396238)
			(xy 348.778183 -173.379322) (xy 348.77248 -173.372272) (xy 348.772226 -173.372018) (xy 348.754296 -173.351024)
			(xy 348.724109 -173.304797) (xy 348.700901 -173.254701) (xy 348.685157 -173.201782) (xy 348.677207 -173.147147)
			(xy 348.676722 -173.119542) (xy 346.693998 -173.119542) (xy 346.693551 -173.146512) (xy 346.685939 -173.199914)
			(xy 346.670874 -173.251708) (xy 346.648657 -173.300861) (xy 346.619731 -173.34639) (xy 346.602558 -173.367192)
			(xy 346.597009 -173.374358) (xy 346.590897 -173.391407) (xy 346.59062 -173.400466) (xy 346.591382 -173.47692)
			(xy 346.597732 -173.493684) (xy 346.604082 -173.500796) (xy 346.622136 -173.521899) (xy 346.652648 -173.568299)
			(xy 346.676116 -173.618629) (xy 346.692045 -173.671829) (xy 346.700099 -173.726775) (xy 346.700602 -173.754542)
			(xy 346.700101 -173.781911) (xy 346.692292 -173.836089) (xy 346.676811 -173.888591) (xy 346.653977 -173.938339)
			(xy 346.62426 -173.984307) (xy 346.606622 -174.00524) (xy 346.606368 -174.005494) (xy 346.600774 -174.012575)
			(xy 346.594533 -174.029496) (xy 346.594176 -174.038514) (xy 346.594176 -174.10557) (xy 346.594553 -174.114585)
			(xy 346.600787 -174.131502) (xy 346.606368 -174.13859) (xy 346.606622 -174.13859) (xy 346.606622 -174.138844)
			(xy 346.624302 -174.159744) (xy 346.654021 -174.205719) (xy 346.676861 -174.255471) (xy 346.692352 -174.307977)
			(xy 346.700176 -174.36216) (xy 346.700171 -174.416904) (xy 346.692338 -174.471084) (xy 346.676839 -174.523588)
			(xy 346.653991 -174.573337) (xy 346.624264 -174.619306) (xy 346.606622 -174.64024) (xy 346.606368 -174.640494)
			(xy 346.600774 -174.647575) (xy 346.594533 -174.664496) (xy 346.594176 -174.673514) (xy 346.594176 -174.74057)
			(xy 346.594553 -174.749585) (xy 346.600787 -174.766502) (xy 346.606368 -174.77359) (xy 346.606622 -174.77359)
			(xy 346.606622 -174.773844) (xy 346.624302 -174.794744) (xy 346.654021 -174.840719) (xy 346.676861 -174.890471)
			(xy 346.692352 -174.942977) (xy 346.700176 -174.99716) (xy 346.700171 -175.051904) (xy 346.692338 -175.106084)
			(xy 346.676839 -175.158588) (xy 346.653991 -175.208337) (xy 346.624264 -175.254306) (xy 346.606622 -175.27524)
			(xy 346.606368 -175.275494) (xy 346.600774 -175.282575) (xy 346.594533 -175.299496) (xy 346.594176 -175.308514)
			(xy 346.594176 -175.37557) (xy 346.594553 -175.384585) (xy 346.600787 -175.401502) (xy 346.606368 -175.40859)
			(xy 346.606622 -175.40859) (xy 346.606622 -175.408844) (xy 346.624252 -175.429784) (xy 346.653964 -175.475755)
			(xy 346.676802 -175.5255) (xy 346.692295 -175.577999) (xy 346.700126 -175.632173) (xy 346.700602 -175.659542)
			(xy 346.700084 -175.687972) (xy 346.691634 -175.744201) (xy 346.674928 -175.798551) (xy 346.650337 -175.849818)
			(xy 346.618406 -175.896866) (xy 346.59951 -175.918114) (xy 346.59316 -175.924972) (xy 346.586302 -175.942752)
			(xy 346.586302 -176.031144) (xy 346.59316 -176.048924) (xy 346.59951 -176.055782) (xy 346.618427 -176.077012)
			(xy 346.650357 -176.124063) (xy 346.674944 -176.175335) (xy 346.691642 -176.22969) (xy 346.70008 -176.285923)
			(xy 346.700602 -176.314354) (xy 346.700108 -176.341723) (xy 346.692297 -176.395901) (xy 346.676815 -176.448404)
			(xy 346.653979 -176.498151) (xy 346.62426 -176.544119) (xy 346.606622 -176.565052) (xy 346.606368 -176.565306)
			(xy 346.600769 -176.572384) (xy 346.594531 -176.589308) (xy 346.594176 -176.598326) (xy 346.594176 -176.665382)
			(xy 346.594547 -176.674397) (xy 346.600785 -176.691314) (xy 346.606368 -176.698402) (xy 346.606622 -176.698402)
			(xy 346.606622 -176.698656) (xy 346.624216 -176.719626) (xy 346.653939 -176.765589) (xy 346.676784 -176.815329)
			(xy 346.692281 -176.867825) (xy 346.700113 -176.921998) (xy 346.700118 -176.976733) (xy 346.692296 -177.030907)
			(xy 346.676808 -177.083406) (xy 346.653972 -177.13315) (xy 346.624257 -177.179118) (xy 346.606622 -177.200052)
			(xy 346.606368 -177.200306) (xy 346.600769 -177.207384) (xy 346.594531 -177.224308) (xy 346.594176 -177.233326)
			(xy 346.594176 -177.300382) (xy 346.594547 -177.309397) (xy 346.600785 -177.326314) (xy 346.606368 -177.333402)
			(xy 346.606622 -177.333402) (xy 346.606622 -177.333656) (xy 346.624257 -177.354591) (xy 346.653969 -177.400563)
			(xy 346.676805 -177.45031) (xy 346.692297 -177.50281) (xy 346.700127 -177.556985) (xy 346.700602 -177.584354)
			(xy 346.700116 -177.611605) (xy 346.69236 -177.665553) (xy 346.677005 -177.717848) (xy 346.654363 -177.767425)
			(xy 346.624897 -177.813275) (xy 346.589206 -177.854466) (xy 346.548015 -177.890157) (xy 346.502165 -177.919623)
			(xy 346.452588 -177.942265) (xy 346.400293 -177.95762) (xy 346.346345 -177.965376) (xy 346.291843 -177.965376)
			(xy 346.237895 -177.95762) (xy 346.1856 -177.942265) (xy 346.136023 -177.919623) (xy 346.090173 -177.890157)
			(xy 346.048982 -177.854466) (xy 346.013291 -177.813275) (xy 345.983825 -177.767425) (xy 345.961183 -177.717848)
			(xy 345.945828 -177.665553) (xy 345.938072 -177.611605) (xy 345.937586 -177.584354) (xy 345.938163 -177.554878)
			(xy 345.947224 -177.496627) (xy 345.965138 -177.440462) (xy 345.991479 -177.387723) (xy 346.025619 -177.339663)
			(xy 346.04579 -177.318162) (xy 346.052333 -177.310834) (xy 346.059774 -177.292669) (xy 346.060268 -177.282856)
			(xy 346.060268 -177.229516) (xy 346.052902 -177.222658) (xy 346.045566 -177.216125) (xy 346.027406 -177.20868)
			(xy 346.017596 -177.20818) (xy 345.985592 -177.20818) (xy 345.975779 -177.208677) (xy 345.957615 -177.216115)
			(xy 345.950286 -177.222658) (xy 345.928793 -177.242839) (xy 345.880732 -177.276983) (xy 345.827991 -177.303328)
			(xy 345.771825 -177.321247) (xy 345.713571 -177.330314) (xy 345.684094 -177.330862) (xy 345.656839 -177.33045)
			(xy 345.602884 -177.322691) (xy 345.550582 -177.307332) (xy 345.500999 -177.284685) (xy 345.455144 -177.255213)
			(xy 345.41395 -177.219513) (xy 345.378256 -177.178315) (xy 345.34879 -177.132455) (xy 345.32615 -177.082869)
			(xy 345.310798 -177.030565) (xy 345.303046 -176.976609) (xy 345.302586 -176.949354) (xy 345.303163 -176.919878)
			(xy 345.312224 -176.861627) (xy 345.330138 -176.805462) (xy 345.356479 -176.752723) (xy 345.390619 -176.704663)
			(xy 345.41079 -176.683162) (xy 345.417333 -176.675834) (xy 345.424774 -176.657669) (xy 345.425268 -176.647856)
			(xy 345.425268 -176.594516) (xy 345.417902 -176.587658) (xy 345.410566 -176.581125) (xy 345.392406 -176.57368)
			(xy 345.382596 -176.57318) (xy 345.350592 -176.57318) (xy 345.340779 -176.573677) (xy 345.322615 -176.581115)
			(xy 345.315286 -176.587658) (xy 345.293793 -176.607839) (xy 345.245732 -176.641983) (xy 345.192991 -176.668328)
			(xy 345.136825 -176.686247) (xy 345.078571 -176.695314) (xy 345.049094 -176.695862) (xy 345.021839 -176.69545)
			(xy 344.967884 -176.687691) (xy 344.915582 -176.672332) (xy 344.865999 -176.649685) (xy 344.820144 -176.620213)
			(xy 344.77895 -176.584513) (xy 344.743256 -176.543315) (xy 344.71379 -176.497455) (xy 344.69115 -176.447869)
			(xy 344.675798 -176.395565) (xy 344.668046 -176.341609) (xy 344.667586 -176.314354) (xy 344.668087 -176.286985)
			(xy 344.675897 -176.232808) (xy 344.691378 -176.180305) (xy 344.714212 -176.130558) (xy 344.743929 -176.084589)
			(xy 344.761566 -176.063656) (xy 344.76182 -176.063402) (xy 344.767414 -176.056321) (xy 344.773656 -176.0394)
			(xy 344.774012 -176.030382) (xy 344.774012 -175.963326) (xy 344.77364 -175.954311) (xy 344.767403 -175.937394)
			(xy 344.76182 -175.930306) (xy 344.761566 -175.930306) (xy 344.761566 -175.930052) (xy 344.743879 -175.909157)
			(xy 344.714153 -175.863183) (xy 344.691308 -175.813431) (xy 344.675813 -175.760923) (xy 344.667988 -175.706739)
			(xy 344.667993 -175.651992) (xy 344.675828 -175.597809) (xy 344.691332 -175.545304) (xy 344.714186 -175.495556)
			(xy 344.74392 -175.449588) (xy 344.761566 -175.428656) (xy 344.76182 -175.428402) (xy 344.767414 -175.421321)
			(xy 344.773656 -175.4044) (xy 344.774012 -175.395382) (xy 344.774012 -175.328326) (xy 344.77364 -175.319311)
			(xy 344.767403 -175.302394) (xy 344.76182 -175.295306) (xy 344.761566 -175.295306) (xy 344.761566 -175.295052)
			(xy 344.743879 -175.274157) (xy 344.714153 -175.228183) (xy 344.691308 -175.178431) (xy 344.675813 -175.125923)
			(xy 344.667988 -175.071739) (xy 344.667993 -175.016992) (xy 344.675828 -174.962809) (xy 344.691332 -174.910304)
			(xy 344.714186 -174.860556) (xy 344.74392 -174.814588) (xy 344.761566 -174.793656) (xy 344.76182 -174.793402)
			(xy 344.767414 -174.786321) (xy 344.773656 -174.7694) (xy 344.774012 -174.760382) (xy 344.774012 -174.693326)
			(xy 344.77364 -174.684311) (xy 344.767403 -174.667394) (xy 344.76182 -174.660306) (xy 344.761566 -174.660306)
			(xy 344.761566 -174.660052) (xy 344.743879 -174.639157) (xy 344.714153 -174.593183) (xy 344.691308 -174.543431)
			(xy 344.675813 -174.490923) (xy 344.667988 -174.436739) (xy 344.667993 -174.381992) (xy 344.675828 -174.327809)
			(xy 344.691332 -174.275304) (xy 344.714186 -174.225556) (xy 344.74392 -174.179588) (xy 344.761566 -174.158656)
			(xy 344.76182 -174.158402) (xy 344.767414 -174.151321) (xy 344.773656 -174.1344) (xy 344.774012 -174.125382)
			(xy 344.774012 -174.058326) (xy 344.77364 -174.049311) (xy 344.767403 -174.032394) (xy 344.76182 -174.025306)
			(xy 344.761566 -174.025306) (xy 344.761566 -174.025052) (xy 344.743933 -174.004116) (xy 344.714221 -173.958143)
			(xy 344.691385 -173.908397) (xy 344.675892 -173.855897) (xy 344.668062 -173.801723) (xy 344.667586 -173.774354)
			(xy 344.667586 -173.7741) (xy 344.668066 -173.746084) (xy 344.676297 -173.69066) (xy 344.692536 -173.637032)
			(xy 344.716436 -173.586353) (xy 344.747484 -173.539709) (xy 344.765884 -173.518576) (xy 344.772488 -173.511464)
			(xy 344.779346 -173.493684) (xy 344.778076 -173.405292) (xy 344.771218 -173.38802) (xy 344.764614 -173.380908)
			(xy 344.745242 -173.359576) (xy 344.712517 -173.312148) (xy 344.6873 -173.260336) (xy 344.670166 -173.205321)
			(xy 344.661505 -173.148353) (xy 344.660982 -173.119542) (xy 339.094064 -173.119542) (xy 350.010984 -184.036462)
			(xy 352.88347 -184.036462) (xy 352.883955 -184.009092) (xy 352.891766 -183.954913) (xy 352.90725 -183.90241)
			(xy 352.930087 -183.852662) (xy 352.95981 -183.806696) (xy 352.97745 -183.785764) (xy 352.977704 -183.78551)
			(xy 352.983293 -183.778425) (xy 352.989538 -183.761507) (xy 352.989896 -183.75249) (xy 352.989896 -183.685434)
			(xy 352.989524 -183.676419) (xy 352.983287 -183.659501) (xy 352.977704 -183.652414) (xy 352.97745 -183.652414)
			(xy 352.97745 -183.65216) (xy 352.959771 -183.631258) (xy 352.930046 -183.585285) (xy 352.907202 -183.535534)
			(xy 352.891707 -183.483027) (xy 352.883882 -183.428844) (xy 352.883886 -183.374099) (xy 352.891719 -183.319917)
			(xy 352.907222 -183.267412) (xy 352.930074 -183.217664) (xy 352.959806 -183.171696) (xy 352.97745 -183.150764)
			(xy 352.977704 -183.15051) (xy 352.983293 -183.143425) (xy 352.989538 -183.126507) (xy 352.989896 -183.11749)
			(xy 352.989896 -183.050434) (xy 352.989524 -183.041419) (xy 352.983287 -183.024501) (xy 352.977704 -183.017414)
			(xy 352.97745 -183.017414) (xy 352.97745 -183.01716) (xy 352.959771 -182.996258) (xy 352.930046 -182.950285)
			(xy 352.907202 -182.900534) (xy 352.891707 -182.848027) (xy 352.883882 -182.793844) (xy 352.883886 -182.739099)
			(xy 352.891719 -182.684917) (xy 352.907222 -182.632412) (xy 352.930074 -182.582664) (xy 352.959806 -182.536696)
			(xy 352.97745 -182.515764) (xy 352.977704 -182.51551) (xy 352.983293 -182.508425) (xy 352.989538 -182.491507)
			(xy 352.989896 -182.48249) (xy 352.989896 -182.415434) (xy 352.989524 -182.406419) (xy 352.983287 -182.389501)
			(xy 352.977704 -182.382414) (xy 352.97745 -182.382414) (xy 352.97745 -182.38216) (xy 352.959833 -182.36121)
			(xy 352.930116 -182.315243) (xy 352.907275 -182.2655) (xy 352.891779 -182.213003) (xy 352.883946 -182.15883)
			(xy 352.88347 -182.131462) (xy 352.884003 -182.102829) (xy 352.892542 -182.046205) (xy 352.909453 -181.991494)
			(xy 352.934356 -181.939927) (xy 352.966689 -181.892665) (xy 352.985832 -181.871366) (xy 352.992436 -181.864254)
			(xy 352.999294 -181.846728) (xy 352.999802 -181.767988) (xy 352.999426 -181.75846) (xy 352.992519 -181.740705)
			(xy 352.98634 -181.733444) (xy 352.967563 -181.712232) (xy 352.935865 -181.665281) (xy 352.911464 -181.614157)
			(xy 352.894894 -181.559986) (xy 352.886523 -181.503959) (xy 352.88601 -181.475634) (xy 352.886487 -181.448381)
			(xy 352.89424 -181.39443) (xy 352.909592 -181.342131) (xy 352.932232 -181.29255) (xy 352.961698 -181.246696)
			(xy 352.997391 -181.205502) (xy 353.038583 -181.169808) (xy 353.084436 -181.14034) (xy 353.134016 -181.117698)
			(xy 353.186314 -181.102343) (xy 353.240265 -181.094588) (xy 353.267518 -181.094126) (xy 353.294889 -181.094575)
			(xy 353.349069 -181.102396) (xy 353.401573 -181.117889) (xy 353.451319 -181.140734) (xy 353.497285 -181.170463)
			(xy 353.518216 -181.188106) (xy 353.51847 -181.18836) (xy 353.525556 -181.193947) (xy 353.542473 -181.200192)
			(xy 353.55149 -181.200552) (xy 353.618546 -181.200552) (xy 353.627562 -181.20018) (xy 353.644479 -181.193944)
			(xy 353.651566 -181.18836) (xy 353.651566 -181.188106) (xy 353.65182 -181.188106) (xy 353.672753 -181.170465)
			(xy 353.718721 -181.140741) (xy 353.768467 -181.117895) (xy 353.820969 -181.102399) (xy 353.875147 -181.09457)
			(xy 353.929889 -181.09457) (xy 353.984067 -181.102399) (xy 354.036569 -181.117895) (xy 354.086315 -181.140741)
			(xy 354.132283 -181.170465) (xy 354.153216 -181.188106) (xy 354.15347 -181.18836) (xy 354.160556 -181.193947)
			(xy 354.177473 -181.200192) (xy 354.18649 -181.200552) (xy 354.253546 -181.200552) (xy 354.262562 -181.20018)
			(xy 354.279479 -181.193944) (xy 354.286566 -181.18836) (xy 354.286566 -181.188106) (xy 354.28682 -181.188106)
			(xy 354.307772 -181.170492) (xy 354.353739 -181.140776) (xy 354.403482 -181.117935) (xy 354.455978 -181.102438)
			(xy 354.51015 -181.094604) (xy 354.537518 -181.094126) (xy 354.564773 -181.094538) (xy 354.618727 -181.102299)
			(xy 354.671028 -181.117659) (xy 354.720611 -181.140306) (xy 354.766466 -181.169779) (xy 354.807659 -181.205478)
			(xy 354.843352 -181.246676) (xy 354.872819 -181.292535) (xy 354.89546 -181.34212) (xy 354.910813 -181.394423)
			(xy 354.918565 -181.448379) (xy 354.919026 -181.475634) (xy 356.90175 -181.475634) (xy 356.90231 -181.448386)
			(xy 356.910061 -181.394443) (xy 356.925409 -181.342152) (xy 356.948043 -181.292578) (xy 356.977502 -181.246729)
			(xy 357.013186 -181.20554) (xy 357.054368 -181.169848) (xy 357.100211 -181.14038) (xy 357.149781 -181.117736)
			(xy 357.202068 -181.102377) (xy 357.25601 -181.094615) (xy 357.283258 -181.094126) (xy 357.310628 -181.09461)
			(xy 357.364806 -181.102423) (xy 357.417309 -181.117907) (xy 357.467057 -181.140745) (xy 357.513024 -181.170466)
			(xy 357.533956 -181.188106) (xy 357.53421 -181.18836) (xy 357.541284 -181.193964) (xy 357.558211 -181.200199)
			(xy 357.56723 -181.200552) (xy 357.634286 -181.200552) (xy 357.643303 -181.200199) (xy 357.660221 -181.19395)
			(xy 357.667306 -181.18836) (xy 357.667306 -181.188106) (xy 357.66756 -181.188106) (xy 357.688497 -181.170473)
			(xy 357.734468 -181.14076) (xy 357.784215 -181.117923) (xy 357.836714 -181.10243) (xy 357.890889 -181.094601)
			(xy 357.918258 -181.094126) (xy 357.945511 -181.094594) (xy 357.999464 -181.102347) (xy 358.051764 -181.117699)
			(xy 358.101346 -181.140339) (xy 358.147201 -181.169806) (xy 358.188395 -181.205499) (xy 358.224089 -181.246693)
			(xy 358.253557 -181.292547) (xy 358.276198 -181.342129) (xy 358.291552 -181.394428) (xy 358.299305 -181.448381)
			(xy 358.299766 -181.475634) (xy 358.299284 -181.502768) (xy 358.291597 -181.556488) (xy 358.276368 -181.608574)
			(xy 358.253905 -181.657974) (xy 358.224663 -181.703689) (xy 358.20731 -181.724554) (xy 358.201671 -181.73176)
			(xy 358.195413 -181.748938) (xy 358.195118 -181.758082) (xy 358.195372 -181.824884) (xy 358.195871 -181.833939)
			(xy 358.202368 -181.850855) (xy 358.208072 -181.857904) (xy 358.208326 -181.858158) (xy 358.226238 -181.879168)
			(xy 358.256429 -181.92539) (xy 358.279641 -181.975482) (xy 358.295389 -182.028397) (xy 358.303344 -182.08303)
			(xy 358.30383 -182.110634) (xy 358.303401 -182.138006) (xy 358.295577 -182.192187) (xy 358.28008 -182.244691)
			(xy 358.25723 -182.294438) (xy 358.227496 -182.340402) (xy 358.20985 -182.361332) (xy 358.209596 -182.361586)
			(xy 358.204009 -182.368672) (xy 358.197763 -182.385589) (xy 358.197404 -182.394606) (xy 358.197404 -182.461662)
			(xy 358.197779 -182.470677) (xy 358.204014 -182.487594) (xy 358.209596 -182.494682) (xy 358.20985 -182.494682)
			(xy 358.20985 -182.494936) (xy 358.227525 -182.515841) (xy 358.25725 -182.561813) (xy 358.280095 -182.611564)
			(xy 358.29559 -182.66407) (xy 358.303415 -182.718253) (xy 358.303412 -182.772998) (xy 358.295579 -182.82718)
			(xy 358.280077 -182.879684) (xy 358.257225 -182.929432) (xy 358.227494 -182.9754) (xy 358.20985 -182.996332)
			(xy 358.209596 -182.996586) (xy 358.204009 -183.003672) (xy 358.197763 -183.020589) (xy 358.197404 -183.029606)
			(xy 358.197404 -183.096662) (xy 358.197779 -183.105677) (xy 358.204014 -183.122594) (xy 358.209596 -183.129682)
			(xy 358.20985 -183.129682) (xy 358.20985 -183.129936) (xy 358.227525 -183.150841) (xy 358.25725 -183.196813)
			(xy 358.280095 -183.246564) (xy 358.29559 -183.29907) (xy 358.303415 -183.353253) (xy 358.303412 -183.407998)
			(xy 358.295579 -183.46218) (xy 358.280077 -183.514684) (xy 358.257225 -183.564432) (xy 358.227494 -183.6104)
			(xy 358.20985 -183.631332) (xy 358.209596 -183.631586) (xy 358.204009 -183.638672) (xy 358.197763 -183.655589)
			(xy 358.197404 -183.664606) (xy 358.197404 -183.731662) (xy 358.197779 -183.740677) (xy 358.204014 -183.757594)
			(xy 358.209596 -183.764682) (xy 358.20985 -183.764682) (xy 358.20985 -183.764936) (xy 358.227465 -183.785888)
			(xy 358.257182 -183.831854) (xy 358.280023 -183.881597) (xy 358.29552 -183.934093) (xy 358.303353 -183.988266)
			(xy 358.30383 -184.015634) (xy 358.303325 -184.043343) (xy 358.295298 -184.098177) (xy 358.279418 -184.151271)
			(xy 358.25602 -184.201507) (xy 358.225597 -184.247828) (xy 358.207564 -184.268872) (xy 358.207564 -184.269126)
			(xy 358.201701 -184.27638) (xy 358.195184 -184.29384) (xy 358.194864 -184.303162) (xy 358.195372 -184.371488)
			(xy 358.195926 -184.380747) (xy 358.202833 -184.397943) (xy 358.208834 -184.405016) (xy 358.208834 -184.40527)
			(xy 358.227749 -184.426502) (xy 358.259679 -184.473552) (xy 358.284265 -184.524824) (xy 358.300964 -184.579179)
			(xy 358.309403 -184.635411) (xy 358.309926 -184.663842) (xy 358.309444 -184.691212) (xy 358.301633 -184.745391)
			(xy 358.286148 -184.797895) (xy 358.26331 -184.847642) (xy 358.233587 -184.893609) (xy 358.215946 -184.91454)
			(xy 358.215692 -184.914794) (xy 358.210101 -184.921877) (xy 358.203857 -184.938797) (xy 358.2035 -184.947814)
			(xy 358.2035 -185.01487) (xy 358.203871 -185.023885) (xy 358.210109 -185.040803) (xy 358.215692 -185.04789)
			(xy 358.215946 -185.04789) (xy 358.215946 -185.048144) (xy 358.233629 -185.069043) (xy 358.263354 -185.115016)
			(xy 358.286199 -185.164768) (xy 358.301693 -185.217275) (xy 358.309518 -185.271459) (xy 358.309514 -185.326205)
			(xy 358.301679 -185.380387) (xy 358.286176 -185.432892) (xy 358.263324 -185.48264) (xy 358.233591 -185.528608)
			(xy 358.215946 -185.54954) (xy 358.215692 -185.549794) (xy 358.210101 -185.556877) (xy 358.203857 -185.573797)
			(xy 358.2035 -185.582814) (xy 358.2035 -185.64987) (xy 358.203871 -185.658885) (xy 358.210109 -185.675803)
			(xy 358.215692 -185.68289) (xy 358.215946 -185.68289) (xy 358.215946 -185.683144) (xy 358.233629 -185.704043)
			(xy 358.263354 -185.750016) (xy 358.286199 -185.799768) (xy 358.301693 -185.852275) (xy 358.309518 -185.906459)
			(xy 358.309514 -185.961205) (xy 358.301679 -186.015387) (xy 358.286176 -186.067892) (xy 358.263324 -186.11764)
			(xy 358.233591 -186.163608) (xy 358.215946 -186.18454) (xy 358.215692 -186.184794) (xy 358.210101 -186.191877)
			(xy 358.203857 -186.208797) (xy 358.2035 -186.217814) (xy 358.2035 -186.28487) (xy 358.203871 -186.293885)
			(xy 358.210109 -186.310803) (xy 358.215692 -186.31789) (xy 358.215946 -186.31789) (xy 358.215946 -186.318144)
			(xy 358.233629 -186.339043) (xy 358.263354 -186.385016) (xy 358.286199 -186.434768) (xy 358.301693 -186.487275)
			(xy 358.309518 -186.541459) (xy 358.309514 -186.596205) (xy 358.301679 -186.650387) (xy 358.286176 -186.702892)
			(xy 358.263324 -186.75264) (xy 358.233591 -186.798608) (xy 358.215946 -186.81954) (xy 358.215692 -186.819794)
			(xy 358.210101 -186.826877) (xy 358.203857 -186.843797) (xy 358.2035 -186.852814) (xy 358.2035 -186.91987)
			(xy 358.203871 -186.928885) (xy 358.210109 -186.945803) (xy 358.21109 -186.947048) (xy 404.034244 -186.947048)
			(xy 404.034727 -186.919678) (xy 404.042539 -186.8655) (xy 404.058024 -186.812996) (xy 404.080862 -186.763249)
			(xy 404.110584 -186.717282) (xy 404.128224 -186.69635) (xy 404.128478 -186.696096) (xy 404.134081 -186.689021)
			(xy 404.140316 -186.672095) (xy 404.14067 -186.663076) (xy 404.14067 -186.59602) (xy 404.14031 -186.587003)
			(xy 404.134065 -186.570086) (xy 404.128478 -186.563) (xy 404.128224 -186.563) (xy 404.128224 -186.562746)
			(xy 404.11063 -186.541775) (xy 404.080904 -186.495814) (xy 404.058056 -186.446074) (xy 404.042556 -186.393578)
			(xy 404.034723 -186.339404) (xy 404.034718 -186.284668) (xy 404.042541 -186.230493) (xy 404.058031 -186.177994)
			(xy 404.080869 -186.12825) (xy 404.110587 -186.082283) (xy 404.128224 -186.06135) (xy 404.128478 -186.061096)
			(xy 404.134081 -186.054021) (xy 404.140316 -186.037095) (xy 404.14067 -186.028076) (xy 404.14067 -185.96102)
			(xy 404.14031 -185.952003) (xy 404.134065 -185.935086) (xy 404.128478 -185.928) (xy 404.128224 -185.928)
			(xy 404.128224 -185.927746) (xy 404.11063 -185.906775) (xy 404.080904 -185.860814) (xy 404.058056 -185.811074)
			(xy 404.042556 -185.758578) (xy 404.034723 -185.704404) (xy 404.034718 -185.649668) (xy 404.042541 -185.595493)
			(xy 404.058031 -185.542994) (xy 404.080869 -185.49325) (xy 404.110587 -185.447283) (xy 404.128224 -185.42635)
			(xy 404.128478 -185.426096) (xy 404.134081 -185.419021) (xy 404.140316 -185.402095) (xy 404.14067 -185.393076)
			(xy 404.14067 -185.32602) (xy 404.14031 -185.317003) (xy 404.134065 -185.300086) (xy 404.128478 -185.293)
			(xy 404.128224 -185.293) (xy 404.128224 -185.292746) (xy 404.11063 -185.271775) (xy 404.080904 -185.225814)
			(xy 404.058056 -185.176074) (xy 404.042556 -185.123578) (xy 404.034723 -185.069404) (xy 404.034718 -185.014668)
			(xy 404.042541 -184.960493) (xy 404.058031 -184.907994) (xy 404.080869 -184.85825) (xy 404.110587 -184.812283)
			(xy 404.128224 -184.79135) (xy 404.128478 -184.791096) (xy 404.134081 -184.784021) (xy 404.140316 -184.767095)
			(xy 404.14067 -184.758076) (xy 404.14067 -184.69102) (xy 404.14031 -184.682003) (xy 404.134065 -184.665086)
			(xy 404.128478 -184.658) (xy 404.128224 -184.658) (xy 404.128224 -184.657746) (xy 404.11063 -184.636775)
			(xy 404.080904 -184.590814) (xy 404.058056 -184.541074) (xy 404.042556 -184.488578) (xy 404.034723 -184.434404)
			(xy 404.034718 -184.379668) (xy 404.042541 -184.325493) (xy 404.058031 -184.272994) (xy 404.080869 -184.22325)
			(xy 404.110587 -184.177283) (xy 404.128224 -184.15635) (xy 404.128478 -184.156096) (xy 404.134081 -184.149021)
			(xy 404.140316 -184.132095) (xy 404.14067 -184.123076) (xy 404.14067 -184.05602) (xy 404.14031 -184.047003)
			(xy 404.134065 -184.030086) (xy 404.128478 -184.023) (xy 404.128224 -184.023) (xy 404.128224 -184.022746)
			(xy 404.110597 -184.001804) (xy 404.080882 -183.955835) (xy 404.058044 -183.90609) (xy 404.04255 -183.853591)
			(xy 404.034719 -183.799417) (xy 404.034244 -183.772048) (xy 404.034643 -183.746226) (xy 404.041601 -183.695052)
			(xy 404.055395 -183.645284) (xy 404.075773 -183.597831) (xy 404.102365 -183.553559) (xy 404.134683 -183.513276)
			(xy 404.153116 -183.495188) (xy 404.160228 -183.488584) (xy 404.168356 -183.471058) (xy 404.172928 -183.392064)
			(xy 404.173113 -183.382582) (xy 404.167234 -183.364565) (xy 404.161498 -183.357012) (xy 404.161498 -183.356758)
			(xy 404.144997 -183.336149) (xy 404.117263 -183.291225) (xy 404.095989 -183.242906) (xy 404.081579 -183.192116)
			(xy 404.07431 -183.139824) (xy 404.073868 -183.113426) (xy 404.074333 -183.086056) (xy 404.082148 -183.031876)
			(xy 404.097637 -182.979372) (xy 404.120479 -182.929625) (xy 404.150206 -182.883659) (xy 404.167848 -182.862728)
			(xy 404.168102 -182.862474) (xy 404.173664 -182.855371) (xy 404.179925 -182.838467) (xy 404.180294 -182.829454)
			(xy 404.180294 -182.762398) (xy 404.179939 -182.753381) (xy 404.17369 -182.736464) (xy 404.168102 -182.729378)
			(xy 404.167848 -182.729378) (xy 404.167848 -182.729124) (xy 404.150232 -182.708171) (xy 404.120504 -182.662207)
			(xy 404.097656 -182.612464) (xy 404.082157 -182.559965) (xy 404.074326 -182.505789) (xy 404.074323 -182.45105)
			(xy 404.082149 -182.396873) (xy 404.097643 -182.344372) (xy 404.120486 -182.294627) (xy 404.150208 -182.24866)
			(xy 404.167848 -182.227728) (xy 404.168102 -182.227474) (xy 404.173664 -182.220371) (xy 404.179925 -182.203467)
			(xy 404.180294 -182.194454) (xy 404.180294 -182.127398) (xy 404.179939 -182.118381) (xy 404.17369 -182.101464)
			(xy 404.168102 -182.094378) (xy 404.167848 -182.094378) (xy 404.167848 -182.094124) (xy 404.150232 -182.073171)
			(xy 404.120504 -182.027207) (xy 404.097656 -181.977464) (xy 404.082157 -181.924965) (xy 404.074326 -181.870789)
			(xy 404.074323 -181.81605) (xy 404.082149 -181.761873) (xy 404.097643 -181.709372) (xy 404.120486 -181.659627)
			(xy 404.150208 -181.61366) (xy 404.167848 -181.592728) (xy 404.168102 -181.592474) (xy 404.173664 -181.585371)
			(xy 404.179925 -181.568467) (xy 404.180294 -181.559454) (xy 404.180294 -181.492398) (xy 404.179939 -181.483381)
			(xy 404.17369 -181.466464) (xy 404.168102 -181.459378) (xy 404.167848 -181.459378) (xy 404.167848 -181.459124)
			(xy 404.150214 -181.438188) (xy 404.1205 -181.392217) (xy 404.097662 -181.34247) (xy 404.08217 -181.28997)
			(xy 404.074342 -181.235795) (xy 404.073868 -181.208426) (xy 404.074379 -181.181175) (xy 404.082132 -181.127227)
			(xy 404.097484 -181.074931) (xy 404.120121 -181.025353) (xy 404.149585 -180.979501) (xy 404.185273 -180.938309)
			(xy 404.226461 -180.902615) (xy 404.272309 -180.873145) (xy 404.321885 -180.850501) (xy 404.374178 -180.835143)
			(xy 404.428125 -180.827383) (xy 404.455376 -180.826918) (xy 404.484853 -180.827468) (xy 404.543106 -180.836534)
			(xy 404.599271 -180.854454) (xy 404.65201 -180.880801) (xy 404.700069 -180.914948) (xy 404.721568 -180.935122)
			(xy 404.728916 -180.941639) (xy 404.747066 -180.949094) (xy 404.756874 -180.9496) (xy 404.810214 -180.9496)
			(xy 404.814532 -180.945028) (xy 404.82087 -180.937623) (xy 404.827914 -180.919464) (xy 404.828248 -180.909722)
			(xy 404.827994 -180.877718) (xy 404.827431 -180.867883) (xy 404.819867 -180.849718) (xy 404.813262 -180.842412)
			(xy 404.792587 -180.820843) (xy 404.757575 -180.772433) (xy 404.73054 -180.719156) (xy 404.712144 -180.662314)
			(xy 404.702839 -180.603298) (xy 404.702264 -180.573426) (xy 404.70275 -180.546175) (xy 404.710506 -180.492227)
			(xy 404.725861 -180.439932) (xy 404.748503 -180.390355) (xy 404.777969 -180.344505) (xy 404.81366 -180.303314)
			(xy 404.854851 -180.267623) (xy 404.900701 -180.238157) (xy 404.950278 -180.215515) (xy 405.002573 -180.20016)
			(xy 405.056521 -180.192404) (xy 405.111023 -180.192404) (xy 405.164971 -180.20016) (xy 405.217266 -180.215515)
			(xy 405.266843 -180.238157) (xy 405.312693 -180.267623) (xy 405.353884 -180.303314) (xy 405.389575 -180.344505)
			(xy 405.419041 -180.390355) (xy 405.441683 -180.439932) (xy 405.457038 -180.492227) (xy 405.464794 -180.546175)
			(xy 405.46528 -180.573426) (xy 405.464827 -180.600396) (xy 405.457217 -180.653797) (xy 405.442154 -180.705592)
			(xy 405.419938 -180.754745) (xy 405.391013 -180.800274) (xy 405.37384 -180.821076) (xy 405.368308 -180.828253)
			(xy 405.362184 -180.845293) (xy 405.361902 -180.85435) (xy 405.362664 -180.930804) (xy 405.369014 -180.947568)
			(xy 405.375364 -180.95468) (xy 405.393471 -180.975739) (xy 405.423972 -181.022152) (xy 405.447429 -181.072495)
			(xy 405.463345 -181.125703) (xy 405.471387 -181.180657) (xy 405.471884 -181.208426) (xy 405.471437 -181.235797)
			(xy 405.463615 -181.289977) (xy 405.448122 -181.342481) (xy 405.425276 -181.392227) (xy 405.395547 -181.438193)
			(xy 405.377904 -181.459124) (xy 405.37765 -181.459378) (xy 405.372061 -181.466462) (xy 405.365817 -181.483381)
			(xy 405.365458 -181.492398) (xy 405.365458 -181.559454) (xy 405.365824 -181.56847) (xy 405.372064 -181.585388)
			(xy 405.37765 -181.592474) (xy 405.377904 -181.592474) (xy 405.377904 -181.592728) (xy 405.395569 -181.613641)
			(xy 405.42529 -181.659613) (xy 405.448132 -181.709363) (xy 405.463625 -181.761867) (xy 405.471451 -181.816048)
			(xy 405.471448 -181.870791) (xy 405.463617 -181.924971) (xy 405.448118 -181.977474) (xy 405.425271 -182.027222)
			(xy 405.395545 -182.073191) (xy 405.377904 -182.094124) (xy 405.37765 -182.094378) (xy 405.372061 -182.101462)
			(xy 405.365817 -182.118381) (xy 405.365458 -182.127398) (xy 405.365458 -182.194454) (xy 405.365824 -182.20347)
			(xy 405.372064 -182.220388) (xy 405.37765 -182.227474) (xy 405.377904 -182.227474) (xy 405.377904 -182.227728)
			(xy 405.395569 -182.248641) (xy 405.42529 -182.294613) (xy 405.448132 -182.344363) (xy 405.463625 -182.396867)
			(xy 405.471451 -182.451048) (xy 405.471448 -182.505791) (xy 405.463617 -182.559971) (xy 405.448118 -182.612474)
			(xy 405.425271 -182.662222) (xy 405.395545 -182.708191) (xy 405.377904 -182.729124) (xy 405.37765 -182.729378)
			(xy 405.372061 -182.736462) (xy 405.365817 -182.753381) (xy 405.365458 -182.762398) (xy 405.365458 -182.829454)
			(xy 405.365824 -182.83847) (xy 405.372064 -182.855388) (xy 405.37765 -182.862474) (xy 405.377904 -182.862474)
			(xy 405.377904 -182.862728) (xy 405.395523 -182.883676) (xy 405.425238 -182.929644) (xy 405.448078 -182.979388)
			(xy 405.463573 -183.031885) (xy 405.471407 -183.086058) (xy 405.471884 -183.113426) (xy 405.47149 -183.139249)
			(xy 405.464535 -183.190423) (xy 405.450741 -183.240192) (xy 405.430361 -183.287646) (xy 405.403768 -183.331918)
			(xy 405.371447 -183.372199) (xy 405.353012 -183.390286) (xy 405.3459 -183.39689) (xy 405.337772 -183.414416)
			(xy 405.3332 -183.49341) (xy 405.333023 -183.502892) (xy 405.338896 -183.520908) (xy 405.34463 -183.528462)
			(xy 405.34463 -183.528716) (xy 405.361123 -183.549331) (xy 405.388857 -183.594254) (xy 405.410133 -183.642571)
			(xy 405.424544 -183.69336) (xy 405.431816 -183.745651) (xy 405.43226 -183.772048) (xy 405.431773 -183.799418)
			(xy 405.423962 -183.853596) (xy 405.408478 -183.906099) (xy 405.385641 -183.955847) (xy 405.35592 -184.001814)
			(xy 405.33828 -184.022746) (xy 405.338026 -184.023) (xy 405.332425 -184.030076) (xy 405.326189 -184.047001)
			(xy 405.325834 -184.05602) (xy 405.325834 -184.123076) (xy 405.326195 -184.132093) (xy 405.332439 -184.14901)
			(xy 405.338026 -184.156096) (xy 405.33828 -184.156096) (xy 405.33828 -184.15635) (xy 405.355967 -184.177245)
			(xy 405.38569 -184.223219) (xy 405.408532 -184.272972) (xy 405.424024 -184.32548) (xy 405.431848 -184.379663)
			(xy 405.431843 -184.434409) (xy 405.424009 -184.488591) (xy 405.408506 -184.541096) (xy 405.385655 -184.590844)
			(xy 405.355924 -184.636813) (xy 405.33828 -184.657746) (xy 405.338026 -184.658) (xy 405.332425 -184.665076)
			(xy 405.326189 -184.682001) (xy 405.325834 -184.69102) (xy 405.325834 -184.758076) (xy 405.326195 -184.767093)
			(xy 405.332439 -184.78401) (xy 405.338026 -184.791096) (xy 405.33828 -184.791096) (xy 405.33828 -184.79135)
			(xy 405.355967 -184.812245) (xy 405.38569 -184.858219) (xy 405.408532 -184.907972) (xy 405.424024 -184.96048)
			(xy 405.431848 -185.014663) (xy 405.431845 -185.042048) (xy 407.445464 -185.042048) (xy 407.445943 -185.014678)
			(xy 407.453755 -184.960499) (xy 407.46924 -184.907995) (xy 407.49208 -184.858248) (xy 407.521803 -184.812281)
			(xy 407.539444 -184.79135) (xy 407.539698 -184.791096) (xy 407.545292 -184.784015) (xy 407.551534 -184.767094)
			(xy 407.55189 -184.758076) (xy 407.55189 -184.69102) (xy 407.551526 -184.682004) (xy 407.545284 -184.665087)
			(xy 407.539698 -184.658) (xy 407.539444 -184.658) (xy 407.539444 -184.657746) (xy 407.52185 -184.636776)
			(xy 407.492122 -184.590815) (xy 407.469272 -184.541075) (xy 407.453772 -184.488578) (xy 407.445938 -184.434405)
			(xy 407.445933 -184.379668) (xy 407.453756 -184.325492) (xy 407.469247 -184.272993) (xy 407.492087 -184.223249)
			(xy 407.521806 -184.177282) (xy 407.539444 -184.15635) (xy 407.539698 -184.156096) (xy 407.545292 -184.149015)
			(xy 407.551534 -184.132094) (xy 407.55189 -184.123076) (xy 407.55189 -184.05602) (xy 407.551526 -184.047004)
			(xy 407.545284 -184.030087) (xy 407.539698 -184.023) (xy 407.539444 -184.023) (xy 407.539444 -184.022746)
			(xy 407.52182 -184.001802) (xy 407.492104 -183.955833) (xy 407.469265 -183.906089) (xy 407.45377 -183.85359)
			(xy 407.445939 -183.799416) (xy 407.445464 -183.772048) (xy 407.446035 -183.743037) (xy 407.454796 -183.685682)
			(xy 407.472139 -183.630313) (xy 407.497665 -183.578209) (xy 407.530784 -183.530569) (xy 407.550366 -183.509158)
			(xy 407.557224 -183.5023) (xy 407.564336 -183.484266) (xy 407.565352 -183.39562) (xy 407.558494 -183.37784)
			(xy 407.55189 -183.370728) (xy 407.533224 -183.349514) (xy 407.501686 -183.30263) (xy 407.477407 -183.251608)
			(xy 407.460918 -183.197564) (xy 407.452581 -183.141678) (xy 407.452068 -183.113426) (xy 407.452533 -183.086056)
			(xy 407.460348 -183.031876) (xy 407.475837 -182.979372) (xy 407.498679 -182.929625) (xy 407.528406 -182.883659)
			(xy 407.546048 -182.862728) (xy 407.546302 -182.862474) (xy 407.551864 -182.855371) (xy 407.558125 -182.838467)
			(xy 407.558494 -182.829454) (xy 407.558494 -182.762398) (xy 407.558139 -182.753381) (xy 407.55189 -182.736464)
			(xy 407.546302 -182.729378) (xy 407.546048 -182.729378) (xy 407.546048 -182.729124) (xy 407.528432 -182.708171)
			(xy 407.498704 -182.662207) (xy 407.475856 -182.612464) (xy 407.460357 -182.559965) (xy 407.452526 -182.505789)
			(xy 407.452523 -182.45105) (xy 407.460349 -182.396873) (xy 407.475843 -182.344372) (xy 407.498686 -182.294627)
			(xy 407.528408 -182.24866) (xy 407.546048 -182.227728) (xy 407.546302 -182.227474) (xy 407.551864 -182.220371)
			(xy 407.558125 -182.203467) (xy 407.558494 -182.194454) (xy 407.558494 -182.127398) (xy 407.558139 -182.118381)
			(xy 407.55189 -182.101464) (xy 407.546302 -182.094378) (xy 407.546048 -182.094378) (xy 407.546048 -182.094124)
			(xy 407.528432 -182.073171) (xy 407.498704 -182.027207) (xy 407.475856 -181.977464) (xy 407.460357 -181.924965)
			(xy 407.452526 -181.870789) (xy 407.452523 -181.81605) (xy 407.460349 -181.761873) (xy 407.475843 -181.709372)
			(xy 407.498686 -181.659627) (xy 407.528408 -181.61366) (xy 407.546048 -181.592728) (xy 407.546302 -181.592474)
			(xy 407.551864 -181.585371) (xy 407.558125 -181.568467) (xy 407.558494 -181.559454) (xy 407.558494 -181.492398)
			(xy 407.558139 -181.483381) (xy 407.55189 -181.466464) (xy 407.546302 -181.459378) (xy 407.546048 -181.459378)
			(xy 407.546048 -181.459124) (xy 407.528414 -181.438188) (xy 407.4987 -181.392217) (xy 407.475862 -181.34247)
			(xy 407.46037 -181.28997) (xy 407.452542 -181.235795) (xy 407.452068 -181.208426) (xy 407.452518 -181.181291)
			(xy 407.460212 -181.127569) (xy 407.475448 -181.075482) (xy 407.497918 -181.026083) (xy 407.527168 -180.98037)
			(xy 407.544524 -180.959506) (xy 407.550184 -180.952315) (xy 407.556428 -180.935125) (xy 407.556716 -180.925978)
			(xy 407.556462 -180.859176) (xy 407.555974 -180.85012) (xy 407.549469 -180.833204) (xy 407.543762 -180.826156)
			(xy 407.543508 -180.825902) (xy 407.52563 -180.804865) (xy 407.495432 -180.758651) (xy 407.472213 -180.708566)
			(xy 407.456458 -180.655657) (xy 407.448495 -180.601029) (xy 407.448004 -180.573426) (xy 407.44848 -180.546173)
			(xy 407.456233 -180.492222) (xy 407.471587 -180.439924) (xy 407.494227 -180.390343) (xy 407.523693 -180.344489)
			(xy 407.559386 -180.303296) (xy 407.600578 -180.267602) (xy 407.646431 -180.238134) (xy 407.696011 -180.215492)
			(xy 407.748308 -180.200136) (xy 407.802259 -180.192381) (xy 407.829512 -180.191918) (xy 407.856883 -180.192373)
			(xy 407.911062 -180.200193) (xy 407.963566 -180.215684) (xy 408.013313 -180.238528) (xy 408.059279 -180.268256)
			(xy 408.08021 -180.285898) (xy 408.080464 -180.286152) (xy 408.087552 -180.291736) (xy 408.104468 -180.297983)
			(xy 408.113484 -180.298344) (xy 408.18054 -180.298344) (xy 408.18956 -180.298018) (xy 408.206478 -180.29175)
			(xy 408.21356 -180.286152) (xy 408.21356 -180.285898) (xy 408.213814 -180.285898) (xy 408.234747 -180.268257)
			(xy 408.280715 -180.238533) (xy 408.330461 -180.215687) (xy 408.382963 -180.200191) (xy 408.437141 -180.192362)
			(xy 408.491883 -180.192362) (xy 408.546061 -180.200191) (xy 408.598563 -180.215687) (xy 408.648309 -180.238533)
			(xy 408.694277 -180.268257) (xy 408.71521 -180.285898) (xy 408.715464 -180.286152) (xy 408.722552 -180.291736)
			(xy 408.739468 -180.297983) (xy 408.748484 -180.298344) (xy 408.81554 -180.298344) (xy 408.82456 -180.298018)
			(xy 408.841478 -180.29175) (xy 408.84856 -180.286152) (xy 408.84856 -180.285898) (xy 408.848814 -180.285898)
			(xy 408.869767 -180.268285) (xy 408.915734 -180.23857) (xy 408.965476 -180.215729) (xy 409.017972 -180.200231)
			(xy 409.072144 -180.192396) (xy 409.099512 -180.191918) (xy 409.126766 -180.192344) (xy 409.18072 -180.200103)
			(xy 409.23302 -180.215462) (xy 409.282602 -180.238108) (xy 409.328457 -180.267579) (xy 409.36965 -180.303277)
			(xy 409.405343 -180.344474) (xy 409.43481 -180.390331) (xy 409.457451 -180.439915) (xy 409.472805 -180.492217)
			(xy 409.480559 -180.546172) (xy 409.48102 -180.573426) (xy 409.480529 -180.600759) (xy 409.472725 -180.654865)
			(xy 409.45728 -180.707303) (xy 409.43451 -180.757001) (xy 409.404881 -180.802942) (xy 409.387294 -180.82387)
			(xy 409.38704 -180.824124) (xy 409.381121 -180.831613) (xy 409.374859 -180.84963) (xy 409.374857 -180.851048)
			(xy 412.39821 -180.851048) (xy 412.398702 -180.823679) (xy 412.406513 -180.769501) (xy 412.421996 -180.716998)
			(xy 412.444832 -180.66725) (xy 412.474551 -180.621282) (xy 412.49219 -180.60035) (xy 412.492444 -180.600096)
			(xy 412.498044 -180.593019) (xy 412.504281 -180.576095) (xy 412.504636 -180.567076) (xy 412.504636 -180.50002)
			(xy 412.504261 -180.491005) (xy 412.498025 -180.474088) (xy 412.492444 -180.467) (xy 412.49219 -180.467)
			(xy 412.49219 -180.466746) (xy 412.474598 -180.445774) (xy 412.444874 -180.399812) (xy 412.422028 -180.350072)
			(xy 412.40653 -180.297577) (xy 412.398697 -180.243404) (xy 412.398692 -180.188668) (xy 412.406514 -180.134494)
			(xy 412.422003 -180.081995) (xy 412.444839 -180.032251) (xy 412.474554 -179.986283) (xy 412.49219 -179.96535)
			(xy 412.492444 -179.965096) (xy 412.498044 -179.958019) (xy 412.504281 -179.941095) (xy 412.504636 -179.932076)
			(xy 412.504636 -179.86502) (xy 412.504261 -179.856005) (xy 412.498025 -179.839088) (xy 412.492444 -179.832)
			(xy 412.49219 -179.832) (xy 412.49219 -179.831746) (xy 412.474598 -179.810774) (xy 412.444874 -179.764812)
			(xy 412.422028 -179.715072) (xy 412.40653 -179.662577) (xy 412.398697 -179.608404) (xy 412.398692 -179.553668)
			(xy 412.406514 -179.499494) (xy 412.422003 -179.446995) (xy 412.444839 -179.397251) (xy 412.474554 -179.351283)
			(xy 412.49219 -179.33035) (xy 412.492444 -179.330096) (xy 412.498044 -179.323019) (xy 412.504281 -179.306095)
			(xy 412.504636 -179.297076) (xy 412.504636 -179.23002) (xy 412.504261 -179.221005) (xy 412.498025 -179.204088)
			(xy 412.492444 -179.197) (xy 412.49219 -179.197) (xy 412.49219 -179.196746) (xy 412.474557 -179.175809)
			(xy 412.444845 -179.129837) (xy 412.422008 -179.080091) (xy 412.406515 -179.027592) (xy 412.398685 -178.973417)
			(xy 412.39821 -178.946048) (xy 412.398768 -178.917037) (xy 412.407531 -178.85968) (xy 412.424876 -178.804311)
			(xy 412.450405 -178.752207) (xy 412.483528 -178.704568) (xy 412.503112 -178.683158) (xy 412.50997 -178.6763)
			(xy 412.517082 -178.658266) (xy 412.518098 -178.56962) (xy 412.51124 -178.55184) (xy 412.504636 -178.544728)
			(xy 412.485962 -178.523521) (xy 412.454426 -178.476635) (xy 412.43015 -178.425611) (xy 412.413663 -178.371565)
			(xy 412.405327 -178.315678) (xy 412.404814 -178.287426) (xy 412.405292 -178.260056) (xy 412.413106 -178.205877)
			(xy 412.428592 -178.153374) (xy 412.451432 -178.103627) (xy 412.481154 -178.05766) (xy 412.498794 -178.036728)
			(xy 412.499048 -178.036474) (xy 412.504616 -178.029375) (xy 412.510872 -178.012467) (xy 412.51124 -178.003454)
			(xy 412.51124 -177.936398) (xy 412.510897 -177.927379) (xy 412.504641 -177.910462) (xy 412.499048 -177.903378)
			(xy 412.498794 -177.903378) (xy 412.498794 -177.903124) (xy 412.48118 -177.88217) (xy 412.451457 -177.836205)
			(xy 412.428612 -177.786462) (xy 412.413115 -177.733964) (xy 412.405285 -177.679789) (xy 412.405282 -177.625051)
			(xy 412.413107 -177.570875) (xy 412.428598 -177.518375) (xy 412.451438 -177.468629) (xy 412.481157 -177.422661)
			(xy 412.498794 -177.401728) (xy 412.499048 -177.401474) (xy 412.504616 -177.394375) (xy 412.510872 -177.377467)
			(xy 412.51124 -177.368454) (xy 412.51124 -177.301398) (xy 412.510897 -177.292379) (xy 412.504641 -177.275462)
			(xy 412.499048 -177.268378) (xy 412.498794 -177.268378) (xy 412.498794 -177.268124) (xy 412.48118 -177.24717)
			(xy 412.451457 -177.201205) (xy 412.428612 -177.151462) (xy 412.413115 -177.098964) (xy 412.405285 -177.044789)
			(xy 412.405282 -176.990051) (xy 412.413107 -176.935875) (xy 412.428598 -176.883375) (xy 412.451438 -176.833629)
			(xy 412.481157 -176.787661) (xy 412.498794 -176.766728) (xy 412.499048 -176.766474) (xy 412.504616 -176.759375)
			(xy 412.510872 -176.742467) (xy 412.51124 -176.733454) (xy 412.51124 -176.666398) (xy 412.510897 -176.657379)
			(xy 412.504641 -176.640462) (xy 412.499048 -176.633378) (xy 412.498794 -176.633378) (xy 412.498794 -176.633124)
			(xy 412.481152 -176.612194) (xy 412.451441 -176.566221) (xy 412.428605 -176.516473) (xy 412.413115 -176.463972)
			(xy 412.405288 -176.409795) (xy 412.404814 -176.382426) (xy 412.405298 -176.355457) (xy 412.412901 -176.302057)
			(xy 412.427957 -176.250263) (xy 412.450166 -176.20111) (xy 412.479085 -176.155579) (xy 412.496254 -176.134776)
			(xy 412.501806 -176.127612) (xy 412.507918 -176.110562) (xy 412.508192 -176.101502) (xy 412.50743 -176.025048)
			(xy 412.50108 -176.008284) (xy 412.49473 -176.001172) (xy 412.476663 -175.98008) (xy 412.446152 -175.933677)
			(xy 412.422686 -175.883344) (xy 412.406761 -175.830142) (xy 412.398711 -175.775193) (xy 412.39821 -175.747426)
			(xy 412.39868 -175.720173) (xy 412.406433 -175.666221) (xy 412.421787 -175.613922) (xy 412.444428 -175.564341)
			(xy 412.473895 -175.518487) (xy 412.509588 -175.477294) (xy 412.550781 -175.4416) (xy 412.596634 -175.412132)
			(xy 412.646215 -175.38949) (xy 412.698514 -175.374135) (xy 412.752465 -175.36638) (xy 412.779718 -175.365918)
			(xy 412.807089 -175.366369) (xy 412.861269 -175.37419) (xy 412.913772 -175.389682) (xy 412.963519 -175.412527)
			(xy 413.009485 -175.442255) (xy 413.030416 -175.459898) (xy 413.03067 -175.460152) (xy 413.037756 -175.465738)
			(xy 413.054674 -175.471984) (xy 413.06369 -175.472344) (xy 413.130746 -175.472344) (xy 413.139762 -175.471973)
			(xy 413.156679 -175.465737) (xy 413.163766 -175.460152) (xy 413.163766 -175.459898) (xy 413.16402 -175.459898)
			(xy 413.184971 -175.442283) (xy 413.230939 -175.412567) (xy 413.280681 -175.389727) (xy 413.333178 -175.37423)
			(xy 413.38735 -175.366396) (xy 413.414718 -175.365918) (xy 413.441973 -175.366338) (xy 413.495926 -175.374098)
			(xy 413.548227 -175.389458) (xy 413.597809 -175.412104) (xy 413.643663 -175.441577) (xy 413.684856 -175.477275)
			(xy 413.72055 -175.518472) (xy 413.750017 -175.56433) (xy 413.772657 -175.613915) (xy 413.788011 -175.666217)
			(xy 413.795765 -175.720171) (xy 413.796226 -175.747426) (xy 413.795786 -175.774397) (xy 413.788175 -175.827799)
			(xy 413.773109 -175.879594) (xy 413.75089 -175.928747) (xy 413.721961 -175.974275) (xy 413.704786 -175.995076)
			(xy 413.699248 -176.002249) (xy 413.693128 -176.019293) (xy 413.692848 -176.02835) (xy 413.69361 -176.104804)
			(xy 413.69996 -176.121568) (xy 413.70631 -176.12868) (xy 413.724408 -176.149746) (xy 413.754913 -176.196157)
			(xy 413.778372 -176.246497) (xy 413.79429 -176.299705) (xy 413.802333 -176.354657) (xy 413.80283 -176.382426)
			(xy 413.802396 -176.409798) (xy 413.794573 -176.463979) (xy 413.779078 -176.516483) (xy 413.756228 -176.566229)
			(xy 413.726495 -176.612194) (xy 413.70885 -176.633124) (xy 413.708596 -176.633378) (xy 413.703012 -176.640466)
			(xy 413.696764 -176.657382) (xy 413.696404 -176.666398) (xy 413.696404 -176.733454) (xy 413.696782 -176.742469)
			(xy 413.703015 -176.759386) (xy 413.708596 -176.766474) (xy 413.70885 -176.766474) (xy 413.70885 -176.766728)
			(xy 413.726517 -176.78764) (xy 413.756243 -176.833611) (xy 413.779088 -176.88336) (xy 413.794583 -176.935866)
			(xy 413.80241 -176.990047) (xy 413.802407 -177.044792) (xy 413.794575 -177.098973) (xy 413.779074 -177.151477)
			(xy 413.756224 -177.201224) (xy 413.726493 -177.247192) (xy 413.70885 -177.268124) (xy 413.708596 -177.268378)
			(xy 413.703012 -177.275466) (xy 413.696764 -177.292382) (xy 413.696404 -177.301398) (xy 413.696404 -177.368454)
			(xy 413.696782 -177.377469) (xy 413.703015 -177.394386) (xy 413.708596 -177.401474) (xy 413.70885 -177.401474)
			(xy 413.70885 -177.401728) (xy 413.726517 -177.42264) (xy 413.756243 -177.468611) (xy 413.779088 -177.51836)
			(xy 413.794583 -177.570866) (xy 413.80241 -177.625047) (xy 413.802407 -177.679792) (xy 413.794575 -177.733973)
			(xy 413.779074 -177.786477) (xy 413.756224 -177.836224) (xy 413.726493 -177.882192) (xy 413.70885 -177.903124)
			(xy 413.708596 -177.903378) (xy 413.703012 -177.910466) (xy 413.696764 -177.927382) (xy 413.696404 -177.936398)
			(xy 413.696404 -178.003454) (xy 413.696782 -178.012469) (xy 413.703015 -178.029386) (xy 413.708596 -178.036474)
			(xy 413.70885 -178.036474) (xy 413.70885 -178.036728) (xy 413.726461 -178.057683) (xy 413.756179 -178.103649)
			(xy 413.779021 -178.15339) (xy 413.794518 -178.205886) (xy 413.802353 -178.260058) (xy 413.80283 -178.287426)
			(xy 413.802306 -178.316438) (xy 413.793534 -178.373796) (xy 413.77618 -178.429165) (xy 413.750644 -178.481269)
			(xy 413.717515 -178.528906) (xy 413.697928 -178.550316) (xy 413.69107 -178.557174) (xy 413.683958 -178.575208)
			(xy 413.682942 -178.663854) (xy 413.6898 -178.681634) (xy 413.696404 -178.688746) (xy 413.715056 -178.709972)
			(xy 413.746597 -178.756852) (xy 413.770879 -178.807871) (xy 413.78737 -178.861913) (xy 413.795711 -178.917797)
			(xy 413.796226 -178.946048) (xy 413.795747 -178.973418) (xy 413.787935 -179.027597) (xy 413.77245 -179.080101)
			(xy 413.749611 -179.129848) (xy 413.719887 -179.175815) (xy 413.702246 -179.196746) (xy 413.701992 -179.197)
			(xy 413.696398 -179.204082) (xy 413.690156 -179.221002) (xy 413.6898 -179.23002) (xy 413.6898 -179.297076)
			(xy 413.690168 -179.306092) (xy 413.696408 -179.323009) (xy 413.701992 -179.330096) (xy 413.702246 -179.330096)
			(xy 413.702246 -179.33035) (xy 413.719935 -179.351244) (xy 413.74966 -179.397218) (xy 413.772504 -179.44697)
			(xy 413.787998 -179.499479) (xy 413.795822 -179.553663) (xy 413.795817 -179.608409) (xy 413.787982 -179.662592)
			(xy 413.772479 -179.715097) (xy 413.749625 -179.764846) (xy 413.719891 -179.810814) (xy 413.702246 -179.831746)
			(xy 413.701992 -179.832) (xy 413.696398 -179.839082) (xy 413.690156 -179.856002) (xy 413.6898 -179.86502)
			(xy 413.6898 -179.932076) (xy 413.690168 -179.941092) (xy 413.696408 -179.958009) (xy 413.701992 -179.965096)
			(xy 413.702246 -179.965096) (xy 413.702246 -179.96535) (xy 413.719935 -179.986244) (xy 413.74966 -180.032218)
			(xy 413.772504 -180.08197) (xy 413.787998 -180.134479) (xy 413.795822 -180.188663) (xy 413.795817 -180.243409)
			(xy 413.787982 -180.297592) (xy 413.772479 -180.350097) (xy 413.749625 -180.399846) (xy 413.719891 -180.445814)
			(xy 413.702246 -180.466746) (xy 413.701992 -180.467) (xy 413.696398 -180.474082) (xy 413.690156 -180.491002)
			(xy 413.6898 -180.50002) (xy 413.6898 -180.567076) (xy 413.690168 -180.576092) (xy 413.696408 -180.593009)
			(xy 413.701992 -180.600096) (xy 413.702246 -180.600096) (xy 413.702246 -180.60035) (xy 413.719867 -180.621297)
			(xy 413.749583 -180.667265) (xy 413.772424 -180.717008) (xy 413.787919 -180.769506) (xy 413.79575 -180.82368)
			(xy 413.796049 -180.840888) (xy 415.76625 -180.840888) (xy 415.766697 -180.813517) (xy 415.774517 -180.759337)
			(xy 415.79001 -180.706833) (xy 415.812857 -180.657086) (xy 415.842586 -180.611121) (xy 415.86023 -180.59019)
			(xy 415.860484 -180.589936) (xy 415.86606 -180.582842) (xy 415.872313 -180.565931) (xy 415.872676 -180.556916)
			(xy 415.872676 -180.48986) (xy 415.872343 -180.480841) (xy 415.866079 -180.463924) (xy 415.860484 -180.45684)
			(xy 415.86023 -180.45684) (xy 415.86023 -180.456586) (xy 415.842577 -180.435663) (xy 415.812853 -180.389693)
			(xy 415.790008 -180.339946) (xy 415.774513 -180.287442) (xy 415.766685 -180.233262) (xy 415.766686 -180.17852)
			(xy 415.774516 -180.12434) (xy 415.790014 -180.071837) (xy 415.812862 -180.022091) (xy 415.842588 -179.976123)
			(xy 415.86023 -179.95519) (xy 415.860484 -179.954936) (xy 415.86606 -179.947842) (xy 415.872313 -179.930931)
			(xy 415.872676 -179.921916) (xy 415.872676 -179.85486) (xy 415.872343 -179.845841) (xy 415.866079 -179.828924)
			(xy 415.860484 -179.82184) (xy 415.86023 -179.82184) (xy 415.86023 -179.821586) (xy 415.842577 -179.800663)
			(xy 415.812853 -179.754693) (xy 415.790008 -179.704946) (xy 415.774513 -179.652442) (xy 415.766685 -179.598262)
			(xy 415.766686 -179.54352) (xy 415.774516 -179.48934) (xy 415.790014 -179.436837) (xy 415.812862 -179.387091)
			(xy 415.842588 -179.341123) (xy 415.86023 -179.32019) (xy 415.860484 -179.319936) (xy 415.86606 -179.312842)
			(xy 415.872313 -179.295931) (xy 415.872676 -179.286916) (xy 415.872676 -179.21986) (xy 415.872343 -179.210841)
			(xy 415.866079 -179.193924) (xy 415.860484 -179.18684) (xy 415.86023 -179.18684) (xy 415.86023 -179.186586)
			(xy 415.842622 -179.165628) (xy 415.812905 -179.119663) (xy 415.790062 -179.069922) (xy 415.774564 -179.017427)
			(xy 415.766728 -178.963256) (xy 415.76625 -178.935888) (xy 415.766777 -178.906805) (xy 415.775602 -178.849312)
			(xy 415.793047 -178.793823) (xy 415.818707 -178.741622) (xy 415.851989 -178.693918) (xy 415.87166 -178.67249)
			(xy 415.877809 -178.665401) (xy 415.884971 -178.64807) (xy 415.88563 -178.638708) (xy 415.887408 -178.570382)
			(xy 415.887219 -178.561129) (xy 415.881116 -178.543677) (xy 415.87547 -178.536346) (xy 415.875216 -178.536346)
			(xy 415.875216 -178.536092) (xy 415.857881 -178.515257) (xy 415.828724 -178.469568) (xy 415.806329 -178.420211)
			(xy 415.791147 -178.368181) (xy 415.783485 -178.314526) (xy 415.783014 -178.287426) (xy 415.783492 -178.260056)
			(xy 415.791306 -178.205877) (xy 415.806792 -178.153374) (xy 415.829632 -178.103627) (xy 415.859354 -178.05766)
			(xy 415.876994 -178.036728) (xy 415.877248 -178.036474) (xy 415.882816 -178.029375) (xy 415.889072 -178.012467)
			(xy 415.88944 -178.003454) (xy 415.88944 -177.936398) (xy 415.889097 -177.927379) (xy 415.882841 -177.910462)
			(xy 415.877248 -177.903378) (xy 415.876994 -177.903378) (xy 415.876994 -177.903124) (xy 415.85938 -177.88217)
			(xy 415.829657 -177.836205) (xy 415.806812 -177.786462) (xy 415.791315 -177.733964) (xy 415.783485 -177.679789)
			(xy 415.783482 -177.625051) (xy 415.791307 -177.570875) (xy 415.806798 -177.518375) (xy 415.829638 -177.468629)
			(xy 415.859357 -177.422661) (xy 415.876994 -177.401728) (xy 415.877248 -177.401474) (xy 415.882816 -177.394375)
			(xy 415.889072 -177.377467) (xy 415.88944 -177.368454) (xy 415.88944 -177.301398) (xy 415.889097 -177.292379)
			(xy 415.882841 -177.275462) (xy 415.877248 -177.268378) (xy 415.876994 -177.268378) (xy 415.876994 -177.268124)
			(xy 415.85938 -177.24717) (xy 415.829657 -177.201205) (xy 415.806812 -177.151462) (xy 415.791315 -177.098964)
			(xy 415.783485 -177.044789) (xy 415.783482 -176.990051) (xy 415.791307 -176.935875) (xy 415.806798 -176.883375)
			(xy 415.829638 -176.833629) (xy 415.859357 -176.787661) (xy 415.876994 -176.766728) (xy 415.877248 -176.766474)
			(xy 415.882816 -176.759375) (xy 415.889072 -176.742467) (xy 415.88944 -176.733454) (xy 415.88944 -176.666398)
			(xy 415.889097 -176.657379) (xy 415.882841 -176.640462) (xy 415.877248 -176.633378) (xy 415.876994 -176.633378)
			(xy 415.876994 -176.633124) (xy 415.859352 -176.612194) (xy 415.829641 -176.566221) (xy 415.806805 -176.516473)
			(xy 415.791315 -176.463972) (xy 415.783488 -176.409795) (xy 415.783014 -176.382426) (xy 415.783477 -176.355292)
			(xy 415.79117 -176.301571) (xy 415.806404 -176.249484) (xy 415.82887 -176.200085) (xy 415.858116 -176.154371)
			(xy 415.87547 -176.133506) (xy 415.881123 -176.12631) (xy 415.887373 -176.109125) (xy 415.887662 -176.099978)
			(xy 415.887408 -176.033176) (xy 415.88691 -176.024122) (xy 415.880411 -176.007206) (xy 415.874708 -176.000156)
			(xy 415.874454 -175.999902) (xy 415.856568 -175.978872) (xy 415.826373 -175.932655) (xy 415.803156 -175.882568)
			(xy 415.787403 -175.829658) (xy 415.779441 -175.775029) (xy 415.77895 -175.747426) (xy 415.779502 -175.720177)
			(xy 415.787254 -175.666234) (xy 415.802604 -175.613943) (xy 415.825239 -175.564369) (xy 415.854699 -175.518521)
			(xy 415.890383 -175.477331) (xy 415.931566 -175.441639) (xy 415.977409 -175.412172) (xy 416.02698 -175.389528)
			(xy 416.079268 -175.374169) (xy 416.133209 -175.366407) (xy 416.160458 -175.365918) (xy 416.187828 -175.366404)
			(xy 416.242006 -175.374217) (xy 416.294509 -175.389701) (xy 416.344256 -175.412538) (xy 416.390224 -175.442259)
			(xy 416.411156 -175.459898) (xy 416.41141 -175.460152) (xy 416.418485 -175.465755) (xy 416.435411 -175.471991)
			(xy 416.44443 -175.472344) (xy 416.511486 -175.472344) (xy 416.520504 -175.471992) (xy 416.537421 -175.465742)
			(xy 416.544506 -175.460152) (xy 416.544506 -175.459898) (xy 416.54476 -175.459898) (xy 416.565693 -175.442257)
			(xy 416.611661 -175.412533) (xy 416.661407 -175.389687) (xy 416.713909 -175.374191) (xy 416.768087 -175.366362)
			(xy 416.822829 -175.366362) (xy 416.877007 -175.374191) (xy 416.929509 -175.389687) (xy 416.979255 -175.412533)
			(xy 417.025223 -175.442257) (xy 417.046156 -175.459898) (xy 417.04641 -175.460152) (xy 417.053485 -175.465755)
			(xy 417.070411 -175.471991) (xy 417.07943 -175.472344) (xy 417.146486 -175.472344) (xy 417.155504 -175.471992)
			(xy 417.172421 -175.465742) (xy 417.179506 -175.460152) (xy 417.179506 -175.459898) (xy 417.17976 -175.459898)
			(xy 417.200696 -175.442264) (xy 417.246668 -175.412551) (xy 417.296414 -175.389715) (xy 417.348914 -175.374222)
			(xy 417.403089 -175.366393) (xy 417.430458 -175.365918) (xy 417.457711 -175.366394) (xy 417.511663 -175.374146)
			(xy 417.563962 -175.389498) (xy 417.613544 -175.412138) (xy 417.659398 -175.441604) (xy 417.700592 -175.477297)
			(xy 417.736286 -175.518489) (xy 417.765754 -175.564342) (xy 417.788396 -175.613923) (xy 417.80375 -175.666222)
			(xy 417.811504 -175.720173) (xy 417.811966 -175.747426) (xy 417.811488 -175.77476) (xy 417.803683 -175.828867)
			(xy 417.788235 -175.881306) (xy 417.765462 -175.931004) (xy 417.735829 -175.976943) (xy 417.71824 -175.99787)
			(xy 417.717986 -175.998124) (xy 417.712073 -176.005617) (xy 417.705806 -176.023631) (xy 417.705794 -176.033176)
			(xy 417.70808 -176.102264) (xy 417.708842 -176.111859) (xy 417.716535 -176.129484) (xy 417.723066 -176.136554)
			(xy 417.74386 -176.158159) (xy 417.779117 -176.206658) (xy 417.806349 -176.260077) (xy 417.824885 -176.317101)
			(xy 417.834268 -176.376322) (xy 417.834826 -176.406302) (xy 417.834379 -176.433673) (xy 417.826559 -176.487854)
			(xy 417.811067 -176.540358) (xy 417.78822 -176.590104) (xy 417.75849 -176.63607) (xy 417.740846 -176.657)
			(xy 417.740592 -176.657254) (xy 417.735018 -176.664349) (xy 417.728764 -176.681259) (xy 417.7284 -176.690274)
			(xy 417.7284 -176.75733) (xy 417.728743 -176.766348) (xy 417.735 -176.783265) (xy 417.740592 -176.79035)
			(xy 417.740846 -176.79035) (xy 417.740846 -176.790604) (xy 417.75849 -176.811535) (xy 417.788217 -176.857502)
			(xy 417.789456 -176.8602) (xy 421.86225 -176.8602) (xy 421.862749 -176.831282) (xy 421.87148 -176.774109)
			(xy 421.88874 -176.718909) (xy 421.914135 -176.666947) (xy 421.947083 -176.619414) (xy 421.986828 -176.577399)
			(xy 422.009316 -176.55921) (xy 422.018112 -176.551592) (xy 422.028301 -176.530699) (xy 422.028874 -176.519078)
			(xy 422.028874 -176.439322) (xy 422.028317 -176.427692) (xy 422.018142 -176.406782) (xy 422.009316 -176.39919)
			(xy 421.986831 -176.381001) (xy 421.947095 -176.338981) (xy 421.914156 -176.291446) (xy 421.888768 -176.239484)
			(xy 421.871512 -176.184286) (xy 421.862784 -176.127116) (xy 421.86225 -176.0982) (xy 421.862736 -176.070949)
			(xy 421.870492 -176.017001) (xy 421.885847 -175.964706) (xy 421.908489 -175.915129) (xy 421.937955 -175.869279)
			(xy 421.973646 -175.828088) (xy 422.014837 -175.792397) (xy 422.060687 -175.762931) (xy 422.110264 -175.740289)
			(xy 422.162559 -175.724934) (xy 422.216507 -175.717178) (xy 422.271009 -175.717178) (xy 422.324957 -175.724934)
			(xy 422.377252 -175.740289) (xy 422.426829 -175.762931) (xy 422.472679 -175.792397) (xy 422.51387 -175.828088)
			(xy 422.549561 -175.869279) (xy 422.579027 -175.915129) (xy 422.601669 -175.964706) (xy 422.617024 -176.017001)
			(xy 422.62478 -176.070949) (xy 422.625266 -176.0982) (xy 422.62476 -176.127118) (xy 422.616031 -176.18429)
			(xy 422.598771 -176.23949) (xy 422.573377 -176.291451) (xy 422.540431 -176.338985) (xy 422.500687 -176.381001)
			(xy 422.4782 -176.39919) (xy 422.469407 -176.406811) (xy 422.459216 -176.427701) (xy 422.458642 -176.439322)
			(xy 422.458642 -176.519078) (xy 422.459194 -176.530709) (xy 422.469372 -176.551619) (xy 422.4782 -176.55921)
			(xy 422.500688 -176.577395) (xy 422.540423 -176.619416) (xy 422.573362 -176.666952) (xy 422.598749 -176.718915)
			(xy 422.616004 -176.774113) (xy 422.624732 -176.831284) (xy 422.625266 -176.8602) (xy 422.62478 -176.887451)
			(xy 422.617024 -176.941399) (xy 422.601669 -176.993694) (xy 422.579027 -177.043271) (xy 422.549561 -177.089121)
			(xy 422.51387 -177.130312) (xy 422.472679 -177.166003) (xy 422.426829 -177.195469) (xy 422.377252 -177.218111)
			(xy 422.324957 -177.233466) (xy 422.271009 -177.241222) (xy 422.216507 -177.241222) (xy 422.162559 -177.233466)
			(xy 422.110264 -177.218111) (xy 422.060687 -177.195469) (xy 422.014837 -177.166003) (xy 421.973646 -177.130312)
			(xy 421.937955 -177.089121) (xy 421.908489 -177.043271) (xy 421.885847 -176.993694) (xy 421.870492 -176.941399)
			(xy 421.862736 -176.887451) (xy 421.86225 -176.8602) (xy 417.789456 -176.8602) (xy 417.811063 -176.907249)
			(xy 417.826561 -176.959751) (xy 417.83439 -177.01393) (xy 417.83439 -177.068673) (xy 417.82656 -177.122852)
			(xy 417.811062 -177.175354) (xy 417.788215 -177.225101) (xy 417.758488 -177.271068) (xy 417.740846 -177.292)
			(xy 417.740592 -177.292254) (xy 417.735018 -177.299349) (xy 417.728764 -177.316259) (xy 417.7284 -177.325274)
			(xy 417.7284 -177.39233) (xy 417.728743 -177.401348) (xy 417.735 -177.418265) (xy 417.740592 -177.42535)
			(xy 417.740846 -177.42535) (xy 417.740846 -177.425604) (xy 417.75849 -177.446535) (xy 417.788217 -177.492502)
			(xy 417.811063 -177.542249) (xy 417.826561 -177.594751) (xy 417.83439 -177.64893) (xy 417.83439 -177.703673)
			(xy 417.82656 -177.757852) (xy 417.811062 -177.810354) (xy 417.788215 -177.860101) (xy 417.758488 -177.906068)
			(xy 417.740846 -177.927) (xy 417.740592 -177.927254) (xy 417.735018 -177.934349) (xy 417.728764 -177.951259)
			(xy 417.7284 -177.960274) (xy 417.7284 -178.02733) (xy 417.728743 -178.036348) (xy 417.735 -178.053265)
			(xy 417.740592 -178.06035) (xy 417.740846 -178.06035) (xy 417.740846 -178.060604) (xy 417.758492 -178.081531)
			(xy 417.788205 -178.127504) (xy 417.81104 -178.177253) (xy 417.826529 -178.229755) (xy 417.834354 -178.283932)
			(xy 417.834826 -178.311302) (xy 417.834273 -178.340815) (xy 417.825182 -178.399136) (xy 417.807217 -178.455361)
			(xy 417.780808 -178.508149) (xy 417.746584 -178.55624) (xy 417.726368 -178.577748) (xy 417.720198 -178.584562)
			(xy 417.712776 -178.601364) (xy 417.71189 -178.610514) (xy 417.707572 -178.68646) (xy 417.712906 -178.703732)
			(xy 417.718748 -178.711098) (xy 417.73393 -178.731286) (xy 417.759435 -178.774884) (xy 417.778966 -178.821465)
			(xy 417.792183 -178.870216) (xy 417.798853 -178.920285) (xy 417.799266 -178.94554) (xy 417.798773 -178.972909)
			(xy 417.790963 -179.027088) (xy 417.775481 -179.079591) (xy 417.752645 -179.129338) (xy 417.722925 -179.175306)
			(xy 417.705286 -179.196238) (xy 417.705032 -179.196492) (xy 417.699435 -179.203571) (xy 417.693196 -179.220494)
			(xy 417.69284 -179.229512) (xy 417.69284 -179.296568) (xy 417.693204 -179.305584) (xy 417.699446 -179.322502)
			(xy 417.705032 -179.329588) (xy 417.705286 -179.329588) (xy 417.705286 -179.329842) (xy 417.722965 -179.350743)
			(xy 417.752688 -179.396717) (xy 417.77553 -179.446468) (xy 417.791022 -179.498975) (xy 417.798847 -179.553158)
			(xy 417.798843 -179.607902) (xy 417.791009 -179.662084) (xy 417.775509 -179.714588) (xy 417.752658 -179.764336)
			(xy 417.722929 -179.810305) (xy 417.705286 -179.831238) (xy 417.705032 -179.831492) (xy 417.699435 -179.838571)
			(xy 417.693196 -179.855494) (xy 417.69284 -179.864512) (xy 417.69284 -179.931568) (xy 417.693204 -179.940584)
			(xy 417.699446 -179.957502) (xy 417.705032 -179.964588) (xy 417.705286 -179.964588) (xy 417.705286 -179.964842)
			(xy 417.722965 -179.985743) (xy 417.723739 -179.98694) (xy 427.834042 -179.98694) (xy 427.838113 -179.931318)
			(xy 427.850239 -179.876881) (xy 427.870162 -179.82479) (xy 427.897458 -179.776155) (xy 427.931544 -179.732012)
			(xy 427.971693 -179.693303) (xy 428.017051 -179.660852) (xy 428.066651 -179.635351) (xy 428.119435 -179.617344)
			(xy 428.174278 -179.607214) (xy 428.230012 -179.605177) (xy 428.285449 -179.611277) (xy 428.339406 -179.625383)
			(xy 428.390735 -179.647195) (xy 428.438341 -179.676249) (xy 428.481209 -179.711924) (xy 428.518426 -179.753461)
			(xy 428.549199 -179.799974) (xy 428.572871 -179.850471) (xy 428.588939 -179.903878) (xy 428.597059 -179.959054)
			(xy 428.597568 -179.98694) (xy 428.597059 -180.014826) (xy 428.588939 -180.070002) (xy 428.572871 -180.123409)
			(xy 428.549199 -180.173906) (xy 428.518426 -180.220419) (xy 428.481209 -180.261956) (xy 428.438341 -180.297631)
			(xy 428.390735 -180.326685) (xy 428.339406 -180.348497) (xy 428.285449 -180.362603) (xy 428.230012 -180.368703)
			(xy 428.174278 -180.366666) (xy 428.119435 -180.356536) (xy 428.066651 -180.338529) (xy 428.017051 -180.313028)
			(xy 427.971693 -180.280577) (xy 427.931544 -180.241868) (xy 427.897458 -180.197725) (xy 427.870162 -180.14909)
			(xy 427.850239 -180.096999) (xy 427.838113 -180.042562) (xy 427.834042 -179.98694) (xy 417.723739 -179.98694)
			(xy 417.752688 -180.031717) (xy 417.77553 -180.081468) (xy 417.791022 -180.133975) (xy 417.798847 -180.188158)
			(xy 417.798843 -180.242902) (xy 417.791009 -180.297084) (xy 417.775509 -180.349588) (xy 417.752658 -180.399336)
			(xy 417.722929 -180.445305) (xy 417.705286 -180.466238) (xy 417.705032 -180.466492) (xy 417.699435 -180.473571)
			(xy 417.693196 -180.490494) (xy 417.69284 -180.499512) (xy 417.69284 -180.566568) (xy 417.693204 -180.575584)
			(xy 417.699446 -180.592502) (xy 417.705032 -180.599588) (xy 417.705286 -180.599588) (xy 417.705286 -180.599842)
			(xy 417.722909 -180.620787) (xy 417.752624 -180.666756) (xy 417.775463 -180.7165) (xy 417.790958 -180.768998)
			(xy 417.79879 -180.823172) (xy 417.799266 -180.85054) (xy 417.798882 -180.877796) (xy 417.791119 -180.931752)
			(xy 417.775755 -180.984054) (xy 417.753105 -181.033637) (xy 417.723629 -181.079492) (xy 417.687927 -181.120685)
			(xy 417.646726 -181.156378) (xy 417.600865 -181.185845) (xy 417.551277 -181.208484) (xy 417.498972 -181.223836)
			(xy 417.445014 -181.231588) (xy 417.417758 -181.232048) (xy 417.389811 -181.231583) (xy 417.334518 -181.223411)
			(xy 417.281008 -181.207262) (xy 417.230426 -181.183481) (xy 417.183852 -181.152578) (xy 417.162742 -181.134258)
			(xy 417.162488 -181.134258) (xy 417.155531 -181.128491) (xy 417.138742 -181.121846) (xy 417.129722 -181.121304)
			(xy 417.053522 -181.120034) (xy 417.035996 -181.12613) (xy 417.029138 -181.132226) (xy 417.008385 -181.149181)
			(xy 416.96302 -181.17771) (xy 416.91411 -181.199611) (xy 416.862617 -181.214454) (xy 416.809553 -181.221946)
			(xy 416.782758 -181.222396) (xy 416.755389 -181.221897) (xy 416.701211 -181.214087) (xy 416.648708 -181.198606)
			(xy 416.598961 -181.175771) (xy 416.552993 -181.146054) (xy 416.53206 -181.128416) (xy 416.531806 -181.128162)
			(xy 416.524725 -181.122568) (xy 416.507804 -181.116327) (xy 416.498786 -181.11597) (xy 416.43173 -181.11597)
			(xy 416.422715 -181.116348) (xy 416.405799 -181.122582) (xy 416.39871 -181.128162) (xy 416.39871 -181.128416)
			(xy 416.398456 -181.128416) (xy 416.377516 -181.146045) (xy 416.331545 -181.175758) (xy 416.281799 -181.198595)
			(xy 416.229301 -181.214089) (xy 416.175127 -181.22192) (xy 416.147758 -181.222396) (xy 416.120505 -181.221961)
			(xy 416.066555 -181.214199) (xy 416.014259 -181.198838) (xy 415.96468 -181.176191) (xy 415.91883 -181.146719)
			(xy 415.87764 -181.111022) (xy 415.841949 -181.069827) (xy 415.812483 -181.023972) (xy 415.789843 -180.974391)
			(xy 415.77449 -180.922092) (xy 415.766735 -180.868141) (xy 415.76625 -180.840888) (xy 413.796049 -180.840888)
			(xy 413.796226 -180.851048) (xy 413.795767 -180.8783) (xy 413.788004 -180.932247) (xy 413.772644 -180.984541)
			(xy 413.749999 -181.034118) (xy 413.720529 -181.079967) (xy 413.684835 -181.121156) (xy 413.643643 -181.156847)
			(xy 413.597791 -181.186313) (xy 413.548213 -181.208955) (xy 413.495918 -181.224311) (xy 413.44197 -181.232069)
			(xy 413.414718 -181.232556) (xy 413.387348 -181.23209) (xy 413.333168 -181.224274) (xy 413.280665 -181.208785)
			(xy 413.230918 -181.185943) (xy 413.184951 -181.156218) (xy 413.16402 -181.138576) (xy 413.163766 -181.138322)
			(xy 413.156671 -181.132748) (xy 413.13976 -181.126496) (xy 413.130746 -181.12613) (xy 413.06369 -181.12613)
			(xy 413.054672 -181.126476) (xy 413.037755 -181.13273) (xy 413.03067 -181.138322) (xy 413.03067 -181.138576)
			(xy 413.030416 -181.138576) (xy 413.009486 -181.156217) (xy 412.963513 -181.18593) (xy 412.913765 -181.208766)
			(xy 412.861264 -181.224256) (xy 412.807087 -181.232083) (xy 412.779718 -181.232556) (xy 412.752469 -181.232005)
			(xy 412.698527 -181.224252) (xy 412.646236 -181.208902) (xy 412.596662 -181.186266) (xy 412.550814 -181.156807)
			(xy 412.509625 -181.121122) (xy 412.473933 -181.079939) (xy 412.444465 -181.034096) (xy 412.421821 -180.984526)
			(xy 412.406462 -180.932238) (xy 412.3987 -180.878297) (xy 412.39821 -180.851048) (xy 409.374857 -180.851048)
			(xy 409.374848 -180.859176) (xy 409.377134 -180.928264) (xy 409.377908 -180.937857) (xy 409.385594 -180.955482)
			(xy 409.39212 -180.962554) (xy 409.412923 -180.98415) (xy 409.448177 -181.032653) (xy 409.475406 -181.086074)
			(xy 409.49394 -181.143099) (xy 409.503322 -181.202321) (xy 409.50388 -181.232302) (xy 409.50342 -181.259673)
			(xy 409.495601 -181.313852) (xy 409.480111 -181.366355) (xy 409.457268 -181.416102) (xy 409.427542 -181.462069)
			(xy 409.4099 -181.483) (xy 409.409646 -181.483254) (xy 409.404066 -181.490345) (xy 409.397817 -181.507259)
			(xy 409.397454 -181.516274) (xy 409.397454 -181.58333) (xy 409.397785 -181.59235) (xy 409.404049 -181.609267)
			(xy 409.409646 -181.61635) (xy 409.4099 -181.61635) (xy 409.4099 -181.616604) (xy 409.427542 -181.637536)
			(xy 409.457264 -181.683504) (xy 409.480108 -181.733251) (xy 409.495603 -181.785753) (xy 409.503431 -181.839931)
			(xy 409.50343 -181.894672) (xy 409.495602 -181.94885) (xy 409.480107 -182.001352) (xy 409.457263 -182.051098)
			(xy 409.42754 -182.097067) (xy 409.4099 -182.118) (xy 409.409646 -182.118254) (xy 409.404066 -182.125345)
			(xy 409.397817 -182.142259) (xy 409.397454 -182.151274) (xy 409.397454 -182.21833) (xy 409.397785 -182.22735)
			(xy 409.404049 -182.244267) (xy 409.409646 -182.25135) (xy 409.4099 -182.25135) (xy 409.4099 -182.251604)
			(xy 409.427542 -182.272536) (xy 409.457264 -182.318504) (xy 409.480108 -182.368251) (xy 409.495603 -182.420753)
			(xy 409.503431 -182.474931) (xy 409.50343 -182.529672) (xy 409.495602 -182.58385) (xy 409.480107 -182.636352)
			(xy 409.457263 -182.686098) (xy 409.42754 -182.732067) (xy 409.4099 -182.753) (xy 409.409646 -182.753254)
			(xy 409.404066 -182.760345) (xy 409.397817 -182.777259) (xy 409.397454 -182.786274) (xy 409.397454 -182.85333)
			(xy 409.397785 -182.86235) (xy 409.404049 -182.879267) (xy 409.409646 -182.88635) (xy 409.4099 -182.88635)
			(xy 409.4099 -182.886604) (xy 409.427554 -182.907524) (xy 409.457264 -182.9535) (xy 409.480097 -183.003251)
			(xy 409.495584 -183.055754) (xy 409.503408 -183.109932) (xy 409.50388 -183.137302) (xy 409.503376 -183.16622)
			(xy 409.494639 -183.223394) (xy 409.477365 -183.278591) (xy 409.451952 -183.330545) (xy 409.418982 -183.378065)
			(xy 409.399486 -183.39943) (xy 409.393136 -183.406034) (xy 409.386024 -183.422798) (xy 409.382976 -183.498998)
			(xy 409.38293 -183.508103) (xy 409.388546 -183.525413) (xy 409.393898 -183.53278) (xy 409.394152 -183.533034)
			(xy 409.410035 -183.553429) (xy 409.436709 -183.597709) (xy 409.457164 -183.645184) (xy 409.471023 -183.694985)
			(xy 409.478034 -183.746201) (xy 409.47848 -183.772048) (xy 409.478067 -183.799302) (xy 409.470303 -183.853253)
			(xy 409.45494 -183.905551) (xy 409.432292 -183.955131) (xy 409.402818 -184.000982) (xy 409.367119 -184.042172)
			(xy 409.325921 -184.077863) (xy 409.280064 -184.107328) (xy 409.23048 -184.129967) (xy 409.178179 -184.145319)
			(xy 409.124226 -184.153072) (xy 409.096972 -184.153556) (xy 409.067496 -184.152983) (xy 409.009243 -184.143924)
			(xy 408.953078 -184.126009) (xy 408.900339 -184.099667) (xy 408.85228 -184.065524) (xy 408.83078 -184.045352)
			(xy 408.823452 -184.038809) (xy 408.805286 -184.03137) (xy 408.795474 -184.030874) (xy 408.742134 -184.030874)
			(xy 408.735276 -184.03824) (xy 408.728728 -184.045564) (xy 408.721291 -184.063733) (xy 408.720798 -184.073546)
			(xy 408.720798 -184.10555) (xy 408.721268 -184.115366) (xy 408.728724 -184.13353) (xy 408.735276 -184.140856)
			(xy 408.755433 -184.16237) (xy 408.789579 -184.210426) (xy 408.815928 -184.263162) (xy 408.833853 -184.319323)
			(xy 408.842928 -184.377572) (xy 408.84348 -184.407048) (xy 408.843067 -184.434302) (xy 408.835303 -184.488253)
			(xy 408.81994 -184.540551) (xy 408.797292 -184.590131) (xy 408.767818 -184.635982) (xy 408.732119 -184.677172)
			(xy 408.690921 -184.712863) (xy 408.645064 -184.742328) (xy 408.59548 -184.764967) (xy 408.543179 -184.780319)
			(xy 408.489226 -184.788072) (xy 408.461972 -184.788556) (xy 408.432496 -184.787983) (xy 408.374243 -184.778924)
			(xy 408.318078 -184.761009) (xy 408.265339 -184.734667) (xy 408.21728 -184.700524) (xy 408.19578 -184.680352)
			(xy 408.188452 -184.673809) (xy 408.170286 -184.66637) (xy 408.160474 -184.665874) (xy 408.107134 -184.665874)
			(xy 408.100276 -184.67324) (xy 408.093728 -184.680564) (xy 408.086291 -184.698733) (xy 408.085798 -184.708546)
			(xy 408.085798 -184.74055) (xy 408.086268 -184.750366) (xy 408.093724 -184.76853) (xy 408.100276 -184.775856)
			(xy 408.120433 -184.79737) (xy 408.154579 -184.845426) (xy 408.180928 -184.898162) (xy 408.198853 -184.954323)
			(xy 408.207928 -185.012572) (xy 408.20848 -185.042048) (xy 408.207994 -185.069299) (xy 408.200238 -185.123247)
			(xy 408.184883 -185.175542) (xy 408.162241 -185.225119) (xy 408.132775 -185.270969) (xy 408.097084 -185.31216)
			(xy 408.055893 -185.347851) (xy 408.010043 -185.377317) (xy 407.960466 -185.399959) (xy 407.908171 -185.415314)
			(xy 407.854223 -185.42307) (xy 407.799721 -185.42307) (xy 407.745773 -185.415314) (xy 407.693478 -185.399959)
			(xy 407.643901 -185.377317) (xy 407.598051 -185.347851) (xy 407.55686 -185.31216) (xy 407.521169 -185.270969)
			(xy 407.491703 -185.225119) (xy 407.469061 -185.175542) (xy 407.453706 -185.123247) (xy 407.44595 -185.069299)
			(xy 407.445464 -185.042048) (xy 405.431845 -185.042048) (xy 405.431843 -185.069409) (xy 405.424009 -185.123591)
			(xy 405.408506 -185.176096) (xy 405.385655 -185.225844) (xy 405.355924 -185.271813) (xy 405.33828 -185.292746)
			(xy 405.338026 -185.293) (xy 405.332425 -185.300076) (xy 405.326189 -185.317001) (xy 405.325834 -185.32602)
			(xy 405.325834 -185.393076) (xy 405.326195 -185.402093) (xy 405.332439 -185.41901) (xy 405.338026 -185.426096)
			(xy 405.33828 -185.426096) (xy 405.33828 -185.42635) (xy 405.355967 -185.447245) (xy 405.38569 -185.493219)
			(xy 405.408532 -185.542972) (xy 405.424024 -185.59548) (xy 405.431848 -185.649663) (xy 405.431843 -185.704409)
			(xy 405.424009 -185.758591) (xy 405.408506 -185.811096) (xy 405.385655 -185.860844) (xy 405.355924 -185.906813)
			(xy 405.33828 -185.927746) (xy 405.338026 -185.928) (xy 405.332425 -185.935076) (xy 405.326189 -185.952001)
			(xy 405.325834 -185.96102) (xy 405.325834 -186.028076) (xy 405.326195 -186.037093) (xy 405.332439 -186.05401)
			(xy 405.338026 -186.061096) (xy 405.33828 -186.061096) (xy 405.33828 -186.06135) (xy 405.355967 -186.082245)
			(xy 405.38569 -186.128219) (xy 405.408532 -186.177972) (xy 405.424024 -186.23048) (xy 405.431848 -186.284663)
			(xy 405.431843 -186.339409) (xy 405.424009 -186.393591) (xy 405.408506 -186.446096) (xy 405.385655 -186.495844)
			(xy 405.355924 -186.541813) (xy 405.33828 -186.562746) (xy 405.338026 -186.563) (xy 405.332425 -186.570076)
			(xy 405.326189 -186.587001) (xy 405.325834 -186.59602) (xy 405.325834 -186.663076) (xy 405.326195 -186.672093)
			(xy 405.332439 -186.68901) (xy 405.338026 -186.696096) (xy 405.33828 -186.696096) (xy 405.33828 -186.69635)
			(xy 405.355906 -186.717293) (xy 405.38562 -186.763262) (xy 405.408459 -186.813007) (xy 405.423953 -186.865505)
			(xy 405.431785 -186.91968) (xy 405.43226 -186.947048) (xy 405.431867 -186.974303) (xy 405.424102 -187.028256)
			(xy 405.408739 -187.080556) (xy 405.386089 -187.130136) (xy 405.356613 -187.175989) (xy 405.320912 -187.21718)
			(xy 405.279712 -187.25287) (xy 405.233852 -187.282335) (xy 405.184265 -187.304972) (xy 405.131962 -187.320323)
			(xy 405.078007 -187.328074) (xy 405.050752 -187.328556) (xy 405.023382 -187.32807) (xy 404.969204 -187.320259)
			(xy 404.9167 -187.304775) (xy 404.866953 -187.281937) (xy 404.820986 -187.252216) (xy 404.800054 -187.234576)
			(xy 404.7998 -187.234322) (xy 404.792724 -187.22872) (xy 404.775799 -187.222485) (xy 404.76678 -187.22213)
			(xy 404.699724 -187.22213) (xy 404.690708 -187.222492) (xy 404.67379 -187.228736) (xy 404.666704 -187.234322)
			(xy 404.666704 -187.234576) (xy 404.66645 -187.234576) (xy 404.645507 -187.252201) (xy 404.599537 -187.281916)
			(xy 404.549793 -187.304755) (xy 404.497294 -187.320249) (xy 404.44312 -187.328081) (xy 404.415752 -187.328556)
			(xy 404.388502 -187.328067) (xy 404.334557 -187.320305) (xy 404.282265 -187.304946) (xy 404.232691 -187.282303)
			(xy 404.186843 -187.252836) (xy 404.145654 -187.217146) (xy 404.109964 -187.175957) (xy 404.080497 -187.130109)
			(xy 404.057854 -187.080535) (xy 404.042495 -187.028243) (xy 404.034733 -186.974298) (xy 404.034244 -186.947048)
			(xy 358.21109 -186.947048) (xy 358.215692 -186.95289) (xy 358.215946 -186.95289) (xy 358.215946 -186.953144)
			(xy 358.233629 -186.974043) (xy 358.263354 -187.020016) (xy 358.286199 -187.069768) (xy 358.301693 -187.122275)
			(xy 358.309518 -187.176459) (xy 358.309514 -187.231205) (xy 358.301679 -187.285387) (xy 358.286176 -187.337892)
			(xy 358.263324 -187.38764) (xy 358.233591 -187.433608) (xy 358.215946 -187.45454) (xy 358.215692 -187.454794)
			(xy 358.210101 -187.461877) (xy 358.203857 -187.478797) (xy 358.2035 -187.487814) (xy 358.2035 -187.55487)
			(xy 358.203871 -187.563885) (xy 358.210109 -187.580803) (xy 358.215692 -187.58789) (xy 358.215946 -187.58789)
			(xy 358.215946 -187.588144) (xy 358.233564 -187.609093) (xy 358.263281 -187.655061) (xy 358.286122 -187.704804)
			(xy 358.301618 -187.757301) (xy 358.30945 -187.811474) (xy 358.309926 -187.838842) (xy 358.309461 -187.866093)
			(xy 358.3017 -187.920041) (xy 358.28634 -187.972335) (xy 358.263695 -188.021911) (xy 358.234226 -188.067761)
			(xy 358.198533 -188.10895) (xy 358.157341 -188.144641) (xy 358.11149 -188.174107) (xy 358.061913 -188.196748)
			(xy 358.009618 -188.212105) (xy 357.955669 -188.219863) (xy 357.928418 -188.22035) (xy 357.901048 -188.219886)
			(xy 357.846868 -188.212069) (xy 357.794364 -188.19658) (xy 357.744617 -188.173738) (xy 357.698651 -188.144012)
			(xy 357.67772 -188.12637) (xy 357.677466 -188.126116) (xy 357.670363 -188.120553) (xy 357.653459 -188.114292)
			(xy 357.644446 -188.113924) (xy 357.57739 -188.113924) (xy 357.568372 -188.114271) (xy 357.551455 -188.120525)
			(xy 357.54437 -188.126116) (xy 357.54437 -188.12637) (xy 357.544116 -188.12637) (xy 357.523185 -188.14401)
			(xy 357.477212 -188.173723) (xy 357.427465 -188.196559) (xy 357.374964 -188.21205) (xy 357.320787 -188.219877)
			(xy 357.293418 -188.22035) (xy 357.266169 -188.219805) (xy 357.212226 -188.212052) (xy 357.159935 -188.196701)
			(xy 357.11036 -188.174065) (xy 357.064512 -188.144605) (xy 357.023323 -188.10892) (xy 356.987631 -188.067736)
			(xy 356.958163 -188.021892) (xy 356.93552 -187.972322) (xy 356.920161 -187.920033) (xy 356.912399 -187.866091)
			(xy 356.91191 -187.838842) (xy 356.912398 -187.811473) (xy 356.92021 -187.757294) (xy 356.935694 -187.704791)
			(xy 356.958531 -187.655044) (xy 356.988251 -187.609076) (xy 357.00589 -187.588144) (xy 357.006144 -187.58789)
			(xy 357.011746 -187.580814) (xy 357.017982 -187.563889) (xy 357.018336 -187.55487) (xy 357.018336 -187.487814)
			(xy 357.017964 -187.478799) (xy 357.011726 -187.461882) (xy 357.006144 -187.454794) (xy 357.00589 -187.454794)
			(xy 357.00589 -187.45454) (xy 356.988292 -187.433573) (xy 356.958568 -187.38761) (xy 356.935723 -187.33787)
			(xy 356.920225 -187.285373) (xy 356.912393 -187.2312) (xy 356.912389 -187.176463) (xy 356.920211 -187.122289)
			(xy 356.935701 -187.06979) (xy 356.958538 -187.020045) (xy 356.988254 -186.974077) (xy 357.00589 -186.953144)
			(xy 357.006144 -186.95289) (xy 357.011746 -186.945814) (xy 357.017982 -186.928889) (xy 357.018336 -186.91987)
			(xy 357.018336 -186.852814) (xy 357.017964 -186.843799) (xy 357.011726 -186.826882) (xy 357.006144 -186.819794)
			(xy 357.00589 -186.819794) (xy 357.00589 -186.81954) (xy 356.988292 -186.798573) (xy 356.958568 -186.75261)
			(xy 356.935723 -186.70287) (xy 356.920225 -186.650373) (xy 356.912393 -186.5962) (xy 356.912389 -186.541463)
			(xy 356.920211 -186.487289) (xy 356.935701 -186.43479) (xy 356.958538 -186.385045) (xy 356.988254 -186.339077)
			(xy 357.00589 -186.318144) (xy 357.006144 -186.31789) (xy 357.011746 -186.310814) (xy 357.017982 -186.293889)
			(xy 357.018336 -186.28487) (xy 357.018336 -186.217814) (xy 357.017964 -186.208799) (xy 357.011726 -186.191882)
			(xy 357.006144 -186.184794) (xy 357.00589 -186.184794) (xy 357.00589 -186.18454) (xy 356.988292 -186.163573)
			(xy 356.958568 -186.11761) (xy 356.935723 -186.06787) (xy 356.920225 -186.015373) (xy 356.912393 -185.9612)
			(xy 356.912389 -185.906463) (xy 356.920211 -185.852289) (xy 356.935701 -185.79979) (xy 356.958538 -185.750045)
			(xy 356.988254 -185.704077) (xy 357.00589 -185.683144) (xy 357.006144 -185.68289) (xy 357.011746 -185.675814)
			(xy 357.017982 -185.658889) (xy 357.018336 -185.64987) (xy 357.018336 -185.582814) (xy 357.017964 -185.573799)
			(xy 357.011726 -185.556882) (xy 357.006144 -185.549794) (xy 357.00589 -185.549794) (xy 357.00589 -185.54954)
			(xy 356.988292 -185.528573) (xy 356.958568 -185.48261) (xy 356.935723 -185.43287) (xy 356.920225 -185.380373)
			(xy 356.912393 -185.3262) (xy 356.912389 -185.271463) (xy 356.920211 -185.217289) (xy 356.935701 -185.16479)
			(xy 356.958538 -185.115045) (xy 356.988254 -185.069077) (xy 357.00589 -185.048144) (xy 357.006144 -185.04789)
			(xy 357.011746 -185.040814) (xy 357.017982 -185.023889) (xy 357.018336 -185.01487) (xy 357.018336 -184.947814)
			(xy 357.017964 -184.938799) (xy 357.011726 -184.921882) (xy 357.006144 -184.914794) (xy 357.00589 -184.914794)
			(xy 357.00589 -184.91454) (xy 356.988255 -184.893605) (xy 356.958543 -184.847633) (xy 356.935706 -184.797886)
			(xy 356.920214 -184.745386) (xy 356.912385 -184.691211) (xy 356.91191 -184.663842) (xy 356.912391 -184.636132)
			(xy 356.920422 -184.581297) (xy 356.936307 -184.528202) (xy 356.959711 -184.477966) (xy 356.99014 -184.431647)
			(xy 357.008176 -184.410604) (xy 357.008176 -184.41035) (xy 357.014043 -184.403097) (xy 357.020559 -184.385637)
			(xy 357.020876 -184.376314) (xy 357.020368 -184.307988) (xy 357.019816 -184.298729) (xy 357.012906 -184.281533)
			(xy 357.006906 -184.27446) (xy 357.006906 -184.274206) (xy 356.988033 -184.252938) (xy 356.956096 -184.205898)
			(xy 356.931501 -184.154636) (xy 356.914793 -184.100289) (xy 356.906342 -184.044063) (xy 356.905814 -184.015634)
			(xy 356.906297 -183.988264) (xy 356.91411 -183.934086) (xy 356.929595 -183.881583) (xy 356.952433 -183.831836)
			(xy 356.982154 -183.785868) (xy 356.999794 -183.764936) (xy 357.000048 -183.764682) (xy 357.005654 -183.757609)
			(xy 357.011888 -183.740682) (xy 357.01224 -183.731662) (xy 357.01224 -183.664606) (xy 357.011893 -183.655588)
			(xy 357.00564 -183.63867) (xy 357.000048 -183.631586) (xy 356.999794 -183.631586) (xy 356.999794 -183.631332)
			(xy 356.982188 -183.610372) (xy 356.952464 -183.564408) (xy 356.929619 -183.514666) (xy 356.914122 -183.462168)
			(xy 356.90629 -183.407994) (xy 356.906287 -183.353257) (xy 356.914111 -183.299082) (xy 356.929601 -183.246582)
			(xy 356.95244 -183.196837) (xy 356.982157 -183.150869) (xy 356.999794 -183.129936) (xy 357.000048 -183.129682)
			(xy 357.005654 -183.122609) (xy 357.011888 -183.105682) (xy 357.01224 -183.096662) (xy 357.01224 -183.029606)
			(xy 357.011893 -183.020588) (xy 357.00564 -183.00367) (xy 357.000048 -182.996586) (xy 356.999794 -182.996586)
			(xy 356.999794 -182.996332) (xy 356.982188 -182.975372) (xy 356.952464 -182.929408) (xy 356.929619 -182.879666)
			(xy 356.914122 -182.827168) (xy 356.90629 -182.772994) (xy 356.906287 -182.718257) (xy 356.914111 -182.664082)
			(xy 356.929601 -182.611582) (xy 356.95244 -182.561837) (xy 356.982157 -182.515869) (xy 356.999794 -182.494936)
			(xy 357.000048 -182.494682) (xy 357.005654 -182.487609) (xy 357.011888 -182.470682) (xy 357.01224 -182.461662)
			(xy 357.01224 -182.394606) (xy 357.011893 -182.385588) (xy 357.00564 -182.36867) (xy 357.000048 -182.361586)
			(xy 356.999794 -182.361586) (xy 356.999794 -182.361332) (xy 356.982156 -182.340399) (xy 356.952444 -182.294427)
			(xy 356.929608 -182.244679) (xy 356.914117 -182.192179) (xy 356.906288 -182.138003) (xy 356.905814 -182.110634)
			(xy 356.906282 -182.0835) (xy 356.913973 -182.029779) (xy 356.929206 -181.977693) (xy 356.951672 -181.928293)
			(xy 356.980916 -181.882579) (xy 356.99827 -181.861714) (xy 357.00392 -181.854516) (xy 357.010171 -181.837332)
			(xy 357.010462 -181.828186) (xy 357.010208 -181.761384) (xy 357.009706 -181.75233) (xy 357.003209 -181.735414)
			(xy 356.997508 -181.728364) (xy 356.997254 -181.72811) (xy 356.979371 -181.707077) (xy 356.949176 -181.660861)
			(xy 356.925959 -181.610775) (xy 356.910204 -181.557865) (xy 356.902241 -181.503237) (xy 356.90175 -181.475634)
			(xy 354.919026 -181.475634) (xy 354.918591 -181.502605) (xy 354.910979 -181.556007) (xy 354.895912 -181.607803)
			(xy 354.873691 -181.656955) (xy 354.844761 -181.702483) (xy 354.827586 -181.723284) (xy 354.822044 -181.730454)
			(xy 354.815927 -181.7475) (xy 354.815648 -181.756558) (xy 354.81641 -181.833012) (xy 354.82276 -181.849776)
			(xy 354.82911 -181.856888) (xy 354.847212 -181.877951) (xy 354.877716 -181.924363) (xy 354.901174 -181.974703)
			(xy 354.917092 -182.027912) (xy 354.925133 -182.082865) (xy 354.92563 -182.110634) (xy 354.925201 -182.138006)
			(xy 354.917377 -182.192187) (xy 354.90188 -182.244691) (xy 354.87903 -182.294438) (xy 354.849296 -182.340402)
			(xy 354.83165 -182.361332) (xy 354.831396 -182.361586) (xy 354.825809 -182.368672) (xy 354.819563 -182.385589)
			(xy 354.819204 -182.394606) (xy 354.819204 -182.461662) (xy 354.819579 -182.470677) (xy 354.825814 -182.487594)
			(xy 354.831396 -182.494682) (xy 354.83165 -182.494682) (xy 354.83165 -182.494936) (xy 354.849325 -182.515841)
			(xy 354.87905 -182.561813) (xy 354.901895 -182.611564) (xy 354.91739 -182.66407) (xy 354.925215 -182.718253)
			(xy 354.925212 -182.772998) (xy 354.917379 -182.82718) (xy 354.901877 -182.879684) (xy 354.879025 -182.929432)
			(xy 354.849294 -182.9754) (xy 354.83165 -182.996332) (xy 354.831396 -182.996586) (xy 354.825809 -183.003672)
			(xy 354.819563 -183.020589) (xy 354.819204 -183.029606) (xy 354.819204 -183.096662) (xy 354.819579 -183.105677)
			(xy 354.825814 -183.122594) (xy 354.831396 -183.129682) (xy 354.83165 -183.129682) (xy 354.83165 -183.129936)
			(xy 354.849325 -183.150841) (xy 354.87905 -183.196813) (xy 354.901895 -183.246564) (xy 354.91739 -183.29907)
			(xy 354.925215 -183.353253) (xy 354.925212 -183.407998) (xy 354.917379 -183.46218) (xy 354.901877 -183.514684)
			(xy 354.879025 -183.564432) (xy 354.849294 -183.6104) (xy 354.83165 -183.631332) (xy 354.831396 -183.631586)
			(xy 354.825809 -183.638672) (xy 354.819563 -183.655589) (xy 354.819204 -183.664606) (xy 354.819204 -183.731662)
			(xy 354.819579 -183.740677) (xy 354.825814 -183.757594) (xy 354.831396 -183.764682) (xy 354.83165 -183.764682)
			(xy 354.83165 -183.764936) (xy 354.849265 -183.785888) (xy 354.878982 -183.831854) (xy 354.901823 -183.881597)
			(xy 354.91732 -183.934093) (xy 354.925153 -183.988266) (xy 354.92563 -184.015634) (xy 354.925125 -184.043343)
			(xy 354.917098 -184.098177) (xy 354.901218 -184.151271) (xy 354.87782 -184.201507) (xy 354.847397 -184.247828)
			(xy 354.829364 -184.268872) (xy 354.829364 -184.269126) (xy 354.823501 -184.27638) (xy 354.816984 -184.29384)
			(xy 354.816664 -184.303162) (xy 354.817172 -184.371488) (xy 354.817726 -184.380747) (xy 354.824633 -184.397943)
			(xy 354.830634 -184.405016) (xy 354.830634 -184.40527) (xy 354.849549 -184.426502) (xy 354.881479 -184.473552)
			(xy 354.906065 -184.524824) (xy 354.922764 -184.579179) (xy 354.931203 -184.635411) (xy 354.931726 -184.663842)
			(xy 354.931244 -184.691212) (xy 354.923433 -184.745391) (xy 354.907948 -184.797895) (xy 354.88511 -184.847642)
			(xy 354.855387 -184.893609) (xy 354.837746 -184.91454) (xy 354.837492 -184.914794) (xy 354.831901 -184.921877)
			(xy 354.825657 -184.938797) (xy 354.8253 -184.947814) (xy 354.8253 -185.01487) (xy 354.825671 -185.023885)
			(xy 354.831909 -185.040803) (xy 354.837492 -185.04789) (xy 354.837746 -185.04789) (xy 354.837746 -185.048144)
			(xy 354.855429 -185.069043) (xy 354.885154 -185.115016) (xy 354.907999 -185.164768) (xy 354.923493 -185.217275)
			(xy 354.931318 -185.271459) (xy 354.931314 -185.326205) (xy 354.923479 -185.380387) (xy 354.907976 -185.432892)
			(xy 354.885124 -185.48264) (xy 354.855391 -185.528608) (xy 354.837746 -185.54954) (xy 354.837492 -185.549794)
			(xy 354.831901 -185.556877) (xy 354.825657 -185.573797) (xy 354.8253 -185.582814) (xy 354.8253 -185.64987)
			(xy 354.825671 -185.658885) (xy 354.831909 -185.675803) (xy 354.837492 -185.68289) (xy 354.837746 -185.68289)
			(xy 354.837746 -185.683144) (xy 354.855364 -185.704093) (xy 354.885081 -185.750061) (xy 354.907922 -185.799804)
			(xy 354.923418 -185.852301) (xy 354.93125 -185.906474) (xy 354.931726 -185.933842) (xy 354.93124 -185.961093)
			(xy 354.923484 -186.015041) (xy 354.908129 -186.067336) (xy 354.885487 -186.116913) (xy 354.856021 -186.162763)
			(xy 354.82033 -186.203954) (xy 354.779139 -186.239645) (xy 354.733289 -186.269111) (xy 354.683712 -186.291753)
			(xy 354.631417 -186.307108) (xy 354.577469 -186.314864) (xy 354.522967 -186.314864) (xy 354.469019 -186.307108)
			(xy 354.416724 -186.291753) (xy 354.367147 -186.269111) (xy 354.321297 -186.239645) (xy 354.280106 -186.203954)
			(xy 354.244415 -186.162763) (xy 354.214949 -186.116913) (xy 354.192307 -186.067336) (xy 354.176952 -186.015041)
			(xy 354.169196 -185.961093) (xy 354.16871 -185.933842) (xy 354.169273 -185.904365) (xy 354.178336 -185.846113)
			(xy 354.196253 -185.789948) (xy 354.222597 -185.737209) (xy 354.256742 -185.68915) (xy 354.276914 -185.66765)
			(xy 354.283422 -185.660295) (xy 354.290882 -185.64215) (xy 354.291392 -185.632344) (xy 354.291392 -185.579004)
			(xy 354.284026 -185.572146) (xy 354.276683 -185.565622) (xy 354.258529 -185.558172) (xy 354.24872 -185.557668)
			(xy 354.216716 -185.557668) (xy 354.206899 -185.558128) (xy 354.188735 -185.565592) (xy 354.18141 -185.572146)
			(xy 354.159905 -185.592314) (xy 354.111847 -185.62646) (xy 354.059109 -185.652807) (xy 354.002946 -185.67073)
			(xy 353.944695 -185.6798) (xy 353.915218 -185.68035) (xy 353.887969 -185.679805) (xy 353.834026 -185.672052)
			(xy 353.781735 -185.656701) (xy 353.73216 -185.634065) (xy 353.686312 -185.604605) (xy 353.645123 -185.56892)
			(xy 353.609431 -185.527736) (xy 353.579963 -185.481892) (xy 353.55732 -185.432322) (xy 353.541961 -185.380033)
			(xy 353.534199 -185.326091) (xy 353.53371 -185.298842) (xy 353.534273 -185.269365) (xy 353.543336 -185.211113)
			(xy 353.561253 -185.154948) (xy 353.587597 -185.102209) (xy 353.621742 -185.05415) (xy 353.641914 -185.03265)
			(xy 353.648422 -185.025295) (xy 353.655882 -185.00715) (xy 353.656392 -184.997344) (xy 353.656392 -184.944004)
			(xy 353.650804 -184.93867) (xy 353.643363 -184.932239) (xy 353.625073 -184.925056) (xy 353.615244 -184.9247)
			(xy 353.582986 -184.924954) (xy 353.573059 -184.925507) (xy 353.554757 -184.933223) (xy 353.547426 -184.93994)
			(xy 353.525806 -184.960943) (xy 353.477204 -184.996588) (xy 353.423595 -185.024132) (xy 353.366316 -185.04289)
			(xy 353.306798 -185.052392) (xy 353.276662 -185.05297) (xy 353.249408 -185.052557) (xy 353.195456 -185.044795)
			(xy 353.143157 -185.029433) (xy 353.093577 -185.006785) (xy 353.047725 -184.977311) (xy 353.006535 -184.941612)
			(xy 352.970844 -184.900414) (xy 352.941379 -184.854556) (xy 352.918741 -184.804971) (xy 352.903389 -184.75267)
			(xy 352.895637 -184.698716) (xy 352.895154 -184.671462) (xy 352.895604 -184.644797) (xy 352.903045 -184.591989)
			(xy 352.917765 -184.54073) (xy 352.939475 -184.492019) (xy 352.967754 -184.446803) (xy 352.984562 -184.426098)
			(xy 352.984816 -184.425844) (xy 352.990308 -184.418663) (xy 352.996278 -184.401609) (xy 352.9965 -184.39257)
			(xy 352.99523 -184.325768) (xy 352.994704 -184.316595) (xy 352.987927 -184.299533) (xy 352.982022 -184.292494)
			(xy 352.963583 -184.271317) (xy 352.93244 -184.224596) (xy 352.908474 -184.173819) (xy 352.892201 -184.120079)
			(xy 352.883971 -184.064537) (xy 352.88347 -184.036462) (xy 350.010984 -184.036462) (xy 355.125528 -189.151006)
			(xy 395.017244 -189.151006) (xy 395.017244 -189.150752) (xy 395.017733 -189.123502) (xy 395.025495 -189.069557)
			(xy 395.040854 -189.017265) (xy 395.063497 -188.967691) (xy 395.092964 -188.921843) (xy 395.128654 -188.880654)
			(xy 395.169843 -188.844964) (xy 395.215691 -188.815497) (xy 395.265265 -188.792854) (xy 395.317557 -188.777495)
			(xy 395.371502 -188.769733) (xy 395.398752 -188.769244) (xy 395.426122 -188.769727) (xy 395.4803 -188.777539)
			(xy 395.532804 -188.793024) (xy 395.582551 -188.815862) (xy 395.628518 -188.845584) (xy 395.64945 -188.863224)
			(xy 395.649704 -188.863478) (xy 395.656779 -188.869081) (xy 395.673705 -188.875316) (xy 395.682724 -188.87567)
			(xy 395.74978 -188.87567) (xy 395.758797 -188.87531) (xy 395.775714 -188.869065) (xy 395.7828 -188.863478)
			(xy 395.7828 -188.863224) (xy 395.783054 -188.863224) (xy 395.803987 -188.845583) (xy 395.849955 -188.815859)
			(xy 395.899701 -188.793013) (xy 395.952203 -188.777517) (xy 396.006381 -188.769688) (xy 396.061123 -188.769688)
			(xy 396.115301 -188.777517) (xy 396.167803 -188.793013) (xy 396.217549 -188.815859) (xy 396.263517 -188.845583)
			(xy 396.28445 -188.863224) (xy 396.284704 -188.863478) (xy 396.291779 -188.869081) (xy 396.308705 -188.875316)
			(xy 396.317724 -188.87567) (xy 396.38478 -188.87567) (xy 396.393797 -188.87531) (xy 396.410714 -188.869065)
			(xy 396.4178 -188.863478) (xy 396.4178 -188.863224) (xy 396.418054 -188.863224) (xy 396.438996 -188.845597)
			(xy 396.484965 -188.815882) (xy 396.53471 -188.793044) (xy 396.587209 -188.77755) (xy 396.641383 -188.769719)
			(xy 396.668752 -188.769244) (xy 396.696 -188.769823) (xy 396.749942 -188.777571) (xy 396.802232 -188.792918)
			(xy 396.851806 -188.81555) (xy 396.897654 -188.845007) (xy 396.938843 -188.880689) (xy 396.974536 -188.921869)
			(xy 397.004004 -188.96771) (xy 397.026648 -189.017278) (xy 397.042008 -189.069564) (xy 397.04977 -189.123504)
			(xy 397.05026 -189.150752) (xy 399.032984 -189.150752) (xy 399.033433 -189.1235) (xy 399.041196 -189.069551)
			(xy 399.056557 -189.017256) (xy 399.079203 -188.96768) (xy 399.108673 -188.92183) (xy 399.144369 -188.88064)
			(xy 399.185562 -188.844949) (xy 399.231415 -188.815484) (xy 399.280994 -188.792843) (xy 399.33329 -188.777487)
			(xy 399.38724 -188.76973) (xy 399.414492 -188.769244) (xy 399.441863 -188.769704) (xy 399.496042 -188.777522)
			(xy 399.548546 -188.793012) (xy 399.598293 -188.815855) (xy 399.644259 -188.845582) (xy 399.66519 -188.863224)
			(xy 399.665444 -188.863478) (xy 399.672536 -188.869056) (xy 399.689449 -188.875306) (xy 399.698464 -188.87567)
			(xy 399.76552 -188.87567) (xy 399.774539 -188.875329) (xy 399.791456 -188.869071) (xy 399.79854 -188.863478)
			(xy 399.79854 -188.863224) (xy 399.798794 -188.863224) (xy 399.819727 -188.845583) (xy 399.865695 -188.815859)
			(xy 399.915441 -188.793013) (xy 399.967943 -188.777517) (xy 400.022121 -188.769688) (xy 400.076863 -188.769688)
			(xy 400.131041 -188.777517) (xy 400.183543 -188.793013) (xy 400.233289 -188.815859) (xy 400.279257 -188.845583)
			(xy 400.30019 -188.863224) (xy 400.300444 -188.863478) (xy 400.307536 -188.869056) (xy 400.324449 -188.875306)
			(xy 400.333464 -188.87567) (xy 400.40052 -188.87567) (xy 400.409539 -188.875329) (xy 400.426456 -188.869071)
			(xy 400.43354 -188.863478) (xy 400.43354 -188.863224) (xy 400.433794 -188.863224) (xy 400.454721 -188.845578)
			(xy 400.500695 -188.815866) (xy 400.550443 -188.793031) (xy 400.602945 -188.777542) (xy 400.657122 -188.769716)
			(xy 400.684492 -188.769244) (xy 400.711741 -188.769785) (xy 400.765684 -188.777539) (xy 400.817975 -188.792891)
			(xy 400.867549 -188.815528) (xy 400.913397 -188.844989) (xy 400.954586 -188.880674) (xy 400.990278 -188.921858)
			(xy 401.019745 -188.967702) (xy 401.042389 -189.017273) (xy 401.057749 -189.069561) (xy 401.065511 -189.123503)
			(xy 401.066 -189.150752) (xy 401.065529 -189.178086) (xy 401.057721 -189.232193) (xy 401.042271 -189.284632)
			(xy 401.019497 -189.334329) (xy 400.989863 -189.380268) (xy 400.972274 -189.401196) (xy 400.97202 -189.40145)
			(xy 400.966099 -189.408938) (xy 400.959835 -189.426956) (xy 400.959828 -189.436502) (xy 400.962114 -189.50559)
			(xy 400.962854 -189.515188) (xy 400.970562 -189.532813) (xy 400.9771 -189.53988) (xy 400.997912 -189.561467)
			(xy 401.033165 -189.609972) (xy 401.060393 -189.663396) (xy 401.078925 -189.720423) (xy 401.088304 -189.779647)
			(xy 401.08886 -189.809628) (xy 401.08842 -189.836999) (xy 401.080597 -189.89118) (xy 401.065103 -189.943684)
			(xy 401.042255 -189.99343) (xy 401.012524 -190.039395) (xy 400.99488 -190.060326) (xy 400.994626 -190.06058)
			(xy 400.989033 -190.067662) (xy 400.982792 -190.084583) (xy 400.982434 -190.0936) (xy 400.982434 -190.160656)
			(xy 400.982805 -190.169672) (xy 400.989042 -190.186589) (xy 400.994626 -190.193676) (xy 400.99488 -190.193676)
			(xy 400.99488 -190.19393) (xy 401.012548 -190.214841) (xy 401.042271 -190.260812) (xy 401.065114 -190.310562)
			(xy 401.080608 -190.363068) (xy 401.088434 -190.417249) (xy 401.088431 -190.471993) (xy 401.080599 -190.526173)
			(xy 401.065099 -190.578677) (xy 401.042251 -190.628425) (xy 401.012522 -190.674393) (xy 400.99488 -190.695326)
			(xy 400.994626 -190.69558) (xy 400.989033 -190.702662) (xy 400.982792 -190.719583) (xy 400.982434 -190.7286)
			(xy 400.982434 -190.795656) (xy 400.982805 -190.804672) (xy 400.989042 -190.821589) (xy 400.994626 -190.828676)
			(xy 400.99488 -190.828676) (xy 400.99488 -190.82893) (xy 401.012548 -190.849841) (xy 401.042271 -190.895812)
			(xy 401.065114 -190.945562) (xy 401.080608 -190.998068) (xy 401.088434 -191.052249) (xy 401.088431 -191.106993)
			(xy 401.080599 -191.161173) (xy 401.065099 -191.213677) (xy 401.042251 -191.263425) (xy 401.012522 -191.309393)
			(xy 400.99488 -191.330326) (xy 400.994626 -191.33058) (xy 400.989033 -191.337662) (xy 400.982792 -191.354583)
			(xy 400.982434 -191.3636) (xy 400.982434 -191.430656) (xy 400.982805 -191.439672) (xy 400.989042 -191.456589)
			(xy 400.994626 -191.463676) (xy 400.99488 -191.463676) (xy 400.99488 -191.46393) (xy 401.012497 -191.48488)
			(xy 401.042213 -191.530848) (xy 401.065053 -191.580591) (xy 401.080549 -191.633087) (xy 401.088383 -191.68726)
			(xy 401.08886 -191.714628) (xy 401.088471 -191.741884) (xy 401.080709 -191.79584) (xy 401.065347 -191.848142)
			(xy 401.042698 -191.897726) (xy 401.013222 -191.943581) (xy 400.977521 -191.984775) (xy 400.93632 -192.020468)
			(xy 400.890459 -192.049934) (xy 400.840871 -192.072574) (xy 400.788566 -192.087925) (xy 400.734608 -192.095676)
			(xy 400.707352 -192.096136) (xy 400.680648 -192.095706) (xy 400.627762 -192.088251) (xy 400.576432 -192.073494)
			(xy 400.527662 -192.051723) (xy 400.482405 -192.023363) (xy 400.441545 -191.98897) (xy 400.42338 -191.96939)
			(xy 400.416144 -191.962107) (xy 400.397544 -191.953459) (xy 400.387312 -191.952626) (xy 400.332956 -191.950594)
			(xy 400.324066 -191.959738) (xy 400.31713 -191.967446) (xy 400.309518 -191.98671) (xy 400.309334 -191.997076)
			(xy 400.310096 -192.029334) (xy 400.310973 -192.039653) (xy 400.319734 -192.058394) (xy 400.327114 -192.065656)
			(xy 400.346701 -192.083813) (xy 400.381094 -192.124674) (xy 400.409451 -192.169933) (xy 400.431218 -192.218705)
			(xy 400.445968 -192.270036) (xy 400.453414 -192.322924) (xy 400.45386 -192.349628) (xy 400.453471 -192.376884)
			(xy 400.445709 -192.43084) (xy 400.430347 -192.483142) (xy 400.407698 -192.532726) (xy 400.378222 -192.578581)
			(xy 400.342521 -192.619775) (xy 400.30132 -192.655468) (xy 400.255459 -192.684934) (xy 400.205871 -192.707574)
			(xy 400.153566 -192.722925) (xy 400.099608 -192.730676) (xy 400.072352 -192.731136) (xy 400.042875 -192.730581)
			(xy 399.984621 -192.721518) (xy 399.928456 -192.7036) (xy 399.875717 -192.677254) (xy 399.827659 -192.643106)
			(xy 399.80616 -192.622932) (xy 399.798841 -192.616378) (xy 399.780668 -192.608946) (xy 399.770854 -192.608454)
			(xy 399.717514 -192.608454) (xy 399.710656 -192.61582) (xy 399.704114 -192.623148) (xy 399.696674 -192.641314)
			(xy 399.696178 -192.651126) (xy 399.696178 -192.68313) (xy 399.696664 -192.692944) (xy 399.70411 -192.711108)
			(xy 399.710656 -192.718436) (xy 399.730847 -192.739919) (xy 399.76499 -192.787983) (xy 399.791333 -192.840727)
			(xy 399.809249 -192.896895) (xy 399.818314 -192.95515) (xy 399.81886 -192.984628) (xy 399.818374 -193.011879)
			(xy 399.810618 -193.065827) (xy 399.795263 -193.118122) (xy 399.772621 -193.167699) (xy 399.743155 -193.213549)
			(xy 399.707464 -193.25474) (xy 399.666273 -193.290431) (xy 399.620423 -193.319897) (xy 399.570846 -193.342539)
			(xy 399.518551 -193.357894) (xy 399.464603 -193.36565) (xy 399.410101 -193.36565) (xy 399.356153 -193.357894)
			(xy 399.303858 -193.342539) (xy 399.254281 -193.319897) (xy 399.208431 -193.290431) (xy 399.16724 -193.25474)
			(xy 399.131549 -193.213549) (xy 399.102083 -193.167699) (xy 399.079441 -193.118122) (xy 399.064086 -193.065827)
			(xy 399.05633 -193.011879) (xy 399.055844 -192.984628) (xy 399.056316 -192.957258) (xy 399.064131 -192.903079)
			(xy 399.079618 -192.850575) (xy 399.102458 -192.800828) (xy 399.132183 -192.754861) (xy 399.149824 -192.73393)
			(xy 399.150078 -192.733676) (xy 399.15569 -192.726607) (xy 399.161919 -192.709676) (xy 399.16227 -192.700656)
			(xy 399.16227 -192.6336) (xy 399.16192 -192.624582) (xy 399.155668 -192.607665) (xy 399.150078 -192.60058)
			(xy 399.149824 -192.60058) (xy 399.149824 -192.600326) (xy 399.132187 -192.579392) (xy 399.102474 -192.53342)
			(xy 399.079638 -192.483673) (xy 399.064146 -192.431173) (xy 399.056318 -192.376997) (xy 399.055844 -192.349628)
			(xy 399.056294 -192.322058) (xy 399.064231 -192.267491) (xy 399.079943 -192.214636) (xy 399.103103 -192.164595)
			(xy 399.133228 -192.11841) (xy 399.151094 -192.097406) (xy 399.157698 -192.09004) (xy 399.164048 -192.07226)
			(xy 399.161508 -191.983614) (xy 399.153888 -191.965834) (xy 399.14703 -191.958976) (xy 399.126586 -191.937422)
			(xy 399.091906 -191.889194) (xy 399.065123 -191.836172) (xy 399.046886 -191.779639) (xy 399.037635 -191.720961)
			(xy 399.037048 -191.69126) (xy 399.037048 -191.690752) (xy 399.037533 -191.663382) (xy 399.045344 -191.609204)
			(xy 399.060828 -191.5567) (xy 399.083666 -191.506953) (xy 399.113388 -191.460986) (xy 399.131028 -191.440054)
			(xy 399.131282 -191.4398) (xy 399.136872 -191.432716) (xy 399.143117 -191.415797) (xy 399.143474 -191.40678)
			(xy 399.143474 -191.339724) (xy 399.143111 -191.330708) (xy 399.136868 -191.31379) (xy 399.131282 -191.306704)
			(xy 399.131028 -191.306704) (xy 399.131028 -191.30645) (xy 399.11334 -191.285555) (xy 399.083617 -191.239581)
			(xy 399.060775 -191.189828) (xy 399.045282 -191.137321) (xy 399.037458 -191.083137) (xy 399.037463 -191.028391)
			(xy 399.045298 -190.974209) (xy 399.0608 -190.921704) (xy 399.083652 -190.871956) (xy 399.113384 -190.825987)
			(xy 399.131028 -190.805054) (xy 399.131282 -190.8048) (xy 399.136872 -190.797716) (xy 399.143117 -190.780797)
			(xy 399.143474 -190.77178) (xy 399.143474 -190.704724) (xy 399.143111 -190.695708) (xy 399.136868 -190.67879)
			(xy 399.131282 -190.671704) (xy 399.131028 -190.671704) (xy 399.131028 -190.67145) (xy 399.11334 -190.650555)
			(xy 399.083617 -190.604581) (xy 399.060775 -190.554828) (xy 399.045282 -190.502321) (xy 399.037458 -190.448137)
			(xy 399.037463 -190.393391) (xy 399.045298 -190.339209) (xy 399.0608 -190.286704) (xy 399.083652 -190.236956)
			(xy 399.113384 -190.190987) (xy 399.131028 -190.170054) (xy 399.131282 -190.1698) (xy 399.136872 -190.162716)
			(xy 399.143117 -190.145797) (xy 399.143474 -190.13678) (xy 399.143474 -190.069724) (xy 399.143111 -190.060708)
			(xy 399.136868 -190.04379) (xy 399.131282 -190.036704) (xy 399.131028 -190.036704) (xy 399.131028 -190.03645)
			(xy 399.113403 -190.015506) (xy 399.083688 -189.969537) (xy 399.060849 -189.919793) (xy 399.045355 -189.867294)
			(xy 399.037524 -189.81312) (xy 399.037048 -189.785752) (xy 399.037518 -189.758618) (xy 399.045208 -189.704897)
			(xy 399.06044 -189.65281) (xy 399.082905 -189.603411) (xy 399.11215 -189.557697) (xy 399.129504 -189.536832)
			(xy 399.135151 -189.529631) (xy 399.141403 -189.512449) (xy 399.141696 -189.503304) (xy 399.141442 -189.436502)
			(xy 399.140947 -189.427447) (xy 399.134447 -189.410531) (xy 399.128742 -189.403482) (xy 399.128488 -189.403228)
			(xy 399.110572 -189.382222) (xy 399.080381 -189.335999) (xy 399.057169 -189.285906) (xy 399.041422 -189.23299)
			(xy 399.033469 -189.178357) (xy 399.032984 -189.150752) (xy 397.05026 -189.150752) (xy 397.049769 -189.177721)
			(xy 397.042169 -189.231121) (xy 397.027115 -189.282915) (xy 397.004907 -189.332069) (xy 396.975989 -189.377599)
			(xy 396.95882 -189.398402) (xy 396.953274 -189.40557) (xy 396.947159 -189.422617) (xy 396.946882 -189.431676)
			(xy 396.947644 -189.50813) (xy 396.953994 -189.524894) (xy 396.960344 -189.532006) (xy 396.978413 -189.553096)
			(xy 397.00892 -189.599501) (xy 397.032385 -189.649835) (xy 397.04831 -189.703037) (xy 397.056361 -189.757985)
			(xy 397.056864 -189.785752) (xy 397.056379 -189.813122) (xy 397.048567 -189.8673) (xy 397.033083 -189.919803)
			(xy 397.010245 -189.969551) (xy 396.980524 -190.015518) (xy 396.962884 -190.03645) (xy 396.96263 -190.036704)
			(xy 396.957027 -190.043779) (xy 396.950792 -190.060705) (xy 396.950438 -190.069724) (xy 396.950438 -190.13678)
			(xy 396.950796 -190.145797) (xy 396.957042 -190.162714) (xy 396.96263 -190.1698) (xy 396.962884 -190.1698)
			(xy 396.962884 -190.170054) (xy 396.980477 -190.191025) (xy 397.010203 -190.236986) (xy 397.033051 -190.286726)
			(xy 397.04855 -190.339223) (xy 397.056383 -190.393396) (xy 397.056388 -190.448132) (xy 397.048566 -190.502307)
			(xy 397.033076 -190.554806) (xy 397.010238 -190.60455) (xy 396.980521 -190.650517) (xy 396.962884 -190.67145)
			(xy 396.96263 -190.671704) (xy 396.957027 -190.678779) (xy 396.950792 -190.695705) (xy 396.950438 -190.704724)
			(xy 396.950438 -190.77178) (xy 396.950796 -190.780797) (xy 396.957042 -190.797714) (xy 396.96263 -190.8048)
			(xy 396.962884 -190.8048) (xy 396.962884 -190.805054) (xy 396.980477 -190.826025) (xy 397.010203 -190.871986)
			(xy 397.033051 -190.921726) (xy 397.04855 -190.974223) (xy 397.056383 -191.028396) (xy 397.056388 -191.083132)
			(xy 397.048566 -191.137307) (xy 397.033076 -191.189806) (xy 397.010238 -191.23955) (xy 396.980521 -191.285517)
			(xy 396.962884 -191.30645) (xy 396.96263 -191.306704) (xy 396.957027 -191.313779) (xy 396.950792 -191.330705)
			(xy 396.950438 -191.339724) (xy 396.950438 -191.40678) (xy 396.950796 -191.415797) (xy 396.957042 -191.432714)
			(xy 396.96263 -191.4398) (xy 396.962884 -191.4398) (xy 396.962884 -191.440054) (xy 396.980513 -191.460995)
			(xy 397.010226 -191.506965) (xy 397.033065 -191.55671) (xy 397.048558 -191.609209) (xy 397.056389 -191.663383)
			(xy 397.056864 -191.690752) (xy 397.056355 -191.719491) (xy 397.047726 -191.776318) (xy 397.030672 -191.831209)
			(xy 397.005577 -191.88292) (xy 396.973011 -191.930283) (xy 396.95374 -191.95161) (xy 396.947136 -191.958468)
			(xy 396.940024 -191.976502) (xy 396.93977 -192.065148) (xy 396.946882 -192.083182) (xy 396.953486 -192.09004)
			(xy 396.972533 -192.111328) (xy 397.004699 -192.15853) (xy 397.029473 -192.209999) (xy 397.046302 -192.264584)
			(xy 397.054809 -192.321068) (xy 397.05534 -192.349628) (xy 397.054905 -192.377) (xy 397.047082 -192.431181)
			(xy 397.031586 -192.483685) (xy 397.008737 -192.533431) (xy 396.979005 -192.579396) (xy 396.96136 -192.600326)
			(xy 396.961106 -192.60058) (xy 396.955522 -192.607669) (xy 396.949274 -192.624584) (xy 396.948914 -192.6336)
			(xy 396.948914 -192.700656) (xy 396.949289 -192.709671) (xy 396.955524 -192.726588) (xy 396.961106 -192.733676)
			(xy 396.96136 -192.733676) (xy 396.96136 -192.73393) (xy 396.979029 -192.75484) (xy 397.008753 -192.800812)
			(xy 397.031598 -192.850562) (xy 397.047092 -192.903067) (xy 397.054919 -192.957249) (xy 397.054916 -193.011993)
			(xy 397.047083 -193.066174) (xy 397.031583 -193.118678) (xy 397.008733 -193.168425) (xy 396.979003 -193.214393)
			(xy 396.96136 -193.235326) (xy 396.961106 -193.23558) (xy 396.955522 -193.242669) (xy 396.949274 -193.259584)
			(xy 396.948914 -193.2686) (xy 396.948914 -193.335656) (xy 396.949289 -193.344671) (xy 396.955524 -193.361588)
			(xy 396.961106 -193.368676) (xy 396.96136 -193.368676) (xy 396.96136 -193.36893) (xy 396.979029 -193.38984)
			(xy 397.008753 -193.435812) (xy 397.031598 -193.485562) (xy 397.047092 -193.538067) (xy 397.054919 -193.592249)
			(xy 397.054916 -193.646993) (xy 397.047083 -193.701174) (xy 397.031583 -193.753678) (xy 397.008733 -193.803425)
			(xy 396.979003 -193.849393) (xy 396.96136 -193.870326) (xy 396.961106 -193.87058) (xy 396.955522 -193.877669)
			(xy 396.949274 -193.894584) (xy 396.948914 -193.9036) (xy 396.948914 -193.970656) (xy 396.949289 -193.979671)
			(xy 396.955524 -193.996588) (xy 396.961106 -194.003676) (xy 396.96136 -194.003676) (xy 396.96136 -194.00393)
			(xy 396.979029 -194.02484) (xy 397.008753 -194.070812) (xy 397.031598 -194.120562) (xy 397.047092 -194.173067)
			(xy 397.054919 -194.227249) (xy 397.054916 -194.281993) (xy 397.047083 -194.336174) (xy 397.031583 -194.388678)
			(xy 397.008733 -194.438425) (xy 396.979003 -194.484393) (xy 396.96136 -194.505326) (xy 396.961106 -194.50558)
			(xy 396.955522 -194.512669) (xy 396.949274 -194.529584) (xy 396.948914 -194.5386) (xy 396.948914 -194.605656)
			(xy 396.949289 -194.614671) (xy 396.955524 -194.631588) (xy 396.961106 -194.638676) (xy 396.96136 -194.638676)
			(xy 396.96136 -194.63893) (xy 396.979029 -194.65984) (xy 397.008753 -194.705812) (xy 397.031598 -194.755562)
			(xy 397.047092 -194.808067) (xy 397.054919 -194.862249) (xy 397.054916 -194.916993) (xy 397.047083 -194.971174)
			(xy 397.031583 -195.023678) (xy 397.008733 -195.073425) (xy 396.979003 -195.119393) (xy 396.96136 -195.140326)
			(xy 396.961106 -195.14058) (xy 396.955522 -195.147669) (xy 396.949274 -195.164584) (xy 396.948914 -195.1736)
			(xy 396.948914 -195.240656) (xy 396.949289 -195.249671) (xy 396.955524 -195.266588) (xy 396.961106 -195.273676)
			(xy 396.96136 -195.273676) (xy 396.96136 -195.27393) (xy 396.978974 -195.294883) (xy 397.008691 -195.340849)
			(xy 397.031532 -195.390591) (xy 397.047029 -195.443088) (xy 397.054863 -195.49726) (xy 397.05534 -195.524628)
			(xy 397.054848 -195.551878) (xy 397.047089 -195.605824) (xy 397.031732 -195.658117) (xy 397.00909 -195.707692)
			(xy 396.979623 -195.753541) (xy 396.943933 -195.79473) (xy 396.902744 -195.830421) (xy 396.856896 -195.859888)
			(xy 396.807321 -195.88253) (xy 396.755028 -195.897888) (xy 396.701082 -195.905648) (xy 396.673832 -195.906136)
			(xy 396.646462 -195.905667) (xy 396.592282 -195.897852) (xy 396.539778 -195.882365) (xy 396.490031 -195.859523)
			(xy 396.444065 -195.829798) (xy 396.423134 -195.812156) (xy 396.42288 -195.811902) (xy 396.415803 -195.806301)
			(xy 396.398879 -195.800063) (xy 396.38986 -195.79971) (xy 396.322804 -195.79971) (xy 396.313787 -195.800067)
			(xy 396.29687 -195.806314) (xy 396.289784 -195.811902) (xy 396.28953 -195.812156) (xy 396.268597 -195.829797)
			(xy 396.222629 -195.859521) (xy 396.172883 -195.882367) (xy 396.120381 -195.897863) (xy 396.066203 -195.905692)
			(xy 396.011461 -195.905692) (xy 395.957283 -195.897863) (xy 395.904781 -195.882367) (xy 395.855035 -195.859521)
			(xy 395.809067 -195.829797) (xy 395.788134 -195.812156) (xy 395.78788 -195.811902) (xy 395.780803 -195.806301)
			(xy 395.763879 -195.800063) (xy 395.75486 -195.79971) (xy 395.687804 -195.79971) (xy 395.678787 -195.800067)
			(xy 395.66187 -195.806314) (xy 395.654784 -195.811902) (xy 395.654784 -195.812156) (xy 395.65453 -195.812156)
			(xy 395.633592 -195.829788) (xy 395.587621 -195.859502) (xy 395.537876 -195.88234) (xy 395.485376 -195.897833)
			(xy 395.431201 -195.905662) (xy 395.403832 -195.906136) (xy 395.376581 -195.905615) (xy 395.322634 -195.897863)
			(xy 395.270339 -195.882513) (xy 395.220761 -195.859876) (xy 395.174909 -195.830414) (xy 395.133716 -195.794726)
			(xy 395.098022 -195.753539) (xy 395.068553 -195.707692) (xy 395.045908 -195.658118) (xy 395.03055 -195.605825)
			(xy 395.022789 -195.551879) (xy 395.022324 -195.524628) (xy 395.022801 -195.497258) (xy 395.030615 -195.443079)
			(xy 395.046101 -195.390576) (xy 395.068941 -195.340829) (xy 395.098664 -195.294862) (xy 395.116304 -195.27393)
			(xy 395.116558 -195.273676) (xy 395.122168 -195.266605) (xy 395.128399 -195.249676) (xy 395.12875 -195.240656)
			(xy 395.12875 -195.1736) (xy 395.128404 -195.164582) (xy 395.12215 -195.147664) (xy 395.116558 -195.14058)
			(xy 395.116304 -195.14058) (xy 395.116304 -195.140326) (xy 395.098692 -195.119371) (xy 395.068968 -195.073406)
			(xy 395.046122 -195.023664) (xy 395.030624 -194.971165) (xy 395.022794 -194.91699) (xy 395.022791 -194.862252)
			(xy 395.030615 -194.808076) (xy 395.046107 -194.755576) (xy 395.068947 -194.705831) (xy 395.098666 -194.659863)
			(xy 395.116304 -194.63893) (xy 395.116558 -194.638676) (xy 395.122168 -194.631605) (xy 395.128399 -194.614676)
			(xy 395.12875 -194.605656) (xy 395.12875 -194.5386) (xy 395.128404 -194.529582) (xy 395.12215 -194.512664)
			(xy 395.116558 -194.50558) (xy 395.116304 -194.50558) (xy 395.116304 -194.505326) (xy 395.098692 -194.484371)
			(xy 395.068968 -194.438406) (xy 395.046122 -194.388664) (xy 395.030624 -194.336165) (xy 395.022794 -194.28199)
			(xy 395.022791 -194.227252) (xy 395.030615 -194.173076) (xy 395.046107 -194.120576) (xy 395.068947 -194.070831)
			(xy 395.098666 -194.024863) (xy 395.116304 -194.00393) (xy 395.116558 -194.003676) (xy 395.122168 -193.996605)
			(xy 395.128399 -193.979676) (xy 395.12875 -193.970656) (xy 395.12875 -193.9036) (xy 395.128404 -193.894582)
			(xy 395.12215 -193.877664) (xy 395.116558 -193.87058) (xy 395.116304 -193.87058) (xy 395.116304 -193.870326)
			(xy 395.098692 -193.849371) (xy 395.068968 -193.803406) (xy 395.046122 -193.753664) (xy 395.030624 -193.701165)
			(xy 395.022794 -193.64699) (xy 395.022791 -193.592252) (xy 395.030615 -193.538076) (xy 395.046107 -193.485576)
			(xy 395.068947 -193.435831) (xy 395.098666 -193.389863) (xy 395.116304 -193.36893) (xy 395.116558 -193.368676)
			(xy 395.122168 -193.361605) (xy 395.128399 -193.344676) (xy 395.12875 -193.335656) (xy 395.12875 -193.2686)
			(xy 395.128404 -193.259582) (xy 395.12215 -193.242664) (xy 395.116558 -193.23558) (xy 395.116304 -193.23558)
			(xy 395.116304 -193.235326) (xy 395.098692 -193.214371) (xy 395.068968 -193.168406) (xy 395.046122 -193.118664)
			(xy 395.030624 -193.066165) (xy 395.022794 -193.01199) (xy 395.022791 -192.957252) (xy 395.030615 -192.903076)
			(xy 395.046107 -192.850576) (xy 395.068947 -192.800831) (xy 395.098666 -192.754863) (xy 395.116304 -192.73393)
			(xy 395.116558 -192.733676) (xy 395.122168 -192.726605) (xy 395.128399 -192.709676) (xy 395.12875 -192.700656)
			(xy 395.12875 -192.6336) (xy 395.128404 -192.624582) (xy 395.12215 -192.607664) (xy 395.116558 -192.60058)
			(xy 395.116304 -192.60058) (xy 395.116304 -192.600326) (xy 395.098692 -192.579371) (xy 395.068968 -192.533406)
			(xy 395.046122 -192.483664) (xy 395.030624 -192.431165) (xy 395.022794 -192.37699) (xy 395.022791 -192.322252)
			(xy 395.030615 -192.268076) (xy 395.046107 -192.215576) (xy 395.068947 -192.165831) (xy 395.098666 -192.119863)
			(xy 395.116304 -192.09893) (xy 395.116558 -192.098676) (xy 395.122168 -192.091605) (xy 395.128399 -192.074676)
			(xy 395.12875 -192.065656) (xy 395.12875 -191.9986) (xy 395.128404 -191.989582) (xy 395.12215 -191.972664)
			(xy 395.116558 -191.96558) (xy 395.116304 -191.96558) (xy 395.116304 -191.965326) (xy 395.098692 -191.944371)
			(xy 395.068968 -191.898406) (xy 395.046122 -191.848664) (xy 395.030624 -191.796165) (xy 395.022794 -191.74199)
			(xy 395.022791 -191.687252) (xy 395.030615 -191.633076) (xy 395.046107 -191.580576) (xy 395.068947 -191.530831)
			(xy 395.098666 -191.484863) (xy 395.116304 -191.46393) (xy 395.116558 -191.463676) (xy 395.122168 -191.456605)
			(xy 395.128399 -191.439676) (xy 395.12875 -191.430656) (xy 395.12875 -191.3636) (xy 395.128404 -191.354582)
			(xy 395.12215 -191.337664) (xy 395.116558 -191.33058) (xy 395.116304 -191.33058) (xy 395.116304 -191.330326)
			(xy 395.098692 -191.309371) (xy 395.068968 -191.263406) (xy 395.046122 -191.213664) (xy 395.030624 -191.161165)
			(xy 395.022794 -191.10699) (xy 395.022791 -191.052252) (xy 395.030615 -190.998076) (xy 395.046107 -190.945576)
			(xy 395.068947 -190.895831) (xy 395.098666 -190.849863) (xy 395.116304 -190.82893) (xy 395.116558 -190.828676)
			(xy 395.122168 -190.821605) (xy 395.128399 -190.804676) (xy 395.12875 -190.795656) (xy 395.12875 -190.7286)
			(xy 395.128404 -190.719582) (xy 395.12215 -190.702664) (xy 395.116558 -190.69558) (xy 395.116304 -190.69558)
			(xy 395.116304 -190.695326) (xy 395.098692 -190.674371) (xy 395.068968 -190.628406) (xy 395.046122 -190.578664)
			(xy 395.030624 -190.526165) (xy 395.022794 -190.47199) (xy 395.022791 -190.417252) (xy 395.030615 -190.363076)
			(xy 395.046107 -190.310576) (xy 395.068947 -190.260831) (xy 395.098666 -190.214863) (xy 395.116304 -190.19393)
			(xy 395.116558 -190.193676) (xy 395.122168 -190.186605) (xy 395.128399 -190.169676) (xy 395.12875 -190.160656)
			(xy 395.12875 -190.0936) (xy 395.128404 -190.084582) (xy 395.12215 -190.067664) (xy 395.116558 -190.06058)
			(xy 395.116304 -190.06058) (xy 395.116304 -190.060326) (xy 395.098664 -190.039394) (xy 395.068952 -189.993422)
			(xy 395.046116 -189.943674) (xy 395.030626 -189.891173) (xy 395.022798 -189.836997) (xy 395.022324 -189.809628)
			(xy 395.022851 -189.781268) (xy 395.03124 -189.725173) (xy 395.04785 -189.670941) (xy 395.072315 -189.619771)
			(xy 395.104095 -189.572791) (xy 395.122908 -189.551564) (xy 395.129013 -189.54427) (xy 395.135817 -189.526526)
			(xy 395.136116 -189.51702) (xy 395.135608 -189.438026) (xy 395.128496 -189.419992) (xy 395.121638 -189.413134)
			(xy 395.102142 -189.391769) (xy 395.069174 -189.344251) (xy 395.043765 -189.292296) (xy 395.026499 -189.237097)
			(xy 395.017774 -189.179924) (xy 395.017244 -189.151006) (xy 355.125528 -189.151006) (xy 358.286304 -192.311782)
			(xy 361.16387 -192.311782) (xy 361.164308 -192.284411) (xy 361.17213 -192.23023) (xy 361.187625 -192.177726)
			(xy 361.210473 -192.127979) (xy 361.240205 -192.082014) (xy 361.25785 -192.061084) (xy 361.258104 -192.06083)
			(xy 361.263685 -192.053739) (xy 361.269935 -192.036826) (xy 361.270296 -192.02781) (xy 361.270296 -191.960754)
			(xy 361.269914 -191.95174) (xy 361.263684 -191.934823) (xy 361.258104 -191.927734) (xy 361.25785 -191.927734)
			(xy 361.25785 -191.92748) (xy 361.240191 -191.906562) (xy 361.210465 -191.860592) (xy 361.187619 -191.810844)
			(xy 361.172123 -191.758339) (xy 361.164296 -191.704158) (xy 361.164298 -191.649415) (xy 361.172129 -191.595234)
			(xy 361.187629 -191.542731) (xy 361.210478 -191.492984) (xy 361.240207 -191.447016) (xy 361.25785 -191.426084)
			(xy 361.258104 -191.42583) (xy 361.263685 -191.418739) (xy 361.269935 -191.401826) (xy 361.270296 -191.39281)
			(xy 361.270296 -191.325754) (xy 361.269914 -191.31674) (xy 361.263684 -191.299823) (xy 361.258104 -191.292734)
			(xy 361.25785 -191.292734) (xy 361.25785 -191.29248) (xy 361.240191 -191.271562) (xy 361.210465 -191.225592)
			(xy 361.187619 -191.175844) (xy 361.172123 -191.123339) (xy 361.164296 -191.069158) (xy 361.164298 -191.014415)
			(xy 361.172129 -190.960234) (xy 361.187629 -190.907731) (xy 361.210478 -190.857984) (xy 361.240207 -190.812016)
			(xy 361.25785 -190.791084) (xy 361.258104 -190.79083) (xy 361.263685 -190.783739) (xy 361.269935 -190.766826)
			(xy 361.270296 -190.75781) (xy 361.270296 -190.690754) (xy 361.269914 -190.68174) (xy 361.263684 -190.664823)
			(xy 361.258104 -190.657734) (xy 361.25785 -190.657734) (xy 361.25785 -190.65748) (xy 361.240243 -190.636522)
			(xy 361.210524 -190.590557) (xy 361.187682 -190.540816) (xy 361.172183 -190.488321) (xy 361.164348 -190.43415)
			(xy 361.16387 -190.406782) (xy 361.164354 -190.378148) (xy 361.172906 -190.321521) (xy 361.189828 -190.26681)
			(xy 361.214741 -190.215244) (xy 361.247085 -190.167983) (xy 361.266232 -190.146686) (xy 361.272836 -190.139574)
			(xy 361.279694 -190.122048) (xy 361.280202 -190.043308) (xy 361.279816 -190.033781) (xy 361.272916 -190.016026)
			(xy 361.26674 -190.008764) (xy 361.247972 -189.987544) (xy 361.216273 -189.940595) (xy 361.19187 -189.889473)
			(xy 361.175299 -189.835304) (xy 361.166924 -189.779278) (xy 361.16641 -189.750954) (xy 361.166835 -189.723701)
			(xy 361.174598 -189.66975) (xy 361.18996 -189.617453) (xy 361.212608 -189.567874) (xy 361.242081 -189.522023)
			(xy 361.277779 -189.480833) (xy 361.318975 -189.445142) (xy 361.364831 -189.415677) (xy 361.414413 -189.393038)
			(xy 361.466713 -189.377685) (xy 361.520665 -189.369931) (xy 361.547918 -189.369446) (xy 361.575289 -189.36989)
			(xy 361.62947 -189.377712) (xy 361.681973 -189.393205) (xy 361.73172 -189.416052) (xy 361.777685 -189.445782)
			(xy 361.798616 -189.463426) (xy 361.79887 -189.46368) (xy 361.805954 -189.469269) (xy 361.822873 -189.475512)
			(xy 361.83189 -189.475872) (xy 361.898946 -189.475872) (xy 361.907961 -189.475495) (xy 361.924878 -189.469262)
			(xy 361.931966 -189.46368) (xy 361.931966 -189.463426) (xy 361.93222 -189.463426) (xy 361.953153 -189.445785)
			(xy 361.999121 -189.416061) (xy 362.048867 -189.393215) (xy 362.101369 -189.377719) (xy 362.155547 -189.36989)
			(xy 362.210289 -189.36989) (xy 362.264467 -189.377719) (xy 362.316969 -189.393215) (xy 362.366715 -189.416061)
			(xy 362.412683 -189.445785) (xy 362.433616 -189.463426) (xy 362.43387 -189.46368) (xy 362.440954 -189.469269)
			(xy 362.457873 -189.475512) (xy 362.46689 -189.475872) (xy 362.533946 -189.475872) (xy 362.542961 -189.475495)
			(xy 362.559878 -189.469262) (xy 362.566966 -189.46368) (xy 362.566966 -189.463426) (xy 362.56722 -189.463426)
			(xy 362.588175 -189.445815) (xy 362.634141 -189.416098) (xy 362.683883 -189.393256) (xy 362.736378 -189.377759)
			(xy 362.79055 -189.369924) (xy 362.817918 -189.369446) (xy 362.845168 -189.369961) (xy 362.899112 -189.377719)
			(xy 362.951403 -189.393074) (xy 363.000978 -189.415714) (xy 363.046826 -189.445178) (xy 363.088014 -189.480866)
			(xy 363.123706 -189.522052) (xy 363.153173 -189.567898) (xy 363.175816 -189.61747) (xy 363.191175 -189.669761)
			(xy 363.198937 -189.723704) (xy 363.199426 -189.750954) (xy 365.18215 -189.750954) (xy 365.182635 -189.723704)
			(xy 365.190397 -189.669758) (xy 365.205755 -189.617466) (xy 365.228399 -189.567891) (xy 365.257866 -189.522043)
			(xy 365.293557 -189.480854) (xy 365.334746 -189.445164) (xy 365.380595 -189.415697) (xy 365.43017 -189.393054)
			(xy 365.482462 -189.377696) (xy 365.536408 -189.369935) (xy 365.563658 -189.369446) (xy 365.591028 -189.369925)
			(xy 365.645207 -189.377738) (xy 365.69771 -189.393224) (xy 365.747457 -189.416063) (xy 365.793424 -189.445785)
			(xy 365.814356 -189.463426) (xy 365.81461 -189.46368) (xy 365.821683 -189.469286) (xy 365.83861 -189.475519)
			(xy 365.84763 -189.475872) (xy 365.914686 -189.475872) (xy 365.923703 -189.475514) (xy 365.94062 -189.469268)
			(xy 365.947706 -189.46368) (xy 365.947706 -189.463426) (xy 365.94796 -189.463426) (xy 365.9689 -189.445796)
			(xy 366.01487 -189.416082) (xy 366.064616 -189.393244) (xy 366.117115 -189.377751) (xy 366.171289 -189.369921)
			(xy 366.198658 -189.369446) (xy 366.225906 -189.370017) (xy 366.279848 -189.377767) (xy 366.332139 -189.393114)
			(xy 366.381713 -189.415747) (xy 366.427561 -189.445205) (xy 366.46875 -189.480887) (xy 366.504443 -189.522069)
			(xy 366.533911 -189.56791) (xy 366.556555 -189.617479) (xy 366.571915 -189.669766) (xy 366.579677 -189.723706)
			(xy 366.580166 -189.750954) (xy 366.579696 -189.778088) (xy 366.572006 -189.831809) (xy 366.556774 -189.883895)
			(xy 366.534308 -189.933295) (xy 366.505064 -189.979009) (xy 366.48771 -189.999874) (xy 366.482062 -190.007074)
			(xy 366.47581 -190.024256) (xy 366.475518 -190.033402) (xy 366.475772 -190.100204) (xy 366.476261 -190.10926)
			(xy 366.482765 -190.126176) (xy 366.488472 -190.133224) (xy 366.488726 -190.133478) (xy 366.506647 -190.15448)
			(xy 366.536837 -190.200704) (xy 366.560047 -190.250798) (xy 366.575793 -190.303715) (xy 366.583745 -190.358349)
			(xy 366.58423 -190.385954) (xy 366.583754 -190.413324) (xy 366.575941 -190.467503) (xy 366.560455 -190.520007)
			(xy 366.537615 -190.569754) (xy 366.507891 -190.615721) (xy 366.49025 -190.636652) (xy 366.489996 -190.636906)
			(xy 366.4844 -190.643986) (xy 366.478159 -190.660908) (xy 366.477804 -190.669926) (xy 366.477804 -190.736982)
			(xy 366.478169 -190.745998) (xy 366.484411 -190.762915) (xy 366.489996 -190.770002) (xy 366.49025 -190.770002)
			(xy 366.49025 -190.770256) (xy 366.507847 -190.791225) (xy 366.537575 -190.837186) (xy 366.560424 -190.886926)
			(xy 366.575925 -190.939423) (xy 366.583759 -190.993597) (xy 366.583764 -191.048334) (xy 366.57594 -191.10251)
			(xy 366.560449 -191.155009) (xy 366.537608 -191.204753) (xy 366.507888 -191.25072) (xy 366.49025 -191.271652)
			(xy 366.489996 -191.271906) (xy 366.4844 -191.278986) (xy 366.478159 -191.295908) (xy 366.477804 -191.304926)
			(xy 366.477804 -191.371982) (xy 366.478169 -191.380998) (xy 366.484411 -191.397915) (xy 366.489996 -191.405002)
			(xy 366.49025 -191.405002) (xy 366.49025 -191.405256) (xy 366.507874 -191.4262) (xy 366.53759 -191.472169)
			(xy 366.56043 -191.521913) (xy 366.575924 -191.574412) (xy 366.583755 -191.628586) (xy 366.58423 -191.655954)
			(xy 366.583681 -191.685431) (xy 366.574617 -191.743685) (xy 366.556697 -191.79985) (xy 366.530349 -191.85259)
			(xy 366.496201 -191.900647) (xy 366.476026 -191.922146) (xy 366.469469 -191.929463) (xy 366.462039 -191.947637)
			(xy 366.461548 -191.957452) (xy 366.461548 -192.010792) (xy 366.464088 -192.013078) (xy 366.470946 -192.019428)
			(xy 366.487964 -192.02654) (xy 366.573816 -192.029588) (xy 366.591342 -192.023492) (xy 366.598454 -192.017396)
			(xy 366.61901 -192.000977) (xy 366.663813 -191.973401) (xy 366.711984 -191.952251) (xy 366.762607 -191.937929)
			(xy 366.814719 -191.930708) (xy 366.841024 -191.930274) (xy 366.841278 -191.930274) (xy 366.868529 -191.930776)
			(xy 366.922478 -191.938529) (xy 366.974774 -191.953882) (xy 367.024353 -191.97652) (xy 367.070205 -192.005984)
			(xy 367.111398 -192.041674) (xy 367.147092 -192.082863) (xy 367.176561 -192.128712) (xy 367.199204 -192.178288)
			(xy 367.214562 -192.230583) (xy 367.222321 -192.284531) (xy 367.222786 -192.311782) (xy 367.222313 -192.339152)
			(xy 367.214497 -192.393331) (xy 367.19901 -192.445834) (xy 367.17617 -192.495581) (xy 367.146447 -192.541548)
			(xy 367.128806 -192.56248) (xy 367.128552 -192.562734) (xy 367.122981 -192.569831) (xy 367.116726 -192.58674)
			(xy 367.11636 -192.595754) (xy 367.11636 -192.66281) (xy 367.116699 -192.671829) (xy 367.122958 -192.688746)
			(xy 367.128552 -192.69583) (xy 367.128806 -192.69583) (xy 367.128806 -192.696084) (xy 367.146428 -192.717032)
			(xy 367.176151 -192.762998) (xy 367.198995 -192.812742) (xy 367.214491 -192.865241) (xy 367.222321 -192.919417)
			(xy 367.222323 -192.974156) (xy 367.214497 -193.028332) (xy 367.199005 -193.080833) (xy 367.176164 -193.130579)
			(xy 367.146444 -193.176547) (xy 367.128806 -193.19748) (xy 367.128552 -193.197734) (xy 367.122981 -193.204831)
			(xy 367.116726 -193.22174) (xy 367.11636 -193.230754) (xy 367.11636 -193.29781) (xy 367.116699 -193.306829)
			(xy 367.122958 -193.323746) (xy 367.128552 -193.33083) (xy 367.128806 -193.33083) (xy 367.128806 -193.331084)
			(xy 367.146428 -193.352032) (xy 367.176151 -193.397998) (xy 367.198995 -193.447742) (xy 367.214491 -193.500241)
			(xy 367.222321 -193.554417) (xy 367.222323 -193.609156) (xy 367.214497 -193.663332) (xy 367.199005 -193.715833)
			(xy 367.176164 -193.765579) (xy 367.146444 -193.811547) (xy 367.128806 -193.83248) (xy 367.128552 -193.832734)
			(xy 367.122981 -193.839831) (xy 367.116726 -193.85674) (xy 367.11636 -193.865754) (xy 367.11636 -193.93281)
			(xy 367.116699 -193.941829) (xy 367.122958 -193.958746) (xy 367.128552 -193.96583) (xy 367.128806 -193.96583)
			(xy 367.128806 -193.966084) (xy 367.146428 -193.987032) (xy 367.176151 -194.032998) (xy 367.198995 -194.082742)
			(xy 367.214491 -194.135241) (xy 367.222321 -194.189417) (xy 367.222323 -194.244156) (xy 367.214497 -194.298332)
			(xy 367.199005 -194.350833) (xy 367.176164 -194.400579) (xy 367.146444 -194.446547) (xy 367.128806 -194.46748)
			(xy 367.128552 -194.467734) (xy 367.122981 -194.474831) (xy 367.116726 -194.49174) (xy 367.11636 -194.500754)
			(xy 367.11636 -194.56781) (xy 367.116699 -194.576829) (xy 367.122958 -194.593746) (xy 367.128552 -194.60083)
			(xy 367.128806 -194.60083) (xy 367.128806 -194.601084) (xy 367.146428 -194.622032) (xy 367.176151 -194.667998)
			(xy 367.198995 -194.717742) (xy 367.214491 -194.770241) (xy 367.222321 -194.824417) (xy 367.222323 -194.879156)
			(xy 367.214497 -194.933332) (xy 367.199005 -194.985833) (xy 367.176164 -195.035579) (xy 367.146444 -195.081547)
			(xy 367.128806 -195.10248) (xy 367.128552 -195.102734) (xy 367.122981 -195.109831) (xy 367.116726 -195.12674)
			(xy 367.11636 -195.135754) (xy 367.11636 -195.20281) (xy 367.116699 -195.211829) (xy 367.122958 -195.228746)
			(xy 367.128552 -195.23583) (xy 367.128806 -195.23583) (xy 367.128806 -195.236084) (xy 367.146428 -195.257032)
			(xy 367.176151 -195.302998) (xy 367.198995 -195.352742) (xy 367.214491 -195.405241) (xy 367.222321 -195.459417)
			(xy 367.222323 -195.514156) (xy 367.214497 -195.568332) (xy 367.199005 -195.620833) (xy 367.176164 -195.670579)
			(xy 367.146444 -195.716547) (xy 367.128806 -195.73748) (xy 367.128552 -195.737734) (xy 367.122981 -195.744831)
			(xy 367.116726 -195.76174) (xy 367.11636 -195.770754) (xy 367.11636 -195.83781) (xy 367.116699 -195.846829)
			(xy 367.122958 -195.863746) (xy 367.128552 -195.87083) (xy 367.128806 -195.87083) (xy 367.128806 -195.871084)
			(xy 367.146452 -195.89201) (xy 367.176163 -195.937985) (xy 367.198997 -195.987734) (xy 367.214487 -196.040236)
			(xy 367.222313 -196.094412) (xy 367.222786 -196.121782) (xy 367.222328 -196.149035) (xy 367.214573 -196.202988)
			(xy 367.199218 -196.255287) (xy 367.176576 -196.304868) (xy 367.147108 -196.350723) (xy 367.111413 -196.391916)
			(xy 367.07022 -196.42761) (xy 367.024365 -196.457078) (xy 366.974783 -196.479719) (xy 366.922484 -196.495074)
			(xy 366.868531 -196.502828) (xy 366.841278 -196.50329) (xy 366.813907 -196.502839) (xy 366.759727 -196.495018)
			(xy 366.707224 -196.479526) (xy 366.657477 -196.45668) (xy 366.611511 -196.426953) (xy 366.59058 -196.40931)
			(xy 366.590326 -196.409056) (xy 366.58324 -196.403469) (xy 366.566323 -196.397224) (xy 366.557306 -196.396864)
			(xy 366.49025 -196.396864) (xy 366.481236 -196.397253) (xy 366.46432 -196.403479) (xy 366.45723 -196.409056)
			(xy 366.45723 -196.40931) (xy 366.456976 -196.40931) (xy 366.436027 -196.426928) (xy 366.390059 -196.456643)
			(xy 366.340316 -196.479483) (xy 366.287819 -196.494979) (xy 366.233646 -196.502813) (xy 366.206278 -196.50329)
			(xy 366.179025 -196.502843) (xy 366.125075 -196.495083) (xy 366.072779 -196.479724) (xy 366.0232 -196.457079)
			(xy 365.977349 -196.427609) (xy 365.936159 -196.391913) (xy 365.900467 -196.350719) (xy 365.871002 -196.304865)
			(xy 365.848362 -196.255284) (xy 365.833009 -196.202986) (xy 365.825255 -196.149035) (xy 365.82477 -196.121782)
			(xy 365.825279 -196.092303) (xy 365.834353 -196.034047) (xy 365.852282 -195.977882) (xy 365.878638 -195.925143)
			(xy 365.912795 -195.877087) (xy 365.932974 -195.85559) (xy 365.939516 -195.848261) (xy 365.946955 -195.830096)
			(xy 365.947452 -195.820284) (xy 365.947452 -195.766944) (xy 365.940086 -195.760086) (xy 365.932752 -195.75355)
			(xy 365.914591 -195.746106) (xy 365.90478 -195.745608) (xy 365.872776 -195.745608) (xy 365.862961 -195.746089)
			(xy 365.844797 -195.753537) (xy 365.83747 -195.760086) (xy 365.815989 -195.78028) (xy 365.767924 -195.81442)
			(xy 365.71518 -195.840762) (xy 365.659012 -195.858679) (xy 365.600756 -195.867743) (xy 365.571278 -195.86829)
			(xy 365.544025 -195.867843) (xy 365.490075 -195.860083) (xy 365.437779 -195.844724) (xy 365.3882 -195.822079)
			(xy 365.342349 -195.792609) (xy 365.301159 -195.756913) (xy 365.265467 -195.715719) (xy 365.236002 -195.669865)
			(xy 365.213362 -195.620284) (xy 365.198009 -195.567986) (xy 365.190255 -195.514035) (xy 365.18977 -195.486782)
			(xy 365.190208 -195.459411) (xy 365.19803 -195.40523) (xy 365.213525 -195.352726) (xy 365.236373 -195.302979)
			(xy 365.266105 -195.257014) (xy 365.28375 -195.236084) (xy 365.284004 -195.23583) (xy 365.289585 -195.228739)
			(xy 365.295835 -195.211826) (xy 365.296196 -195.20281) (xy 365.296196 -195.135754) (xy 365.295814 -195.12674)
			(xy 365.289584 -195.109823) (xy 365.284004 -195.102734) (xy 365.28375 -195.102734) (xy 365.28375 -195.10248)
			(xy 365.266091 -195.081562) (xy 365.236365 -195.035592) (xy 365.213519 -194.985844) (xy 365.198023 -194.933339)
			(xy 365.190196 -194.879158) (xy 365.190198 -194.824415) (xy 365.198029 -194.770234) (xy 365.213529 -194.717731)
			(xy 365.236378 -194.667984) (xy 365.266107 -194.622016) (xy 365.28375 -194.601084) (xy 365.284004 -194.60083)
			(xy 365.289585 -194.593739) (xy 365.295835 -194.576826) (xy 365.296196 -194.56781) (xy 365.296196 -194.500754)
			(xy 365.295814 -194.49174) (xy 365.289584 -194.474823) (xy 365.284004 -194.467734) (xy 365.28375 -194.467734)
			(xy 365.28375 -194.46748) (xy 365.266091 -194.446562) (xy 365.236365 -194.400592) (xy 365.213519 -194.350844)
			(xy 365.198023 -194.298339) (xy 365.190196 -194.244158) (xy 365.190198 -194.189415) (xy 365.198029 -194.135234)
			(xy 365.213529 -194.082731) (xy 365.236378 -194.032984) (xy 365.266107 -193.987016) (xy 365.28375 -193.966084)
			(xy 365.284004 -193.96583) (xy 365.289585 -193.958739) (xy 365.295835 -193.941826) (xy 365.296196 -193.93281)
			(xy 365.296196 -193.865754) (xy 365.295814 -193.85674) (xy 365.289584 -193.839823) (xy 365.284004 -193.832734)
			(xy 365.28375 -193.832734) (xy 365.28375 -193.83248) (xy 365.266091 -193.811562) (xy 365.236365 -193.765592)
			(xy 365.213519 -193.715844) (xy 365.198023 -193.663339) (xy 365.190196 -193.609158) (xy 365.190198 -193.554415)
			(xy 365.198029 -193.500234) (xy 365.213529 -193.447731) (xy 365.236378 -193.397984) (xy 365.266107 -193.352016)
			(xy 365.28375 -193.331084) (xy 365.284004 -193.33083) (xy 365.289585 -193.323739) (xy 365.295835 -193.306826)
			(xy 365.296196 -193.29781) (xy 365.296196 -193.230754) (xy 365.295814 -193.22174) (xy 365.289584 -193.204823)
			(xy 365.284004 -193.197734) (xy 365.28375 -193.197734) (xy 365.28375 -193.19748) (xy 365.266143 -193.176522)
			(xy 365.236424 -193.130557) (xy 365.213582 -193.080816) (xy 365.198083 -193.028321) (xy 365.190248 -192.97415)
			(xy 365.18977 -192.946782) (xy 365.190317 -192.918496) (xy 365.198672 -192.862543) (xy 365.215196 -192.808438)
			(xy 365.239527 -192.757364) (xy 365.271132 -192.710443) (xy 365.289846 -192.689226) (xy 365.296196 -192.682368)
			(xy 365.303054 -192.664588) (xy 365.302546 -192.585594) (xy 365.302105 -192.576233) (xy 365.295311 -192.558781)
			(xy 365.289338 -192.551558) (xy 365.28883 -192.55105) (xy 365.269645 -192.529775) (xy 365.237265 -192.482517)
			(xy 365.212312 -192.430951) (xy 365.195345 -192.376235) (xy 365.186746 -192.319597) (xy 365.186214 -192.290954)
			(xy 365.186708 -192.263585) (xy 365.194519 -192.209407) (xy 365.210001 -192.156904) (xy 365.232837 -192.107156)
			(xy 365.262555 -192.061188) (xy 365.280194 -192.040256) (xy 365.280448 -192.040002) (xy 365.286046 -192.032923)
			(xy 365.292285 -192.016) (xy 365.29264 -192.006982) (xy 365.29264 -191.939926) (xy 365.292284 -191.930909)
			(xy 365.286037 -191.913991) (xy 365.280448 -191.906906) (xy 365.280194 -191.906906) (xy 365.280194 -191.906652)
			(xy 365.26251 -191.885755) (xy 365.232789 -191.83978) (xy 365.209949 -191.790028) (xy 365.194457 -191.737521)
			(xy 365.186634 -191.683338) (xy 365.186639 -191.628593) (xy 365.194472 -191.574412) (xy 365.209973 -191.521907)
			(xy 365.232823 -191.472159) (xy 365.262551 -191.426189) (xy 365.280194 -191.405256) (xy 365.280448 -191.405002)
			(xy 365.286046 -191.397923) (xy 365.292285 -191.381) (xy 365.29264 -191.371982) (xy 365.29264 -191.304926)
			(xy 365.292284 -191.295909) (xy 365.286037 -191.278991) (xy 365.280448 -191.271906) (xy 365.280194 -191.271906)
			(xy 365.280194 -191.271652) (xy 365.26251 -191.250755) (xy 365.232789 -191.20478) (xy 365.209949 -191.155028)
			(xy 365.194457 -191.102521) (xy 365.186634 -191.048338) (xy 365.186639 -190.993593) (xy 365.194472 -190.939412)
			(xy 365.209973 -190.886907) (xy 365.232823 -190.837159) (xy 365.262551 -190.791189) (xy 365.280194 -190.770256)
			(xy 365.280448 -190.770002) (xy 365.286046 -190.762923) (xy 365.292285 -190.746) (xy 365.29264 -190.736982)
			(xy 365.29264 -190.669926) (xy 365.292284 -190.660909) (xy 365.286037 -190.643991) (xy 365.280448 -190.636906)
			(xy 365.280194 -190.636906) (xy 365.280194 -190.636652) (xy 365.262565 -190.615712) (xy 365.232852 -190.569741)
			(xy 365.210014 -190.519996) (xy 365.194521 -190.467497) (xy 365.18669 -190.413323) (xy 365.186214 -190.385954)
			(xy 365.186693 -190.35882) (xy 365.194382 -190.3051) (xy 365.209612 -190.253014) (xy 365.232075 -190.203614)
			(xy 365.261318 -190.157899) (xy 365.27867 -190.137034) (xy 365.284312 -190.12983) (xy 365.290568 -190.112651)
			(xy 365.290862 -190.103506) (xy 365.290608 -190.036704) (xy 365.290097 -190.027651) (xy 365.283607 -190.010735)
			(xy 365.277908 -190.003684) (xy 365.277654 -190.00343) (xy 365.259734 -189.982428) (xy 365.229544 -189.936203)
			(xy 365.206334 -189.886109) (xy 365.190588 -189.833193) (xy 365.182635 -189.778559) (xy 365.18215 -189.750954)
			(xy 363.199426 -189.750954) (xy 363.198944 -189.777923) (xy 363.191343 -189.831324) (xy 363.176288 -189.883118)
			(xy 363.154077 -189.932272) (xy 363.125157 -189.977802) (xy 363.107986 -189.998604) (xy 363.102436 -190.005769)
			(xy 363.096324 -190.022819) (xy 363.096048 -190.031878) (xy 363.09681 -190.108332) (xy 363.10316 -190.125096)
			(xy 363.10951 -190.132208) (xy 363.127574 -190.153302) (xy 363.158084 -190.199705) (xy 363.181549 -190.250038)
			(xy 363.197476 -190.30324) (xy 363.205528 -190.358187) (xy 363.20603 -190.385954) (xy 363.205554 -190.413324)
			(xy 363.197741 -190.467503) (xy 363.182255 -190.520007) (xy 363.159415 -190.569754) (xy 363.129691 -190.615721)
			(xy 363.11205 -190.636652) (xy 363.111796 -190.636906) (xy 363.1062 -190.643986) (xy 363.099959 -190.660908)
			(xy 363.099604 -190.669926) (xy 363.099604 -190.736982) (xy 363.099969 -190.745998) (xy 363.106211 -190.762915)
			(xy 363.111796 -190.770002) (xy 363.11205 -190.770002) (xy 363.11205 -190.770256) (xy 363.129647 -190.791225)
			(xy 363.159375 -190.837186) (xy 363.182224 -190.886926) (xy 363.197725 -190.939423) (xy 363.205559 -190.993597)
			(xy 363.205564 -191.048334) (xy 363.19774 -191.10251) (xy 363.182249 -191.155009) (xy 363.159408 -191.204753)
			(xy 363.129688 -191.25072) (xy 363.11205 -191.271652) (xy 363.111796 -191.271906) (xy 363.1062 -191.278986)
			(xy 363.099959 -191.295908) (xy 363.099604 -191.304926) (xy 363.099604 -191.371982) (xy 363.099969 -191.380998)
			(xy 363.106211 -191.397915) (xy 363.111796 -191.405002) (xy 363.11205 -191.405002) (xy 363.11205 -191.405256)
			(xy 363.129647 -191.426225) (xy 363.159375 -191.472186) (xy 363.182224 -191.521926) (xy 363.197725 -191.574423)
			(xy 363.205559 -191.628597) (xy 363.205564 -191.683334) (xy 363.19774 -191.73751) (xy 363.182249 -191.790009)
			(xy 363.159408 -191.839753) (xy 363.129688 -191.88572) (xy 363.11205 -191.906652) (xy 363.111796 -191.906906)
			(xy 363.1062 -191.913986) (xy 363.099959 -191.930908) (xy 363.099604 -191.939926) (xy 363.099604 -192.006982)
			(xy 363.099969 -192.015998) (xy 363.106211 -192.032915) (xy 363.111796 -192.040002) (xy 363.11205 -192.040002)
			(xy 363.11205 -192.040256) (xy 363.129674 -192.0612) (xy 363.15939 -192.107169) (xy 363.18223 -192.156913)
			(xy 363.197724 -192.209412) (xy 363.205555 -192.263586) (xy 363.20603 -192.290954) (xy 363.205462 -192.319965)
			(xy 363.1967 -192.377321) (xy 363.179357 -192.432689) (xy 363.153831 -192.484793) (xy 363.120711 -192.532433)
			(xy 363.101128 -192.553844) (xy 363.094895 -192.561035) (xy 363.087703 -192.578635) (xy 363.087158 -192.588134)
			(xy 363.086142 -192.666874) (xy 363.092746 -192.684654) (xy 363.099096 -192.691766) (xy 363.117437 -192.712859)
			(xy 363.148343 -192.759433) (xy 363.172118 -192.81002) (xy 363.188253 -192.863536) (xy 363.196402 -192.918834)
			(xy 363.196886 -192.946782) (xy 363.196413 -192.974152) (xy 363.188597 -193.028331) (xy 363.17311 -193.080834)
			(xy 363.15027 -193.130581) (xy 363.120547 -193.176548) (xy 363.102906 -193.19748) (xy 363.102652 -193.197734)
			(xy 363.097081 -193.204831) (xy 363.090826 -193.22174) (xy 363.09046 -193.230754) (xy 363.09046 -193.29781)
			(xy 363.090799 -193.306829) (xy 363.097058 -193.323746) (xy 363.102652 -193.33083) (xy 363.102906 -193.33083)
			(xy 363.102906 -193.331084) (xy 363.120552 -193.35201) (xy 363.150263 -193.397985) (xy 363.173097 -193.447734)
			(xy 363.188587 -193.500236) (xy 363.196413 -193.554412) (xy 363.196886 -193.581782) (xy 363.1964 -193.609033)
			(xy 363.188644 -193.662981) (xy 363.173289 -193.715276) (xy 363.150647 -193.764853) (xy 363.121181 -193.810703)
			(xy 363.08549 -193.851894) (xy 363.044299 -193.887585) (xy 362.998449 -193.917051) (xy 362.948872 -193.939693)
			(xy 362.896577 -193.955048) (xy 362.842629 -193.962804) (xy 362.788127 -193.962804) (xy 362.734179 -193.955048)
			(xy 362.681884 -193.939693) (xy 362.632307 -193.917051) (xy 362.586457 -193.887585) (xy 362.545266 -193.851894)
			(xy 362.509575 -193.810703) (xy 362.480109 -193.764853) (xy 362.457467 -193.715276) (xy 362.442112 -193.662981)
			(xy 362.434356 -193.609033) (xy 362.43387 -193.581782) (xy 362.434379 -193.552303) (xy 362.443453 -193.494047)
			(xy 362.461382 -193.437882) (xy 362.487738 -193.385143) (xy 362.521895 -193.337087) (xy 362.542074 -193.31559)
			(xy 362.548616 -193.308261) (xy 362.556055 -193.290096) (xy 362.556552 -193.280284) (xy 362.556552 -193.226944)
			(xy 362.549186 -193.220086) (xy 362.541852 -193.21355) (xy 362.523691 -193.206106) (xy 362.51388 -193.205608)
			(xy 362.481876 -193.205608) (xy 362.472061 -193.206089) (xy 362.453897 -193.213537) (xy 362.44657 -193.220086)
			(xy 362.425089 -193.24028) (xy 362.377024 -193.27442) (xy 362.32428 -193.300762) (xy 362.268112 -193.318679)
			(xy 362.209856 -193.327743) (xy 362.180378 -193.32829) (xy 362.153125 -193.327843) (xy 362.099175 -193.320083)
			(xy 362.046879 -193.304724) (xy 361.9973 -193.282079) (xy 361.951449 -193.252609) (xy 361.910259 -193.216913)
			(xy 361.874567 -193.175719) (xy 361.845102 -193.129865) (xy 361.822462 -193.080284) (xy 361.807109 -193.027986)
			(xy 361.799355 -192.974035) (xy 361.79887 -192.946782) (xy 361.799306 -192.920708) (xy 361.8064 -192.869043)
			(xy 361.820466 -192.818828) (xy 361.841242 -192.770996) (xy 361.868342 -192.726441) (xy 361.901258 -192.685994)
			(xy 361.920028 -192.66789) (xy 361.927144 -192.66052) (xy 361.935405 -192.641793) (xy 361.93603 -192.631568)
			(xy 361.937046 -192.576958) (xy 361.927902 -192.56883) (xy 361.920282 -192.562348) (xy 361.901583 -192.555295)
			(xy 361.89158 -192.555114) (xy 361.859576 -192.55613) (xy 361.849539 -192.55684) (xy 361.831204 -192.565091)
			(xy 361.824016 -192.572132) (xy 361.805905 -192.590864) (xy 361.765495 -192.623754) (xy 361.720986 -192.65084)
			(xy 361.673206 -192.671617) (xy 361.623042 -192.685701) (xy 361.571429 -192.692828) (xy 361.545378 -192.69329)
			(xy 361.518125 -192.692843) (xy 361.464175 -192.685083) (xy 361.411879 -192.669724) (xy 361.3623 -192.647079)
			(xy 361.316449 -192.617609) (xy 361.275259 -192.581913) (xy 361.239567 -192.540719) (xy 361.210102 -192.494865)
			(xy 361.187462 -192.445284) (xy 361.172109 -192.392986) (xy 361.164355 -192.339035) (xy 361.16387 -192.311782)
			(xy 358.286304 -192.311782) (xy 363.258862 -197.28434) (xy 369.527582 -197.28434) (xy 369.528052 -197.25697)
			(xy 369.535865 -197.20279) (xy 369.551353 -197.150286) (xy 369.574194 -197.100539) (xy 369.60392 -197.054573)
			(xy 369.621562 -197.033642) (xy 369.621816 -197.033388) (xy 369.627416 -197.02631) (xy 369.633654 -197.009387)
			(xy 369.634008 -197.000368) (xy 369.634008 -196.933312) (xy 369.633644 -196.924296) (xy 369.627401 -196.907379)
			(xy 369.621816 -196.900292) (xy 369.621562 -196.900292) (xy 369.621562 -196.900038) (xy 369.603959 -196.879074)
			(xy 369.57423 -196.833113) (xy 369.55138 -196.783372) (xy 369.535879 -196.730874) (xy 369.528046 -196.676699)
			(xy 369.528042 -196.621961) (xy 369.535866 -196.567785) (xy 369.551359 -196.515285) (xy 369.574201 -196.46554)
			(xy 369.603923 -196.419574) (xy 369.621562 -196.398642) (xy 369.621816 -196.398388) (xy 369.627416 -196.39131)
			(xy 369.633654 -196.374387) (xy 369.634008 -196.365368) (xy 369.634008 -196.298312) (xy 369.633644 -196.289296)
			(xy 369.627401 -196.272379) (xy 369.621816 -196.265292) (xy 369.621562 -196.265292) (xy 369.621562 -196.265038)
			(xy 369.603959 -196.244074) (xy 369.57423 -196.198113) (xy 369.55138 -196.148372) (xy 369.535879 -196.095874)
			(xy 369.528046 -196.041699) (xy 369.528042 -195.986961) (xy 369.535866 -195.932785) (xy 369.551359 -195.880285)
			(xy 369.574201 -195.83054) (xy 369.603923 -195.784574) (xy 369.621562 -195.763642) (xy 369.621816 -195.763388)
			(xy 369.627416 -195.75631) (xy 369.633654 -195.739387) (xy 369.634008 -195.730368) (xy 369.634008 -195.663312)
			(xy 369.633644 -195.654296) (xy 369.627401 -195.637379) (xy 369.621816 -195.630292) (xy 369.621562 -195.630292)
			(xy 369.621562 -195.630038) (xy 369.603921 -195.609108) (xy 369.574211 -195.563134) (xy 369.551376 -195.513386)
			(xy 369.535885 -195.460885) (xy 369.528056 -195.406709) (xy 369.527582 -195.37934) (xy 369.528079 -195.35085)
			(xy 369.536545 -195.294502) (xy 369.553294 -195.240039) (xy 369.577955 -195.188671) (xy 369.609979 -195.141541)
			(xy 369.628928 -195.12026) (xy 369.635532 -195.113148) (xy 369.64239 -195.095622) (xy 369.64239 -195.00723)
			(xy 369.635532 -194.989704) (xy 369.628928 -194.982592) (xy 369.609976 -194.961315) (xy 369.577969 -194.914177)
			(xy 369.55332 -194.862808) (xy 369.536577 -194.808346) (xy 369.52811 -194.752001) (xy 369.527582 -194.723512)
			(xy 369.528066 -194.69626) (xy 369.535822 -194.64231) (xy 369.551176 -194.590013) (xy 369.573816 -194.540434)
			(xy 369.603282 -194.494581) (xy 369.638973 -194.453389) (xy 369.680164 -194.417695) (xy 369.726015 -194.388226)
			(xy 369.775593 -194.365583) (xy 369.827889 -194.350226) (xy 369.881838 -194.342468) (xy 369.90909 -194.342004)
			(xy 369.93646 -194.342475) (xy 369.990639 -194.350291) (xy 370.043142 -194.365779) (xy 370.092889 -194.38862)
			(xy 370.138856 -194.418343) (xy 370.159788 -194.435984) (xy 370.160042 -194.436238) (xy 370.167138 -194.441811)
			(xy 370.184048 -194.448065) (xy 370.193062 -194.44843) (xy 370.260118 -194.44843) (xy 370.269135 -194.448075)
			(xy 370.286052 -194.441826) (xy 370.293138 -194.436238) (xy 370.293138 -194.435984) (xy 370.293392 -194.435984)
			(xy 370.314325 -194.418343) (xy 370.360293 -194.388619) (xy 370.410039 -194.365773) (xy 370.462541 -194.350277)
			(xy 370.516719 -194.342448) (xy 370.571461 -194.342448) (xy 370.625639 -194.350277) (xy 370.678141 -194.365773)
			(xy 370.727887 -194.388619) (xy 370.773855 -194.418343) (xy 370.794788 -194.435984) (xy 370.795042 -194.436238)
			(xy 370.802138 -194.441811) (xy 370.819048 -194.448065) (xy 370.828062 -194.44843) (xy 370.895118 -194.44843)
			(xy 370.904135 -194.448075) (xy 370.921052 -194.441826) (xy 370.928138 -194.436238) (xy 370.928138 -194.435984)
			(xy 370.928392 -194.435984) (xy 370.949314 -194.418333) (xy 370.99529 -194.388623) (xy 371.04504 -194.36579)
			(xy 371.097543 -194.350302) (xy 371.15172 -194.342476) (xy 371.17909 -194.342004) (xy 371.206343 -194.342465)
			(xy 371.260295 -194.350221) (xy 371.312593 -194.365576) (xy 371.362174 -194.388218) (xy 371.408028 -194.417686)
			(xy 371.449221 -194.45338) (xy 371.484915 -194.494574) (xy 371.514383 -194.540427) (xy 371.537025 -194.590008)
			(xy 371.55238 -194.642307) (xy 371.560135 -194.696259) (xy 371.560598 -194.723512) (xy 373.543322 -194.723512)
			(xy 373.543767 -194.696258) (xy 373.551523 -194.642305) (xy 373.566879 -194.590005) (xy 373.589522 -194.540423)
			(xy 373.618992 -194.494568) (xy 373.654687 -194.453375) (xy 373.695883 -194.417681) (xy 373.741739 -194.388213)
			(xy 373.791322 -194.365572) (xy 373.843623 -194.350219) (xy 373.897576 -194.342465) (xy 373.92483 -194.342004)
			(xy 373.952201 -194.342452) (xy 374.006381 -194.350274) (xy 374.058884 -194.365767) (xy 374.108631 -194.388613)
			(xy 374.154597 -194.418341) (xy 374.175528 -194.435984) (xy 374.175782 -194.436238) (xy 374.182866 -194.441827)
			(xy 374.199785 -194.448071) (xy 374.208802 -194.44843) (xy 374.275858 -194.44843) (xy 374.284872 -194.448046)
			(xy 374.301789 -194.441817) (xy 374.308878 -194.436238) (xy 374.308878 -194.435984) (xy 374.309132 -194.435984)
			(xy 374.330065 -194.418343) (xy 374.376033 -194.388619) (xy 374.425779 -194.365773) (xy 374.478281 -194.350277)
			(xy 374.532459 -194.342448) (xy 374.587201 -194.342448) (xy 374.641379 -194.350277) (xy 374.693881 -194.365773)
			(xy 374.743627 -194.388619) (xy 374.789595 -194.418343) (xy 374.810528 -194.435984) (xy 374.810782 -194.436238)
			(xy 374.817866 -194.441827) (xy 374.834785 -194.448071) (xy 374.843802 -194.44843) (xy 374.910858 -194.44843)
			(xy 374.919872 -194.448046) (xy 374.936789 -194.441817) (xy 374.943878 -194.436238) (xy 374.943878 -194.435984)
			(xy 374.944132 -194.435984) (xy 374.965077 -194.418361) (xy 375.011046 -194.388647) (xy 375.060791 -194.365808)
			(xy 375.113288 -194.350314) (xy 375.167462 -194.342481) (xy 375.19483 -194.342004) (xy 375.222083 -194.34245)
			(xy 375.276032 -194.350211) (xy 375.328329 -194.36557) (xy 375.377907 -194.388216) (xy 375.423757 -194.417686)
			(xy 375.464948 -194.453382) (xy 375.500639 -194.494576) (xy 375.530104 -194.54043) (xy 375.552744 -194.590011)
			(xy 375.568098 -194.642309) (xy 375.575853 -194.696259) (xy 375.576338 -194.723512) (xy 375.575846 -194.751423)
			(xy 375.56771 -194.806648) (xy 375.551614 -194.860099) (xy 375.527901 -194.910634) (xy 375.497078 -194.957174)
			(xy 375.478802 -194.978274) (xy 375.472762 -194.98559) (xy 375.466094 -195.003335) (xy 375.465848 -195.012818)
			(xy 375.46661 -195.081398) (xy 375.467083 -195.090821) (xy 375.474141 -195.108307) (xy 375.480326 -195.115434)
			(xy 375.499512 -195.136741) (xy 375.531918 -195.184041) (xy 375.556883 -195.235657) (xy 375.573846 -195.290426)
			(xy 375.582426 -195.347116) (xy 375.582942 -195.375784) (xy 375.582481 -195.403155) (xy 375.574664 -195.457334)
			(xy 375.559174 -195.509838) (xy 375.536331 -195.559585) (xy 375.506605 -195.605551) (xy 375.488962 -195.626482)
			(xy 375.488708 -195.626736) (xy 375.483143 -195.633837) (xy 375.476883 -195.650743) (xy 375.476516 -195.659756)
			(xy 375.476516 -195.726812) (xy 375.476864 -195.73583) (xy 375.483117 -195.752747) (xy 375.488708 -195.759832)
			(xy 375.488962 -195.759832) (xy 375.488962 -195.760086) (xy 375.506587 -195.781031) (xy 375.536314 -195.826997)
			(xy 375.559161 -195.876741) (xy 375.574659 -195.929241) (xy 375.582489 -195.983418) (xy 375.582491 -196.038158)
			(xy 375.574664 -196.092335) (xy 375.559169 -196.144837) (xy 375.536325 -196.194582) (xy 375.506602 -196.24055)
			(xy 375.488962 -196.261482) (xy 375.488708 -196.261736) (xy 375.483143 -196.268837) (xy 375.476883 -196.285743)
			(xy 375.476516 -196.294756) (xy 375.476516 -196.361812) (xy 375.476864 -196.37083) (xy 375.483117 -196.387747)
			(xy 375.488708 -196.394832) (xy 375.488962 -196.394832) (xy 375.488962 -196.395086) (xy 375.506587 -196.416031)
			(xy 375.536314 -196.461997) (xy 375.559161 -196.511741) (xy 375.574659 -196.564241) (xy 375.582489 -196.618418)
			(xy 375.582491 -196.673158) (xy 375.574664 -196.727335) (xy 375.559169 -196.779837) (xy 375.536325 -196.829582)
			(xy 375.506602 -196.87555) (xy 375.488962 -196.896482) (xy 375.488708 -196.896736) (xy 375.483143 -196.903837)
			(xy 375.476883 -196.920743) (xy 375.476516 -196.929756) (xy 375.476516 -196.996812) (xy 375.476864 -197.00583)
			(xy 375.483117 -197.022747) (xy 375.488708 -197.029832) (xy 375.488962 -197.029832) (xy 375.488962 -197.030086)
			(xy 375.506587 -197.051031) (xy 375.536314 -197.096997) (xy 375.559161 -197.146741) (xy 375.574659 -197.199241)
			(xy 375.582489 -197.253418) (xy 375.58249 -197.284594) (xy 377.93041 -197.284594) (xy 377.93041 -197.28434)
			(xy 377.930897 -197.25697) (xy 377.938709 -197.202792) (xy 377.954193 -197.150289) (xy 377.977031 -197.100542)
			(xy 378.006751 -197.054574) (xy 378.02439 -197.033642) (xy 378.024644 -197.033388) (xy 378.030247 -197.026313)
			(xy 378.036483 -197.009387) (xy 378.036836 -197.000368) (xy 378.036836 -196.933312) (xy 378.036465 -196.924297)
			(xy 378.030226 -196.90738) (xy 378.024644 -196.900292) (xy 378.02439 -196.900292) (xy 378.02439 -196.900038)
			(xy 378.00679 -196.879073) (xy 377.977066 -196.83311) (xy 377.954221 -196.783369) (xy 377.938723 -196.730872)
			(xy 377.930892 -196.676698) (xy 377.930887 -196.621962) (xy 377.93871 -196.567787) (xy 377.9542 -196.515288)
			(xy 377.977037 -196.465543) (xy 378.006754 -196.419575) (xy 378.02439 -196.398642) (xy 378.024644 -196.398388)
			(xy 378.030247 -196.391313) (xy 378.036483 -196.374387) (xy 378.036836 -196.365368) (xy 378.036836 -196.298312)
			(xy 378.036465 -196.289297) (xy 378.030226 -196.27238) (xy 378.024644 -196.265292) (xy 378.02439 -196.265292)
			(xy 378.02439 -196.265038) (xy 378.00679 -196.244073) (xy 377.977066 -196.19811) (xy 377.954221 -196.148369)
			(xy 377.938723 -196.095872) (xy 377.930892 -196.041698) (xy 377.930887 -195.986962) (xy 377.93871 -195.932787)
			(xy 377.9542 -195.880288) (xy 377.977037 -195.830543) (xy 378.006754 -195.784575) (xy 378.02439 -195.763642)
			(xy 378.024644 -195.763388) (xy 378.030247 -195.756313) (xy 378.036483 -195.739387) (xy 378.036836 -195.730368)
			(xy 378.036836 -195.663312) (xy 378.036465 -195.654297) (xy 378.030226 -195.63738) (xy 378.024644 -195.630292)
			(xy 378.02439 -195.630292) (xy 378.02439 -195.630038) (xy 378.006754 -195.609104) (xy 377.977042 -195.563131)
			(xy 377.954205 -195.513384) (xy 377.938714 -195.460884) (xy 377.930885 -195.406709) (xy 377.93041 -195.37934)
			(xy 377.930926 -195.350851) (xy 377.93939 -195.294504) (xy 377.956136 -195.240042) (xy 377.980792 -195.188675)
			(xy 378.01281 -195.141543) (xy 378.031756 -195.12026) (xy 378.03836 -195.113148) (xy 378.045218 -195.095622)
			(xy 378.045218 -195.00723) (xy 378.03836 -194.989704) (xy 378.031756 -194.982592) (xy 378.012809 -194.961311)
			(xy 377.9808 -194.914175) (xy 377.95615 -194.862806) (xy 377.939405 -194.808345) (xy 377.930938 -194.752001)
			(xy 377.93041 -194.723512) (xy 377.930867 -194.696259) (xy 377.938622 -194.642307) (xy 377.953978 -194.590007)
			(xy 377.97662 -194.540426) (xy 378.006089 -194.494572) (xy 378.041783 -194.453379) (xy 378.082977 -194.417685)
			(xy 378.128831 -194.388217) (xy 378.178413 -194.365576) (xy 378.230712 -194.350221) (xy 378.284665 -194.342466)
			(xy 378.311918 -194.342004) (xy 378.339289 -194.342459) (xy 378.393468 -194.350279) (xy 378.445972 -194.365771)
			(xy 378.495718 -194.388615) (xy 378.541685 -194.418342) (xy 378.562616 -194.435984) (xy 378.56287 -194.436238)
			(xy 378.569958 -194.441822) (xy 378.586874 -194.448069) (xy 378.59589 -194.44843) (xy 378.662946 -194.44843)
			(xy 378.671959 -194.448041) (xy 378.688876 -194.441815) (xy 378.695966 -194.436238) (xy 378.695966 -194.435984)
			(xy 378.69622 -194.435984) (xy 378.717153 -194.418343) (xy 378.763121 -194.388619) (xy 378.812867 -194.365773)
			(xy 378.865369 -194.350277) (xy 378.919547 -194.342448) (xy 378.974289 -194.342448) (xy 379.028467 -194.350277)
			(xy 379.080969 -194.365773) (xy 379.130715 -194.388619) (xy 379.176683 -194.418343) (xy 379.197616 -194.435984)
			(xy 379.19787 -194.436238) (xy 379.204958 -194.441822) (xy 379.221874 -194.448069) (xy 379.23089 -194.44843)
			(xy 379.297946 -194.44843) (xy 379.306959 -194.448041) (xy 379.323876 -194.441815) (xy 379.330966 -194.436238)
			(xy 379.330966 -194.435984) (xy 379.33122 -194.435984) (xy 379.352169 -194.418366) (xy 379.398138 -194.388652)
			(xy 379.447881 -194.365812) (xy 379.500378 -194.350316) (xy 379.55455 -194.342482) (xy 379.581918 -194.342004)
			(xy 379.60917 -194.342461) (xy 379.66312 -194.35022) (xy 379.715416 -194.365578) (xy 379.764994 -194.388222)
			(xy 379.810845 -194.417692) (xy 379.852035 -194.453386) (xy 379.887726 -194.494579) (xy 379.917192 -194.540433)
			(xy 379.939832 -194.590013) (xy 379.955186 -194.64231) (xy 379.962941 -194.69626) (xy 379.963426 -194.723512)
			(xy 381.94615 -194.723512) (xy 381.946689 -194.696263) (xy 381.954443 -194.642319) (xy 381.969795 -194.590028)
			(xy 381.992431 -194.540454) (xy 382.021892 -194.494606) (xy 382.057578 -194.453416) (xy 382.098762 -194.417725)
			(xy 382.144607 -194.388257) (xy 382.194178 -194.365613) (xy 382.246467 -194.350255) (xy 382.300409 -194.342493)
			(xy 382.327658 -194.342004) (xy 382.355027 -194.342494) (xy 382.409205 -194.350306) (xy 382.461708 -194.365789)
			(xy 382.511456 -194.388626) (xy 382.557424 -194.418345) (xy 382.578356 -194.435984) (xy 382.57861 -194.436238)
			(xy 382.585686 -194.441839) (xy 382.602611 -194.448076) (xy 382.61163 -194.44843) (xy 382.678686 -194.44843)
			(xy 382.687701 -194.44806) (xy 382.704618 -194.441821) (xy 382.711706 -194.436238) (xy 382.711706 -194.435984)
			(xy 382.71196 -194.435984) (xy 382.732893 -194.418343) (xy 382.778861 -194.388619) (xy 382.828607 -194.365773)
			(xy 382.881109 -194.350277) (xy 382.935287 -194.342448) (xy 382.990029 -194.342448) (xy 383.044207 -194.350277)
			(xy 383.096709 -194.365773) (xy 383.146455 -194.388619) (xy 383.192423 -194.418343) (xy 383.213356 -194.435984)
			(xy 383.21361 -194.436238) (xy 383.220686 -194.441839) (xy 383.237611 -194.448076) (xy 383.24663 -194.44843)
			(xy 383.313686 -194.44843) (xy 383.322701 -194.44806) (xy 383.339618 -194.441821) (xy 383.346706 -194.436238)
			(xy 383.346706 -194.435984) (xy 383.34696 -194.435984) (xy 383.367894 -194.418348) (xy 383.413867 -194.388636)
			(xy 383.463614 -194.3658) (xy 383.516114 -194.350308) (xy 383.570289 -194.342479) (xy 383.597658 -194.342004)
			(xy 383.62491 -194.342494) (xy 383.678861 -194.350246) (xy 383.731159 -194.365597) (xy 383.78074 -194.388236)
			(xy 383.826594 -194.417701) (xy 383.867787 -194.453392) (xy 383.903481 -194.494582) (xy 383.93295 -194.540434)
			(xy 383.955592 -194.590013) (xy 383.970948 -194.64231) (xy 383.978703 -194.69626) (xy 383.979166 -194.723512)
			(xy 383.978663 -194.751115) (xy 383.970705 -194.805745) (xy 383.954957 -194.858657) (xy 383.931748 -194.908747)
			(xy 383.901562 -194.95497) (xy 383.883662 -194.975988) (xy 383.877623 -194.98336) (xy 383.871106 -195.001256)
			(xy 383.870962 -195.010786) (xy 383.87274 -195.089526) (xy 383.880106 -195.107052) (xy 383.886964 -195.11391)
			(xy 383.90698 -195.135409) (xy 383.940892 -195.183366) (xy 383.967056 -195.235954) (xy 383.984852 -195.29193)
			(xy 383.993861 -195.349972) (xy 383.994406 -195.37934) (xy 383.993903 -195.406709) (xy 383.986094 -195.460886)
			(xy 383.970613 -195.513389) (xy 383.94778 -195.563136) (xy 383.918063 -195.609105) (xy 383.900426 -195.630038)
			(xy 383.900172 -195.630292) (xy 383.89458 -195.637374) (xy 383.888337 -195.654294) (xy 383.88798 -195.663312)
			(xy 383.88798 -195.730368) (xy 383.888357 -195.739383) (xy 383.894591 -195.7563) (xy 383.900172 -195.763388)
			(xy 383.900426 -195.763388) (xy 383.900426 -195.763642) (xy 383.918108 -195.784542) (xy 383.947835 -195.830514)
			(xy 383.97068 -195.880266) (xy 383.986176 -195.932773) (xy 383.994002 -195.986957) (xy 383.993997 -196.041703)
			(xy 383.986163 -196.095886) (xy 383.970659 -196.148391) (xy 383.947806 -196.198139) (xy 383.918071 -196.244106)
			(xy 383.900426 -196.265038) (xy 383.900172 -196.265292) (xy 383.89458 -196.272374) (xy 383.888337 -196.289294)
			(xy 383.88798 -196.298312) (xy 383.88798 -196.365368) (xy 383.888357 -196.374383) (xy 383.894591 -196.3913)
			(xy 383.900172 -196.398388) (xy 383.900426 -196.398388) (xy 383.900426 -196.398642) (xy 383.918108 -196.419542)
			(xy 383.947835 -196.465514) (xy 383.97068 -196.515266) (xy 383.986176 -196.567773) (xy 383.994002 -196.621957)
			(xy 383.993997 -196.676703) (xy 383.986163 -196.730886) (xy 383.970659 -196.783391) (xy 383.947806 -196.833139)
			(xy 383.918071 -196.879106) (xy 383.900426 -196.900038) (xy 383.900172 -196.900292) (xy 383.89458 -196.907374)
			(xy 383.888337 -196.924294) (xy 383.88798 -196.933312) (xy 383.88798 -197.000368) (xy 383.888357 -197.009383)
			(xy 383.894591 -197.0263) (xy 383.900172 -197.033388) (xy 383.900426 -197.033388) (xy 383.900426 -197.033642)
			(xy 383.918108 -197.054542) (xy 383.947835 -197.100514) (xy 383.97068 -197.150266) (xy 383.986176 -197.202773)
			(xy 383.994002 -197.256957) (xy 383.993997 -197.311703) (xy 383.986163 -197.365886) (xy 383.970659 -197.418391)
			(xy 383.947806 -197.468139) (xy 383.918071 -197.514106) (xy 383.900426 -197.535038) (xy 383.900172 -197.535292)
			(xy 383.89458 -197.542374) (xy 383.888337 -197.559294) (xy 383.88798 -197.568312) (xy 383.88798 -197.635368)
			(xy 383.888357 -197.644383) (xy 383.894591 -197.6613) (xy 383.900172 -197.668388) (xy 383.900426 -197.668388)
			(xy 383.900426 -197.668642) (xy 383.918108 -197.689542) (xy 383.947835 -197.735514) (xy 383.97068 -197.785266)
			(xy 383.986176 -197.837773) (xy 383.994002 -197.891957) (xy 383.993997 -197.946703) (xy 383.986163 -198.000886)
			(xy 383.970659 -198.053391) (xy 383.947806 -198.103139) (xy 383.918071 -198.149106) (xy 383.900426 -198.170038)
			(xy 383.900172 -198.170292) (xy 383.89458 -198.177374) (xy 383.888337 -198.194294) (xy 383.88798 -198.203312)
			(xy 383.88798 -198.270368) (xy 383.888357 -198.279383) (xy 383.894591 -198.2963) (xy 383.900172 -198.303388)
			(xy 383.900426 -198.303388) (xy 383.900426 -198.303642) (xy 383.918108 -198.324542) (xy 383.947835 -198.370514)
			(xy 383.97068 -198.420266) (xy 383.986176 -198.472773) (xy 383.994002 -198.526957) (xy 383.993997 -198.581703)
			(xy 383.986163 -198.635886) (xy 383.970659 -198.688391) (xy 383.947806 -198.738139) (xy 383.918071 -198.784106)
			(xy 383.900426 -198.805038) (xy 383.900172 -198.805292) (xy 383.89458 -198.812374) (xy 383.888337 -198.829294)
			(xy 383.88798 -198.838312) (xy 383.88798 -198.905368) (xy 383.888357 -198.914383) (xy 383.894591 -198.9313)
			(xy 383.900172 -198.938388) (xy 383.900426 -198.938388) (xy 383.900426 -198.938642) (xy 383.918108 -198.959542)
			(xy 383.947835 -199.005514) (xy 383.97068 -199.055266) (xy 383.986176 -199.107773) (xy 383.994002 -199.161957)
			(xy 383.993997 -199.216703) (xy 383.986163 -199.270886) (xy 383.970659 -199.323391) (xy 383.947806 -199.373139)
			(xy 383.918071 -199.419106) (xy 383.900426 -199.440038) (xy 383.900172 -199.440292) (xy 383.89458 -199.447374)
			(xy 383.888337 -199.464294) (xy 383.88798 -199.473312) (xy 383.88798 -199.540368) (xy 383.888357 -199.549383)
			(xy 383.894591 -199.5663) (xy 383.900172 -199.573388) (xy 383.900426 -199.573388) (xy 383.900426 -199.573642)
			(xy 383.918055 -199.594582) (xy 383.947768 -199.640553) (xy 383.970605 -199.690298) (xy 383.986099 -199.742797)
			(xy 383.99393 -199.796971) (xy 383.994406 -199.82434) (xy 386.26161 -199.82434) (xy 386.262097 -199.79697)
			(xy 386.269909 -199.742792) (xy 386.285393 -199.690289) (xy 386.308231 -199.640542) (xy 386.337951 -199.594574)
			(xy 386.35559 -199.573642) (xy 386.355844 -199.573388) (xy 386.361447 -199.566313) (xy 386.367683 -199.549387)
			(xy 386.368036 -199.540368) (xy 386.368036 -199.473312) (xy 386.367665 -199.464297) (xy 386.361426 -199.44738)
			(xy 386.355844 -199.440292) (xy 386.35559 -199.440292) (xy 386.35559 -199.440038) (xy 386.33799 -199.419073)
			(xy 386.308266 -199.37311) (xy 386.285421 -199.323369) (xy 386.269923 -199.270872) (xy 386.262092 -199.216698)
			(xy 386.262087 -199.161962) (xy 386.26991 -199.107787) (xy 386.2854 -199.055288) (xy 386.308237 -199.005543)
			(xy 386.337954 -198.959575) (xy 386.35559 -198.938642) (xy 386.355844 -198.938388) (xy 386.361447 -198.931313)
			(xy 386.367683 -198.914387) (xy 386.368036 -198.905368) (xy 386.368036 -198.838312) (xy 386.367665 -198.829297)
			(xy 386.361426 -198.81238) (xy 386.355844 -198.805292) (xy 386.35559 -198.805292) (xy 386.35559 -198.805038)
			(xy 386.33799 -198.784073) (xy 386.308266 -198.73811) (xy 386.285421 -198.688369) (xy 386.269923 -198.635872)
			(xy 386.262092 -198.581698) (xy 386.262087 -198.526962) (xy 386.26991 -198.472787) (xy 386.2854 -198.420288)
			(xy 386.308237 -198.370543) (xy 386.337954 -198.324575) (xy 386.35559 -198.303642) (xy 386.355844 -198.303388)
			(xy 386.361447 -198.296313) (xy 386.367683 -198.279387) (xy 386.368036 -198.270368) (xy 386.368036 -198.203312)
			(xy 386.367665 -198.194297) (xy 386.361426 -198.17738) (xy 386.355844 -198.170292) (xy 386.35559 -198.170292)
			(xy 386.35559 -198.170038) (xy 386.33799 -198.149073) (xy 386.308266 -198.10311) (xy 386.285421 -198.053369)
			(xy 386.269923 -198.000872) (xy 386.262092 -197.946698) (xy 386.262087 -197.891962) (xy 386.26991 -197.837787)
			(xy 386.2854 -197.785288) (xy 386.308237 -197.735543) (xy 386.337954 -197.689575) (xy 386.35559 -197.668642)
			(xy 386.355844 -197.668388) (xy 386.361447 -197.661313) (xy 386.367683 -197.644387) (xy 386.368036 -197.635368)
			(xy 386.368036 -197.568312) (xy 386.367665 -197.559297) (xy 386.361426 -197.54238) (xy 386.355844 -197.535292)
			(xy 386.35559 -197.535292) (xy 386.35559 -197.535038) (xy 386.33799 -197.514073) (xy 386.308266 -197.46811)
			(xy 386.285421 -197.418369) (xy 386.269923 -197.365872) (xy 386.262092 -197.311698) (xy 386.262087 -197.256962)
			(xy 386.26991 -197.202787) (xy 386.2854 -197.150288) (xy 386.308237 -197.100543) (xy 386.337954 -197.054575)
			(xy 386.35559 -197.033642) (xy 386.355844 -197.033388) (xy 386.361447 -197.026313) (xy 386.367683 -197.009387)
			(xy 386.368036 -197.000368) (xy 386.368036 -196.933312) (xy 386.367665 -196.924297) (xy 386.361426 -196.90738)
			(xy 386.355844 -196.900292) (xy 386.35559 -196.900292) (xy 386.35559 -196.900038) (xy 386.33799 -196.879073)
			(xy 386.308266 -196.83311) (xy 386.285421 -196.783369) (xy 386.269923 -196.730872) (xy 386.262092 -196.676698)
			(xy 386.262087 -196.621962) (xy 386.26991 -196.567787) (xy 386.2854 -196.515288) (xy 386.308237 -196.465543)
			(xy 386.337954 -196.419575) (xy 386.35559 -196.398642) (xy 386.355844 -196.398388) (xy 386.361447 -196.391313)
			(xy 386.367683 -196.374387) (xy 386.368036 -196.365368) (xy 386.368036 -196.298312) (xy 386.367665 -196.289297)
			(xy 386.361426 -196.27238) (xy 386.355844 -196.265292) (xy 386.35559 -196.265292) (xy 386.35559 -196.265038)
			(xy 386.33799 -196.244073) (xy 386.308266 -196.19811) (xy 386.285421 -196.148369) (xy 386.269923 -196.095872)
			(xy 386.262092 -196.041698) (xy 386.262087 -195.986962) (xy 386.26991 -195.932787) (xy 386.2854 -195.880288)
			(xy 386.308237 -195.830543) (xy 386.337954 -195.784575) (xy 386.35559 -195.763642) (xy 386.355844 -195.763388)
			(xy 386.361447 -195.756313) (xy 386.367683 -195.739387) (xy 386.368036 -195.730368) (xy 386.368036 -195.663312)
			(xy 386.367665 -195.654297) (xy 386.361426 -195.63738) (xy 386.355844 -195.630292) (xy 386.35559 -195.630292)
			(xy 386.35559 -195.630038) (xy 386.337954 -195.609104) (xy 386.308242 -195.563131) (xy 386.285405 -195.513384)
			(xy 386.269914 -195.460884) (xy 386.262085 -195.406709) (xy 386.26161 -195.37934) (xy 386.262126 -195.350851)
			(xy 386.27059 -195.294504) (xy 386.287336 -195.240042) (xy 386.311992 -195.188675) (xy 386.34401 -195.141543)
			(xy 386.362956 -195.12026) (xy 386.36956 -195.113148) (xy 386.376418 -195.095622) (xy 386.376418 -195.00723)
			(xy 386.36956 -194.989704) (xy 386.362956 -194.982592) (xy 386.344009 -194.961311) (xy 386.312 -194.914175)
			(xy 386.28735 -194.862806) (xy 386.270605 -194.808345) (xy 386.262138 -194.752001) (xy 386.26161 -194.723512)
			(xy 386.262067 -194.696259) (xy 386.269822 -194.642307) (xy 386.285178 -194.590007) (xy 386.30782 -194.540426)
			(xy 386.337289 -194.494572) (xy 386.372983 -194.453379) (xy 386.414177 -194.417685) (xy 386.460031 -194.388217)
			(xy 386.509613 -194.365576) (xy 386.561912 -194.350221) (xy 386.615865 -194.342466) (xy 386.643118 -194.342004)
			(xy 386.670489 -194.342459) (xy 386.724668 -194.350279) (xy 386.777172 -194.365771) (xy 386.826918 -194.388615)
			(xy 386.872885 -194.418342) (xy 386.893816 -194.435984) (xy 386.89407 -194.436238) (xy 386.901158 -194.441822)
			(xy 386.918074 -194.448069) (xy 386.92709 -194.44843) (xy 386.994146 -194.44843) (xy 387.003159 -194.448041)
			(xy 387.020076 -194.441815) (xy 387.027166 -194.436238) (xy 387.027166 -194.435984) (xy 387.02742 -194.435984)
			(xy 387.048353 -194.418343) (xy 387.094321 -194.388619) (xy 387.144067 -194.365773) (xy 387.196569 -194.350277)
			(xy 387.250747 -194.342448) (xy 387.305489 -194.342448) (xy 387.359667 -194.350277) (xy 387.412169 -194.365773)
			(xy 387.461915 -194.388619) (xy 387.507883 -194.418343) (xy 387.528816 -194.435984) (xy 387.52907 -194.436238)
			(xy 387.536158 -194.441822) (xy 387.553074 -194.448069) (xy 387.56209 -194.44843) (xy 387.629146 -194.44843)
			(xy 387.638159 -194.448041) (xy 387.655076 -194.441815) (xy 387.662166 -194.436238) (xy 387.662166 -194.435984)
			(xy 387.66242 -194.435984) (xy 387.683369 -194.418366) (xy 387.729338 -194.388652) (xy 387.779081 -194.365812)
			(xy 387.831578 -194.350316) (xy 387.88575 -194.342482) (xy 387.913118 -194.342004) (xy 387.94037 -194.342461)
			(xy 387.99432 -194.35022) (xy 388.046616 -194.365578) (xy 388.096194 -194.388222) (xy 388.142045 -194.417692)
			(xy 388.183235 -194.453386) (xy 388.218926 -194.494579) (xy 388.248392 -194.540433) (xy 388.271032 -194.590013)
			(xy 388.286386 -194.64231) (xy 388.294141 -194.69626) (xy 388.294626 -194.723512) (xy 388.294178 -194.750483)
			(xy 388.286569 -194.803884) (xy 388.271505 -194.855679) (xy 388.249287 -194.904832) (xy 388.22036 -194.950361)
			(xy 388.203186 -194.971162) (xy 388.197653 -194.978339) (xy 388.191531 -194.99538) (xy 388.191248 -195.004436)
			(xy 388.19201 -195.08089) (xy 388.19836 -195.097654) (xy 388.20471 -195.104766) (xy 388.222802 -195.125838)
			(xy 388.253307 -195.172247) (xy 388.276767 -195.222585) (xy 388.292688 -195.275792) (xy 388.300732 -195.330743)
			(xy 388.30123 -195.358512) (xy 388.300788 -195.385883) (xy 388.292967 -195.440064) (xy 388.277473 -195.492568)
			(xy 388.254626 -195.542315) (xy 388.224895 -195.58828) (xy 388.20725 -195.60921) (xy 388.206996 -195.609464)
			(xy 388.201418 -195.616556) (xy 388.195166 -195.633469) (xy 388.194804 -195.642484) (xy 388.194804 -195.70954)
			(xy 388.195141 -195.718559) (xy 388.201403 -195.735476) (xy 388.206996 -195.74256) (xy 388.20725 -195.74256)
			(xy 388.20725 -195.742814) (xy 388.224903 -195.763737) (xy 388.254629 -195.809706) (xy 388.277476 -195.859453)
			(xy 388.292972 -195.911957) (xy 388.3008 -195.966138) (xy 388.300799 -196.02088) (xy 388.292968 -196.07506)
			(xy 388.277469 -196.127563) (xy 388.254621 -196.17731) (xy 388.224892 -196.223278) (xy 388.20725 -196.24421)
			(xy 388.206996 -196.244464) (xy 388.201418 -196.251556) (xy 388.195166 -196.268469) (xy 388.194804 -196.277484)
			(xy 388.194804 -196.34454) (xy 388.195141 -196.353559) (xy 388.201403 -196.370476) (xy 388.206996 -196.37756)
			(xy 388.20725 -196.37756) (xy 388.20725 -196.377814) (xy 388.224903 -196.398737) (xy 388.254629 -196.444706)
			(xy 388.277476 -196.494453) (xy 388.292972 -196.546957) (xy 388.3008 -196.601138) (xy 388.300799 -196.65588)
			(xy 388.292968 -196.71006) (xy 388.277469 -196.762563) (xy 388.254621 -196.81231) (xy 388.224892 -196.858278)
			(xy 388.20725 -196.87921) (xy 388.206996 -196.879464) (xy 388.201418 -196.886556) (xy 388.195166 -196.903469)
			(xy 388.194804 -196.912484) (xy 388.194804 -196.97954) (xy 388.195141 -196.988559) (xy 388.201403 -197.005476)
			(xy 388.206996 -197.01256) (xy 388.20725 -197.01256) (xy 388.20725 -197.012814) (xy 388.224854 -197.033774)
			(xy 388.254573 -197.079738) (xy 388.277417 -197.129479) (xy 388.292916 -197.181973) (xy 388.300752 -197.236145)
			(xy 388.30123 -197.263512) (xy 388.30123 -197.263766) (xy 388.300704 -197.292611) (xy 388.291999 -197.34964)
			(xy 388.274811 -197.40471) (xy 388.249533 -197.456567) (xy 388.21674 -197.50403) (xy 388.197344 -197.525386)
			(xy 388.19074 -197.532498) (xy 388.183628 -197.550024) (xy 388.182612 -197.638416) (xy 388.18947 -197.656196)
			(xy 388.19582 -197.663308) (xy 388.214294 -197.684467) (xy 388.245486 -197.731179) (xy 388.269503 -197.781955)
			(xy 388.285826 -197.8357) (xy 388.294103 -197.891256) (xy 388.294626 -197.91934) (xy 388.294143 -197.94671)
			(xy 388.286332 -198.000889) (xy 388.270848 -198.053393) (xy 388.248009 -198.10314) (xy 388.218287 -198.149107)
			(xy 388.200646 -198.170038) (xy 388.200392 -198.170292) (xy 388.194802 -198.177376) (xy 388.188558 -198.194295)
			(xy 388.1882 -198.203312) (xy 388.1882 -198.270368) (xy 388.188572 -198.279383) (xy 388.194809 -198.2963)
			(xy 388.200392 -198.303388) (xy 388.200646 -198.303388) (xy 388.200646 -198.303642) (xy 388.218327 -198.324542)
			(xy 388.248052 -198.370515) (xy 388.270897 -198.420267) (xy 388.286391 -198.472774) (xy 388.294217 -198.526957)
			(xy 388.294212 -198.581703) (xy 388.286378 -198.635885) (xy 388.270876 -198.68839) (xy 388.248023 -198.738138)
			(xy 388.218291 -198.784106) (xy 388.200646 -198.805038) (xy 388.200392 -198.805292) (xy 388.194802 -198.812376)
			(xy 388.188558 -198.829295) (xy 388.1882 -198.838312) (xy 388.1882 -198.905368) (xy 388.188572 -198.914383)
			(xy 388.194809 -198.9313) (xy 388.200392 -198.938388) (xy 388.200646 -198.938388) (xy 388.200646 -198.938642)
			(xy 388.218327 -198.959542) (xy 388.248052 -199.005515) (xy 388.270897 -199.055267) (xy 388.286391 -199.107774)
			(xy 388.294217 -199.161957) (xy 388.294212 -199.216703) (xy 388.286378 -199.270885) (xy 388.272957 -199.31634)
			(xy 390.27735 -199.31634) (xy 390.277878 -199.287423) (xy 390.286602 -199.230252) (xy 390.303857 -199.175052)
			(xy 390.329247 -199.12309) (xy 390.36219 -199.075556) (xy 390.40193 -199.03354) (xy 390.424416 -199.01535)
			(xy 390.433193 -199.007714) (xy 390.443393 -198.986835) (xy 390.443974 -198.975218) (xy 390.443974 -198.895462)
			(xy 390.443451 -198.883828) (xy 390.433252 -198.862918) (xy 390.424416 -198.85533) (xy 390.40195 -198.837118)
			(xy 390.362213 -198.795103) (xy 390.329272 -198.747573) (xy 390.30388 -198.695615) (xy 390.28662 -198.640421)
			(xy 390.277887 -198.583255) (xy 390.27735 -198.55434) (xy 390.277827 -198.52697) (xy 390.285641 -198.472791)
			(xy 390.301126 -198.420287) (xy 390.323966 -198.37054) (xy 390.353689 -198.324574) (xy 390.37133 -198.303642)
			(xy 390.371584 -198.303388) (xy 390.37718 -198.296308) (xy 390.383422 -198.279386) (xy 390.383776 -198.270368)
			(xy 390.383776 -198.203312) (xy 390.383419 -198.194295) (xy 390.377172 -198.177378) (xy 390.371584 -198.170292)
			(xy 390.37133 -198.170292) (xy 390.37133 -198.170038) (xy 390.3537 -198.149099) (xy 390.323986 -198.103128)
			(xy 390.301148 -198.053383) (xy 390.285654 -198.000883) (xy 390.277825 -197.946709) (xy 390.27735 -197.91934)
			(xy 390.27787 -197.890636) (xy 390.286467 -197.833876) (xy 390.303472 -197.779046) (xy 390.328502 -197.727382)
			(xy 390.360991 -197.680053) (xy 390.38022 -197.658736) (xy 390.386824 -197.651878) (xy 390.393936 -197.633844)
			(xy 390.394444 -197.545452) (xy 390.387586 -197.527672) (xy 390.381236 -197.520814) (xy 390.362555 -197.499613)
			(xy 390.331021 -197.452725) (xy 390.306745 -197.4017) (xy 390.29026 -197.347652) (xy 390.281926 -197.291765)
			(xy 390.281414 -197.263512) (xy 390.281884 -197.236142) (xy 390.2897 -197.181963) (xy 390.305188 -197.12946)
			(xy 390.328029 -197.079713) (xy 390.357753 -197.033746) (xy 390.375394 -197.012814) (xy 390.375648 -197.01256)
			(xy 390.381221 -197.005465) (xy 390.387475 -196.988554) (xy 390.38784 -196.97954) (xy 390.38784 -196.912484)
			(xy 390.387503 -196.903465) (xy 390.381243 -196.886547) (xy 390.375648 -196.879464) (xy 390.375394 -196.879464)
			(xy 390.375394 -196.87921) (xy 390.357766 -196.858267) (xy 390.328044 -196.8123) (xy 390.3052 -196.762555)
			(xy 390.289704 -196.710055) (xy 390.281875 -196.655879) (xy 390.281874 -196.601139) (xy 390.2897 -196.546962)
			(xy 390.305193 -196.494461) (xy 390.328035 -196.444716) (xy 390.357756 -196.398747) (xy 390.375394 -196.377814)
			(xy 390.375648 -196.37756) (xy 390.381221 -196.370465) (xy 390.387475 -196.353554) (xy 390.38784 -196.34454)
			(xy 390.38784 -196.277484) (xy 390.387503 -196.268465) (xy 390.381243 -196.251547) (xy 390.375648 -196.244464)
			(xy 390.375394 -196.244464) (xy 390.375394 -196.24421) (xy 390.357766 -196.223267) (xy 390.328044 -196.1773)
			(xy 390.3052 -196.127555) (xy 390.289704 -196.075055) (xy 390.281875 -196.020879) (xy 390.281874 -195.966139)
			(xy 390.2897 -195.911962) (xy 390.305193 -195.859461) (xy 390.328035 -195.809716) (xy 390.357756 -195.763747)
			(xy 390.375394 -195.742814) (xy 390.375648 -195.74256) (xy 390.381221 -195.735465) (xy 390.387475 -195.718554)
			(xy 390.38784 -195.70954) (xy 390.38784 -195.642484) (xy 390.387503 -195.633465) (xy 390.381243 -195.616547)
			(xy 390.375648 -195.609464) (xy 390.375394 -195.609464) (xy 390.375394 -195.60921) (xy 390.357745 -195.588286)
			(xy 390.328035 -195.542311) (xy 390.305201 -195.492561) (xy 390.289712 -195.440059) (xy 390.281887 -195.385882)
			(xy 390.281414 -195.358512) (xy 390.281869 -195.331377) (xy 390.289564 -195.277656) (xy 390.304799 -195.22557)
			(xy 390.327268 -195.17617) (xy 390.356515 -195.130456) (xy 390.37387 -195.109592) (xy 390.379529 -195.1024)
			(xy 390.385775 -195.085212) (xy 390.386062 -195.076064) (xy 390.385808 -195.009262) (xy 390.385317 -195.000207)
			(xy 390.378812 -194.983291) (xy 390.373108 -194.976242) (xy 390.372854 -194.975988) (xy 390.354961 -194.954963)
			(xy 390.324767 -194.908745) (xy 390.301552 -194.858657) (xy 390.2858 -194.805745) (xy 390.27784 -194.751115)
			(xy 390.27735 -194.723512) (xy 390.277889 -194.696263) (xy 390.285643 -194.642319) (xy 390.300995 -194.590028)
			(xy 390.323631 -194.540454) (xy 390.353092 -194.494606) (xy 390.388778 -194.453416) (xy 390.429962 -194.417725)
			(xy 390.475807 -194.388257) (xy 390.525378 -194.365613) (xy 390.577667 -194.350255) (xy 390.631609 -194.342493)
			(xy 390.658858 -194.342004) (xy 390.686227 -194.342494) (xy 390.740405 -194.350306) (xy 390.792908 -194.365789)
			(xy 390.842656 -194.388626) (xy 390.888624 -194.418345) (xy 390.909556 -194.435984) (xy 390.90981 -194.436238)
			(xy 390.916886 -194.441839) (xy 390.933811 -194.448076) (xy 390.94283 -194.44843) (xy 391.009886 -194.44843)
			(xy 391.018901 -194.44806) (xy 391.035818 -194.441821) (xy 391.042906 -194.436238) (xy 391.042906 -194.435984)
			(xy 391.04316 -194.435984) (xy 391.064094 -194.418348) (xy 391.110067 -194.388636) (xy 391.159814 -194.3658)
			(xy 391.212314 -194.350308) (xy 391.266489 -194.342479) (xy 391.293858 -194.342004) (xy 391.32111 -194.342494)
			(xy 391.375061 -194.350246) (xy 391.427359 -194.365597) (xy 391.47694 -194.388236) (xy 391.522794 -194.417701)
			(xy 391.563987 -194.453392) (xy 391.599681 -194.494582) (xy 391.62915 -194.540434) (xy 391.651792 -194.590013)
			(xy 391.667148 -194.64231) (xy 391.674903 -194.69626) (xy 391.675366 -194.723512) (xy 391.674872 -194.750645)
			(xy 391.667187 -194.804365) (xy 391.651961 -194.856451) (xy 391.629501 -194.905851) (xy 391.600261 -194.951567)
			(xy 391.58291 -194.972432) (xy 391.57728 -194.979644) (xy 391.571017 -194.996817) (xy 391.570718 -195.00596)
			(xy 391.570972 -195.072762) (xy 391.571434 -195.081821) (xy 391.577957 -195.098737) (xy 391.583672 -195.105782)
			(xy 391.583926 -195.106036) (xy 391.601827 -195.127054) (xy 391.63202 -195.173274) (xy 391.655234 -195.223364)
			(xy 391.670985 -195.276277) (xy 391.678942 -195.330908) (xy 391.67943 -195.358512) (xy 391.678988 -195.385883)
			(xy 391.671167 -195.440064) (xy 391.655673 -195.492568) (xy 391.632826 -195.542315) (xy 391.603095 -195.58828)
			(xy 391.58545 -195.60921) (xy 391.585196 -195.609464) (xy 391.579618 -195.616556) (xy 391.573366 -195.633469)
			(xy 391.573004 -195.642484) (xy 391.573004 -195.70954) (xy 391.573341 -195.718559) (xy 391.579603 -195.735476)
			(xy 391.585196 -195.74256) (xy 391.58545 -195.74256) (xy 391.58545 -195.742814) (xy 391.603103 -195.763737)
			(xy 391.632829 -195.809706) (xy 391.655676 -195.859453) (xy 391.671172 -195.911957) (xy 391.679 -195.966138)
			(xy 391.678999 -196.02088) (xy 391.671168 -196.07506) (xy 391.655669 -196.127563) (xy 391.632821 -196.17731)
			(xy 391.603092 -196.223278) (xy 391.58545 -196.24421) (xy 391.585196 -196.244464) (xy 391.579618 -196.251556)
			(xy 391.573366 -196.268469) (xy 391.573004 -196.277484) (xy 391.573004 -196.34454) (xy 391.573341 -196.353559)
			(xy 391.579603 -196.370476) (xy 391.585196 -196.37756) (xy 391.58545 -196.37756) (xy 391.58545 -196.377814)
			(xy 391.603103 -196.398737) (xy 391.632829 -196.444706) (xy 391.655676 -196.494453) (xy 391.671172 -196.546957)
			(xy 391.679 -196.601138) (xy 391.678999 -196.65588) (xy 391.671168 -196.71006) (xy 391.655669 -196.762563)
			(xy 391.632821 -196.81231) (xy 391.603092 -196.858278) (xy 391.58545 -196.87921) (xy 391.585196 -196.879464)
			(xy 391.579618 -196.886556) (xy 391.573366 -196.903469) (xy 391.573004 -196.912484) (xy 391.573004 -196.97954)
			(xy 391.573341 -196.988559) (xy 391.579603 -197.005476) (xy 391.585196 -197.01256) (xy 391.58545 -197.01256)
			(xy 391.58545 -197.012814) (xy 391.603054 -197.033774) (xy 391.632773 -197.079738) (xy 391.655617 -197.129479)
			(xy 391.671116 -197.181973) (xy 391.678952 -197.236145) (xy 391.67943 -197.263512) (xy 391.678947 -197.292217)
			(xy 391.670342 -197.348979) (xy 391.653328 -197.40381) (xy 391.62829 -197.455473) (xy 391.595793 -197.5028)
			(xy 391.57656 -197.524116) (xy 391.569956 -197.530974) (xy 391.562844 -197.549008) (xy 391.562336 -197.6374)
			(xy 391.569194 -197.65518) (xy 391.575544 -197.662038) (xy 391.594246 -197.683221) (xy 391.625778 -197.730114)
			(xy 391.65005 -197.781144) (xy 391.66653 -197.835195) (xy 391.674858 -197.891086) (xy 391.675366 -197.91934)
			(xy 391.674873 -197.946709) (xy 391.667063 -198.000888) (xy 391.651581 -198.053391) (xy 391.628745 -198.103138)
			(xy 391.599025 -198.149106) (xy 391.581386 -198.170038) (xy 391.581132 -198.170292) (xy 391.575535 -198.177371)
			(xy 391.569296 -198.194294) (xy 391.56894 -198.203312) (xy 391.56894 -198.270368) (xy 391.569304 -198.279384)
			(xy 391.575546 -198.296302) (xy 391.581132 -198.303388) (xy 391.581386 -198.303388) (xy 391.581386 -198.303642)
			(xy 391.599009 -198.324587) (xy 391.628724 -198.370556) (xy 391.651563 -198.4203) (xy 391.667058 -198.472798)
			(xy 391.67489 -198.526972) (xy 391.675366 -198.55434) (xy 391.674982 -198.581596) (xy 391.667219 -198.635552)
			(xy 391.651855 -198.687854) (xy 391.629205 -198.737437) (xy 391.599729 -198.783292) (xy 391.564027 -198.824485)
			(xy 391.522826 -198.860178) (xy 391.476965 -198.889645) (xy 391.427377 -198.912284) (xy 391.375072 -198.927636)
			(xy 391.321114 -198.935388) (xy 391.293858 -198.935848) (xy 391.266488 -198.935361) (xy 391.21231 -198.92755)
			(xy 391.159806 -198.912066) (xy 391.110059 -198.889229) (xy 391.064092 -198.859508) (xy 391.04316 -198.841868)
			(xy 391.042906 -198.841614) (xy 391.035821 -198.836025) (xy 391.018903 -198.829779) (xy 391.009886 -198.829422)
			(xy 390.94283 -198.829422) (xy 390.933814 -198.829789) (xy 390.916897 -198.836029) (xy 390.90981 -198.841614)
			(xy 390.90981 -198.841868) (xy 390.909302 -198.841868) (xy 390.8933 -198.85533) (xy 390.884489 -198.862934)
			(xy 390.874307 -198.883837) (xy 390.873742 -198.895462) (xy 390.873742 -198.975218) (xy 390.874271 -198.986852)
			(xy 390.884465 -199.007762) (xy 390.8933 -199.01535) (xy 390.91576 -199.033569) (xy 390.955496 -199.075583)
			(xy 390.988438 -199.123112) (xy 391.013831 -199.175068) (xy 391.031092 -199.23026) (xy 391.039827 -199.287426)
			(xy 391.040366 -199.31634) (xy 391.03988 -199.343591) (xy 391.032124 -199.397539) (xy 391.016769 -199.449834)
			(xy 390.994127 -199.499411) (xy 390.964661 -199.545261) (xy 390.92897 -199.586452) (xy 390.887779 -199.622143)
			(xy 390.841929 -199.651609) (xy 390.792352 -199.674251) (xy 390.740057 -199.689606) (xy 390.686109 -199.697362)
			(xy 390.631607 -199.697362) (xy 390.577659 -199.689606) (xy 390.525364 -199.674251) (xy 390.475787 -199.651609)
			(xy 390.429937 -199.622143) (xy 390.388746 -199.586452) (xy 390.353055 -199.545261) (xy 390.323589 -199.499411)
			(xy 390.300947 -199.449834) (xy 390.285592 -199.397539) (xy 390.277836 -199.343591) (xy 390.27735 -199.31634)
			(xy 388.272957 -199.31634) (xy 388.270876 -199.32339) (xy 388.248023 -199.373138) (xy 388.218291 -199.419106)
			(xy 388.200646 -199.440038) (xy 388.200392 -199.440292) (xy 388.194802 -199.447376) (xy 388.188558 -199.464295)
			(xy 388.1882 -199.473312) (xy 388.1882 -199.540368) (xy 388.188572 -199.549383) (xy 388.194809 -199.5663)
			(xy 388.200392 -199.573388) (xy 388.200646 -199.573388) (xy 388.200646 -199.573642) (xy 388.218263 -199.594592)
			(xy 388.24798 -199.640559) (xy 388.270821 -199.690302) (xy 388.286317 -199.742799) (xy 388.29415 -199.796972)
			(xy 388.294626 -199.82434) (xy 388.294159 -199.851591) (xy 388.286398 -199.905539) (xy 388.271039 -199.957833)
			(xy 388.248394 -200.007409) (xy 388.218925 -200.053258) (xy 388.183232 -200.094448) (xy 388.142041 -200.130139)
			(xy 388.09619 -200.159605) (xy 388.046612 -200.182246) (xy 387.994317 -200.197603) (xy 387.940369 -200.205361)
			(xy 387.913118 -200.205848) (xy 387.885748 -200.205384) (xy 387.831568 -200.197568) (xy 387.779064 -200.182079)
			(xy 387.729317 -200.159236) (xy 387.683351 -200.12951) (xy 387.66242 -200.111868) (xy 387.662166 -200.111614)
			(xy 387.655064 -200.10605) (xy 387.638159 -200.099789) (xy 387.629146 -200.099422) (xy 387.56209 -200.099422)
			(xy 387.553072 -200.099769) (xy 387.536155 -200.106023) (xy 387.52907 -200.111614) (xy 387.528816 -200.111868)
			(xy 387.507883 -200.129509) (xy 387.461915 -200.159233) (xy 387.412169 -200.182079) (xy 387.359667 -200.197575)
			(xy 387.305489 -200.205404) (xy 387.250747 -200.205404) (xy 387.196569 -200.197575) (xy 387.144067 -200.182079)
			(xy 387.094321 -200.159233) (xy 387.048353 -200.129509) (xy 387.02742 -200.111868) (xy 387.027166 -200.111614)
			(xy 387.020064 -200.10605) (xy 387.003159 -200.099789) (xy 386.994146 -200.099422) (xy 386.92709 -200.099422)
			(xy 386.918072 -200.099769) (xy 386.901155 -200.106023) (xy 386.89407 -200.111614) (xy 386.89407 -200.111868)
			(xy 386.893816 -200.111868) (xy 386.872885 -200.129508) (xy 386.826912 -200.159221) (xy 386.777165 -200.182057)
			(xy 386.724663 -200.197548) (xy 386.670487 -200.205375) (xy 386.643118 -200.205848) (xy 386.615869 -200.205305)
			(xy 386.561925 -200.197552) (xy 386.509634 -200.182201) (xy 386.46006 -200.159565) (xy 386.414211 -200.130105)
			(xy 386.373022 -200.094419) (xy 386.33733 -200.053235) (xy 386.307863 -200.007391) (xy 386.285219 -199.95782)
			(xy 386.26986 -199.905531) (xy 386.262099 -199.851589) (xy 386.26161 -199.82434) (xy 383.994406 -199.82434)
			(xy 383.993959 -199.851592) (xy 383.986197 -199.905542) (xy 383.970837 -199.957837) (xy 383.948191 -200.007415)
			(xy 383.91872 -200.053265) (xy 383.883025 -200.094455) (xy 383.841831 -200.130146) (xy 383.795978 -200.159611)
			(xy 383.746398 -200.182252) (xy 383.6941 -200.197606) (xy 383.64015 -200.205362) (xy 383.612898 -200.205848)
			(xy 383.585527 -200.205396) (xy 383.531347 -200.197577) (xy 383.478843 -200.182085) (xy 383.429096 -200.15924)
			(xy 383.383131 -200.129511) (xy 383.3622 -200.111868) (xy 383.361946 -200.111614) (xy 383.354849 -200.106042)
			(xy 383.33794 -200.099786) (xy 383.328926 -200.099422) (xy 383.26187 -200.099422) (xy 383.252851 -200.09976)
			(xy 383.235934 -200.10602) (xy 383.22885 -200.111614) (xy 383.228596 -200.111868) (xy 383.207663 -200.129509)
			(xy 383.161695 -200.159233) (xy 383.111949 -200.182079) (xy 383.059447 -200.197575) (xy 383.005269 -200.205404)
			(xy 382.950527 -200.205404) (xy 382.896349 -200.197575) (xy 382.843847 -200.182079) (xy 382.794101 -200.159233)
			(xy 382.748133 -200.129509) (xy 382.7272 -200.111868) (xy 382.726946 -200.111614) (xy 382.719849 -200.106042)
			(xy 382.70294 -200.099786) (xy 382.693926 -200.099422) (xy 382.62687 -200.099422) (xy 382.617851 -200.09976)
			(xy 382.600934 -200.10602) (xy 382.59385 -200.111614) (xy 382.59385 -200.111868) (xy 382.593596 -200.111868)
			(xy 382.572672 -200.129517) (xy 382.526698 -200.159229) (xy 382.476948 -200.182063) (xy 382.424445 -200.197552)
			(xy 382.370268 -200.205376) (xy 382.342898 -200.205848) (xy 382.315649 -200.205324) (xy 382.261704 -200.197568)
			(xy 382.209413 -200.182215) (xy 382.159838 -200.159577) (xy 382.11399 -200.130114) (xy 382.0728 -200.094426)
			(xy 382.037109 -200.053241) (xy 382.007642 -200.007395) (xy 381.984998 -199.957823) (xy 381.96964 -199.905533)
			(xy 381.961879 -199.851589) (xy 381.96139 -199.82434) (xy 381.961882 -199.796971) (xy 381.969694 -199.742793)
			(xy 381.985177 -199.69029) (xy 382.008013 -199.640543) (xy 382.037732 -199.594575) (xy 382.05537 -199.573642)
			(xy 382.055624 -199.573388) (xy 382.061224 -199.566311) (xy 382.067462 -199.549387) (xy 382.067816 -199.540368)
			(xy 382.067816 -199.473312) (xy 382.06745 -199.464296) (xy 382.061208 -199.447379) (xy 382.055624 -199.440292)
			(xy 382.05537 -199.440292) (xy 382.05537 -199.440038) (xy 382.037767 -199.419074) (xy 382.008037 -199.373113)
			(xy 381.985187 -199.323372) (xy 381.969685 -199.270874) (xy 381.961852 -199.216699) (xy 381.961848 -199.161961)
			(xy 381.969673 -199.107785) (xy 381.985165 -199.055284) (xy 382.008008 -199.00554) (xy 382.03773 -198.959574)
			(xy 382.05537 -198.938642) (xy 382.055624 -198.938388) (xy 382.061224 -198.931311) (xy 382.067462 -198.914387)
			(xy 382.067816 -198.905368) (xy 382.067816 -198.838312) (xy 382.06745 -198.829296) (xy 382.061208 -198.812379)
			(xy 382.055624 -198.805292) (xy 382.05537 -198.805292) (xy 382.05537 -198.805038) (xy 382.037767 -198.784074)
			(xy 382.008037 -198.738113) (xy 381.985187 -198.688372) (xy 381.969685 -198.635874) (xy 381.961852 -198.581699)
			(xy 381.961848 -198.526961) (xy 381.969673 -198.472785) (xy 381.985165 -198.420284) (xy 382.008008 -198.37054)
			(xy 382.03773 -198.324574) (xy 382.05537 -198.303642) (xy 382.055624 -198.303388) (xy 382.061224 -198.296311)
			(xy 382.067462 -198.279387) (xy 382.067816 -198.270368) (xy 382.067816 -198.203312) (xy 382.06745 -198.194296)
			(xy 382.061208 -198.177379) (xy 382.055624 -198.170292) (xy 382.05537 -198.170292) (xy 382.05537 -198.170038)
			(xy 382.037731 -198.149106) (xy 382.00802 -198.103133) (xy 381.985184 -198.053385) (xy 381.969693 -198.000885)
			(xy 381.961865 -197.946709) (xy 381.96139 -197.91934) (xy 381.961892 -197.891502) (xy 381.969997 -197.83642)
			(xy 381.986012 -197.783097) (xy 382.009598 -197.732663) (xy 382.040254 -197.686188) (xy 382.058418 -197.665086)
			(xy 382.064768 -197.657974) (xy 382.071372 -197.640194) (xy 382.070102 -197.561454) (xy 382.069532 -197.552014)
			(xy 382.062368 -197.534527) (xy 382.056132 -197.527418) (xy 382.056132 -197.527164) (xy 382.036377 -197.505752)
			(xy 382.002977 -197.45802) (xy 381.977212 -197.405771) (xy 381.959679 -197.350214) (xy 381.950786 -197.29264)
			(xy 381.950214 -197.263512) (xy 381.950684 -197.236142) (xy 381.9585 -197.181963) (xy 381.973988 -197.12946)
			(xy 381.996829 -197.079713) (xy 382.026553 -197.033746) (xy 382.044194 -197.012814) (xy 382.044448 -197.01256)
			(xy 382.050021 -197.005465) (xy 382.056275 -196.988554) (xy 382.05664 -196.97954) (xy 382.05664 -196.912484)
			(xy 382.056303 -196.903465) (xy 382.050043 -196.886547) (xy 382.044448 -196.879464) (xy 382.044194 -196.879464)
			(xy 382.044194 -196.87921) (xy 382.026566 -196.858267) (xy 381.996844 -196.8123) (xy 381.974 -196.762555)
			(xy 381.958504 -196.710055) (xy 381.950675 -196.655879) (xy 381.950674 -196.601139) (xy 381.9585 -196.546962)
			(xy 381.973993 -196.494461) (xy 381.996835 -196.444716) (xy 382.026556 -196.398747) (xy 382.044194 -196.377814)
			(xy 382.044448 -196.37756) (xy 382.050021 -196.370465) (xy 382.056275 -196.353554) (xy 382.05664 -196.34454)
			(xy 382.05664 -196.277484) (xy 382.056303 -196.268465) (xy 382.050043 -196.251547) (xy 382.044448 -196.244464)
			(xy 382.044194 -196.244464) (xy 382.044194 -196.24421) (xy 382.026566 -196.223267) (xy 381.996844 -196.1773)
			(xy 381.974 -196.127555) (xy 381.958504 -196.075055) (xy 381.950675 -196.020879) (xy 381.950674 -195.966139)
			(xy 381.9585 -195.911962) (xy 381.973993 -195.859461) (xy 381.996835 -195.809716) (xy 382.026556 -195.763747)
			(xy 382.044194 -195.742814) (xy 382.044448 -195.74256) (xy 382.050021 -195.735465) (xy 382.056275 -195.718554)
			(xy 382.05664 -195.70954) (xy 382.05664 -195.642484) (xy 382.056303 -195.633465) (xy 382.050043 -195.616547)
			(xy 382.044448 -195.609464) (xy 382.044194 -195.609464) (xy 382.044194 -195.60921) (xy 382.026545 -195.588286)
			(xy 381.996835 -195.542311) (xy 381.974001 -195.492561) (xy 381.958512 -195.440059) (xy 381.950687 -195.385882)
			(xy 381.950214 -195.358512) (xy 381.950669 -195.331377) (xy 381.958364 -195.277656) (xy 381.973599 -195.22557)
			(xy 381.996068 -195.17617) (xy 382.025315 -195.130456) (xy 382.04267 -195.109592) (xy 382.048329 -195.1024)
			(xy 382.054575 -195.085212) (xy 382.054862 -195.076064) (xy 382.054608 -195.009262) (xy 382.054117 -195.000207)
			(xy 382.047612 -194.983291) (xy 382.041908 -194.976242) (xy 382.041654 -194.975988) (xy 382.023761 -194.954963)
			(xy 381.993567 -194.908745) (xy 381.970352 -194.858657) (xy 381.9546 -194.805745) (xy 381.94664 -194.751115)
			(xy 381.94615 -194.723512) (xy 379.963426 -194.723512) (xy 379.962978 -194.750483) (xy 379.955369 -194.803884)
			(xy 379.940305 -194.855679) (xy 379.918087 -194.904832) (xy 379.88916 -194.950361) (xy 379.871986 -194.971162)
			(xy 379.866453 -194.978339) (xy 379.860331 -194.99538) (xy 379.860048 -195.004436) (xy 379.86081 -195.08089)
			(xy 379.86716 -195.097654) (xy 379.87351 -195.104766) (xy 379.891602 -195.125838) (xy 379.922107 -195.172247)
			(xy 379.945567 -195.222585) (xy 379.961488 -195.275792) (xy 379.969532 -195.330743) (xy 379.97003 -195.358512)
			(xy 379.969588 -195.385883) (xy 379.961767 -195.440064) (xy 379.946273 -195.492568) (xy 379.923426 -195.542315)
			(xy 379.893695 -195.58828) (xy 379.87605 -195.60921) (xy 379.875796 -195.609464) (xy 379.870218 -195.616556)
			(xy 379.863966 -195.633469) (xy 379.863604 -195.642484) (xy 379.863604 -195.70954) (xy 379.863941 -195.718559)
			(xy 379.870203 -195.735476) (xy 379.875796 -195.74256) (xy 379.87605 -195.74256) (xy 379.87605 -195.742814)
			(xy 379.893703 -195.763737) (xy 379.923429 -195.809706) (xy 379.946276 -195.859453) (xy 379.961772 -195.911957)
			(xy 379.9696 -195.966138) (xy 379.969599 -196.02088) (xy 379.961768 -196.07506) (xy 379.946269 -196.127563)
			(xy 379.923421 -196.17731) (xy 379.893692 -196.223278) (xy 379.87605 -196.24421) (xy 379.875796 -196.244464)
			(xy 379.870218 -196.251556) (xy 379.863966 -196.268469) (xy 379.863604 -196.277484) (xy 379.863604 -196.34454)
			(xy 379.863941 -196.353559) (xy 379.870203 -196.370476) (xy 379.875796 -196.37756) (xy 379.87605 -196.37756)
			(xy 379.87605 -196.377814) (xy 379.893703 -196.398737) (xy 379.923429 -196.444706) (xy 379.946276 -196.494453)
			(xy 379.961772 -196.546957) (xy 379.9696 -196.601138) (xy 379.969599 -196.65588) (xy 379.961768 -196.71006)
			(xy 379.946269 -196.762563) (xy 379.923421 -196.81231) (xy 379.893692 -196.858278) (xy 379.87605 -196.87921)
			(xy 379.875796 -196.879464) (xy 379.870218 -196.886556) (xy 379.863966 -196.903469) (xy 379.863604 -196.912484)
			(xy 379.863604 -196.97954) (xy 379.863941 -196.988559) (xy 379.870203 -197.005476) (xy 379.875796 -197.01256)
			(xy 379.87605 -197.01256) (xy 379.87605 -197.012814) (xy 379.893654 -197.033774) (xy 379.923373 -197.079738)
			(xy 379.946217 -197.129479) (xy 379.961716 -197.181973) (xy 379.969552 -197.236145) (xy 379.97003 -197.263512)
			(xy 379.969519 -197.29135) (xy 379.961419 -197.346433) (xy 379.945408 -197.399756) (xy 379.921823 -197.45019)
			(xy 379.891166 -197.496665) (xy 379.873002 -197.517766) (xy 379.866652 -197.524878) (xy 379.860048 -197.542658)
			(xy 379.861318 -197.621398) (xy 379.861857 -197.630842) (xy 379.869042 -197.648329) (xy 379.875288 -197.655434)
			(xy 379.875288 -197.655688) (xy 379.895007 -197.677132) (xy 379.928415 -197.724854) (xy 379.954188 -197.777095)
			(xy 379.971729 -197.832645) (xy 379.98063 -197.890214) (xy 379.981206 -197.91934) (xy 379.980703 -197.946709)
			(xy 379.972894 -198.000886) (xy 379.957413 -198.053389) (xy 379.93458 -198.103136) (xy 379.904863 -198.149105)
			(xy 379.887226 -198.170038) (xy 379.886972 -198.170292) (xy 379.88138 -198.177374) (xy 379.875137 -198.194294)
			(xy 379.87478 -198.203312) (xy 379.87478 -198.270368) (xy 379.875157 -198.279383) (xy 379.881391 -198.2963)
			(xy 379.886972 -198.303388) (xy 379.887226 -198.303388) (xy 379.887226 -198.303642) (xy 379.904908 -198.324542)
			(xy 379.934635 -198.370514) (xy 379.95748 -198.420266) (xy 379.972976 -198.472773) (xy 379.980802 -198.526957)
			(xy 379.980797 -198.581703) (xy 379.972963 -198.635886) (xy 379.957459 -198.688391) (xy 379.934606 -198.738139)
			(xy 379.904871 -198.784106) (xy 379.887226 -198.805038) (xy 379.886972 -198.805292) (xy 379.88138 -198.812374)
			(xy 379.875137 -198.829294) (xy 379.87478 -198.838312) (xy 379.87478 -198.905368) (xy 379.875157 -198.914383)
			(xy 379.881391 -198.9313) (xy 379.886972 -198.938388) (xy 379.887226 -198.938388) (xy 379.887226 -198.938642)
			(xy 379.904908 -198.959542) (xy 379.934635 -199.005514) (xy 379.95748 -199.055266) (xy 379.972976 -199.107773)
			(xy 379.980802 -199.161957) (xy 379.980797 -199.216703) (xy 379.972963 -199.270886) (xy 379.957459 -199.323391)
			(xy 379.934606 -199.373139) (xy 379.904871 -199.419106) (xy 379.887226 -199.440038) (xy 379.886972 -199.440292)
			(xy 379.88138 -199.447374) (xy 379.875137 -199.464294) (xy 379.87478 -199.473312) (xy 379.87478 -199.540368)
			(xy 379.875157 -199.549383) (xy 379.881391 -199.5663) (xy 379.886972 -199.573388) (xy 379.887226 -199.573388)
			(xy 379.887226 -199.573642) (xy 379.904855 -199.594582) (xy 379.934568 -199.640553) (xy 379.957405 -199.690298)
			(xy 379.972899 -199.742797) (xy 379.98073 -199.796971) (xy 379.981206 -199.82434) (xy 379.980759 -199.851592)
			(xy 379.972997 -199.905542) (xy 379.957637 -199.957837) (xy 379.934991 -200.007415) (xy 379.90552 -200.053265)
			(xy 379.869825 -200.094455) (xy 379.828631 -200.130146) (xy 379.782778 -200.159611) (xy 379.733198 -200.182252)
			(xy 379.6809 -200.197606) (xy 379.62695 -200.205362) (xy 379.599698 -200.205848) (xy 379.572327 -200.205396)
			(xy 379.518147 -200.197577) (xy 379.465643 -200.182085) (xy 379.415896 -200.15924) (xy 379.369931 -200.129511)
			(xy 379.349 -200.111868) (xy 379.348746 -200.111614) (xy 379.341649 -200.106042) (xy 379.32474 -200.099786)
			(xy 379.315726 -200.099422) (xy 379.24867 -200.099422) (xy 379.239651 -200.09976) (xy 379.222734 -200.10602)
			(xy 379.21565 -200.111614) (xy 379.215396 -200.111868) (xy 379.194463 -200.129509) (xy 379.148495 -200.159233)
			(xy 379.098749 -200.182079) (xy 379.046247 -200.197575) (xy 378.992069 -200.205404) (xy 378.937327 -200.205404)
			(xy 378.883149 -200.197575) (xy 378.830647 -200.182079) (xy 378.780901 -200.159233) (xy 378.734933 -200.129509)
			(xy 378.714 -200.111868) (xy 378.713746 -200.111614) (xy 378.706649 -200.106042) (xy 378.68974 -200.099786)
			(xy 378.680726 -200.099422) (xy 378.61367 -200.099422) (xy 378.604651 -200.09976) (xy 378.587734 -200.10602)
			(xy 378.58065 -200.111614) (xy 378.58065 -200.111868) (xy 378.580396 -200.111868) (xy 378.559472 -200.129517)
			(xy 378.513498 -200.159229) (xy 378.463748 -200.182063) (xy 378.411245 -200.197552) (xy 378.357068 -200.205376)
			(xy 378.329698 -200.205848) (xy 378.302449 -200.205324) (xy 378.248504 -200.197568) (xy 378.196213 -200.182215)
			(xy 378.146638 -200.159577) (xy 378.10079 -200.130114) (xy 378.0596 -200.094426) (xy 378.023909 -200.053241)
			(xy 377.994442 -200.007395) (xy 377.971798 -199.957823) (xy 377.95644 -199.905533) (xy 377.948679 -199.851589)
			(xy 377.94819 -199.82434) (xy 377.948682 -199.796971) (xy 377.956494 -199.742793) (xy 377.971977 -199.69029)
			(xy 377.994813 -199.640543) (xy 378.024532 -199.594575) (xy 378.04217 -199.573642) (xy 378.042424 -199.573388)
			(xy 378.048024 -199.566311) (xy 378.054262 -199.549387) (xy 378.054616 -199.540368) (xy 378.054616 -199.473312)
			(xy 378.05425 -199.464296) (xy 378.048008 -199.447379) (xy 378.042424 -199.440292) (xy 378.04217 -199.440292)
			(xy 378.04217 -199.440038) (xy 378.024567 -199.419074) (xy 377.994837 -199.373113) (xy 377.971987 -199.323372)
			(xy 377.956485 -199.270874) (xy 377.948652 -199.216699) (xy 377.948648 -199.161961) (xy 377.956473 -199.107785)
			(xy 377.971965 -199.055284) (xy 377.994808 -199.00554) (xy 378.02453 -198.959574) (xy 378.04217 -198.938642)
			(xy 378.042424 -198.938388) (xy 378.048024 -198.931311) (xy 378.054262 -198.914387) (xy 378.054616 -198.905368)
			(xy 378.054616 -198.838312) (xy 378.05425 -198.829296) (xy 378.048008 -198.812379) (xy 378.042424 -198.805292)
			(xy 378.04217 -198.805292) (xy 378.04217 -198.805038) (xy 378.024567 -198.784074) (xy 377.994837 -198.738113)
			(xy 377.971987 -198.688372) (xy 377.956485 -198.635874) (xy 377.948652 -198.581699) (xy 377.948648 -198.526961)
			(xy 377.956473 -198.472785) (xy 377.971965 -198.420284) (xy 377.994808 -198.37054) (xy 378.02453 -198.324574)
			(xy 378.04217 -198.303642) (xy 378.042424 -198.303388) (xy 378.048024 -198.296311) (xy 378.054262 -198.279387)
			(xy 378.054616 -198.270368) (xy 378.054616 -198.203312) (xy 378.05425 -198.194296) (xy 378.048008 -198.177379)
			(xy 378.042424 -198.170292) (xy 378.04217 -198.170292) (xy 378.04217 -198.170038) (xy 378.024531 -198.149106)
			(xy 377.99482 -198.103133) (xy 377.971984 -198.053385) (xy 377.956493 -198.000885) (xy 377.948665 -197.946709)
			(xy 377.94819 -197.91934) (xy 377.948668 -197.893038) (xy 377.955894 -197.840933) (xy 377.970215 -197.790316)
			(xy 377.991358 -197.742149) (xy 378.018922 -197.697345) (xy 378.035312 -197.67677) (xy 378.041408 -197.669404)
			(xy 378.04725 -197.652386) (xy 378.04471 -197.566788) (xy 378.037852 -197.550024) (xy 378.031502 -197.543166)
			(xy 378.012635 -197.521898) (xy 377.980733 -197.47484) (xy 377.956154 -197.423575) (xy 377.93944 -197.369236)
			(xy 377.93096 -197.313019) (xy 377.93041 -197.284594) (xy 375.58249 -197.284594) (xy 375.582491 -197.308158)
			(xy 375.574664 -197.362335) (xy 375.559169 -197.414837) (xy 375.536325 -197.464582) (xy 375.506602 -197.51055)
			(xy 375.488962 -197.531482) (xy 375.488708 -197.531736) (xy 375.483143 -197.538837) (xy 375.476883 -197.555743)
			(xy 375.476516 -197.564756) (xy 375.476516 -197.631812) (xy 375.476864 -197.64083) (xy 375.483117 -197.657747)
			(xy 375.488708 -197.664832) (xy 375.488962 -197.664832) (xy 375.488962 -197.665086) (xy 375.506587 -197.686031)
			(xy 375.536314 -197.731997) (xy 375.559161 -197.781741) (xy 375.574659 -197.834241) (xy 375.582489 -197.888418)
			(xy 375.582491 -197.943158) (xy 375.574664 -197.997335) (xy 375.559169 -198.049837) (xy 375.536325 -198.099582)
			(xy 375.506602 -198.14555) (xy 375.488962 -198.166482) (xy 375.488708 -198.166736) (xy 375.483143 -198.173837)
			(xy 375.476883 -198.190743) (xy 375.476516 -198.199756) (xy 375.476516 -198.266812) (xy 375.476864 -198.27583)
			(xy 375.483117 -198.292747) (xy 375.488708 -198.299832) (xy 375.488962 -198.299832) (xy 375.488962 -198.300086)
			(xy 375.506587 -198.321031) (xy 375.536314 -198.366997) (xy 375.559161 -198.416741) (xy 375.574659 -198.469241)
			(xy 375.582489 -198.523418) (xy 375.582491 -198.578158) (xy 375.574664 -198.632335) (xy 375.559169 -198.684837)
			(xy 375.536325 -198.734582) (xy 375.506602 -198.78055) (xy 375.488962 -198.801482) (xy 375.488708 -198.801736)
			(xy 375.483143 -198.808837) (xy 375.476883 -198.825743) (xy 375.476516 -198.834756) (xy 375.476516 -198.901812)
			(xy 375.476864 -198.91083) (xy 375.483117 -198.927747) (xy 375.488708 -198.934832) (xy 375.488962 -198.934832)
			(xy 375.488962 -198.935086) (xy 375.506587 -198.956031) (xy 375.536314 -199.001997) (xy 375.559161 -199.051741)
			(xy 375.574659 -199.104241) (xy 375.582489 -199.158418) (xy 375.582491 -199.213158) (xy 375.574664 -199.267335)
			(xy 375.559169 -199.319837) (xy 375.536325 -199.369582) (xy 375.506602 -199.41555) (xy 375.488962 -199.436482)
			(xy 375.488708 -199.436736) (xy 375.483143 -199.443837) (xy 375.476883 -199.460743) (xy 375.476516 -199.469756)
			(xy 375.476516 -199.536812) (xy 375.476864 -199.54583) (xy 375.483117 -199.562747) (xy 375.488708 -199.569832)
			(xy 375.488962 -199.569832) (xy 375.488962 -199.570086) (xy 375.506587 -199.591031) (xy 375.536314 -199.636997)
			(xy 375.559161 -199.686741) (xy 375.574659 -199.739241) (xy 375.582489 -199.793418) (xy 375.582491 -199.848158)
			(xy 375.574664 -199.902335) (xy 375.559169 -199.954837) (xy 375.536325 -200.004582) (xy 375.506602 -200.05055)
			(xy 375.488962 -200.071482) (xy 375.488708 -200.071736) (xy 375.483143 -200.078837) (xy 375.476883 -200.095743)
			(xy 375.476516 -200.104756) (xy 375.476516 -200.171812) (xy 375.476864 -200.18083) (xy 375.483117 -200.197747)
			(xy 375.488708 -200.204832) (xy 375.488962 -200.204832) (xy 375.488962 -200.205086) (xy 375.506587 -200.226031)
			(xy 375.536314 -200.271997) (xy 375.559161 -200.321741) (xy 375.574659 -200.374241) (xy 375.582489 -200.428418)
			(xy 375.582491 -200.483158) (xy 375.574664 -200.537335) (xy 375.559169 -200.589837) (xy 375.536325 -200.639582)
			(xy 375.506602 -200.68555) (xy 375.488962 -200.706482) (xy 375.488708 -200.706736) (xy 375.483143 -200.713837)
			(xy 375.476883 -200.730743) (xy 375.476516 -200.739756) (xy 375.476516 -200.806812) (xy 375.476864 -200.81583)
			(xy 375.483117 -200.832747) (xy 375.488708 -200.839832) (xy 375.488962 -200.839832) (xy 375.488962 -200.840086)
			(xy 375.506602 -200.861017) (xy 375.536315 -200.90699) (xy 375.559151 -200.956737) (xy 375.574642 -201.009238)
			(xy 375.582469 -201.063415) (xy 375.582942 -201.090784) (xy 375.582407 -201.118033) (xy 375.574654 -201.171977)
			(xy 375.559302 -201.224269) (xy 375.536665 -201.273844) (xy 375.507204 -201.319693) (xy 375.471518 -201.360882)
			(xy 375.430333 -201.396574) (xy 375.384488 -201.426041) (xy 375.334916 -201.448685) (xy 375.282626 -201.464043)
			(xy 375.228683 -201.471803) (xy 375.201434 -201.472292) (xy 375.174064 -201.471808) (xy 375.119886 -201.463995)
			(xy 375.067383 -201.44851) (xy 375.017636 -201.425672) (xy 374.971668 -201.395951) (xy 374.950736 -201.378312)
			(xy 374.950482 -201.378058) (xy 374.943408 -201.372453) (xy 374.926482 -201.366218) (xy 374.917462 -201.365866)
			(xy 374.850406 -201.365866) (xy 374.84139 -201.366233) (xy 374.824474 -201.372475) (xy 374.817386 -201.378058)
			(xy 374.817132 -201.378312) (xy 374.796199 -201.395953) (xy 374.750231 -201.425677) (xy 374.700485 -201.448523)
			(xy 374.647983 -201.464019) (xy 374.593805 -201.471848) (xy 374.539063 -201.471848) (xy 374.484885 -201.464019)
			(xy 374.432383 -201.448523) (xy 374.382637 -201.425677) (xy 374.336669 -201.395953) (xy 374.315736 -201.378312)
			(xy 374.315482 -201.378058) (xy 374.308408 -201.372453) (xy 374.291482 -201.366218) (xy 374.282462 -201.365866)
			(xy 374.215406 -201.365866) (xy 374.20639 -201.366233) (xy 374.189474 -201.372475) (xy 374.182386 -201.378058)
			(xy 374.182386 -201.378312) (xy 374.182132 -201.378312) (xy 374.1612 -201.395951) (xy 374.115227 -201.425663)
			(xy 374.06548 -201.448498) (xy 374.012979 -201.46399) (xy 373.958803 -201.471818) (xy 373.931434 -201.472292)
			(xy 373.904181 -201.471813) (xy 373.85023 -201.46406) (xy 373.797932 -201.448708) (xy 373.74835 -201.426068)
			(xy 373.702496 -201.396602) (xy 373.661303 -201.36091) (xy 373.625609 -201.319718) (xy 373.596141 -201.273865)
			(xy 373.573499 -201.224285) (xy 373.558144 -201.171988) (xy 373.550388 -201.118037) (xy 373.549926 -201.090784)
			(xy 373.550376 -201.063413) (xy 373.558197 -201.009233) (xy 373.573689 -200.95673) (xy 373.596535 -200.906983)
			(xy 373.626263 -200.861017) (xy 373.643906 -200.840086) (xy 373.64416 -200.839832) (xy 373.649746 -200.832746)
			(xy 373.655992 -200.815828) (xy 373.656352 -200.806812) (xy 373.656352 -200.739756) (xy 373.655979 -200.730741)
			(xy 373.649744 -200.713823) (xy 373.64416 -200.706736) (xy 373.643906 -200.706736) (xy 373.643906 -200.706482)
			(xy 373.626251 -200.685562) (xy 373.596528 -200.639591) (xy 373.573685 -200.589843) (xy 373.558191 -200.537339)
			(xy 373.550364 -200.483159) (xy 373.550366 -200.428417) (xy 373.558196 -200.374237) (xy 373.573693 -200.321735)
			(xy 373.59654 -200.271988) (xy 373.626265 -200.226019) (xy 373.643906 -200.205086) (xy 373.64416 -200.204832)
			(xy 373.649746 -200.197746) (xy 373.655992 -200.180828) (xy 373.656352 -200.171812) (xy 373.656352 -200.104756)
			(xy 373.655979 -200.095741) (xy 373.649744 -200.078823) (xy 373.64416 -200.071736) (xy 373.643906 -200.071736)
			(xy 373.643906 -200.071482) (xy 373.626251 -200.050562) (xy 373.596528 -200.004591) (xy 373.573685 -199.954843)
			(xy 373.558191 -199.902339) (xy 373.550364 -199.848159) (xy 373.550366 -199.793417) (xy 373.558196 -199.739237)
			(xy 373.573693 -199.686735) (xy 373.59654 -199.636988) (xy 373.626265 -199.591019) (xy 373.643906 -199.570086)
			(xy 373.64416 -199.569832) (xy 373.649746 -199.562746) (xy 373.655992 -199.545828) (xy 373.656352 -199.536812)
			(xy 373.656352 -199.469756) (xy 373.655979 -199.460741) (xy 373.649744 -199.443823) (xy 373.64416 -199.436736)
			(xy 373.643906 -199.436736) (xy 373.643906 -199.436482) (xy 373.626251 -199.415562) (xy 373.596528 -199.369591)
			(xy 373.573685 -199.319843) (xy 373.558191 -199.267339) (xy 373.550364 -199.213159) (xy 373.550366 -199.158417)
			(xy 373.558196 -199.104237) (xy 373.573693 -199.051735) (xy 373.59654 -199.001988) (xy 373.626265 -198.956019)
			(xy 373.643906 -198.935086) (xy 373.64416 -198.934832) (xy 373.649746 -198.927746) (xy 373.655992 -198.910828)
			(xy 373.656352 -198.901812) (xy 373.656352 -198.834756) (xy 373.655979 -198.825741) (xy 373.649744 -198.808823)
			(xy 373.64416 -198.801736) (xy 373.643906 -198.801736) (xy 373.643906 -198.801482) (xy 373.626251 -198.780562)
			(xy 373.596528 -198.734591) (xy 373.573685 -198.684843) (xy 373.558191 -198.632339) (xy 373.550364 -198.578159)
			(xy 373.550366 -198.523417) (xy 373.558196 -198.469237) (xy 373.573693 -198.416735) (xy 373.59654 -198.366988)
			(xy 373.626265 -198.321019) (xy 373.643906 -198.300086) (xy 373.64416 -198.299832) (xy 373.649746 -198.292746)
			(xy 373.655992 -198.275828) (xy 373.656352 -198.266812) (xy 373.656352 -198.199756) (xy 373.655979 -198.190741)
			(xy 373.649744 -198.173823) (xy 373.64416 -198.166736) (xy 373.643906 -198.166736) (xy 373.643906 -198.166482)
			(xy 373.626293 -198.145529) (xy 373.596577 -198.099562) (xy 373.573736 -198.04982) (xy 373.558239 -197.997324)
			(xy 373.550404 -197.943152) (xy 373.549926 -197.915784) (xy 373.550459 -197.887639) (xy 373.558725 -197.83196)
			(xy 373.575076 -197.778097) (xy 373.599158 -197.727219) (xy 373.630447 -197.680427) (xy 373.648986 -197.659244)
			(xy 373.655336 -197.652386) (xy 373.662194 -197.634606) (xy 373.66194 -197.546722) (xy 373.655082 -197.529196)
			(xy 373.648478 -197.522084) (xy 373.62959 -197.500829) (xy 373.597656 -197.453785) (xy 373.573064 -197.402519)
			(xy 373.556359 -197.348169) (xy 373.547912 -197.291941) (xy 373.547386 -197.263512) (xy 373.547863 -197.236142)
			(xy 373.555678 -197.181964) (xy 373.571165 -197.129461) (xy 373.594004 -197.079714) (xy 373.623726 -197.033746)
			(xy 373.641366 -197.012814) (xy 373.64162 -197.01256) (xy 373.64719 -197.005462) (xy 373.653446 -196.988554)
			(xy 373.653812 -196.97954) (xy 373.653812 -196.912484) (xy 373.65346 -196.903467) (xy 373.647209 -196.88655)
			(xy 373.64162 -196.879464) (xy 373.641366 -196.879464) (xy 373.641366 -196.87921) (xy 373.623735 -196.858269)
			(xy 373.594007 -196.812303) (xy 373.571159 -196.762559) (xy 373.55566 -196.710058) (xy 373.547829 -196.65588)
			(xy 373.547828 -196.601139) (xy 373.555656 -196.54696) (xy 373.571152 -196.494458) (xy 373.593998 -196.444713)
			(xy 373.623725 -196.398746) (xy 373.641366 -196.377814) (xy 373.64162 -196.37756) (xy 373.64719 -196.370462)
			(xy 373.653446 -196.353554) (xy 373.653812 -196.34454) (xy 373.653812 -196.277484) (xy 373.65346 -196.268467)
			(xy 373.647209 -196.25155) (xy 373.64162 -196.244464) (xy 373.641366 -196.244464) (xy 373.641366 -196.24421)
			(xy 373.623735 -196.223269) (xy 373.594007 -196.177303) (xy 373.571159 -196.127559) (xy 373.55566 -196.075058)
			(xy 373.547829 -196.02088) (xy 373.547828 -195.966139) (xy 373.555656 -195.91196) (xy 373.571152 -195.859458)
			(xy 373.593998 -195.809713) (xy 373.623725 -195.763746) (xy 373.641366 -195.742814) (xy 373.64162 -195.74256)
			(xy 373.64719 -195.735462) (xy 373.653446 -195.718554) (xy 373.653812 -195.70954) (xy 373.653812 -195.642484)
			(xy 373.65346 -195.633467) (xy 373.647209 -195.61655) (xy 373.64162 -195.609464) (xy 373.641366 -195.609464)
			(xy 373.641366 -195.60921) (xy 373.623713 -195.588289) (xy 373.594004 -195.542313) (xy 373.571172 -195.492562)
			(xy 373.555684 -195.440059) (xy 373.547859 -195.385882) (xy 373.547386 -195.358512) (xy 373.547824 -195.331377)
			(xy 373.55552 -195.277654) (xy 373.570759 -195.225567) (xy 373.593232 -195.176167) (xy 373.622484 -195.130455)
			(xy 373.639842 -195.109592) (xy 373.64551 -195.102406) (xy 373.651749 -195.085213) (xy 373.652034 -195.076064)
			(xy 373.65178 -195.009262) (xy 373.651295 -195.000206) (xy 373.644787 -194.98329) (xy 373.63908 -194.976242)
			(xy 373.638826 -194.975988) (xy 373.620929 -194.954967) (xy 373.590737 -194.908747) (xy 373.567523 -194.858658)
			(xy 373.551771 -194.805746) (xy 373.543812 -194.751116) (xy 373.543322 -194.723512) (xy 371.560598 -194.723512)
			(xy 371.560133 -194.750482) (xy 371.552525 -194.803882) (xy 371.537465 -194.855676) (xy 371.515251 -194.90483)
			(xy 371.486329 -194.95036) (xy 371.469158 -194.971162) (xy 371.463622 -194.978336) (xy 371.457502 -194.995379)
			(xy 371.45722 -195.004436) (xy 371.457982 -195.08089) (xy 371.464332 -195.097654) (xy 371.470682 -195.104766)
			(xy 371.488769 -195.125842) (xy 371.519276 -195.172249) (xy 371.542738 -195.222587) (xy 371.558659 -195.275793)
			(xy 371.566704 -195.330744) (xy 371.567202 -195.358512) (xy 371.566742 -195.385882) (xy 371.558923 -195.440062)
			(xy 371.543432 -195.492565) (xy 371.520589 -195.542312) (xy 371.490864 -195.588278) (xy 371.473222 -195.60921)
			(xy 371.472968 -195.609464) (xy 371.467387 -195.616554) (xy 371.461138 -195.633468) (xy 371.460776 -195.642484)
			(xy 371.460776 -195.70954) (xy 371.461119 -195.718558) (xy 371.467377 -195.735475) (xy 371.472968 -195.74256)
			(xy 371.473222 -195.74256) (xy 371.473222 -195.742814) (xy 371.490872 -195.763738) (xy 371.520593 -195.809709)
			(xy 371.543435 -195.859457) (xy 371.558928 -195.91196) (xy 371.566754 -195.966138) (xy 371.566753 -196.02088)
			(xy 371.558924 -196.075058) (xy 371.543428 -196.12756) (xy 371.520584 -196.177307) (xy 371.490861 -196.223276)
			(xy 371.473222 -196.24421) (xy 371.472968 -196.244464) (xy 371.467387 -196.251554) (xy 371.461138 -196.268468)
			(xy 371.460776 -196.277484) (xy 371.460776 -196.34454) (xy 371.461119 -196.353558) (xy 371.467377 -196.370475)
			(xy 371.472968 -196.37756) (xy 371.473222 -196.37756) (xy 371.473222 -196.377814) (xy 371.490872 -196.398738)
			(xy 371.520593 -196.444709) (xy 371.543435 -196.494457) (xy 371.558928 -196.54696) (xy 371.566754 -196.601138)
			(xy 371.566753 -196.65588) (xy 371.558924 -196.710058) (xy 371.543428 -196.76256) (xy 371.520584 -196.812307)
			(xy 371.490861 -196.858276) (xy 371.473222 -196.87921) (xy 371.472968 -196.879464) (xy 371.467387 -196.886554)
			(xy 371.461138 -196.903468) (xy 371.460776 -196.912484) (xy 371.460776 -196.97954) (xy 371.461119 -196.988558)
			(xy 371.467377 -197.005475) (xy 371.472968 -197.01256) (xy 371.473222 -197.01256) (xy 371.473222 -197.012814)
			(xy 371.490838 -197.033765) (xy 371.520552 -197.079733) (xy 371.543392 -197.129476) (xy 371.558889 -197.181972)
			(xy 371.566724 -197.236144) (xy 371.567202 -197.263512) (xy 371.566685 -197.291658) (xy 371.558418 -197.347339)
			(xy 371.542064 -197.401202) (xy 371.517979 -197.45208) (xy 371.486683 -197.498871) (xy 371.468142 -197.520052)
			(xy 371.461792 -197.52691) (xy 371.454934 -197.54469) (xy 371.455188 -197.632574) (xy 371.462046 -197.6501)
			(xy 371.46865 -197.657212) (xy 371.48754 -197.678465) (xy 371.519473 -197.72551) (xy 371.544064 -197.776776)
			(xy 371.560768 -197.831126) (xy 371.569215 -197.887354) (xy 371.569742 -197.915784) (xy 371.569281 -197.943155)
			(xy 371.561464 -197.997334) (xy 371.545974 -198.049838) (xy 371.523131 -198.099585) (xy 371.493405 -198.145551)
			(xy 371.475762 -198.166482) (xy 371.475508 -198.166736) (xy 371.469943 -198.173837) (xy 371.463683 -198.190743)
			(xy 371.463316 -198.199756) (xy 371.463316 -198.266812) (xy 371.463664 -198.27583) (xy 371.469917 -198.292747)
			(xy 371.475508 -198.299832) (xy 371.475762 -198.299832) (xy 371.475762 -198.300086) (xy 371.493387 -198.321031)
			(xy 371.523114 -198.366997) (xy 371.545961 -198.416741) (xy 371.561459 -198.469241) (xy 371.569289 -198.523418)
			(xy 371.569291 -198.578158) (xy 371.561464 -198.632335) (xy 371.545969 -198.684837) (xy 371.523125 -198.734582)
			(xy 371.493402 -198.78055) (xy 371.475762 -198.801482) (xy 371.475508 -198.801736) (xy 371.469943 -198.808837)
			(xy 371.463683 -198.825743) (xy 371.463316 -198.834756) (xy 371.463316 -198.901812) (xy 371.463664 -198.91083)
			(xy 371.469917 -198.927747) (xy 371.475508 -198.934832) (xy 371.475762 -198.934832) (xy 371.475762 -198.935086)
			(xy 371.493387 -198.956031) (xy 371.523114 -199.001997) (xy 371.545961 -199.051741) (xy 371.561459 -199.104241)
			(xy 371.569289 -199.158418) (xy 371.569291 -199.213158) (xy 371.561464 -199.267335) (xy 371.545969 -199.319837)
			(xy 371.523125 -199.369582) (xy 371.493402 -199.41555) (xy 371.475762 -199.436482) (xy 371.475508 -199.436736)
			(xy 371.469943 -199.443837) (xy 371.463683 -199.460743) (xy 371.463316 -199.469756) (xy 371.463316 -199.536812)
			(xy 371.463664 -199.54583) (xy 371.469917 -199.562747) (xy 371.475508 -199.569832) (xy 371.475762 -199.569832)
			(xy 371.475762 -199.570086) (xy 371.493387 -199.591031) (xy 371.523114 -199.636997) (xy 371.545961 -199.686741)
			(xy 371.561459 -199.739241) (xy 371.569289 -199.793418) (xy 371.569291 -199.848158) (xy 371.561464 -199.902335)
			(xy 371.545969 -199.954837) (xy 371.523125 -200.004582) (xy 371.493402 -200.05055) (xy 371.475762 -200.071482)
			(xy 371.475508 -200.071736) (xy 371.469943 -200.078837) (xy 371.463683 -200.095743) (xy 371.463316 -200.104756)
			(xy 371.463316 -200.171812) (xy 371.463664 -200.18083) (xy 371.469917 -200.197747) (xy 371.475508 -200.204832)
			(xy 371.475762 -200.204832) (xy 371.475762 -200.205086) (xy 371.493387 -200.226031) (xy 371.523114 -200.271997)
			(xy 371.545961 -200.321741) (xy 371.561459 -200.374241) (xy 371.569289 -200.428418) (xy 371.569291 -200.483158)
			(xy 371.561464 -200.537335) (xy 371.545969 -200.589837) (xy 371.523125 -200.639582) (xy 371.493402 -200.68555)
			(xy 371.475762 -200.706482) (xy 371.475508 -200.706736) (xy 371.469943 -200.713837) (xy 371.463683 -200.730743)
			(xy 371.463316 -200.739756) (xy 371.463316 -200.806812) (xy 371.463664 -200.81583) (xy 371.469917 -200.832747)
			(xy 371.475508 -200.839832) (xy 371.475762 -200.839832) (xy 371.475762 -200.840086) (xy 371.493402 -200.861017)
			(xy 371.523115 -200.90699) (xy 371.545951 -200.956737) (xy 371.561442 -201.009238) (xy 371.569269 -201.063415)
			(xy 371.569742 -201.090784) (xy 371.569256 -201.118035) (xy 371.5615 -201.171983) (xy 371.546145 -201.224278)
			(xy 371.523503 -201.273855) (xy 371.494037 -201.319705) (xy 371.458346 -201.360896) (xy 371.417155 -201.396587)
			(xy 371.371305 -201.426053) (xy 371.321728 -201.448695) (xy 371.269433 -201.46405) (xy 371.215485 -201.471806)
			(xy 371.160983 -201.471806) (xy 371.107035 -201.46405) (xy 371.05474 -201.448695) (xy 371.005163 -201.426053)
			(xy 370.959313 -201.396587) (xy 370.918122 -201.360896) (xy 370.882431 -201.319705) (xy 370.852965 -201.273855)
			(xy 370.830323 -201.224278) (xy 370.814968 -201.171983) (xy 370.807212 -201.118035) (xy 370.806726 -201.090784)
			(xy 370.807176 -201.063413) (xy 370.814997 -201.009233) (xy 370.830489 -200.95673) (xy 370.853335 -200.906983)
			(xy 370.883063 -200.861017) (xy 370.900706 -200.840086) (xy 370.90096 -200.839832) (xy 370.906546 -200.832746)
			(xy 370.912792 -200.815828) (xy 370.913152 -200.806812) (xy 370.913152 -200.739756) (xy 370.912779 -200.730741)
			(xy 370.906544 -200.713823) (xy 370.90096 -200.706736) (xy 370.900706 -200.706736) (xy 370.900706 -200.706482)
			(xy 370.883093 -200.685529) (xy 370.853377 -200.639562) (xy 370.830536 -200.58982) (xy 370.815039 -200.537324)
			(xy 370.807204 -200.483152) (xy 370.806726 -200.455784) (xy 370.807249 -200.426306) (xy 370.816321 -200.368051)
			(xy 370.834247 -200.311886) (xy 370.860601 -200.259147) (xy 370.894753 -200.21109) (xy 370.91493 -200.189592)
			(xy 370.921465 -200.182258) (xy 370.928909 -200.164097) (xy 370.929408 -200.154286) (xy 370.929408 -200.100946)
			(xy 370.922042 -200.094088) (xy 370.914689 -200.087577) (xy 370.896543 -200.080118) (xy 370.886736 -200.07961)
			(xy 370.854732 -200.07961) (xy 370.844914 -200.080068) (xy 370.82675 -200.087532) (xy 370.819426 -200.094088)
			(xy 370.797921 -200.114255) (xy 370.749862 -200.1484) (xy 370.697124 -200.174746) (xy 370.640961 -200.192669)
			(xy 370.582711 -200.201741) (xy 370.553234 -200.202292) (xy 370.525981 -200.201813) (xy 370.47203 -200.19406)
			(xy 370.419732 -200.178708) (xy 370.37015 -200.156068) (xy 370.324296 -200.126602) (xy 370.283103 -200.09091)
			(xy 370.247409 -200.049718) (xy 370.217941 -200.003865) (xy 370.195299 -199.954285) (xy 370.179944 -199.901988)
			(xy 370.172188 -199.848037) (xy 370.171726 -199.820784) (xy 370.172249 -199.791306) (xy 370.181321 -199.733051)
			(xy 370.199247 -199.676886) (xy 370.225601 -199.624147) (xy 370.259753 -199.57609) (xy 370.27993 -199.554592)
			(xy 370.286465 -199.547258) (xy 370.293909 -199.529097) (xy 370.294408 -199.519286) (xy 370.294408 -199.465946)
			(xy 370.288566 -199.460612) (xy 370.281195 -199.45416) (xy 370.263045 -199.446838) (xy 370.25326 -199.446388)
			(xy 370.22151 -199.446642) (xy 370.211631 -199.447093) (xy 370.193332 -199.45454) (xy 370.18595 -199.46112)
			(xy 370.16443 -199.481586) (xy 370.116174 -199.516201) (xy 370.063136 -199.542919) (xy 370.006599 -199.561094)
			(xy 369.947928 -199.570287) (xy 369.918234 -199.570848) (xy 369.890985 -199.57029) (xy 369.837042 -199.562539)
			(xy 369.784751 -199.547191) (xy 369.735177 -199.524556) (xy 369.689329 -199.495097) (xy 369.648139 -199.459413)
			(xy 369.612447 -199.418231) (xy 369.582979 -199.372388) (xy 369.560335 -199.322818) (xy 369.544976 -199.27053)
			(xy 369.537215 -199.216588) (xy 369.536726 -199.18934) (xy 369.537209 -199.16197) (xy 369.545022 -199.107792)
			(xy 369.560507 -199.055289) (xy 369.583345 -199.005541) (xy 369.613066 -198.959574) (xy 369.630706 -198.938642)
			(xy 369.63096 -198.938388) (xy 369.636565 -198.931314) (xy 369.642799 -198.914387) (xy 369.643152 -198.905368)
			(xy 369.643152 -198.838312) (xy 369.6428 -198.829294) (xy 369.63655 -198.812377) (xy 369.63096 -198.805292)
			(xy 369.630706 -198.805292) (xy 369.630706 -198.805038) (xy 369.613105 -198.784073) (xy 369.583381 -198.73811)
			(xy 369.560534 -198.688369) (xy 369.545036 -198.635872) (xy 369.537204 -198.581699) (xy 369.537199 -198.526962)
			(xy 369.545023 -198.472787) (xy 369.560513 -198.420287) (xy 369.583352 -198.370543) (xy 369.613069 -198.324575)
			(xy 369.630706 -198.303642) (xy 369.63096 -198.303388) (xy 369.636565 -198.296314) (xy 369.642799 -198.279387)
			(xy 369.643152 -198.270368) (xy 369.643152 -198.203312) (xy 369.6428 -198.194294) (xy 369.63655 -198.177377)
			(xy 369.63096 -198.170292) (xy 369.630706 -198.170292) (xy 369.630706 -198.170038) (xy 369.613072 -198.149102)
			(xy 369.583359 -198.10313) (xy 369.560522 -198.053384) (xy 369.54503 -198.000884) (xy 369.537201 -197.946709)
			(xy 369.536726 -197.91934) (xy 369.537161 -197.892509) (xy 369.544677 -197.839377) (xy 369.559567 -197.787823)
			(xy 369.581536 -197.738865) (xy 369.610151 -197.693469) (xy 369.62715 -197.672706) (xy 369.633246 -197.665594)
			(xy 369.639088 -197.648576) (xy 369.638072 -197.572376) (xy 369.637568 -197.563234) (xy 369.630923 -197.546184)
			(xy 369.625118 -197.539102) (xy 369.60687 -197.517978) (xy 369.576037 -197.471447) (xy 369.552316 -197.420918)
			(xy 369.536213 -197.367472) (xy 369.528071 -197.31225) (xy 369.527582 -197.28434) (xy 363.258862 -197.28434)
			(xy 367.709704 -201.735182) (xy 367.712556 -201.737887) (xy 367.718935 -201.742478) (xy 367.722404 -201.744326)
			(xy 367.72783 -201.746912) (xy 367.73951 -201.749743) (xy 367.745518 -201.749914)
		)
		(stroke
			(width 0)
			(type solid)
		)
		(fill yes)
		(layer "In15.Cu")
		(net "GND")
	)
	(gr_poly
		(pts
			(xy 345.247214 -251.22632) (xy 345.259289 -251.225659) (xy 345.280789 -251.214664) (xy 345.288362 -251.205238)
			(xy 345.289124 -251.204476) (xy 345.34348 -251.121926) (xy 345.345766 -251.096526) (xy 345.340686 -251.084842)
			(xy 345.33283 -251.065708) (xy 345.321757 -251.025854) (xy 345.31615 -250.984873) (xy 345.315794 -250.964192)
			(xy 345.316316 -250.938937) (xy 345.324629 -250.889115) (xy 345.34103 -250.841341) (xy 345.365071 -250.796918)
			(xy 345.396095 -250.757058) (xy 345.433257 -250.722848) (xy 345.475543 -250.695222) (xy 345.521799 -250.674932)
			(xy 345.570764 -250.662532) (xy 345.621102 -250.658361) (xy 345.67144 -250.662532) (xy 345.720405 -250.674932)
			(xy 345.766661 -250.695222) (xy 345.808947 -250.722848) (xy 345.846109 -250.757058) (xy 345.877133 -250.796918)
			(xy 345.901174 -250.841341) (xy 345.917575 -250.889115) (xy 345.925888 -250.938937) (xy 345.92641 -250.964192)
			(xy 345.92607 -250.984875) (xy 345.920483 -251.025862) (xy 345.909397 -251.065715) (xy 345.901518 -251.084842)
			(xy 345.896438 -251.096526) (xy 345.898724 -251.121926) (xy 345.952572 -251.20346) (xy 345.953842 -251.205238)
			(xy 345.961452 -251.214624) (xy 345.982927 -251.225625) (xy 345.99499 -251.22632) (xy 346.187268 -251.22632)
			(xy 346.199337 -251.225648) (xy 346.220817 -251.214639) (xy 346.228416 -251.205238) (xy 346.229178 -251.204476)
			(xy 346.283534 -251.121926) (xy 346.28582 -251.096526) (xy 346.28074 -251.084842) (xy 346.272883 -251.065708)
			(xy 346.261809 -251.025855) (xy 346.256201 -250.984873) (xy 346.255848 -250.964192) (xy 346.25637 -250.938937)
			(xy 346.264683 -250.889115) (xy 346.281084 -250.841341) (xy 346.305125 -250.796918) (xy 346.336149 -250.757058)
			(xy 346.373311 -250.722848) (xy 346.415597 -250.695222) (xy 346.461853 -250.674932) (xy 346.510818 -250.662532)
			(xy 346.561156 -250.658361) (xy 346.611494 -250.662532) (xy 346.660459 -250.674932) (xy 346.706715 -250.695222)
			(xy 346.749001 -250.722848) (xy 346.786163 -250.757058) (xy 346.817187 -250.796918) (xy 346.841228 -250.841341)
			(xy 346.857629 -250.889115) (xy 346.865942 -250.938937) (xy 346.866464 -250.964192) (xy 346.866124 -250.984875)
			(xy 346.860536 -251.025862) (xy 346.849448 -251.065714) (xy 346.841572 -251.084842) (xy 346.836492 -251.096526)
			(xy 346.838778 -251.121926) (xy 346.892626 -251.20346) (xy 346.893896 -251.205238) (xy 346.901503 -251.214631)
			(xy 346.922977 -251.225652) (xy 346.935044 -251.22632) (xy 347.127322 -251.22632) (xy 347.139396 -251.225657)
			(xy 347.160893 -251.21466) (xy 347.16847 -251.205238) (xy 347.169232 -251.204476) (xy 347.223588 -251.121926)
			(xy 347.225874 -251.096526) (xy 347.220794 -251.084842) (xy 347.212939 -251.065707) (xy 347.201865 -251.025854)
			(xy 347.196258 -250.984873) (xy 347.195902 -250.964192) (xy 347.196424 -250.938937) (xy 347.204737 -250.889115)
			(xy 347.221138 -250.841341) (xy 347.245179 -250.796918) (xy 347.276203 -250.757058) (xy 347.313365 -250.722848)
			(xy 347.355651 -250.695222) (xy 347.401907 -250.674932) (xy 347.450872 -250.662532) (xy 347.50121 -250.658361)
			(xy 347.551548 -250.662532) (xy 347.600513 -250.674932) (xy 347.646769 -250.695222) (xy 347.689055 -250.722848)
			(xy 347.726217 -250.757058) (xy 347.757241 -250.796918) (xy 347.781282 -250.841341) (xy 347.797683 -250.889115)
			(xy 347.805996 -250.938937) (xy 347.806518 -250.964192) (xy 347.806178 -250.984875) (xy 347.800591 -251.025862)
			(xy 347.789505 -251.065716) (xy 347.781626 -251.084842) (xy 347.776546 -251.096526) (xy 347.778832 -251.121926)
			(xy 347.83268 -251.20346) (xy 347.83395 -251.205238) (xy 347.84156 -251.214622) (xy 347.863036 -251.22562)
			(xy 347.875098 -251.22632) (xy 348.067122 -251.22632) (xy 348.079196 -251.225657) (xy 348.100693 -251.21466)
			(xy 348.10827 -251.205238) (xy 348.109032 -251.204476) (xy 348.163388 -251.121926) (xy 348.165674 -251.096526)
			(xy 348.160594 -251.084842) (xy 348.152739 -251.065707) (xy 348.141665 -251.025854) (xy 348.136058 -250.984873)
			(xy 348.135702 -250.964192) (xy 348.136224 -250.938937) (xy 348.144537 -250.889115) (xy 348.160938 -250.841341)
			(xy 348.184979 -250.796918) (xy 348.216003 -250.757058) (xy 348.253165 -250.722848) (xy 348.295451 -250.695222)
			(xy 348.341707 -250.674932) (xy 348.390672 -250.662532) (xy 348.44101 -250.658361) (xy 348.491348 -250.662532)
			(xy 348.540313 -250.674932) (xy 348.586569 -250.695222) (xy 348.628855 -250.722848) (xy 348.666017 -250.757058)
			(xy 348.697041 -250.796918) (xy 348.721082 -250.841341) (xy 348.737483 -250.889115) (xy 348.745796 -250.938937)
			(xy 348.746318 -250.964192) (xy 348.745978 -250.984875) (xy 348.740391 -251.025862) (xy 348.729305 -251.065716)
			(xy 348.721426 -251.084842) (xy 348.716346 -251.096526) (xy 348.718632 -251.121926) (xy 348.77248 -251.20346)
			(xy 348.77375 -251.205238) (xy 348.78136 -251.214622) (xy 348.802836 -251.22562) (xy 348.814898 -251.22632)
			(xy 349.007176 -251.22632) (xy 349.019244 -251.225646) (xy 349.040721 -251.214635) (xy 349.048324 -251.205238)
			(xy 349.049086 -251.204476) (xy 349.103442 -251.121926) (xy 349.105728 -251.096526) (xy 349.100648 -251.084842)
			(xy 349.092791 -251.065708) (xy 349.081716 -251.025855) (xy 349.076108 -250.984873) (xy 349.075756 -250.964192)
			(xy 349.076278 -250.938937) (xy 349.084591 -250.889115) (xy 349.100992 -250.841341) (xy 349.125033 -250.796918)
			(xy 349.156057 -250.757058) (xy 349.193219 -250.722848) (xy 349.235505 -250.695222) (xy 349.281761 -250.674932)
			(xy 349.330726 -250.662532) (xy 349.381064 -250.658361) (xy 349.431402 -250.662532) (xy 349.480367 -250.674932)
			(xy 349.526623 -250.695222) (xy 349.568909 -250.722848) (xy 349.606071 -250.757058) (xy 349.637095 -250.796918)
			(xy 349.661136 -250.841341) (xy 349.677537 -250.889115) (xy 349.68585 -250.938937) (xy 349.686372 -250.964192)
			(xy 349.686032 -250.984875) (xy 349.680444 -251.025862) (xy 349.669357 -251.065715) (xy 349.66148 -251.084842)
			(xy 349.6564 -251.096526) (xy 349.658686 -251.121926) (xy 349.712534 -251.20346) (xy 349.713804 -251.205238)
			(xy 349.721411 -251.21463) (xy 349.742886 -251.225647) (xy 349.754952 -251.22632) (xy 350.887284 -251.22632)
			(xy 350.899351 -251.225644) (xy 350.920826 -251.214632) (xy 350.928432 -251.205238) (xy 350.929194 -251.204476)
			(xy 350.98355 -251.121926) (xy 350.985836 -251.096526) (xy 350.980756 -251.084842) (xy 350.972901 -251.065707)
			(xy 350.961829 -251.025854) (xy 350.956223 -250.984873) (xy 350.955864 -250.964192) (xy 350.956386 -250.938937)
			(xy 350.964699 -250.889115) (xy 350.9811 -250.841341) (xy 351.005141 -250.796918) (xy 351.036165 -250.757058)
			(xy 351.073327 -250.722848) (xy 351.115613 -250.695222) (xy 351.161869 -250.674932) (xy 351.210834 -250.662532)
			(xy 351.261172 -250.658361) (xy 351.31151 -250.662532) (xy 351.360475 -250.674932) (xy 351.406731 -250.695222)
			(xy 351.449017 -250.722848) (xy 351.486179 -250.757058) (xy 351.517203 -250.796918) (xy 351.541244 -250.841341)
			(xy 351.557645 -250.889115) (xy 351.565958 -250.938937) (xy 351.56648 -250.964192) (xy 351.56614 -250.984875)
			(xy 351.560552 -251.025862) (xy 351.549465 -251.065715) (xy 351.541588 -251.084842) (xy 351.536508 -251.096526)
			(xy 351.538794 -251.121926) (xy 351.592642 -251.20346) (xy 351.593912 -251.205238) (xy 351.60152 -251.214629)
			(xy 351.622995 -251.225642) (xy 351.63506 -251.22632) (xy 352.767138 -251.22632) (xy 352.77921 -251.225654)
			(xy 352.800701 -251.214653) (xy 352.808286 -251.205238) (xy 352.809048 -251.204476) (xy 352.863404 -251.121926)
			(xy 352.86569 -251.096526) (xy 352.86061 -251.084842) (xy 352.852754 -251.065708) (xy 352.841681 -251.025854)
			(xy 352.836073 -250.984873) (xy 352.835718 -250.964192) (xy 352.83624 -250.938937) (xy 352.844553 -250.889115)
			(xy 352.860954 -250.841341) (xy 352.884995 -250.796918) (xy 352.916019 -250.757058) (xy 352.953181 -250.722848)
			(xy 352.995467 -250.695222) (xy 353.041723 -250.674932) (xy 353.090688 -250.662532) (xy 353.141026 -250.658361)
			(xy 353.191364 -250.662532) (xy 353.240329 -250.674932) (xy 353.286585 -250.695222) (xy 353.328871 -250.722848)
			(xy 353.366033 -250.757058) (xy 353.397057 -250.796918) (xy 353.421098 -250.841341) (xy 353.437499 -250.889115)
			(xy 353.445812 -250.938937) (xy 353.446334 -250.964192) (xy 353.445994 -250.984875) (xy 353.440407 -251.025863)
			(xy 353.429322 -251.065716) (xy 353.421442 -251.084842) (xy 353.416362 -251.096526) (xy 353.418648 -251.121926)
			(xy 353.472496 -251.20346) (xy 353.473766 -251.205238) (xy 353.481377 -251.214619) (xy 353.502853 -251.22561)
			(xy 353.514914 -251.22632) (xy 354.647246 -251.22632) (xy 354.659317 -251.225652) (xy 354.680806 -251.214649)
			(xy 354.688394 -251.205238) (xy 354.689156 -251.204476) (xy 354.743512 -251.121926) (xy 354.745798 -251.096526)
			(xy 354.740718 -251.084842) (xy 354.732862 -251.065708) (xy 354.721788 -251.025854) (xy 354.71618 -250.984873)
			(xy 354.715826 -250.964192) (xy 354.716348 -250.938937) (xy 354.724661 -250.889115) (xy 354.741062 -250.841341)
			(xy 354.765103 -250.796918) (xy 354.796127 -250.757058) (xy 354.833289 -250.722848) (xy 354.875575 -250.695222)
			(xy 354.921831 -250.674932) (xy 354.970796 -250.662532) (xy 355.021134 -250.658361) (xy 355.071472 -250.662532)
			(xy 355.120437 -250.674932) (xy 355.166693 -250.695222) (xy 355.208979 -250.722848) (xy 355.246141 -250.757058)
			(xy 355.277165 -250.796918) (xy 355.301206 -250.841341) (xy 355.317607 -250.889115) (xy 355.32592 -250.938937)
			(xy 355.326442 -250.964192) (xy 355.326102 -250.984875) (xy 355.320516 -251.025863) (xy 355.309431 -251.065716)
			(xy 355.30155 -251.084842) (xy 355.29647 -251.096526) (xy 355.298756 -251.121926) (xy 355.352604 -251.20346)
			(xy 355.353874 -251.205238) (xy 355.361479 -251.214635) (xy 355.382954 -251.225664) (xy 355.395022 -251.22632)
			(xy 356.527354 -251.22632) (xy 356.539425 -251.225651) (xy 356.56091 -251.214645) (xy 356.568502 -251.205238)
			(xy 356.569264 -251.204476) (xy 356.62362 -251.121926) (xy 356.625906 -251.096526) (xy 356.620826 -251.084842)
			(xy 356.61297 -251.065708) (xy 356.601896 -251.025854) (xy 356.596288 -250.984873) (xy 356.595934 -250.964192)
			(xy 356.596456 -250.938937) (xy 356.604769 -250.889115) (xy 356.62117 -250.841341) (xy 356.645211 -250.796918)
			(xy 356.676235 -250.757058) (xy 356.713397 -250.722848) (xy 356.755683 -250.695222) (xy 356.801939 -250.674932)
			(xy 356.850904 -250.662532) (xy 356.901242 -250.658361) (xy 356.95158 -250.662532) (xy 357.000545 -250.674932)
			(xy 357.046801 -250.695222) (xy 357.089087 -250.722848) (xy 357.126249 -250.757058) (xy 357.157273 -250.796918)
			(xy 357.181314 -250.841341) (xy 357.197715 -250.889115) (xy 357.206028 -250.938937) (xy 357.20655 -250.964192)
			(xy 357.20621 -250.984875) (xy 357.200622 -251.025862) (xy 357.189534 -251.065714) (xy 357.181658 -251.084842)
			(xy 357.176578 -251.096526) (xy 357.178864 -251.121926) (xy 357.232712 -251.20346) (xy 357.233982 -251.205238)
			(xy 357.241588 -251.214634) (xy 357.263062 -251.22566) (xy 357.27513 -251.22632) (xy 357.467154 -251.22632)
			(xy 357.479225 -251.225651) (xy 357.50071 -251.214645) (xy 357.508302 -251.205238) (xy 357.509064 -251.204476)
			(xy 357.56342 -251.121926) (xy 357.565706 -251.096526) (xy 357.560626 -251.084842) (xy 357.55277 -251.065708)
			(xy 357.541696 -251.025854) (xy 357.536088 -250.984873) (xy 357.535734 -250.964192) (xy 357.536256 -250.938937)
			(xy 357.544569 -250.889115) (xy 357.56097 -250.841341) (xy 357.585011 -250.796918) (xy 357.616035 -250.757058)
			(xy 357.653197 -250.722848) (xy 357.695483 -250.695222) (xy 357.741739 -250.674932) (xy 357.790704 -250.662532)
			(xy 357.841042 -250.658361) (xy 357.89138 -250.662532) (xy 357.940345 -250.674932) (xy 357.986601 -250.695222)
			(xy 358.028887 -250.722848) (xy 358.066049 -250.757058) (xy 358.097073 -250.796918) (xy 358.121114 -250.841341)
			(xy 358.137515 -250.889115) (xy 358.145828 -250.938937) (xy 358.14635 -250.964192) (xy 358.14601 -250.984875)
			(xy 358.140422 -251.025862) (xy 358.129334 -251.065714) (xy 358.121458 -251.084842) (xy 358.116378 -251.096526)
			(xy 358.118664 -251.121926) (xy 358.172512 -251.20346) (xy 358.173782 -251.205238) (xy 358.181388 -251.214634)
			(xy 358.202862 -251.22566) (xy 358.21493 -251.22632) (xy 358.966008 -251.22632) (xy 358.97216 -251.226146)
			(xy 358.984101 -251.223181) (xy 358.98963 -251.220478) (xy 359.014522 -251.20727) (xy 359.023158 -251.199904)
			(xy 359.026714 -251.195332) (xy 359.043043 -251.174247) (xy 359.081121 -251.13691) (xy 359.12451 -251.105903)
			(xy 359.172168 -251.081973) (xy 359.222951 -251.065693) (xy 359.27564 -251.057454) (xy 359.328968 -251.057454)
			(xy 359.381657 -251.065693) (xy 359.43244 -251.081973) (xy 359.480098 -251.105903) (xy 359.523487 -251.13691)
			(xy 359.561565 -251.174247) (xy 359.577894 -251.195332) (xy 359.58145 -251.199904) (xy 359.590086 -251.20727)
			(xy 359.614978 -251.220478) (xy 359.620509 -251.223175) (xy 359.63245 -251.226132) (xy 359.6386 -251.22632)
			(xy 359.880408 -251.22632) (xy 359.88656 -251.226146) (xy 359.898501 -251.223181) (xy 359.90403 -251.220478)
			(xy 359.928922 -251.20727) (xy 359.937558 -251.199904) (xy 359.941114 -251.195332) (xy 359.957443 -251.174247)
			(xy 359.995521 -251.13691) (xy 360.03891 -251.105903) (xy 360.086568 -251.081973) (xy 360.137351 -251.065693)
			(xy 360.19004 -251.057454) (xy 360.243368 -251.057454) (xy 360.296057 -251.065693) (xy 360.34684 -251.081973)
			(xy 360.394498 -251.105903) (xy 360.437887 -251.13691) (xy 360.475965 -251.174247) (xy 360.492294 -251.195332)
			(xy 360.49585 -251.199904) (xy 360.504486 -251.20727) (xy 360.529378 -251.220478) (xy 360.534909 -251.223175)
			(xy 360.54685 -251.226132) (xy 360.553 -251.22632) (xy 361.22102 -251.22632) (xy 361.233094 -251.225658)
			(xy 361.254592 -251.214661) (xy 361.262168 -251.205238) (xy 361.26293 -251.204476) (xy 361.317286 -251.121926)
			(xy 361.319572 -251.096526) (xy 361.314492 -251.084842) (xy 361.306636 -251.065708) (xy 361.295563 -251.025854)
			(xy 361.289956 -250.984873) (xy 361.2896 -250.964192) (xy 361.290122 -250.938937) (xy 361.298435 -250.889115)
			(xy 361.314836 -250.841341) (xy 361.338877 -250.796918) (xy 361.369901 -250.757058) (xy 361.407063 -250.722848)
			(xy 361.449349 -250.695222) (xy 361.495605 -250.674932) (xy 361.54457 -250.662532) (xy 361.594908 -250.658361)
			(xy 361.645246 -250.662532) (xy 361.694211 -250.674932) (xy 361.740467 -250.695222) (xy 361.782753 -250.722848)
			(xy 361.819915 -250.757058) (xy 361.850939 -250.796918) (xy 361.87498 -250.841341) (xy 361.891381 -250.889115)
			(xy 361.899694 -250.938937) (xy 361.900216 -250.964192) (xy 361.899876 -250.984875) (xy 361.894289 -251.025862)
			(xy 361.883203 -251.065715) (xy 361.875324 -251.084842) (xy 361.870244 -251.096526) (xy 361.87253 -251.121926)
			(xy 361.926378 -251.20346) (xy 361.927648 -251.205238) (xy 361.935258 -251.214623) (xy 361.956733 -251.225621)
			(xy 361.968796 -251.22632) (xy 362.16082 -251.22632) (xy 362.172894 -251.225658) (xy 362.194392 -251.214661)
			(xy 362.201968 -251.205238) (xy 362.20273 -251.204476) (xy 362.257086 -251.121926) (xy 362.259372 -251.096526)
			(xy 362.254292 -251.084842) (xy 362.246436 -251.065708) (xy 362.235363 -251.025854) (xy 362.229756 -250.984873)
			(xy 362.2294 -250.964192) (xy 362.229922 -250.938937) (xy 362.238235 -250.889115) (xy 362.254636 -250.841341)
			(xy 362.278677 -250.796918) (xy 362.309701 -250.757058) (xy 362.346863 -250.722848) (xy 362.389149 -250.695222)
			(xy 362.435405 -250.674932) (xy 362.48437 -250.662532) (xy 362.534708 -250.658361) (xy 362.585046 -250.662532)
			(xy 362.634011 -250.674932) (xy 362.680267 -250.695222) (xy 362.722553 -250.722848) (xy 362.759715 -250.757058)
			(xy 362.790739 -250.796918) (xy 362.81478 -250.841341) (xy 362.831181 -250.889115) (xy 362.839494 -250.938937)
			(xy 362.840016 -250.964192) (xy 362.839676 -250.984875) (xy 362.834089 -251.025862) (xy 362.823003 -251.065715)
			(xy 362.815124 -251.084842) (xy 362.810044 -251.096526) (xy 362.81233 -251.121926) (xy 362.866178 -251.20346)
			(xy 362.867448 -251.205238) (xy 362.875058 -251.214623) (xy 362.896533 -251.225621) (xy 362.908596 -251.22632)
			(xy 363.100874 -251.22632) (xy 363.112942 -251.225646) (xy 363.13442 -251.214636) (xy 363.142022 -251.205238)
			(xy 363.142784 -251.204476) (xy 363.19714 -251.121926) (xy 363.199426 -251.096526) (xy 363.194346 -251.084842)
			(xy 363.186489 -251.065708) (xy 363.175414 -251.025855) (xy 363.169806 -250.984873) (xy 363.169454 -250.964192)
			(xy 363.169976 -250.938937) (xy 363.178289 -250.889115) (xy 363.19469 -250.841341) (xy 363.218731 -250.796918)
			(xy 363.249755 -250.757058) (xy 363.286917 -250.722848) (xy 363.329203 -250.695222) (xy 363.375459 -250.674932)
			(xy 363.424424 -250.662532) (xy 363.474762 -250.658361) (xy 363.5251 -250.662532) (xy 363.574065 -250.674932)
			(xy 363.620321 -250.695222) (xy 363.662607 -250.722848) (xy 363.699769 -250.757058) (xy 363.730793 -250.796918)
			(xy 363.754834 -250.841341) (xy 363.771235 -250.889115) (xy 363.779548 -250.938937) (xy 363.78007 -250.964192)
			(xy 363.77973 -250.984875) (xy 363.774142 -251.025862) (xy 363.763055 -251.065714) (xy 363.755178 -251.084842)
			(xy 363.750098 -251.096526) (xy 363.752384 -251.121926) (xy 363.806232 -251.20346) (xy 363.807502 -251.205238)
			(xy 363.815109 -251.21463) (xy 363.836584 -251.225648) (xy 363.84865 -251.22632) (xy 364.980982 -251.22632)
			(xy 364.993049 -251.225645) (xy 365.014525 -251.214633) (xy 365.02213 -251.205238) (xy 365.022892 -251.204476)
			(xy 365.077248 -251.121926) (xy 365.079534 -251.096526) (xy 365.074454 -251.084842) (xy 365.066597 -251.065708)
			(xy 365.055522 -251.025855) (xy 365.049913 -250.984873) (xy 365.049562 -250.964192) (xy 365.050084 -250.938937)
			(xy 365.058397 -250.889115) (xy 365.074798 -250.841341) (xy 365.098839 -250.796918) (xy 365.129863 -250.757058)
			(xy 365.167025 -250.722848) (xy 365.209311 -250.695222) (xy 365.255567 -250.674932) (xy 365.304532 -250.662532)
			(xy 365.35487 -250.658361) (xy 365.405208 -250.662532) (xy 365.454173 -250.674932) (xy 365.500429 -250.695222)
			(xy 365.542715 -250.722848) (xy 365.579877 -250.757058) (xy 365.610901 -250.796918) (xy 365.634942 -250.841341)
			(xy 365.651343 -250.889115) (xy 365.659656 -250.938937) (xy 365.660178 -250.964192) (xy 365.659838 -250.984875)
			(xy 365.65425 -251.025862) (xy 365.643163 -251.065715) (xy 365.635286 -251.084842) (xy 365.630206 -251.096526)
			(xy 365.632492 -251.121926) (xy 365.68634 -251.20346) (xy 365.68761 -251.205238) (xy 365.695217 -251.214629)
			(xy 365.716692 -251.225644) (xy 365.728758 -251.22632) (xy 365.921036 -251.22632) (xy 365.933109 -251.225654)
			(xy 365.9546 -251.214654) (xy 365.962184 -251.205238) (xy 365.962946 -251.204476) (xy 366.017302 -251.121926)
			(xy 366.019588 -251.096526) (xy 366.014508 -251.084842) (xy 366.006652 -251.065708) (xy 365.995579 -251.025854)
			(xy 365.989971 -250.984873) (xy 365.989616 -250.964192) (xy 365.990138 -250.938937) (xy 365.998451 -250.889115)
			(xy 366.014852 -250.841341) (xy 366.038893 -250.796918) (xy 366.069917 -250.757058) (xy 366.107079 -250.722848)
			(xy 366.149365 -250.695222) (xy 366.195621 -250.674932) (xy 366.244586 -250.662532) (xy 366.294924 -250.658361)
			(xy 366.345262 -250.662532) (xy 366.394227 -250.674932) (xy 366.440483 -250.695222) (xy 366.482769 -250.722848)
			(xy 366.519931 -250.757058) (xy 366.550955 -250.796918) (xy 366.574996 -250.841341) (xy 366.591397 -250.889115)
			(xy 366.59971 -250.938937) (xy 366.600232 -250.964192) (xy 366.599892 -250.984875) (xy 366.594305 -251.025863)
			(xy 366.58322 -251.065716) (xy 366.57534 -251.084842) (xy 366.57026 -251.096526) (xy 366.572546 -251.121926)
			(xy 366.626394 -251.20346) (xy 366.627664 -251.205238) (xy 366.635275 -251.21462) (xy 366.656751 -251.225612)
			(xy 366.668812 -251.22632) (xy 366.860836 -251.22632) (xy 366.872909 -251.225654) (xy 366.8944 -251.214654)
			(xy 366.901984 -251.205238) (xy 366.902746 -251.204476) (xy 366.957102 -251.121926) (xy 366.959388 -251.096526)
			(xy 366.954308 -251.084842) (xy 366.946452 -251.065708) (xy 366.935379 -251.025854) (xy 366.929771 -250.984873)
			(xy 366.929416 -250.964192) (xy 366.929938 -250.938937) (xy 366.938251 -250.889115) (xy 366.954652 -250.841341)
			(xy 366.978693 -250.796918) (xy 367.009717 -250.757058) (xy 367.046879 -250.722848) (xy 367.089165 -250.695222)
			(xy 367.135421 -250.674932) (xy 367.184386 -250.662532) (xy 367.234724 -250.658361) (xy 367.285062 -250.662532)
			(xy 367.334027 -250.674932) (xy 367.380283 -250.695222) (xy 367.422569 -250.722848) (xy 367.459731 -250.757058)
			(xy 367.490755 -250.796918) (xy 367.514796 -250.841341) (xy 367.531197 -250.889115) (xy 367.53951 -250.938937)
			(xy 367.540032 -250.964192) (xy 367.539692 -250.984875) (xy 367.534105 -251.025863) (xy 367.52302 -251.065716)
			(xy 367.51514 -251.084842) (xy 367.51006 -251.096526) (xy 367.512346 -251.121926) (xy 367.566194 -251.20346)
			(xy 367.567464 -251.205238) (xy 367.575075 -251.21462) (xy 367.596551 -251.225612) (xy 367.608612 -251.22632)
			(xy 368.740944 -251.22632) (xy 368.753016 -251.225653) (xy 368.774505 -251.21465) (xy 368.782092 -251.205238)
			(xy 368.782854 -251.204476) (xy 368.83721 -251.121926) (xy 368.839496 -251.096526) (xy 368.834416 -251.084842)
			(xy 368.82656 -251.065708) (xy 368.815486 -251.025854) (xy 368.809878 -250.984873) (xy 368.809524 -250.964192)
			(xy 368.810046 -250.938937) (xy 368.818359 -250.889115) (xy 368.83476 -250.841341) (xy 368.858801 -250.796918)
			(xy 368.889825 -250.757058) (xy 368.926987 -250.722848) (xy 368.969273 -250.695222) (xy 369.015529 -250.674932)
			(xy 369.064494 -250.662532) (xy 369.114832 -250.658361) (xy 369.16517 -250.662532) (xy 369.214135 -250.674932)
			(xy 369.260391 -250.695222) (xy 369.302677 -250.722848) (xy 369.339839 -250.757058) (xy 369.370863 -250.796918)
			(xy 369.394904 -250.841341) (xy 369.411305 -250.889115) (xy 369.419618 -250.938937) (xy 369.42014 -250.964192)
			(xy 369.4198 -250.984875) (xy 369.414214 -251.025863) (xy 369.403128 -251.065716) (xy 369.395248 -251.084842)
			(xy 369.390168 -251.096526) (xy 369.392454 -251.121926) (xy 369.446302 -251.20346) (xy 369.447572 -251.205238)
			(xy 369.455184 -251.214618) (xy 369.476659 -251.225607) (xy 369.48872 -251.22632) (xy 369.680998 -251.22632)
			(xy 369.693063 -251.225641) (xy 369.714533 -251.214625) (xy 369.722146 -251.205238) (xy 369.722908 -251.204476)
			(xy 369.777264 -251.121926) (xy 369.77955 -251.096526) (xy 369.77447 -251.084842) (xy 369.766615 -251.065707)
			(xy 369.755542 -251.025854) (xy 369.749936 -250.984873) (xy 369.749578 -250.964192) (xy 369.7501 -250.938937)
			(xy 369.758413 -250.889115) (xy 369.774814 -250.841341) (xy 369.798855 -250.796918) (xy 369.829879 -250.757058)
			(xy 369.867041 -250.722848) (xy 369.909327 -250.695222) (xy 369.955583 -250.674932) (xy 370.004548 -250.662532)
			(xy 370.054886 -250.658361) (xy 370.105224 -250.662532) (xy 370.154189 -250.674932) (xy 370.200445 -250.695222)
			(xy 370.242731 -250.722848) (xy 370.279893 -250.757058) (xy 370.310917 -250.796918) (xy 370.334958 -250.841341)
			(xy 370.351359 -250.889115) (xy 370.359672 -250.938937) (xy 370.360194 -250.964192) (xy 370.359854 -250.984875)
			(xy 370.354267 -251.025862) (xy 370.34318 -251.065715) (xy 370.335302 -251.084842) (xy 370.330222 -251.096526)
			(xy 370.332508 -251.121926) (xy 370.386356 -251.20346) (xy 370.387626 -251.205238) (xy 370.395235 -251.214626)
			(xy 370.41671 -251.225634) (xy 370.428774 -251.22632) (xy 370.620798 -251.22632) (xy 370.632863 -251.225641)
			(xy 370.654333 -251.214625) (xy 370.661946 -251.205238) (xy 370.662708 -251.204476) (xy 370.717064 -251.121926)
			(xy 370.71935 -251.096526) (xy 370.71427 -251.084842) (xy 370.706415 -251.065707) (xy 370.695342 -251.025854)
			(xy 370.689736 -250.984873) (xy 370.689378 -250.964192) (xy 370.6899 -250.938937) (xy 370.698213 -250.889115)
			(xy 370.714614 -250.841341) (xy 370.738655 -250.796918) (xy 370.769679 -250.757058) (xy 370.806841 -250.722848)
			(xy 370.849127 -250.695222) (xy 370.895383 -250.674932) (xy 370.944348 -250.662532) (xy 370.994686 -250.658361)
			(xy 371.045024 -250.662532) (xy 371.093989 -250.674932) (xy 371.140245 -250.695222) (xy 371.182531 -250.722848)
			(xy 371.219693 -250.757058) (xy 371.250717 -250.796918) (xy 371.274758 -250.841341) (xy 371.291159 -250.889115)
			(xy 371.299472 -250.938937) (xy 371.299994 -250.964192) (xy 371.299654 -250.984875) (xy 371.294067 -251.025862)
			(xy 371.28298 -251.065715) (xy 371.275102 -251.084842) (xy 371.270022 -251.096526) (xy 371.272308 -251.121926)
			(xy 371.326156 -251.20346) (xy 371.327426 -251.205238) (xy 371.335035 -251.214626) (xy 371.35651 -251.225634)
			(xy 371.368574 -251.22632) (xy 372.500906 -251.22632) (xy 372.512982 -251.225661) (xy 372.534484 -251.214667)
			(xy 372.542054 -251.205238) (xy 372.542816 -251.204476) (xy 372.597172 -251.121926) (xy 372.599458 -251.096526)
			(xy 372.594378 -251.084842) (xy 372.586522 -251.065708) (xy 372.57545 -251.025854) (xy 372.569843 -250.984873)
			(xy 372.569486 -250.964192) (xy 372.570008 -250.938937) (xy 372.578321 -250.889115) (xy 372.594722 -250.841341)
			(xy 372.618763 -250.796918) (xy 372.649787 -250.757058) (xy 372.686949 -250.722848) (xy 372.729235 -250.695222)
			(xy 372.775491 -250.674932) (xy 372.824456 -250.662532) (xy 372.874794 -250.658361) (xy 372.925132 -250.662532)
			(xy 372.974097 -250.674932) (xy 373.020353 -250.695222) (xy 373.062639 -250.722848) (xy 373.099801 -250.757058)
			(xy 373.130825 -250.796918) (xy 373.154866 -250.841341) (xy 373.171267 -250.889115) (xy 373.17958 -250.938937)
			(xy 373.180102 -250.964192) (xy 373.179762 -250.984875) (xy 373.174175 -251.025862) (xy 373.163088 -251.065715)
			(xy 373.15521 -251.084842) (xy 373.15013 -251.096526) (xy 373.152416 -251.121926) (xy 373.206264 -251.20346)
			(xy 373.207534 -251.205238) (xy 373.215143 -251.214625) (xy 373.236618 -251.225629) (xy 373.248682 -251.22632)
			(xy 373.435118 -251.22632) (xy 373.444996 -251.225861) (xy 373.463296 -251.21842) (xy 373.470678 -251.211842)
			(xy 373.470932 -251.211588) (xy 373.540782 -251.141738) (xy 373.546116 -251.110242) (xy 373.539258 -251.09551)
			(xy 373.529882 -251.074901) (xy 373.516638 -251.031606) (xy 373.509935 -250.98683) (xy 373.50954 -250.964192)
			(xy 373.509987 -250.940201) (xy 373.517495 -250.892809) (xy 373.532325 -250.847175) (xy 373.554111 -250.804424)
			(xy 373.582318 -250.765607) (xy 373.61625 -250.731681) (xy 373.655072 -250.703482) (xy 373.697827 -250.681703)
			(xy 373.743463 -250.666882) (xy 373.790857 -250.659382) (xy 373.814848 -250.658884) (xy 373.837486 -250.659293)
			(xy 373.882265 -250.66598) (xy 373.925562 -250.679215) (xy 373.946166 -250.688602) (xy 373.960898 -250.69546)
			(xy 373.992394 -250.690126) (xy 374.123204 -250.559316) (xy 374.130726 -250.551054) (xy 374.138381 -250.530093)
			(xy 374.137936 -250.51893) (xy 374.130062 -250.43003) (xy 374.118886 -250.41098) (xy 374.109488 -250.404376)
			(xy 374.089752 -250.389953) (xy 374.054708 -250.355878) (xy 374.025538 -250.316656) (xy 374.002989 -250.273289)
			(xy 373.987634 -250.226884) (xy 373.979867 -250.178626) (xy 373.97944 -250.154186) (xy 373.979887 -250.130195)
			(xy 373.987396 -250.082804) (xy 374.002226 -250.037171) (xy 374.024013 -249.994421) (xy 374.05222 -249.955605)
			(xy 374.086152 -249.92168) (xy 374.124973 -249.893481) (xy 374.167729 -249.871703) (xy 374.213364 -249.856882)
			(xy 374.260757 -249.849382) (xy 374.284748 -249.848878) (xy 374.298735 -249.849022) (xy 374.326592 -249.851566)
			(xy 374.340374 -249.853958) (xy 374.35282 -249.856244) (xy 374.363742 -249.85345) (xy 374.369146 -249.851904)
			(xy 374.379145 -249.846776) (xy 374.383554 -249.84329) (xy 374.443498 -249.793506) (xy 374.449848 -249.78741)
			(xy 374.454933 -249.781059) (xy 374.461147 -249.766033) (xy 374.46204 -249.757946) (xy 374.46204 -249.430794)
			(xy 374.460262 -249.42419) (xy 374.453744 -249.397978) (xy 374.44898 -249.344181) (xy 374.453751 -249.290384)
			(xy 374.460262 -249.26417) (xy 374.46204 -249.257566) (xy 374.46204 -247.810782) (xy 374.460262 -247.804178)
			(xy 374.453745 -247.777966) (xy 374.448983 -247.724169) (xy 374.453756 -247.670373) (xy 374.460262 -247.644158)
			(xy 374.46204 -247.637554) (xy 374.46204 -247.313958) (xy 374.46204 -247.310402) (xy 374.461131 -247.302321)
			(xy 374.454908 -247.287305) (xy 374.449848 -247.280938) (xy 374.443498 -247.274842) (xy 374.383554 -247.225058)
			(xy 374.379136 -247.221586) (xy 374.369138 -247.216466) (xy 374.363742 -247.214898) (xy 374.35282 -247.212104)
			(xy 374.340374 -247.21439) (xy 374.326591 -247.216769) (xy 374.298734 -247.219316) (xy 374.284748 -247.21947)
			(xy 374.282716 -247.21947) (xy 374.258828 -247.218852) (xy 374.211678 -247.2111) (xy 374.166311 -247.196097)
			(xy 374.123836 -247.174209) (xy 374.08529 -247.145971) (xy 374.051614 -247.112071) (xy 374.023631 -247.073339)
			(xy 374.002025 -247.030719) (xy 373.987322 -246.985254) (xy 373.979883 -246.938054) (xy 373.97944 -246.914162)
			(xy 373.979889 -246.890172) (xy 373.987401 -246.842784) (xy 374.002233 -246.797155) (xy 374.024021 -246.754407)
			(xy 374.052229 -246.715595) (xy 374.08616 -246.681673) (xy 374.124981 -246.653476) (xy 374.167734 -246.6317)
			(xy 374.213368 -246.616881) (xy 374.260758 -246.609382) (xy 374.284748 -246.608854) (xy 374.298735 -246.608998)
			(xy 374.326593 -246.611541) (xy 374.340374 -246.613934) (xy 374.35282 -246.61622) (xy 374.363742 -246.613426)
			(xy 374.369146 -246.611879) (xy 374.379143 -246.606749) (xy 374.383554 -246.603266) (xy 374.443498 -246.553482)
			(xy 374.449848 -246.547386) (xy 374.454943 -246.541038) (xy 374.461179 -246.526014) (xy 374.46204 -246.517922)
			(xy 374.46204 -246.19077) (xy 374.460262 -246.184166) (xy 374.453746 -246.157954) (xy 374.448986 -246.104157)
			(xy 374.453761 -246.050362) (xy 374.460262 -246.024146) (xy 374.46204 -246.017542) (xy 374.46204 -244.570758)
			(xy 374.460262 -244.564154) (xy 374.453738 -244.537942) (xy 374.448963 -244.484143) (xy 374.453723 -244.430342)
			(xy 374.460262 -244.404134) (xy 374.46204 -244.39753) (xy 374.46204 -244.073934) (xy 374.46204 -244.070378)
			(xy 374.461142 -244.062292) (xy 374.454936 -244.047261) (xy 374.449848 -244.040914) (xy 374.443498 -244.034818)
			(xy 374.383554 -243.985034) (xy 374.379136 -243.981564) (xy 374.369136 -243.976446) (xy 374.363742 -243.974874)
			(xy 374.35282 -243.97208) (xy 374.340374 -243.974366) (xy 374.326591 -243.976745) (xy 374.298734 -243.979293)
			(xy 374.284748 -243.979446) (xy 374.282716 -243.979446) (xy 374.258826 -243.978828) (xy 374.211671 -243.971077)
			(xy 374.166299 -243.956075) (xy 374.123819 -243.934188) (xy 374.085266 -243.905951) (xy 374.051583 -243.872052)
			(xy 374.023592 -243.833321) (xy 374.001976 -243.790701) (xy 373.987264 -243.745235) (xy 373.979813 -243.698032)
			(xy 373.97944 -243.674138) (xy 373.979883 -243.650144) (xy 373.987386 -243.602747) (xy 374.002212 -243.557107)
			(xy 374.023996 -243.514349) (xy 374.052201 -243.475527) (xy 374.086134 -243.441595) (xy 374.124958 -243.41339)
			(xy 374.167717 -243.391608) (xy 374.213357 -243.376783) (xy 374.260754 -243.369283) (xy 374.284748 -243.36883)
			(xy 374.298735 -243.368974) (xy 374.326593 -243.371517) (xy 374.340374 -243.37391) (xy 374.35282 -243.376196)
			(xy 374.363742 -243.373402) (xy 374.369145 -243.371855) (xy 374.379141 -243.366723) (xy 374.383554 -243.363242)
			(xy 374.443498 -243.313458) (xy 374.449848 -243.307362) (xy 374.45494 -243.301013) (xy 374.461169 -243.285988)
			(xy 374.46204 -243.277898) (xy 374.46204 -242.950746) (xy 374.460262 -242.944142) (xy 374.453739 -242.91793)
			(xy 374.448966 -242.864131) (xy 374.453728 -242.810331) (xy 374.460262 -242.784122) (xy 374.46204 -242.777518)
			(xy 374.46204 -241.330734) (xy 374.460262 -241.32413) (xy 374.45374 -241.297918) (xy 374.448969 -241.244119)
			(xy 374.453734 -241.19032) (xy 374.460262 -241.16411) (xy 374.46204 -241.157506) (xy 374.46204 -240.83391)
			(xy 374.46204 -240.830354) (xy 374.461139 -240.822269) (xy 374.454927 -240.807244) (xy 374.449848 -240.80089)
			(xy 374.443498 -240.794794) (xy 374.383554 -240.74501) (xy 374.379138 -240.741535) (xy 374.36914 -240.73641)
			(xy 374.363742 -240.73485) (xy 374.35282 -240.732056) (xy 374.340374 -240.734342) (xy 374.326591 -240.73672)
			(xy 374.298734 -240.739268) (xy 374.284748 -240.739422) (xy 374.282716 -240.739422) (xy 374.258826 -240.738804)
			(xy 374.211673 -240.731053) (xy 374.166303 -240.71605) (xy 374.123824 -240.694163) (xy 374.085274 -240.665925)
			(xy 374.051593 -240.632027) (xy 374.023604 -240.593295) (xy 374.001992 -240.550675) (xy 373.987282 -240.505209)
			(xy 373.979835 -240.458007) (xy 373.97944 -240.434114) (xy 373.979885 -240.410122) (xy 373.98739 -240.362727)
			(xy 374.002218 -240.317091) (xy 374.024004 -240.274336) (xy 374.05221 -240.235516) (xy 374.086142 -240.201588)
			(xy 374.124965 -240.173386) (xy 374.167722 -240.151605) (xy 374.21336 -240.136783) (xy 374.260755 -240.129283)
			(xy 374.284748 -240.128806) (xy 374.298735 -240.12895) (xy 374.326593 -240.131493) (xy 374.340374 -240.133886)
			(xy 374.35282 -240.136172) (xy 374.363742 -240.133378) (xy 374.369145 -240.13183) (xy 374.379139 -240.126696)
			(xy 374.383554 -240.123218) (xy 374.443498 -240.073434) (xy 374.449848 -240.067338) (xy 374.454937 -240.060988)
			(xy 374.461159 -240.045963) (xy 374.46204 -240.037874) (xy 374.46204 -239.710722) (xy 374.460262 -239.704118)
			(xy 374.453741 -239.677906) (xy 374.448973 -239.624108) (xy 374.453739 -239.570309) (xy 374.460262 -239.544098)
			(xy 374.46204 -239.537494) (xy 374.46204 -238.09071) (xy 374.460262 -238.084106) (xy 374.453743 -238.057894)
			(xy 374.448976 -238.004096) (xy 374.453744 -237.950298) (xy 374.460262 -237.924086) (xy 374.46204 -237.917482)
			(xy 374.46204 -237.593886) (xy 374.46204 -237.59033) (xy 374.461135 -237.582247) (xy 374.454918 -237.567226)
			(xy 374.449848 -237.560866) (xy 374.443498 -237.55477) (xy 374.383554 -237.504986) (xy 374.379137 -237.501513)
			(xy 374.369139 -237.49639) (xy 374.363742 -237.494826) (xy 374.35282 -237.492032) (xy 374.340374 -237.494318)
			(xy 374.326591 -237.496696) (xy 374.298734 -237.499244) (xy 374.284748 -237.499398) (xy 374.282716 -237.499398)
			(xy 374.258827 -237.49878) (xy 374.211675 -237.491029) (xy 374.166307 -237.476026) (xy 374.123829 -237.454138)
			(xy 374.085281 -237.4259) (xy 374.051602 -237.392001) (xy 374.023617 -237.353269) (xy 374.002007 -237.31065)
			(xy 373.987301 -237.265184) (xy 373.979858 -237.217982) (xy 373.97944 -237.19409) (xy 373.979887 -237.170099)
			(xy 373.987395 -237.122707) (xy 374.002225 -237.077074) (xy 374.024012 -237.034323) (xy 374.052219 -236.995506)
			(xy 374.086151 -236.961581) (xy 374.124972 -236.933382) (xy 374.167728 -236.911603) (xy 374.213364 -236.896782)
			(xy 374.260757 -236.889282) (xy 374.284748 -236.888782) (xy 374.298735 -236.888926) (xy 374.326592 -236.89147)
			(xy 374.340374 -236.893862) (xy 374.35282 -236.896148) (xy 374.363742 -236.893354) (xy 374.369146 -236.891808)
			(xy 374.379145 -236.88668) (xy 374.383554 -236.883194) (xy 374.443498 -236.83341) (xy 374.449848 -236.827314)
			(xy 374.454934 -236.820963) (xy 374.461149 -236.805937) (xy 374.46204 -236.79785) (xy 374.46204 -236.470698)
			(xy 374.460262 -236.464094) (xy 374.453744 -236.437882) (xy 374.448979 -236.384085) (xy 374.453749 -236.330287)
			(xy 374.460262 -236.304074) (xy 374.46204 -236.29747) (xy 374.46204 -235.973874) (xy 374.46204 -235.970318)
			(xy 374.461134 -235.962236) (xy 374.454914 -235.947217) (xy 374.449848 -235.940854) (xy 374.443498 -235.934758)
			(xy 374.383554 -235.884974) (xy 374.379137 -235.881502) (xy 374.369138 -235.87638) (xy 374.363742 -235.874814)
			(xy 374.35282 -235.87202) (xy 374.340374 -235.874306) (xy 374.326591 -235.876685) (xy 374.298734 -235.879232)
			(xy 374.284748 -235.879386) (xy 374.282716 -235.879386) (xy 374.258827 -235.878768) (xy 374.211676 -235.871017)
			(xy 374.166308 -235.856014) (xy 374.123832 -235.834126) (xy 374.085285 -235.805887) (xy 374.051607 -235.771988)
			(xy 374.023623 -235.733256) (xy 374.002014 -235.690637) (xy 373.98731 -235.645171) (xy 373.979869 -235.59797)
			(xy 373.97944 -235.574078) (xy 373.979888 -235.550087) (xy 373.987398 -235.502697) (xy 374.002229 -235.457066)
			(xy 374.024016 -235.414316) (xy 374.052223 -235.375501) (xy 374.086155 -235.341577) (xy 374.124976 -235.313379)
			(xy 374.16773 -235.291602) (xy 374.213366 -235.276781) (xy 374.260757 -235.269282) (xy 374.284748 -235.26877)
			(xy 374.298735 -235.268914) (xy 374.326592 -235.271458) (xy 374.340374 -235.27385) (xy 374.35282 -235.276136)
			(xy 374.363742 -235.273342) (xy 374.369146 -235.271796) (xy 374.379144 -235.266667) (xy 374.383554 -235.263182)
			(xy 374.443498 -235.213398) (xy 374.449848 -235.207302) (xy 374.454932 -235.200951) (xy 374.461143 -235.185924)
			(xy 374.46204 -235.177838) (xy 374.46204 -234.850686) (xy 374.460262 -234.844082) (xy 374.453745 -234.81787)
			(xy 374.448982 -234.764073) (xy 374.453754 -234.710277) (xy 374.460262 -234.684062) (xy 374.46204 -234.677458)
			(xy 374.46204 -233.230674) (xy 374.460262 -233.22407) (xy 374.453746 -233.197858) (xy 374.448985 -233.144061)
			(xy 374.453759 -233.090266) (xy 374.460262 -233.06405) (xy 374.46204 -233.057446) (xy 374.46204 -232.73385)
			(xy 374.46204 -232.730294) (xy 374.46113 -232.722213) (xy 374.454905 -232.707199) (xy 374.449848 -232.70083)
			(xy 374.443498 -232.694734) (xy 374.383554 -232.64495) (xy 374.379136 -232.641479) (xy 374.369137 -232.63636)
			(xy 374.363742 -232.63479) (xy 374.35282 -232.631996) (xy 374.340374 -232.634282) (xy 374.326591 -232.636661)
			(xy 374.298734 -232.639208) (xy 374.284748 -232.639362) (xy 374.282716 -232.639362) (xy 374.258828 -232.638744)
			(xy 374.211678 -232.630992) (xy 374.166312 -232.615989) (xy 374.123837 -232.594101) (xy 374.085292 -232.565862)
			(xy 374.051617 -232.531962) (xy 374.023635 -232.49323) (xy 374.00203 -232.450611) (xy 373.987329 -232.405146)
			(xy 373.979891 -232.357945) (xy 373.97944 -232.334054) (xy 373.97989 -232.310065) (xy 373.987402 -232.262677)
			(xy 374.002236 -232.217049) (xy 374.024024 -232.174303) (xy 374.052231 -232.135491) (xy 374.086163 -232.10157)
			(xy 374.124983 -232.073375) (xy 374.167736 -232.0516) (xy 374.213369 -232.03678) (xy 374.260758 -232.029282)
			(xy 374.284748 -232.028746) (xy 374.298735 -232.02889) (xy 374.326593 -232.031433) (xy 374.340374 -232.033826)
			(xy 374.35282 -232.036112) (xy 374.363742 -232.033318) (xy 374.369145 -232.031771) (xy 374.379142 -232.026641)
			(xy 374.383554 -232.023158) (xy 374.443498 -231.973374) (xy 374.449848 -231.967278) (xy 374.454942 -231.96093)
			(xy 374.461175 -231.945906) (xy 374.46204 -231.937814) (xy 374.46204 -231.610662) (xy 374.460262 -231.604058)
			(xy 374.453738 -231.577846) (xy 374.448962 -231.524046) (xy 374.453722 -231.470245) (xy 374.460262 -231.444038)
			(xy 374.46204 -231.437434) (xy 374.46204 -229.99065) (xy 374.460262 -229.984046) (xy 374.453739 -229.957834)
			(xy 374.448965 -229.904035) (xy 374.453727 -229.850235) (xy 374.460262 -229.824026) (xy 374.46204 -229.817422)
			(xy 374.46204 -229.49408) (xy 374.46204 -229.490524) (xy 374.461134 -229.482441) (xy 374.454916 -229.467421)
			(xy 374.449848 -229.46106) (xy 374.443498 -229.454964) (xy 374.383554 -229.40518) (xy 374.379137 -229.401707)
			(xy 374.369139 -229.396585) (xy 374.363742 -229.39502) (xy 374.35282 -229.392226) (xy 374.340374 -229.394512)
			(xy 374.326591 -229.39689) (xy 374.298734 -229.399438) (xy 374.284748 -229.399592) (xy 374.282716 -229.399592)
			(xy 374.258827 -229.398974) (xy 374.211676 -229.391223) (xy 374.166308 -229.37622) (xy 374.123831 -229.354332)
			(xy 374.085283 -229.326094) (xy 374.051605 -229.292195) (xy 374.02362 -229.253462) (xy 374.002011 -229.210843)
			(xy 373.987305 -229.165378) (xy 373.979863 -229.118176) (xy 373.97944 -229.094284) (xy 373.979887 -229.070293)
			(xy 373.987396 -229.022902) (xy 374.002227 -228.97727) (xy 374.024014 -228.934519) (xy 374.052221 -228.895704)
			(xy 374.086153 -228.861779) (xy 374.124974 -228.83358) (xy 374.167729 -228.811803) (xy 374.213365 -228.796981)
			(xy 374.260757 -228.789482) (xy 374.284748 -228.788976) (xy 374.298735 -228.78912) (xy 374.326592 -228.791664)
			(xy 374.340374 -228.794056) (xy 374.35282 -228.796342) (xy 374.363742 -228.793548) (xy 374.369146 -228.792002)
			(xy 374.379145 -228.786874) (xy 374.383554 -228.783388) (xy 374.443498 -228.733604) (xy 374.449848 -228.727508)
			(xy 374.454933 -228.721157) (xy 374.461146 -228.706131) (xy 374.46204 -228.698044) (xy 374.46204 -228.595682)
			(xy 374.462468 -228.585614) (xy 374.470191 -228.567018) (xy 374.477026 -228.559614) (xy 374.504712 -228.531928)
			(xy 374.510823 -228.525254) (xy 374.518315 -228.508794) (xy 374.519631 -228.490757) (xy 374.514608 -228.473384)
			(xy 374.509538 -228.465888) (xy 374.495434 -228.446058) (xy 374.473039 -228.402858) (xy 374.457787 -228.356651)
			(xy 374.450065 -228.308608) (xy 374.449594 -228.284278) (xy 374.450066 -228.260288) (xy 374.457575 -228.212899)
			(xy 374.472404 -228.167268) (xy 374.494189 -228.124519) (xy 374.522393 -228.085703) (xy 374.556321 -228.051777)
			(xy 374.595139 -228.023577) (xy 374.63789 -228.001795) (xy 374.683522 -227.98697) (xy 374.730912 -227.979464)
			(xy 374.754902 -227.97897) (xy 374.779232 -227.979444) (xy 374.827274 -227.987166) (xy 374.873482 -228.002416)
			(xy 374.916685 -228.024806) (xy 374.936512 -228.038914) (xy 374.944 -228.043998) (xy 374.961373 -228.049027)
			(xy 374.979412 -228.047702) (xy 374.995864 -228.040188) (xy 375.002552 -228.034088) (xy 375.122694 -227.913946)
			(xy 375.128536 -227.907088) (xy 375.133822 -227.898621) (xy 375.138128 -227.87915) (xy 375.136918 -227.869242)
			(xy 375.120408 -227.775262) (xy 375.105676 -227.755704) (xy 375.094246 -227.75037) (xy 375.072186 -227.739391)
			(xy 375.031627 -227.71141) (xy 374.996081 -227.677286) (xy 374.96647 -227.637902) (xy 374.943561 -227.594277)
			(xy 374.927946 -227.547543) (xy 374.92003 -227.498909) (xy 374.919494 -227.474272) (xy 374.919967 -227.450282)
			(xy 374.927476 -227.402894) (xy 374.942306 -227.357264) (xy 374.964091 -227.314515) (xy 374.992295 -227.275701)
			(xy 375.026224 -227.241776) (xy 375.065041 -227.213576) (xy 375.107792 -227.191795) (xy 375.153423 -227.176969)
			(xy 375.200812 -227.169464) (xy 375.224802 -227.168964) (xy 375.249442 -227.169434) (xy 375.298084 -227.177347)
			(xy 375.344824 -227.192966) (xy 375.388451 -227.215886) (xy 375.427832 -227.245513) (xy 375.461945 -227.281078)
			(xy 375.489906 -227.321658) (xy 375.5009 -227.343716) (xy 375.506234 -227.355146) (xy 375.525792 -227.369878)
			(xy 375.619772 -227.386388) (xy 375.629686 -227.387739) (xy 375.649206 -227.383422) (xy 375.657618 -227.378006)
			(xy 375.661174 -227.375466) (xy 376.323098 -226.713542) (xy 376.330718 -226.69373) (xy 376.329956 -226.682554)
			(xy 376.329448 -226.664266) (xy 376.329921 -226.640275) (xy 376.337431 -226.592885) (xy 376.352261 -226.547253)
			(xy 376.374046 -226.504502) (xy 376.402249 -226.465684) (xy 376.436176 -226.431755) (xy 376.474993 -226.403551)
			(xy 376.517744 -226.381765) (xy 376.563375 -226.366933) (xy 376.610765 -226.359422) (xy 376.634756 -226.358958)
			(xy 376.653044 -226.359466) (xy 376.66422 -226.360228) (xy 376.684032 -226.352608) (xy 376.884692 -226.151948)
			(xy 376.89138 -226.144535) (xy 376.898986 -226.126097) (xy 376.898995 -226.106151) (xy 376.891407 -226.087706)
			(xy 376.884692 -226.08032) (xy 376.884438 -226.080066) (xy 376.884184 -226.079812) (xy 376.866543 -226.061885)
			(xy 376.836609 -226.02147) (xy 376.813467 -225.976819) (xy 376.797702 -225.929061) (xy 376.789713 -225.879406)
			(xy 376.789188 -225.85426) (xy 376.789653 -225.829457) (xy 376.797422 -225.780462) (xy 376.812763 -225.733286)
			(xy 376.835296 -225.689092) (xy 376.864469 -225.648969) (xy 376.89956 -225.613906) (xy 376.939706 -225.584766)
			(xy 376.983917 -225.562267) (xy 377.031105 -225.546964) (xy 377.080106 -225.539233) (xy 377.10491 -225.538792)
			(xy 377.128179 -225.539181) (xy 377.174219 -225.545971) (xy 377.218758 -225.55946) (xy 377.260828 -225.579356)
			(xy 377.299513 -225.605225) (xy 377.317 -225.62058) (xy 377.32419 -225.626456) (xy 377.341508 -225.633112)
			(xy 377.350782 -225.633534) (xy 377.381516 -225.633788) (xy 377.391543 -225.633338) (xy 377.410101 -225.625747)
			(xy 377.417584 -225.619056) (xy 377.527312 -225.509328) (xy 377.52782 -225.50882) (xy 377.533621 -225.502408)
			(xy 377.540903 -225.486738) (xy 377.542532 -225.469535) (xy 377.540774 -225.461068) (xy 377.518168 -225.37039)
			(xy 377.499626 -225.351086) (xy 377.486418 -225.347276) (xy 377.462173 -225.339671) (xy 377.416306 -225.31781)
			(xy 377.37453 -225.288888) (xy 377.337924 -225.253651) (xy 377.307431 -225.213008) (xy 377.283839 -225.168007)
			(xy 377.267756 -225.11981) (xy 377.259597 -225.069659) (xy 377.259088 -225.044254) (xy 377.259578 -225.019447)
			(xy 377.267346 -224.970445) (xy 377.282683 -224.923261) (xy 377.305213 -224.879057) (xy 377.334379 -224.838922)
			(xy 377.369464 -224.803843) (xy 377.409605 -224.774683) (xy 377.453813 -224.752162) (xy 377.501 -224.736833)
			(xy 377.550003 -224.729074) (xy 377.57481 -224.728532) (xy 377.60022 -224.729034) (xy 377.650386 -224.737164)
			(xy 377.6986 -224.753229) (xy 377.743617 -224.776813) (xy 377.784272 -224.807307) (xy 377.819514 -224.843922)
			(xy 377.848433 -224.885711) (xy 377.870281 -224.931595) (xy 377.877832 -224.955862) (xy 377.881642 -224.96907)
			(xy 377.900946 -224.987612) (xy 377.991624 -225.010218) (xy 378.000029 -225.011946) (xy 378.017102 -225.010336)
			(xy 378.032699 -225.003208) (xy 378.039122 -224.997518) (xy 378.039376 -224.997264) (xy 378.685806 -224.350834)
			(xy 378.692918 -224.324926) (xy 378.689362 -224.311718) (xy 378.684746 -224.292877) (xy 378.679774 -224.254405)
			(xy 378.679456 -224.23501) (xy 378.679456 -224.234248) (xy 378.679875 -224.211287) (xy 378.686764 -224.165884)
			(xy 378.700379 -224.122026) (xy 378.720412 -224.080703) (xy 378.73305 -224.061528) (xy 378.737157 -224.055075)
			(xy 378.741683 -224.040471) (xy 378.74194 -224.032826) (xy 378.74194 -223.811338) (xy 378.741686 -223.806258)
			(xy 378.740517 -223.797677) (xy 378.733247 -223.78197) (xy 378.727462 -223.775524) (xy 378.720858 -223.77019)
			(xy 378.644404 -223.714564) (xy 378.620782 -223.710754) (xy 378.609098 -223.714564) (xy 378.586165 -223.721539)
			(xy 378.538829 -223.729074) (xy 378.514864 -223.72955) (xy 378.489607 -223.729025) (xy 378.439783 -223.720706)
			(xy 378.392008 -223.7043) (xy 378.347584 -223.680254) (xy 378.307724 -223.649225) (xy 378.273514 -223.612059)
			(xy 378.245887 -223.569769) (xy 378.225598 -223.52351) (xy 378.213198 -223.474541) (xy 378.209027 -223.4242)
			(xy 378.213198 -223.373859) (xy 378.225598 -223.32489) (xy 378.245887 -223.278631) (xy 378.273514 -223.236341)
			(xy 378.307724 -223.199175) (xy 378.347584 -223.168146) (xy 378.392008 -223.1441) (xy 378.439783 -223.127694)
			(xy 378.489607 -223.119375) (xy 378.514864 -223.118934) (xy 378.538829 -223.119423) (xy 378.586163 -223.126952)
			(xy 378.609098 -223.13392) (xy 378.620782 -223.13773) (xy 378.644404 -223.13392) (xy 378.720858 -223.078294)
			(xy 378.727462 -223.07296) (xy 378.733269 -223.06653) (xy 378.740529 -223.050813) (xy 378.741686 -223.042226)
			(xy 378.74194 -223.037146) (xy 378.74194 -222.815658) (xy 378.741674 -222.808016) (xy 378.737138 -222.79342)
			(xy 378.73305 -222.786956) (xy 378.718637 -222.765012) (xy 378.696751 -222.717293) (xy 378.683354 -222.666533)
			(xy 378.678841 -222.61423) (xy 378.683344 -222.561925) (xy 378.696731 -222.511163) (xy 378.718607 -222.46344)
			(xy 378.73305 -222.441516) (xy 378.737156 -222.435063) (xy 378.741678 -222.420458) (xy 378.74194 -222.412814)
			(xy 378.74194 -222.126302) (xy 378.741516 -222.116233) (xy 378.733795 -222.097634) (xy 378.726954 -222.090234)
			(xy 378.449586 -221.812866) (xy 378.442474 -221.8055) (xy 378.423678 -221.79788) (xy 376.028712 -221.79788)
			(xy 376.000264 -221.823026) (xy 375.997724 -221.84233) (xy 375.994177 -221.86662) (xy 375.980342 -221.913717)
			(xy 375.959153 -221.957994) (xy 375.931155 -221.998312) (xy 375.897068 -222.033633) (xy 375.85777 -222.063047)
			(xy 375.814274 -222.085797) (xy 375.7677 -222.101298) (xy 375.719245 -222.109149) (xy 375.670159 -222.109149)
			(xy 375.621704 -222.101298) (xy 375.57513 -222.085797) (xy 375.531634 -222.063047) (xy 375.492336 -222.033633)
			(xy 375.458249 -221.998312) (xy 375.430251 -221.957994) (xy 375.409062 -221.913717) (xy 375.395227 -221.86662)
			(xy 375.39168 -221.84233) (xy 375.38914 -221.823026) (xy 375.360692 -221.79788) (xy 375.088912 -221.79788)
			(xy 375.060464 -221.823026) (xy 375.057924 -221.84233) (xy 375.054377 -221.86662) (xy 375.040542 -221.913717)
			(xy 375.019353 -221.957994) (xy 374.991355 -221.998312) (xy 374.957268 -222.033633) (xy 374.91797 -222.063047)
			(xy 374.874474 -222.085797) (xy 374.8279 -222.101298) (xy 374.779445 -222.109149) (xy 374.730359 -222.109149)
			(xy 374.681904 -222.101298) (xy 374.63533 -222.085797) (xy 374.591834 -222.063047) (xy 374.552536 -222.033633)
			(xy 374.518449 -221.998312) (xy 374.490451 -221.957994) (xy 374.469262 -221.913717) (xy 374.455427 -221.86662)
			(xy 374.45188 -221.84233) (xy 374.44934 -221.823026) (xy 374.420892 -221.79788) (xy 374.148858 -221.79788)
			(xy 374.12041 -221.823026) (xy 374.11787 -221.84233) (xy 374.114326 -221.866619) (xy 374.100497 -221.913714)
			(xy 374.07931 -221.957989) (xy 374.051311 -221.998303) (xy 374.017222 -222.033617) (xy 373.977921 -222.063021)
			(xy 373.934422 -222.085758) (xy 373.887844 -222.10124) (xy 373.83939 -222.10907) (xy 373.814848 -222.109538)
			(xy 373.789061 -222.109004) (xy 373.738221 -222.100339) (xy 373.689562 -222.083248) (xy 373.666766 -222.071184)
			(xy 373.65178 -222.062802) (xy 373.618252 -222.067628) (xy 373.488458 -222.197422) (xy 373.480846 -222.205998)
			(xy 373.473326 -222.227629) (xy 373.47398 -222.239078) (xy 373.484394 -222.329756) (xy 373.496586 -222.34906)
			(xy 373.506492 -222.35541) (xy 373.528068 -222.369505) (xy 373.566582 -222.403744) (xy 373.598793 -222.44397)
			(xy 373.623782 -222.489038) (xy 373.64084 -222.537666) (xy 373.64948 -222.588469) (xy 373.650002 -222.614236)
			(xy 375.859052 -222.614236) (xy 375.863012 -222.565182) (xy 375.874789 -222.517398) (xy 375.89408 -222.472122)
			(xy 375.920383 -222.430526) (xy 375.953018 -222.393689) (xy 375.991139 -222.362564) (xy 376.03376 -222.337957)
			(xy 376.079776 -222.320505) (xy 376.127995 -222.310661) (xy 376.17717 -222.30868) (xy 376.226025 -222.314612)
			(xy 376.273296 -222.328304) (xy 376.317758 -222.349402) (xy 376.358261 -222.377358) (xy 376.393754 -222.41145)
			(xy 376.423319 -222.450794) (xy 376.44619 -222.494371) (xy 376.461774 -222.541052) (xy 376.469669 -222.589629)
			(xy 376.470164 -222.614236) (xy 376.469669 -222.638843) (xy 376.461774 -222.68742) (xy 376.44619 -222.734101)
			(xy 376.423319 -222.777678) (xy 376.393754 -222.817022) (xy 376.358261 -222.851114) (xy 376.317758 -222.87907)
			(xy 376.273296 -222.900168) (xy 376.226025 -222.91386) (xy 376.17717 -222.919792) (xy 376.127995 -222.917811)
			(xy 376.079776 -222.907967) (xy 376.03376 -222.890515) (xy 375.991139 -222.865908) (xy 375.953018 -222.834783)
			(xy 375.920383 -222.797946) (xy 375.89408 -222.75635) (xy 375.874789 -222.711074) (xy 375.863012 -222.66329)
			(xy 375.859052 -222.614236) (xy 373.650002 -222.614236) (xy 373.649529 -222.638225) (xy 373.642018 -222.685612)
			(xy 373.627187 -222.731241) (xy 373.605402 -222.773988) (xy 373.577198 -222.812801) (xy 373.543269 -222.846725)
			(xy 373.504452 -222.874924) (xy 373.461702 -222.896704) (xy 373.416071 -222.911528) (xy 373.368683 -222.919032)
			(xy 373.344694 -222.919544) (xy 373.318929 -222.919008) (xy 373.26813 -222.910354) (xy 373.219506 -222.893294)
			(xy 373.174436 -222.868311) (xy 373.134202 -222.836115) (xy 373.099945 -222.79762) (xy 373.085868 -222.776034)
			(xy 373.079518 -222.766128) (xy 373.060214 -222.753936) (xy 372.969536 -222.743522) (xy 372.958073 -222.742736)
			(xy 372.936395 -222.750284) (xy 372.92788 -222.758) (xy 372.752366 -222.933514) (xy 372.745 -222.940626)
			(xy 372.73738 -222.959422) (xy 372.73738 -223.018858) (xy 372.737914 -223.029465) (xy 372.746426 -223.048898)
			(xy 372.75389 -223.05645) (xy 372.817136 -223.114362) (xy 372.836948 -223.120966) (xy 372.84787 -223.120204)
			(xy 372.874794 -223.118934) (xy 372.900049 -223.119426) (xy 372.949869 -223.127739) (xy 372.997642 -223.144138)
			(xy 373.042063 -223.168177) (xy 373.081923 -223.1992) (xy 373.116132 -223.236361) (xy 373.143758 -223.278645)
			(xy 373.164048 -223.3249) (xy 373.176447 -223.373863) (xy 373.180618 -223.4242) (xy 373.180615 -223.424242)
			(xy 374.449098 -223.424242) (xy 374.453058 -223.375188) (xy 374.464835 -223.327404) (xy 374.484126 -223.282128)
			(xy 374.510429 -223.240532) (xy 374.543064 -223.203695) (xy 374.581185 -223.17257) (xy 374.623806 -223.147963)
			(xy 374.669822 -223.130511) (xy 374.718041 -223.120667) (xy 374.767216 -223.118686) (xy 374.816071 -223.124618)
			(xy 374.863342 -223.13831) (xy 374.907804 -223.159408) (xy 374.948307 -223.187364) (xy 374.9838 -223.221456)
			(xy 375.013365 -223.2608) (xy 375.036236 -223.304377) (xy 375.05182 -223.351058) (xy 375.059715 -223.399635)
			(xy 375.06021 -223.424242) (xy 375.388898 -223.424242) (xy 375.392858 -223.375188) (xy 375.404635 -223.327404)
			(xy 375.423926 -223.282128) (xy 375.450229 -223.240532) (xy 375.482864 -223.203695) (xy 375.520985 -223.17257)
			(xy 375.563606 -223.147963) (xy 375.609622 -223.130511) (xy 375.657841 -223.120667) (xy 375.707016 -223.118686)
			(xy 375.755871 -223.124618) (xy 375.803142 -223.13831) (xy 375.847604 -223.159408) (xy 375.888107 -223.187364)
			(xy 375.9236 -223.221456) (xy 375.953165 -223.2608) (xy 375.976036 -223.304377) (xy 375.99162 -223.351058)
			(xy 375.999515 -223.399635) (xy 376.00001 -223.424242) (xy 377.269006 -223.424242) (xy 377.272966 -223.375188)
			(xy 377.284743 -223.327404) (xy 377.304034 -223.282128) (xy 377.330337 -223.240532) (xy 377.362972 -223.203695)
			(xy 377.401093 -223.17257) (xy 377.443714 -223.147963) (xy 377.48973 -223.130511) (xy 377.537949 -223.120667)
			(xy 377.587124 -223.118686) (xy 377.635979 -223.124618) (xy 377.68325 -223.13831) (xy 377.727712 -223.159408)
			(xy 377.768215 -223.187364) (xy 377.803708 -223.221456) (xy 377.833273 -223.2608) (xy 377.856144 -223.304377)
			(xy 377.871728 -223.351058) (xy 377.879623 -223.399635) (xy 377.880118 -223.424242) (xy 377.879623 -223.448849)
			(xy 377.871728 -223.497426) (xy 377.856144 -223.544107) (xy 377.833273 -223.587684) (xy 377.803708 -223.627028)
			(xy 377.768215 -223.66112) (xy 377.727712 -223.689076) (xy 377.68325 -223.710174) (xy 377.635979 -223.723866)
			(xy 377.587124 -223.729798) (xy 377.537949 -223.727817) (xy 377.48973 -223.717973) (xy 377.443714 -223.700521)
			(xy 377.401093 -223.675914) (xy 377.362972 -223.644789) (xy 377.330337 -223.607952) (xy 377.304034 -223.566356)
			(xy 377.284743 -223.52108) (xy 377.272966 -223.473296) (xy 377.269006 -223.424242) (xy 376.00001 -223.424242)
			(xy 375.999515 -223.448849) (xy 375.99162 -223.497426) (xy 375.976036 -223.544107) (xy 375.953165 -223.587684)
			(xy 375.9236 -223.627028) (xy 375.888107 -223.66112) (xy 375.847604 -223.689076) (xy 375.803142 -223.710174)
			(xy 375.755871 -223.723866) (xy 375.707016 -223.729798) (xy 375.657841 -223.727817) (xy 375.609622 -223.717973)
			(xy 375.563606 -223.700521) (xy 375.520985 -223.675914) (xy 375.482864 -223.644789) (xy 375.450229 -223.607952)
			(xy 375.423926 -223.566356) (xy 375.404635 -223.52108) (xy 375.392858 -223.473296) (xy 375.388898 -223.424242)
			(xy 375.06021 -223.424242) (xy 375.059715 -223.448849) (xy 375.05182 -223.497426) (xy 375.036236 -223.544107)
			(xy 375.013365 -223.587684) (xy 374.9838 -223.627028) (xy 374.948307 -223.66112) (xy 374.907804 -223.689076)
			(xy 374.863342 -223.710174) (xy 374.816071 -223.723866) (xy 374.767216 -223.729798) (xy 374.718041 -223.727817)
			(xy 374.669822 -223.717973) (xy 374.623806 -223.700521) (xy 374.581185 -223.675914) (xy 374.543064 -223.644789)
			(xy 374.510429 -223.607952) (xy 374.484126 -223.566356) (xy 374.464835 -223.52108) (xy 374.453058 -223.473296)
			(xy 374.449098 -223.424242) (xy 373.180615 -223.424242) (xy 373.176447 -223.474537) (xy 373.164048 -223.5235)
			(xy 373.143758 -223.569755) (xy 373.116132 -223.612039) (xy 373.081923 -223.6492) (xy 373.042063 -223.680223)
			(xy 372.997642 -223.704262) (xy 372.949869 -223.720661) (xy 372.900049 -223.728974) (xy 372.874794 -223.72955)
			(xy 372.84787 -223.72828) (xy 372.836948 -223.727518) (xy 372.817136 -223.734122) (xy 372.75389 -223.792034)
			(xy 372.746348 -223.799533) (xy 372.737818 -223.818997) (xy 372.73738 -223.829626) (xy 372.73738 -224.234248)
			(xy 373.03889 -224.234248) (xy 373.04285 -224.185194) (xy 373.054627 -224.13741) (xy 373.073918 -224.092134)
			(xy 373.100221 -224.050538) (xy 373.132856 -224.013701) (xy 373.170977 -223.982576) (xy 373.213598 -223.957969)
			(xy 373.259614 -223.940517) (xy 373.307833 -223.930673) (xy 373.357008 -223.928692) (xy 373.405863 -223.934624)
			(xy 373.453134 -223.948316) (xy 373.497596 -223.969414) (xy 373.538099 -223.99737) (xy 373.573592 -224.031462)
			(xy 373.603157 -224.070806) (xy 373.626028 -224.114383) (xy 373.641612 -224.161064) (xy 373.649507 -224.209641)
			(xy 373.650002 -224.234248) (xy 375.859052 -224.234248) (xy 375.863012 -224.185194) (xy 375.874789 -224.13741)
			(xy 375.89408 -224.092134) (xy 375.920383 -224.050538) (xy 375.953018 -224.013701) (xy 375.991139 -223.982576)
			(xy 376.03376 -223.957969) (xy 376.079776 -223.940517) (xy 376.127995 -223.930673) (xy 376.17717 -223.928692)
			(xy 376.226025 -223.934624) (xy 376.273296 -223.948316) (xy 376.317758 -223.969414) (xy 376.358261 -223.99737)
			(xy 376.393754 -224.031462) (xy 376.423319 -224.070806) (xy 376.44619 -224.114383) (xy 376.461774 -224.161064)
			(xy 376.469669 -224.209641) (xy 376.470164 -224.234248) (xy 376.799106 -224.234248) (xy 376.803066 -224.185194)
			(xy 376.814843 -224.13741) (xy 376.834134 -224.092134) (xy 376.860437 -224.050538) (xy 376.893072 -224.013701)
			(xy 376.931193 -223.982576) (xy 376.973814 -223.957969) (xy 377.01983 -223.940517) (xy 377.068049 -223.930673)
			(xy 377.117224 -223.928692) (xy 377.166079 -223.934624) (xy 377.21335 -223.948316) (xy 377.257812 -223.969414)
			(xy 377.298315 -223.99737) (xy 377.333808 -224.031462) (xy 377.363373 -224.070806) (xy 377.386244 -224.114383)
			(xy 377.401828 -224.161064) (xy 377.409723 -224.209641) (xy 377.410218 -224.234248) (xy 377.738906 -224.234248)
			(xy 377.742866 -224.185194) (xy 377.754643 -224.13741) (xy 377.773934 -224.092134) (xy 377.800237 -224.050538)
			(xy 377.832872 -224.013701) (xy 377.870993 -223.982576) (xy 377.913614 -223.957969) (xy 377.95963 -223.940517)
			(xy 378.007849 -223.930673) (xy 378.057024 -223.928692) (xy 378.105879 -223.934624) (xy 378.15315 -223.948316)
			(xy 378.197612 -223.969414) (xy 378.238115 -223.99737) (xy 378.273608 -224.031462) (xy 378.303173 -224.070806)
			(xy 378.326044 -224.114383) (xy 378.341628 -224.161064) (xy 378.349523 -224.209641) (xy 378.350018 -224.234248)
			(xy 378.349523 -224.258855) (xy 378.341628 -224.307432) (xy 378.326044 -224.354113) (xy 378.303173 -224.39769)
			(xy 378.273608 -224.437034) (xy 378.238115 -224.471126) (xy 378.197612 -224.499082) (xy 378.15315 -224.52018)
			(xy 378.105879 -224.533872) (xy 378.057024 -224.539804) (xy 378.007849 -224.537823) (xy 377.95963 -224.527979)
			(xy 377.913614 -224.510527) (xy 377.870993 -224.48592) (xy 377.832872 -224.454795) (xy 377.800237 -224.417958)
			(xy 377.773934 -224.376362) (xy 377.754643 -224.331086) (xy 377.742866 -224.283302) (xy 377.738906 -224.234248)
			(xy 377.410218 -224.234248) (xy 377.409723 -224.258855) (xy 377.401828 -224.307432) (xy 377.386244 -224.354113)
			(xy 377.363373 -224.39769) (xy 377.333808 -224.437034) (xy 377.298315 -224.471126) (xy 377.257812 -224.499082)
			(xy 377.21335 -224.52018) (xy 377.166079 -224.533872) (xy 377.117224 -224.539804) (xy 377.068049 -224.537823)
			(xy 377.01983 -224.527979) (xy 376.973814 -224.510527) (xy 376.931193 -224.48592) (xy 376.893072 -224.454795)
			(xy 376.860437 -224.417958) (xy 376.834134 -224.376362) (xy 376.814843 -224.331086) (xy 376.803066 -224.283302)
			(xy 376.799106 -224.234248) (xy 376.470164 -224.234248) (xy 376.469669 -224.258855) (xy 376.461774 -224.307432)
			(xy 376.44619 -224.354113) (xy 376.423319 -224.39769) (xy 376.393754 -224.437034) (xy 376.358261 -224.471126)
			(xy 376.317758 -224.499082) (xy 376.273296 -224.52018) (xy 376.226025 -224.533872) (xy 376.17717 -224.539804)
			(xy 376.127995 -224.537823) (xy 376.079776 -224.527979) (xy 376.03376 -224.510527) (xy 375.991139 -224.48592)
			(xy 375.953018 -224.454795) (xy 375.920383 -224.417958) (xy 375.89408 -224.376362) (xy 375.874789 -224.331086)
			(xy 375.863012 -224.283302) (xy 375.859052 -224.234248) (xy 373.650002 -224.234248) (xy 373.649507 -224.258855)
			(xy 373.641612 -224.307432) (xy 373.626028 -224.354113) (xy 373.603157 -224.39769) (xy 373.573592 -224.437034)
			(xy 373.538099 -224.471126) (xy 373.497596 -224.499082) (xy 373.453134 -224.52018) (xy 373.405863 -224.533872)
			(xy 373.357008 -224.539804) (xy 373.307833 -224.537823) (xy 373.259614 -224.527979) (xy 373.213598 -224.510527)
			(xy 373.170977 -224.48592) (xy 373.132856 -224.454795) (xy 373.100221 -224.417958) (xy 373.073918 -224.376362)
			(xy 373.054627 -224.331086) (xy 373.04285 -224.283302) (xy 373.03889 -224.234248) (xy 372.73738 -224.234248)
			(xy 372.73738 -224.311718) (xy 372.736953 -224.321786) (xy 372.729232 -224.340384) (xy 372.722394 -224.347786)
			(xy 372.634002 -224.436178) (xy 372.632224 -224.43821) (xy 372.607586 -224.462594) (xy 372.60657 -224.46361)
			(xy 372.213886 -224.856294) (xy 372.206487 -224.863139) (xy 372.187889 -224.870869) (xy 372.177818 -224.87128)
			(xy 371.930422 -224.87128) (xy 371.920358 -224.871717) (xy 371.901772 -224.879449) (xy 371.894354 -224.886266)
			(xy 371.77091 -225.00971) (xy 371.76329 -225.028252) (xy 371.76329 -225.038666) (xy 371.76329 -225.04019)
			(xy 371.763544 -225.042222) (xy 371.763544 -225.044254) (xy 372.56899 -225.044254) (xy 372.57295 -224.9952)
			(xy 372.584727 -224.947416) (xy 372.604018 -224.90214) (xy 372.630321 -224.860544) (xy 372.662956 -224.823707)
			(xy 372.701077 -224.792582) (xy 372.743698 -224.767975) (xy 372.789714 -224.750523) (xy 372.837933 -224.740679)
			(xy 372.887108 -224.738698) (xy 372.935963 -224.74463) (xy 372.983234 -224.758322) (xy 373.027696 -224.77942)
			(xy 373.068199 -224.807376) (xy 373.103692 -224.841468) (xy 373.133257 -224.880812) (xy 373.156128 -224.924389)
			(xy 373.171712 -224.97107) (xy 373.179607 -225.019647) (xy 373.180102 -225.044254) (xy 373.509044 -225.044254)
			(xy 373.513004 -224.9952) (xy 373.524781 -224.947416) (xy 373.544072 -224.90214) (xy 373.570375 -224.860544)
			(xy 373.60301 -224.823707) (xy 373.641131 -224.792582) (xy 373.683752 -224.767975) (xy 373.729768 -224.750523)
			(xy 373.777987 -224.740679) (xy 373.827162 -224.738698) (xy 373.876017 -224.74463) (xy 373.923288 -224.758322)
			(xy 373.96775 -224.77942) (xy 374.008253 -224.807376) (xy 374.043746 -224.841468) (xy 374.073311 -224.880812)
			(xy 374.096182 -224.924389) (xy 374.111766 -224.97107) (xy 374.119661 -225.019647) (xy 374.120156 -225.044254)
			(xy 375.388898 -225.044254) (xy 375.392858 -224.9952) (xy 375.404635 -224.947416) (xy 375.423926 -224.90214)
			(xy 375.450229 -224.860544) (xy 375.482864 -224.823707) (xy 375.520985 -224.792582) (xy 375.563606 -224.767975)
			(xy 375.609622 -224.750523) (xy 375.657841 -224.740679) (xy 375.707016 -224.738698) (xy 375.755871 -224.74463)
			(xy 375.803142 -224.758322) (xy 375.847604 -224.77942) (xy 375.888107 -224.807376) (xy 375.9236 -224.841468)
			(xy 375.953165 -224.880812) (xy 375.976036 -224.924389) (xy 375.99162 -224.97107) (xy 375.999515 -225.019647)
			(xy 376.00001 -225.044254) (xy 376.328952 -225.044254) (xy 376.332912 -224.9952) (xy 376.344689 -224.947416)
			(xy 376.36398 -224.90214) (xy 376.390283 -224.860544) (xy 376.422918 -224.823707) (xy 376.461039 -224.792582)
			(xy 376.50366 -224.767975) (xy 376.549676 -224.750523) (xy 376.597895 -224.740679) (xy 376.64707 -224.738698)
			(xy 376.695925 -224.74463) (xy 376.743196 -224.758322) (xy 376.787658 -224.77942) (xy 376.828161 -224.807376)
			(xy 376.863654 -224.841468) (xy 376.893219 -224.880812) (xy 376.91609 -224.924389) (xy 376.931674 -224.97107)
			(xy 376.939569 -225.019647) (xy 376.940064 -225.044254) (xy 376.939569 -225.068861) (xy 376.931674 -225.117438)
			(xy 376.91609 -225.164119) (xy 376.893219 -225.207696) (xy 376.863654 -225.24704) (xy 376.828161 -225.281132)
			(xy 376.787658 -225.309088) (xy 376.743196 -225.330186) (xy 376.695925 -225.343878) (xy 376.64707 -225.34981)
			(xy 376.597895 -225.347829) (xy 376.549676 -225.337985) (xy 376.50366 -225.320533) (xy 376.461039 -225.295926)
			(xy 376.422918 -225.264801) (xy 376.390283 -225.227964) (xy 376.36398 -225.186368) (xy 376.344689 -225.141092)
			(xy 376.332912 -225.093308) (xy 376.328952 -225.044254) (xy 376.00001 -225.044254) (xy 375.999515 -225.068861)
			(xy 375.99162 -225.117438) (xy 375.976036 -225.164119) (xy 375.953165 -225.207696) (xy 375.9236 -225.24704)
			(xy 375.888107 -225.281132) (xy 375.847604 -225.309088) (xy 375.803142 -225.330186) (xy 375.755871 -225.343878)
			(xy 375.707016 -225.34981) (xy 375.657841 -225.347829) (xy 375.609622 -225.337985) (xy 375.563606 -225.320533)
			(xy 375.520985 -225.295926) (xy 375.482864 -225.264801) (xy 375.450229 -225.227964) (xy 375.423926 -225.186368)
			(xy 375.404635 -225.141092) (xy 375.392858 -225.093308) (xy 375.388898 -225.044254) (xy 374.120156 -225.044254)
			(xy 374.119661 -225.068861) (xy 374.111766 -225.117438) (xy 374.096182 -225.164119) (xy 374.073311 -225.207696)
			(xy 374.043746 -225.24704) (xy 374.008253 -225.281132) (xy 373.96775 -225.309088) (xy 373.923288 -225.330186)
			(xy 373.876017 -225.343878) (xy 373.827162 -225.34981) (xy 373.777987 -225.347829) (xy 373.729768 -225.337985)
			(xy 373.683752 -225.320533) (xy 373.641131 -225.295926) (xy 373.60301 -225.264801) (xy 373.570375 -225.227964)
			(xy 373.544072 -225.186368) (xy 373.524781 -225.141092) (xy 373.513004 -225.093308) (xy 373.509044 -225.044254)
			(xy 373.180102 -225.044254) (xy 373.179607 -225.068861) (xy 373.171712 -225.117438) (xy 373.156128 -225.164119)
			(xy 373.133257 -225.207696) (xy 373.103692 -225.24704) (xy 373.068199 -225.281132) (xy 373.027696 -225.309088)
			(xy 372.983234 -225.330186) (xy 372.935963 -225.343878) (xy 372.887108 -225.34981) (xy 372.837933 -225.347829)
			(xy 372.789714 -225.337985) (xy 372.743698 -225.320533) (xy 372.701077 -225.295926) (xy 372.662956 -225.264801)
			(xy 372.630321 -225.227964) (xy 372.604018 -225.186368) (xy 372.584727 -225.141092) (xy 372.57295 -225.093308)
			(xy 372.56899 -225.044254) (xy 371.763544 -225.044254) (xy 371.763544 -225.05162) (xy 371.762715 -225.08922)
			(xy 371.754628 -225.163996) (xy 371.739278 -225.237625) (xy 371.716811 -225.309403) (xy 371.687441 -225.378644)
			(xy 371.65145 -225.444686) (xy 371.630702 -225.476054) (xy 371.625368 -225.484182) (xy 371.62105 -225.502978)
			(xy 371.63502 -225.590862) (xy 371.644672 -225.607372) (xy 371.652546 -225.613214) (xy 371.670525 -225.6278)
			(xy 371.702296 -225.661472) (xy 371.728631 -225.699547) (xy 371.748929 -225.741155) (xy 371.762726 -225.785347)
			(xy 371.769707 -225.831113) (xy 371.770148 -225.85426) (xy 373.03889 -225.85426) (xy 373.04285 -225.805206)
			(xy 373.054627 -225.757422) (xy 373.073918 -225.712146) (xy 373.100221 -225.67055) (xy 373.132856 -225.633713)
			(xy 373.170977 -225.602588) (xy 373.213598 -225.577981) (xy 373.259614 -225.560529) (xy 373.307833 -225.550685)
			(xy 373.357008 -225.548704) (xy 373.405863 -225.554636) (xy 373.453134 -225.568328) (xy 373.497596 -225.589426)
			(xy 373.538099 -225.617382) (xy 373.573592 -225.651474) (xy 373.603157 -225.690818) (xy 373.626028 -225.734395)
			(xy 373.641612 -225.781076) (xy 373.649507 -225.829653) (xy 373.650002 -225.85426) (xy 373.978944 -225.85426)
			(xy 373.982904 -225.805206) (xy 373.994681 -225.757422) (xy 374.013972 -225.712146) (xy 374.040275 -225.67055)
			(xy 374.07291 -225.633713) (xy 374.111031 -225.602588) (xy 374.153652 -225.577981) (xy 374.199668 -225.560529)
			(xy 374.247887 -225.550685) (xy 374.297062 -225.548704) (xy 374.345917 -225.554636) (xy 374.393188 -225.568328)
			(xy 374.43765 -225.589426) (xy 374.478153 -225.617382) (xy 374.513646 -225.651474) (xy 374.543211 -225.690818)
			(xy 374.566082 -225.734395) (xy 374.581666 -225.781076) (xy 374.589561 -225.829653) (xy 374.590056 -225.85426)
			(xy 375.848621 -225.85426) (xy 375.852716 -225.803532) (xy 375.864895 -225.754118) (xy 375.884843 -225.707298)
			(xy 375.912044 -225.664284) (xy 375.945792 -225.62619) (xy 375.985214 -225.594003) (xy 376.029288 -225.568557)
			(xy 376.076874 -225.55051) (xy 376.126738 -225.54033) (xy 376.17759 -225.538281) (xy 376.228111 -225.544415)
			(xy 376.276995 -225.558575) (xy 376.322974 -225.580392) (xy 376.364858 -225.609302) (xy 376.401562 -225.644557)
			(xy 376.432135 -225.685243) (xy 376.455786 -225.730306) (xy 376.471902 -225.77858) (xy 376.480066 -225.828814)
			(xy 376.480578 -225.85426) (xy 376.480066 -225.879706) (xy 376.471902 -225.92994) (xy 376.455786 -225.978214)
			(xy 376.432135 -226.023277) (xy 376.401562 -226.063963) (xy 376.364858 -226.099218) (xy 376.322974 -226.128128)
			(xy 376.276995 -226.149945) (xy 376.228111 -226.164105) (xy 376.17759 -226.170239) (xy 376.126738 -226.16819)
			(xy 376.076874 -226.15801) (xy 376.029288 -226.139963) (xy 375.985214 -226.114517) (xy 375.945792 -226.08233)
			(xy 375.912044 -226.044236) (xy 375.884843 -226.001222) (xy 375.864895 -225.954402) (xy 375.852716 -225.904988)
			(xy 375.848621 -225.85426) (xy 374.590056 -225.85426) (xy 374.589561 -225.878867) (xy 374.581666 -225.927444)
			(xy 374.566082 -225.974125) (xy 374.543211 -226.017702) (xy 374.513646 -226.057046) (xy 374.478153 -226.091138)
			(xy 374.43765 -226.119094) (xy 374.393188 -226.140192) (xy 374.345917 -226.153884) (xy 374.297062 -226.159816)
			(xy 374.247887 -226.157835) (xy 374.199668 -226.147991) (xy 374.153652 -226.130539) (xy 374.111031 -226.105932)
			(xy 374.07291 -226.074807) (xy 374.040275 -226.03797) (xy 374.013972 -225.996374) (xy 373.994681 -225.951098)
			(xy 373.982904 -225.903314) (xy 373.978944 -225.85426) (xy 373.650002 -225.85426) (xy 373.649507 -225.878867)
			(xy 373.641612 -225.927444) (xy 373.626028 -225.974125) (xy 373.603157 -226.017702) (xy 373.573592 -226.057046)
			(xy 373.538099 -226.091138) (xy 373.497596 -226.119094) (xy 373.453134 -226.140192) (xy 373.405863 -226.153884)
			(xy 373.357008 -226.159816) (xy 373.307833 -226.157835) (xy 373.259614 -226.147991) (xy 373.213598 -226.130539)
			(xy 373.170977 -226.105932) (xy 373.132856 -226.074807) (xy 373.100221 -226.03797) (xy 373.073918 -225.996374)
			(xy 373.054627 -225.951098) (xy 373.04285 -225.903314) (xy 373.03889 -225.85426) (xy 371.770148 -225.85426)
			(xy 371.76968 -225.878254) (xy 371.76218 -225.925653) (xy 371.747356 -225.971295) (xy 371.725575 -226.014056)
			(xy 371.697373 -226.052884) (xy 371.663445 -226.086821) (xy 371.624625 -226.115033) (xy 371.581869 -226.136826)
			(xy 371.536231 -226.151661) (xy 371.488834 -226.159174) (xy 371.46484 -226.159568) (xy 371.440591 -226.159097)
			(xy 371.392705 -226.151422) (xy 371.346633 -226.136274) (xy 371.303535 -226.114035) (xy 371.264494 -226.085264)
			(xy 371.230491 -226.050683) (xy 371.202381 -226.011162) (xy 371.180872 -225.967695) (xy 371.166503 -225.921375)
			(xy 371.16258 -225.89744) (xy 371.16131 -225.887788) (xy 371.151658 -225.871024) (xy 371.089682 -225.821494)
			(xy 371.085889 -225.81859) (xy 371.077452 -225.814109) (xy 371.072918 -225.812604) (xy 371.064028 -225.80981)
			(xy 371.026436 -225.81235) (xy 371.026182 -225.81235) (xy 370.994686 -225.813112) (xy 370.860066 -225.813112)
			(xy 370.830602 -225.841814) (xy 370.830094 -225.862642) (xy 370.828928 -225.887444) (xy 370.819556 -225.9362)
			(xy 370.802421 -225.982798) (xy 370.777975 -226.026012) (xy 370.746861 -226.064702) (xy 370.7099 -226.09785)
			(xy 370.668063 -226.124584) (xy 370.622453 -226.144199) (xy 370.574271 -226.156178) (xy 370.524786 -226.160207)
			(xy 370.475301 -226.156178) (xy 370.427119 -226.144199) (xy 370.381509 -226.124584) (xy 370.339672 -226.09785)
			(xy 370.302711 -226.064702) (xy 370.271597 -226.026012) (xy 370.247151 -225.982798) (xy 370.230016 -225.9362)
			(xy 370.220644 -225.887444) (xy 370.219478 -225.862642) (xy 370.21897 -225.841814) (xy 370.189506 -225.813112)
			(xy 370.054886 -225.813112) (xy 370.01462 -225.812602) (xy 369.934529 -225.804183) (xy 369.855757 -225.787437)
			(xy 369.779167 -225.762549) (xy 369.705598 -225.729792) (xy 369.635856 -225.689523) (xy 369.570706 -225.642186)
			(xy 369.510861 -225.588297) (xy 369.456977 -225.528447) (xy 369.409644 -225.463293) (xy 369.369381 -225.393549)
			(xy 369.336629 -225.319977) (xy 369.311747 -225.243385) (xy 369.295008 -225.164612) (xy 369.286595 -225.08452)
			(xy 369.286028 -225.044254) (xy 369.28621 -225.022423) (xy 369.288754 -224.978836) (xy 369.291108 -224.957132)
			(xy 369.292847 -224.942647) (xy 369.297292 -224.91381) (xy 369.299998 -224.899474) (xy 369.302284 -224.887028)
			(xy 369.294918 -224.862898) (xy 368.892074 -224.460054) (xy 368.852958 -224.458276) (xy 368.837718 -224.470722)
			(xy 368.817135 -224.486853) (xy 368.7716 -224.51256) (xy 368.722349 -224.530126) (xy 368.670823 -224.539038)
			(xy 368.644678 -224.539556) (xy 368.636804 -224.539556) (xy 368.611033 -224.538352) (xy 368.560421 -224.528375)
			(xy 368.512203 -224.510038) (xy 368.467751 -224.483862) (xy 368.428328 -224.450591) (xy 368.395053 -224.411171)
			(xy 368.368873 -224.366721) (xy 368.350532 -224.318505) (xy 368.34055 -224.267893) (xy 368.33937 -224.242122)
			(xy 368.33937 -224.23628) (xy 368.33937 -224.234248) (xy 368.339911 -224.208105) (xy 368.34883 -224.156586)
			(xy 368.366396 -224.10734) (xy 368.392098 -224.061808) (xy 368.408204 -224.041208) (xy 368.42065 -224.025968)
			(xy 368.418872 -223.986852) (xy 368.354356 -223.922336) (xy 368.351779 -223.919828) (xy 368.346043 -223.915493)
			(xy 368.342926 -223.9137) (xy 368.33683 -223.910398) (xy 368.278887 -223.895929) (xy 368.165634 -223.857991)
			(xy 368.056238 -223.810055) (xy 368.003582 -223.781874) (xy 368.003074 -223.78162) (xy 367.994438 -223.777048)
			(xy 367.99393 -223.77654) (xy 367.96726 -223.761554) (xy 367.932462 -223.74098) (xy 367.886488 -223.711516)
			(xy 367.848509 -223.684784) (xy 367.775951 -223.626792) (xy 367.707604 -223.563893) (xy 367.675414 -223.530414)
			(xy 367.666524 -223.521016) (xy 367.643156 -223.513142) (xy 367.53546 -223.53016) (xy 367.515648 -223.544892)
			(xy 367.51006 -223.556322) (xy 367.499019 -223.57822) (xy 367.47102 -223.61848) (xy 367.436942 -223.653744)
			(xy 367.397664 -223.683104) (xy 367.354195 -223.705804) (xy 367.307656 -223.721261) (xy 367.259244 -223.729075)
			(xy 367.234724 -223.72955) (xy 367.209462 -223.729059) (xy 367.159625 -223.720746) (xy 367.111837 -223.704344)
			(xy 367.0674 -223.680299) (xy 367.027528 -223.649268) (xy 366.993307 -223.612097) (xy 366.965671 -223.5698)
			(xy 366.945374 -223.523531) (xy 366.932971 -223.474552) (xy 366.928798 -223.4242) (xy 366.932971 -223.373848)
			(xy 366.945374 -223.324869) (xy 366.965671 -223.2786) (xy 366.993307 -223.236303) (xy 367.027528 -223.199132)
			(xy 367.0674 -223.168101) (xy 367.111837 -223.144056) (xy 367.159625 -223.127654) (xy 367.209462 -223.119341)
			(xy 367.234724 -223.118934) (xy 367.259362 -223.11995) (xy 367.272316 -223.120966) (xy 367.294922 -223.111314)
			(xy 367.355628 -223.036384) (xy 367.362817 -223.026353) (xy 367.367708 -223.002204) (xy 367.365026 -222.990156)
			(xy 367.357914 -222.964502) (xy 367.357914 -222.964248) (xy 367.348262 -222.926656) (xy 367.346484 -222.919798)
			(xy 367.33988 -222.90786) (xy 366.674146 -222.242126) (xy 366.667034 -222.23476) (xy 366.648238 -222.22714)
			(xy 365.174784 -222.22714) (xy 365.164792 -222.22764) (xy 365.146325 -222.235283) (xy 365.132151 -222.249374)
			(xy 365.127794 -222.258382) (xy 365.08563 -222.358966) (xy 365.091472 -222.388938) (xy 365.10214 -222.400114)
			(xy 365.118499 -222.417342) (xy 365.146215 -222.455925) (xy 365.167618 -222.498338) (xy 365.182189 -222.543554)
			(xy 365.189577 -222.590483) (xy 365.190024 -222.614236) (xy 365.189502 -222.639491) (xy 365.181189 -222.689313)
			(xy 365.164788 -222.737087) (xy 365.140747 -222.78151) (xy 365.109723 -222.82137) (xy 365.072561 -222.85558)
			(xy 365.030275 -222.883206) (xy 364.984019 -222.903496) (xy 364.935054 -222.915896) (xy 364.884716 -222.920067)
			(xy 364.834378 -222.915896) (xy 364.785413 -222.903496) (xy 364.739157 -222.883206) (xy 364.696871 -222.85558)
			(xy 364.659709 -222.82137) (xy 364.628685 -222.78151) (xy 364.604644 -222.737087) (xy 364.588243 -222.689313)
			(xy 364.57993 -222.639491) (xy 364.579408 -222.614236) (xy 364.579879 -222.590485) (xy 364.587273 -222.54356)
			(xy 364.601841 -222.498345) (xy 364.623232 -222.45593) (xy 364.650931 -222.417338) (xy 364.667292 -222.400114)
			(xy 364.67796 -222.388938) (xy 364.683802 -222.358966) (xy 364.641638 -222.258382) (xy 364.637414 -222.249281)
			(xy 364.623221 -222.23512) (xy 364.604674 -222.227505) (xy 364.594648 -222.22714) (xy 361.414822 -222.22714)
			(xy 361.404826 -222.227634) (xy 361.386347 -222.235268) (xy 361.372162 -222.249358) (xy 361.367832 -222.258382)
			(xy 361.325668 -222.358966) (xy 361.33151 -222.388938) (xy 361.342178 -222.400114) (xy 361.358535 -222.417343)
			(xy 361.386248 -222.455927) (xy 361.407648 -222.49834) (xy 361.422217 -222.543556) (xy 361.429604 -222.590484)
			(xy 361.430062 -222.614236) (xy 361.429613 -222.638226) (xy 361.422102 -222.685614) (xy 361.407269 -222.731244)
			(xy 361.385481 -222.773992) (xy 361.357274 -222.812805) (xy 361.323343 -222.846728) (xy 361.284522 -222.874924)
			(xy 361.241768 -222.896701) (xy 361.196135 -222.911521) (xy 361.148744 -222.91902) (xy 361.124754 -222.919544)
			(xy 361.099666 -222.919033) (xy 361.050166 -222.910822) (xy 361.002675 -222.894628) (xy 360.95847 -222.870888)
			(xy 360.918741 -222.840241) (xy 360.884558 -222.80351) (xy 360.856839 -222.761685) (xy 360.836332 -222.71589)
			(xy 360.823588 -222.667359) (xy 360.820716 -222.64243) (xy 360.819446 -222.627444) (xy 360.801412 -222.604076)
			(xy 360.701082 -222.5675) (xy 360.690414 -222.56496) (xy 360.678703 -222.564038) (xy 360.656483 -222.571588)
			(xy 360.647742 -222.579438) (xy 360.293666 -222.933514) (xy 360.2863 -222.940626) (xy 360.27868 -222.959422)
			(xy 360.27868 -223.424242) (xy 361.289104 -223.424242) (xy 361.293064 -223.375188) (xy 361.304841 -223.327404)
			(xy 361.324132 -223.282128) (xy 361.350435 -223.240532) (xy 361.38307 -223.203695) (xy 361.421191 -223.17257)
			(xy 361.463812 -223.147963) (xy 361.509828 -223.130511) (xy 361.558047 -223.120667) (xy 361.607222 -223.118686)
			(xy 361.656077 -223.124618) (xy 361.703348 -223.13831) (xy 361.74781 -223.159408) (xy 361.788313 -223.187364)
			(xy 361.823806 -223.221456) (xy 361.853371 -223.2608) (xy 361.876242 -223.304377) (xy 361.891826 -223.351058)
			(xy 361.899721 -223.399635) (xy 361.900216 -223.424242) (xy 364.109012 -223.424242) (xy 364.112972 -223.375188)
			(xy 364.124749 -223.327404) (xy 364.14404 -223.282128) (xy 364.170343 -223.240532) (xy 364.202978 -223.203695)
			(xy 364.241099 -223.17257) (xy 364.28372 -223.147963) (xy 364.329736 -223.130511) (xy 364.377955 -223.120667)
			(xy 364.42713 -223.118686) (xy 364.475985 -223.124618) (xy 364.523256 -223.13831) (xy 364.567718 -223.159408)
			(xy 364.608221 -223.187364) (xy 364.643714 -223.221456) (xy 364.673279 -223.2608) (xy 364.69615 -223.304377)
			(xy 364.711734 -223.351058) (xy 364.719629 -223.399635) (xy 364.720124 -223.424242) (xy 365.049066 -223.424242)
			(xy 365.053026 -223.375188) (xy 365.064803 -223.327404) (xy 365.084094 -223.282128) (xy 365.110397 -223.240532)
			(xy 365.143032 -223.203695) (xy 365.181153 -223.17257) (xy 365.223774 -223.147963) (xy 365.26979 -223.130511)
			(xy 365.318009 -223.120667) (xy 365.367184 -223.118686) (xy 365.416039 -223.124618) (xy 365.46331 -223.13831)
			(xy 365.507772 -223.159408) (xy 365.548275 -223.187364) (xy 365.583768 -223.221456) (xy 365.613333 -223.2608)
			(xy 365.636204 -223.304377) (xy 365.651788 -223.351058) (xy 365.659683 -223.399635) (xy 365.660178 -223.424242)
			(xy 365.659683 -223.448849) (xy 365.651788 -223.497426) (xy 365.636204 -223.544107) (xy 365.613333 -223.587684)
			(xy 365.583768 -223.627028) (xy 365.548275 -223.66112) (xy 365.507772 -223.689076) (xy 365.46331 -223.710174)
			(xy 365.416039 -223.723866) (xy 365.367184 -223.729798) (xy 365.318009 -223.727817) (xy 365.26979 -223.717973)
			(xy 365.223774 -223.700521) (xy 365.181153 -223.675914) (xy 365.143032 -223.644789) (xy 365.110397 -223.607952)
			(xy 365.084094 -223.566356) (xy 365.064803 -223.52108) (xy 365.053026 -223.473296) (xy 365.049066 -223.424242)
			(xy 364.720124 -223.424242) (xy 364.719629 -223.448849) (xy 364.711734 -223.497426) (xy 364.69615 -223.544107)
			(xy 364.673279 -223.587684) (xy 364.643714 -223.627028) (xy 364.608221 -223.66112) (xy 364.567718 -223.689076)
			(xy 364.523256 -223.710174) (xy 364.475985 -223.723866) (xy 364.42713 -223.729798) (xy 364.377955 -223.727817)
			(xy 364.329736 -223.717973) (xy 364.28372 -223.700521) (xy 364.241099 -223.675914) (xy 364.202978 -223.644789)
			(xy 364.170343 -223.607952) (xy 364.14404 -223.566356) (xy 364.124749 -223.52108) (xy 364.112972 -223.473296)
			(xy 364.109012 -223.424242) (xy 361.900216 -223.424242) (xy 361.899721 -223.448849) (xy 361.891826 -223.497426)
			(xy 361.876242 -223.544107) (xy 361.853371 -223.587684) (xy 361.823806 -223.627028) (xy 361.788313 -223.66112)
			(xy 361.74781 -223.689076) (xy 361.703348 -223.710174) (xy 361.656077 -223.723866) (xy 361.607222 -223.729798)
			(xy 361.558047 -223.727817) (xy 361.509828 -223.717973) (xy 361.463812 -223.700521) (xy 361.421191 -223.675914)
			(xy 361.38307 -223.644789) (xy 361.350435 -223.607952) (xy 361.324132 -223.566356) (xy 361.304841 -223.52108)
			(xy 361.293064 -223.473296) (xy 361.289104 -223.424242) (xy 360.27868 -223.424242) (xy 360.27868 -224.234248)
			(xy 360.81895 -224.234248) (xy 360.82291 -224.185194) (xy 360.834687 -224.13741) (xy 360.853978 -224.092134)
			(xy 360.880281 -224.050538) (xy 360.912916 -224.013701) (xy 360.951037 -223.982576) (xy 360.993658 -223.957969)
			(xy 361.039674 -223.940517) (xy 361.087893 -223.930673) (xy 361.137068 -223.928692) (xy 361.185923 -223.934624)
			(xy 361.233194 -223.948316) (xy 361.277656 -223.969414) (xy 361.318159 -223.99737) (xy 361.353652 -224.031462)
			(xy 361.383217 -224.070806) (xy 361.406088 -224.114383) (xy 361.421672 -224.161064) (xy 361.429567 -224.209641)
			(xy 361.430062 -224.234248) (xy 362.699058 -224.234248) (xy 362.703018 -224.185194) (xy 362.714795 -224.13741)
			(xy 362.734086 -224.092134) (xy 362.760389 -224.050538) (xy 362.793024 -224.013701) (xy 362.831145 -223.982576)
			(xy 362.873766 -223.957969) (xy 362.919782 -223.940517) (xy 362.968001 -223.930673) (xy 363.017176 -223.928692)
			(xy 363.066031 -223.934624) (xy 363.113302 -223.948316) (xy 363.157764 -223.969414) (xy 363.198267 -223.99737)
			(xy 363.23376 -224.031462) (xy 363.263325 -224.070806) (xy 363.286196 -224.114383) (xy 363.30178 -224.161064)
			(xy 363.309675 -224.209641) (xy 363.31017 -224.234248) (xy 364.578912 -224.234248) (xy 364.582872 -224.185194)
			(xy 364.594649 -224.13741) (xy 364.61394 -224.092134) (xy 364.640243 -224.050538) (xy 364.672878 -224.013701)
			(xy 364.710999 -223.982576) (xy 364.75362 -223.957969) (xy 364.799636 -223.940517) (xy 364.847855 -223.930673)
			(xy 364.89703 -223.928692) (xy 364.945885 -223.934624) (xy 364.993156 -223.948316) (xy 365.037618 -223.969414)
			(xy 365.078121 -223.99737) (xy 365.113614 -224.031462) (xy 365.143179 -224.070806) (xy 365.16605 -224.114383)
			(xy 365.181634 -224.161064) (xy 365.189529 -224.209641) (xy 365.190024 -224.234248) (xy 365.518966 -224.234248)
			(xy 365.522926 -224.185194) (xy 365.534703 -224.13741) (xy 365.553994 -224.092134) (xy 365.580297 -224.050538)
			(xy 365.612932 -224.013701) (xy 365.651053 -223.982576) (xy 365.693674 -223.957969) (xy 365.73969 -223.940517)
			(xy 365.787909 -223.930673) (xy 365.837084 -223.928692) (xy 365.885939 -223.934624) (xy 365.93321 -223.948316)
			(xy 365.977672 -223.969414) (xy 366.018175 -223.99737) (xy 366.053668 -224.031462) (xy 366.083233 -224.070806)
			(xy 366.106104 -224.114383) (xy 366.121688 -224.161064) (xy 366.129583 -224.209641) (xy 366.130078 -224.234248)
			(xy 366.45902 -224.234248) (xy 366.46298 -224.185194) (xy 366.474757 -224.13741) (xy 366.494048 -224.092134)
			(xy 366.520351 -224.050538) (xy 366.552986 -224.013701) (xy 366.591107 -223.982576) (xy 366.633728 -223.957969)
			(xy 366.679744 -223.940517) (xy 366.727963 -223.930673) (xy 366.777138 -223.928692) (xy 366.825993 -223.934624)
			(xy 366.873264 -223.948316) (xy 366.917726 -223.969414) (xy 366.958229 -223.99737) (xy 366.993722 -224.031462)
			(xy 367.023287 -224.070806) (xy 367.046158 -224.114383) (xy 367.061742 -224.161064) (xy 367.069637 -224.209641)
			(xy 367.070132 -224.234248) (xy 367.399074 -224.234248) (xy 367.403034 -224.185194) (xy 367.414811 -224.13741)
			(xy 367.434102 -224.092134) (xy 367.460405 -224.050538) (xy 367.49304 -224.013701) (xy 367.531161 -223.982576)
			(xy 367.573782 -223.957969) (xy 367.619798 -223.940517) (xy 367.668017 -223.930673) (xy 367.717192 -223.928692)
			(xy 367.766047 -223.934624) (xy 367.813318 -223.948316) (xy 367.85778 -223.969414) (xy 367.898283 -223.99737)
			(xy 367.933776 -224.031462) (xy 367.963341 -224.070806) (xy 367.986212 -224.114383) (xy 368.001796 -224.161064)
			(xy 368.009691 -224.209641) (xy 368.010186 -224.234248) (xy 368.009691 -224.258855) (xy 368.001796 -224.307432)
			(xy 367.986212 -224.354113) (xy 367.963341 -224.39769) (xy 367.933776 -224.437034) (xy 367.898283 -224.471126)
			(xy 367.85778 -224.499082) (xy 367.813318 -224.52018) (xy 367.766047 -224.533872) (xy 367.717192 -224.539804)
			(xy 367.668017 -224.537823) (xy 367.619798 -224.527979) (xy 367.573782 -224.510527) (xy 367.531161 -224.48592)
			(xy 367.49304 -224.454795) (xy 367.460405 -224.417958) (xy 367.434102 -224.376362) (xy 367.414811 -224.331086)
			(xy 367.403034 -224.283302) (xy 367.399074 -224.234248) (xy 367.070132 -224.234248) (xy 367.069637 -224.258855)
			(xy 367.061742 -224.307432) (xy 367.046158 -224.354113) (xy 367.023287 -224.39769) (xy 366.993722 -224.437034)
			(xy 366.958229 -224.471126) (xy 366.917726 -224.499082) (xy 366.873264 -224.52018) (xy 366.825993 -224.533872)
			(xy 366.777138 -224.539804) (xy 366.727963 -224.537823) (xy 366.679744 -224.527979) (xy 366.633728 -224.510527)
			(xy 366.591107 -224.48592) (xy 366.552986 -224.454795) (xy 366.520351 -224.417958) (xy 366.494048 -224.376362)
			(xy 366.474757 -224.331086) (xy 366.46298 -224.283302) (xy 366.45902 -224.234248) (xy 366.130078 -224.234248)
			(xy 366.129583 -224.258855) (xy 366.121688 -224.307432) (xy 366.106104 -224.354113) (xy 366.083233 -224.39769)
			(xy 366.053668 -224.437034) (xy 366.018175 -224.471126) (xy 365.977672 -224.499082) (xy 365.93321 -224.52018)
			(xy 365.885939 -224.533872) (xy 365.837084 -224.539804) (xy 365.787909 -224.537823) (xy 365.73969 -224.527979)
			(xy 365.693674 -224.510527) (xy 365.651053 -224.48592) (xy 365.612932 -224.454795) (xy 365.580297 -224.417958)
			(xy 365.553994 -224.376362) (xy 365.534703 -224.331086) (xy 365.522926 -224.283302) (xy 365.518966 -224.234248)
			(xy 365.190024 -224.234248) (xy 365.189529 -224.258855) (xy 365.181634 -224.307432) (xy 365.16605 -224.354113)
			(xy 365.143179 -224.39769) (xy 365.113614 -224.437034) (xy 365.078121 -224.471126) (xy 365.037618 -224.499082)
			(xy 364.993156 -224.52018) (xy 364.945885 -224.533872) (xy 364.89703 -224.539804) (xy 364.847855 -224.537823)
			(xy 364.799636 -224.527979) (xy 364.75362 -224.510527) (xy 364.710999 -224.48592) (xy 364.672878 -224.454795)
			(xy 364.640243 -224.417958) (xy 364.61394 -224.376362) (xy 364.594649 -224.331086) (xy 364.582872 -224.283302)
			(xy 364.578912 -224.234248) (xy 363.31017 -224.234248) (xy 363.309675 -224.258855) (xy 363.30178 -224.307432)
			(xy 363.286196 -224.354113) (xy 363.263325 -224.39769) (xy 363.23376 -224.437034) (xy 363.198267 -224.471126)
			(xy 363.157764 -224.499082) (xy 363.113302 -224.52018) (xy 363.066031 -224.533872) (xy 363.017176 -224.539804)
			(xy 362.968001 -224.537823) (xy 362.919782 -224.527979) (xy 362.873766 -224.510527) (xy 362.831145 -224.48592)
			(xy 362.793024 -224.454795) (xy 362.760389 -224.417958) (xy 362.734086 -224.376362) (xy 362.714795 -224.331086)
			(xy 362.703018 -224.283302) (xy 362.699058 -224.234248) (xy 361.430062 -224.234248) (xy 361.429567 -224.258855)
			(xy 361.421672 -224.307432) (xy 361.406088 -224.354113) (xy 361.383217 -224.39769) (xy 361.353652 -224.437034)
			(xy 361.318159 -224.471126) (xy 361.277656 -224.499082) (xy 361.233194 -224.52018) (xy 361.185923 -224.533872)
			(xy 361.137068 -224.539804) (xy 361.087893 -224.537823) (xy 361.039674 -224.527979) (xy 360.993658 -224.510527)
			(xy 360.951037 -224.48592) (xy 360.912916 -224.454795) (xy 360.880281 -224.417958) (xy 360.853978 -224.376362)
			(xy 360.834687 -224.331086) (xy 360.82291 -224.283302) (xy 360.81895 -224.234248) (xy 360.27868 -224.234248)
			(xy 360.27868 -225.044254) (xy 365.049066 -225.044254) (xy 365.053026 -224.9952) (xy 365.064803 -224.947416)
			(xy 365.084094 -224.90214) (xy 365.110397 -224.860544) (xy 365.143032 -224.823707) (xy 365.181153 -224.792582)
			(xy 365.223774 -224.767975) (xy 365.26979 -224.750523) (xy 365.318009 -224.740679) (xy 365.367184 -224.738698)
			(xy 365.416039 -224.74463) (xy 365.46331 -224.758322) (xy 365.507772 -224.77942) (xy 365.548275 -224.807376)
			(xy 365.583768 -224.841468) (xy 365.613333 -224.880812) (xy 365.636204 -224.924389) (xy 365.651788 -224.97107)
			(xy 365.659683 -225.019647) (xy 365.660178 -225.044254) (xy 365.659683 -225.068861) (xy 365.651788 -225.117438)
			(xy 365.636204 -225.164119) (xy 365.613333 -225.207696) (xy 365.583768 -225.24704) (xy 365.548275 -225.281132)
			(xy 365.507772 -225.309088) (xy 365.46331 -225.330186) (xy 365.416039 -225.343878) (xy 365.367184 -225.34981)
			(xy 365.318009 -225.347829) (xy 365.26979 -225.337985) (xy 365.223774 -225.320533) (xy 365.181153 -225.295926)
			(xy 365.143032 -225.264801) (xy 365.110397 -225.227964) (xy 365.084094 -225.186368) (xy 365.064803 -225.141092)
			(xy 365.053026 -225.093308) (xy 365.049066 -225.044254) (xy 360.27868 -225.044254) (xy 360.27868 -225.85426)
			(xy 360.81895 -225.85426) (xy 360.82291 -225.805206) (xy 360.834687 -225.757422) (xy 360.853978 -225.712146)
			(xy 360.880281 -225.67055) (xy 360.912916 -225.633713) (xy 360.951037 -225.602588) (xy 360.993658 -225.577981)
			(xy 361.039674 -225.560529) (xy 361.087893 -225.550685) (xy 361.137068 -225.548704) (xy 361.185923 -225.554636)
			(xy 361.233194 -225.568328) (xy 361.277656 -225.589426) (xy 361.318159 -225.617382) (xy 361.353652 -225.651474)
			(xy 361.383217 -225.690818) (xy 361.406088 -225.734395) (xy 361.421672 -225.781076) (xy 361.429567 -225.829653)
			(xy 361.430062 -225.85426) (xy 361.759004 -225.85426) (xy 361.762964 -225.805206) (xy 361.774741 -225.757422)
			(xy 361.794032 -225.712146) (xy 361.820335 -225.67055) (xy 361.85297 -225.633713) (xy 361.891091 -225.602588)
			(xy 361.933712 -225.577981) (xy 361.979728 -225.560529) (xy 362.027947 -225.550685) (xy 362.077122 -225.548704)
			(xy 362.125977 -225.554636) (xy 362.173248 -225.568328) (xy 362.21771 -225.589426) (xy 362.258213 -225.617382)
			(xy 362.293706 -225.651474) (xy 362.323271 -225.690818) (xy 362.346142 -225.734395) (xy 362.361726 -225.781076)
			(xy 362.369621 -225.829653) (xy 362.370116 -225.85426) (xy 362.699058 -225.85426) (xy 362.703018 -225.805206)
			(xy 362.714795 -225.757422) (xy 362.734086 -225.712146) (xy 362.760389 -225.67055) (xy 362.793024 -225.633713)
			(xy 362.831145 -225.602588) (xy 362.873766 -225.577981) (xy 362.919782 -225.560529) (xy 362.968001 -225.550685)
			(xy 363.017176 -225.548704) (xy 363.066031 -225.554636) (xy 363.113302 -225.568328) (xy 363.157764 -225.589426)
			(xy 363.198267 -225.617382) (xy 363.23376 -225.651474) (xy 363.263325 -225.690818) (xy 363.286196 -225.734395)
			(xy 363.30178 -225.781076) (xy 363.309675 -225.829653) (xy 363.31017 -225.85426) (xy 364.578912 -225.85426)
			(xy 364.582872 -225.805206) (xy 364.594649 -225.757422) (xy 364.61394 -225.712146) (xy 364.640243 -225.67055)
			(xy 364.672878 -225.633713) (xy 364.710999 -225.602588) (xy 364.75362 -225.577981) (xy 364.799636 -225.560529)
			(xy 364.847855 -225.550685) (xy 364.89703 -225.548704) (xy 364.945885 -225.554636) (xy 364.993156 -225.568328)
			(xy 365.037618 -225.589426) (xy 365.078121 -225.617382) (xy 365.113614 -225.651474) (xy 365.143179 -225.690818)
			(xy 365.16605 -225.734395) (xy 365.181634 -225.781076) (xy 365.189529 -225.829653) (xy 365.190024 -225.85426)
			(xy 365.518966 -225.85426) (xy 365.522926 -225.805206) (xy 365.534703 -225.757422) (xy 365.553994 -225.712146)
			(xy 365.580297 -225.67055) (xy 365.612932 -225.633713) (xy 365.651053 -225.602588) (xy 365.693674 -225.577981)
			(xy 365.73969 -225.560529) (xy 365.787909 -225.550685) (xy 365.837084 -225.548704) (xy 365.885939 -225.554636)
			(xy 365.93321 -225.568328) (xy 365.977672 -225.589426) (xy 366.018175 -225.617382) (xy 366.053668 -225.651474)
			(xy 366.083233 -225.690818) (xy 366.106104 -225.734395) (xy 366.121688 -225.781076) (xy 366.129583 -225.829653)
			(xy 366.130078 -225.85426) (xy 367.399074 -225.85426) (xy 367.403034 -225.805206) (xy 367.414811 -225.757422)
			(xy 367.434102 -225.712146) (xy 367.460405 -225.67055) (xy 367.49304 -225.633713) (xy 367.531161 -225.602588)
			(xy 367.573782 -225.577981) (xy 367.619798 -225.560529) (xy 367.668017 -225.550685) (xy 367.717192 -225.548704)
			(xy 367.766047 -225.554636) (xy 367.813318 -225.568328) (xy 367.85778 -225.589426) (xy 367.898283 -225.617382)
			(xy 367.933776 -225.651474) (xy 367.963341 -225.690818) (xy 367.986212 -225.734395) (xy 368.001796 -225.781076)
			(xy 368.009691 -225.829653) (xy 368.010186 -225.85426) (xy 368.339128 -225.85426) (xy 368.343088 -225.805206)
			(xy 368.354865 -225.757422) (xy 368.374156 -225.712146) (xy 368.400459 -225.67055) (xy 368.433094 -225.633713)
			(xy 368.471215 -225.602588) (xy 368.513836 -225.577981) (xy 368.559852 -225.560529) (xy 368.608071 -225.550685)
			(xy 368.657246 -225.548704) (xy 368.706101 -225.554636) (xy 368.753372 -225.568328) (xy 368.797834 -225.589426)
			(xy 368.838337 -225.617382) (xy 368.87383 -225.651474) (xy 368.903395 -225.690818) (xy 368.926266 -225.734395)
			(xy 368.94185 -225.781076) (xy 368.949745 -225.829653) (xy 368.95024 -225.85426) (xy 368.949745 -225.878867)
			(xy 368.94185 -225.927444) (xy 368.926266 -225.974125) (xy 368.903395 -226.017702) (xy 368.87383 -226.057046)
			(xy 368.838337 -226.091138) (xy 368.797834 -226.119094) (xy 368.753372 -226.140192) (xy 368.706101 -226.153884)
			(xy 368.657246 -226.159816) (xy 368.608071 -226.157835) (xy 368.559852 -226.147991) (xy 368.513836 -226.130539)
			(xy 368.471215 -226.105932) (xy 368.433094 -226.074807) (xy 368.400459 -226.03797) (xy 368.374156 -225.996374)
			(xy 368.354865 -225.951098) (xy 368.343088 -225.903314) (xy 368.339128 -225.85426) (xy 368.010186 -225.85426)
			(xy 368.009691 -225.878867) (xy 368.001796 -225.927444) (xy 367.986212 -225.974125) (xy 367.963341 -226.017702)
			(xy 367.933776 -226.057046) (xy 367.898283 -226.091138) (xy 367.85778 -226.119094) (xy 367.813318 -226.140192)
			(xy 367.766047 -226.153884) (xy 367.717192 -226.159816) (xy 367.668017 -226.157835) (xy 367.619798 -226.147991)
			(xy 367.573782 -226.130539) (xy 367.531161 -226.105932) (xy 367.49304 -226.074807) (xy 367.460405 -226.03797)
			(xy 367.434102 -225.996374) (xy 367.414811 -225.951098) (xy 367.403034 -225.903314) (xy 367.399074 -225.85426)
			(xy 366.130078 -225.85426) (xy 366.129583 -225.878867) (xy 366.121688 -225.927444) (xy 366.106104 -225.974125)
			(xy 366.083233 -226.017702) (xy 366.053668 -226.057046) (xy 366.018175 -226.091138) (xy 365.977672 -226.119094)
			(xy 365.93321 -226.140192) (xy 365.885939 -226.153884) (xy 365.837084 -226.159816) (xy 365.787909 -226.157835)
			(xy 365.73969 -226.147991) (xy 365.693674 -226.130539) (xy 365.651053 -226.105932) (xy 365.612932 -226.074807)
			(xy 365.580297 -226.03797) (xy 365.553994 -225.996374) (xy 365.534703 -225.951098) (xy 365.522926 -225.903314)
			(xy 365.518966 -225.85426) (xy 365.190024 -225.85426) (xy 365.189529 -225.878867) (xy 365.181634 -225.927444)
			(xy 365.16605 -225.974125) (xy 365.143179 -226.017702) (xy 365.113614 -226.057046) (xy 365.078121 -226.091138)
			(xy 365.037618 -226.119094) (xy 364.993156 -226.140192) (xy 364.945885 -226.153884) (xy 364.89703 -226.159816)
			(xy 364.847855 -226.157835) (xy 364.799636 -226.147991) (xy 364.75362 -226.130539) (xy 364.710999 -226.105932)
			(xy 364.672878 -226.074807) (xy 364.640243 -226.03797) (xy 364.61394 -225.996374) (xy 364.594649 -225.951098)
			(xy 364.582872 -225.903314) (xy 364.578912 -225.85426) (xy 363.31017 -225.85426) (xy 363.309675 -225.878867)
			(xy 363.30178 -225.927444) (xy 363.286196 -225.974125) (xy 363.263325 -226.017702) (xy 363.23376 -226.057046)
			(xy 363.198267 -226.091138) (xy 363.157764 -226.119094) (xy 363.113302 -226.140192) (xy 363.066031 -226.153884)
			(xy 363.017176 -226.159816) (xy 362.968001 -226.157835) (xy 362.919782 -226.147991) (xy 362.873766 -226.130539)
			(xy 362.831145 -226.105932) (xy 362.793024 -226.074807) (xy 362.760389 -226.03797) (xy 362.734086 -225.996374)
			(xy 362.714795 -225.951098) (xy 362.703018 -225.903314) (xy 362.699058 -225.85426) (xy 362.370116 -225.85426)
			(xy 362.369621 -225.878867) (xy 362.361726 -225.927444) (xy 362.346142 -225.974125) (xy 362.323271 -226.017702)
			(xy 362.293706 -226.057046) (xy 362.258213 -226.091138) (xy 362.21771 -226.119094) (xy 362.173248 -226.140192)
			(xy 362.125977 -226.153884) (xy 362.077122 -226.159816) (xy 362.027947 -226.157835) (xy 361.979728 -226.147991)
			(xy 361.933712 -226.130539) (xy 361.891091 -226.105932) (xy 361.85297 -226.074807) (xy 361.820335 -226.03797)
			(xy 361.794032 -225.996374) (xy 361.774741 -225.951098) (xy 361.762964 -225.903314) (xy 361.759004 -225.85426)
			(xy 361.430062 -225.85426) (xy 361.429567 -225.878867) (xy 361.421672 -225.927444) (xy 361.406088 -225.974125)
			(xy 361.383217 -226.017702) (xy 361.353652 -226.057046) (xy 361.318159 -226.091138) (xy 361.277656 -226.119094)
			(xy 361.233194 -226.140192) (xy 361.185923 -226.153884) (xy 361.137068 -226.159816) (xy 361.087893 -226.157835)
			(xy 361.039674 -226.147991) (xy 360.993658 -226.130539) (xy 360.951037 -226.105932) (xy 360.912916 -226.074807)
			(xy 360.880281 -226.03797) (xy 360.853978 -225.996374) (xy 360.834687 -225.951098) (xy 360.82291 -225.903314)
			(xy 360.81895 -225.85426) (xy 360.27868 -225.85426) (xy 360.27868 -226.664266) (xy 363.168958 -226.664266)
			(xy 363.172918 -226.615212) (xy 363.184695 -226.567428) (xy 363.203986 -226.522152) (xy 363.230289 -226.480556)
			(xy 363.262924 -226.443719) (xy 363.301045 -226.412594) (xy 363.343666 -226.387987) (xy 363.389682 -226.370535)
			(xy 363.437901 -226.360691) (xy 363.487076 -226.35871) (xy 363.535931 -226.364642) (xy 363.583202 -226.378334)
			(xy 363.627664 -226.399432) (xy 363.668167 -226.427388) (xy 363.70366 -226.46148) (xy 363.733225 -226.500824)
			(xy 363.756096 -226.544401) (xy 363.77168 -226.591082) (xy 363.779575 -226.639659) (xy 363.78007 -226.664266)
			(xy 364.098581 -226.664266) (xy 364.102676 -226.613538) (xy 364.114855 -226.564124) (xy 364.134803 -226.517304)
			(xy 364.162004 -226.47429) (xy 364.195752 -226.436196) (xy 364.235174 -226.404009) (xy 364.279248 -226.378563)
			(xy 364.326834 -226.360516) (xy 364.376698 -226.350336) (xy 364.42755 -226.348287) (xy 364.478071 -226.354421)
			(xy 364.526955 -226.368581) (xy 364.572934 -226.390398) (xy 364.614818 -226.419308) (xy 364.651522 -226.454563)
			(xy 364.682095 -226.495249) (xy 364.705746 -226.540312) (xy 364.721862 -226.588586) (xy 364.730026 -226.63882)
			(xy 364.730538 -226.664266) (xy 365.038635 -226.664266) (xy 365.04273 -226.613538) (xy 365.054909 -226.564124)
			(xy 365.074857 -226.517304) (xy 365.102058 -226.47429) (xy 365.135806 -226.436196) (xy 365.175228 -226.404009)
			(xy 365.219302 -226.378563) (xy 365.266888 -226.360516) (xy 365.316752 -226.350336) (xy 365.367604 -226.348287)
			(xy 365.418125 -226.354421) (xy 365.467009 -226.368581) (xy 365.512988 -226.390398) (xy 365.554872 -226.419308)
			(xy 365.591576 -226.454563) (xy 365.622149 -226.495249) (xy 365.6458 -226.540312) (xy 365.661916 -226.588586)
			(xy 365.67008 -226.63882) (xy 365.670592 -226.664266) (xy 365.98912 -226.664266) (xy 365.99308 -226.615212)
			(xy 366.004857 -226.567428) (xy 366.024148 -226.522152) (xy 366.050451 -226.480556) (xy 366.083086 -226.443719)
			(xy 366.121207 -226.412594) (xy 366.163828 -226.387987) (xy 366.209844 -226.370535) (xy 366.258063 -226.360691)
			(xy 366.307238 -226.35871) (xy 366.356093 -226.364642) (xy 366.403364 -226.378334) (xy 366.447826 -226.399432)
			(xy 366.488329 -226.427388) (xy 366.523822 -226.46148) (xy 366.553387 -226.500824) (xy 366.576258 -226.544401)
			(xy 366.591842 -226.591082) (xy 366.599737 -226.639659) (xy 366.600232 -226.664266) (xy 366.918489 -226.664266)
			(xy 366.922584 -226.613538) (xy 366.934763 -226.564124) (xy 366.954711 -226.517304) (xy 366.981912 -226.47429)
			(xy 367.01566 -226.436196) (xy 367.055082 -226.404009) (xy 367.099156 -226.378563) (xy 367.146742 -226.360516)
			(xy 367.196606 -226.350336) (xy 367.247458 -226.348287) (xy 367.297979 -226.354421) (xy 367.346863 -226.368581)
			(xy 367.392842 -226.390398) (xy 367.434726 -226.419308) (xy 367.47143 -226.454563) (xy 367.502003 -226.495249)
			(xy 367.525654 -226.540312) (xy 367.54177 -226.588586) (xy 367.549934 -226.63882) (xy 367.550446 -226.664266)
			(xy 367.858543 -226.664266) (xy 367.862638 -226.613538) (xy 367.874817 -226.564124) (xy 367.894765 -226.517304)
			(xy 367.921966 -226.47429) (xy 367.955714 -226.436196) (xy 367.995136 -226.404009) (xy 368.03921 -226.378563)
			(xy 368.086796 -226.360516) (xy 368.13666 -226.350336) (xy 368.187512 -226.348287) (xy 368.238033 -226.354421)
			(xy 368.286917 -226.368581) (xy 368.332896 -226.390398) (xy 368.37478 -226.419308) (xy 368.411484 -226.454563)
			(xy 368.442057 -226.495249) (xy 368.465708 -226.540312) (xy 368.481824 -226.588586) (xy 368.489988 -226.63882)
			(xy 368.4905 -226.664266) (xy 368.809028 -226.664266) (xy 368.812988 -226.615212) (xy 368.824765 -226.567428)
			(xy 368.844056 -226.522152) (xy 368.870359 -226.480556) (xy 368.902994 -226.443719) (xy 368.941115 -226.412594)
			(xy 368.983736 -226.387987) (xy 369.029752 -226.370535) (xy 369.077971 -226.360691) (xy 369.127146 -226.35871)
			(xy 369.176001 -226.364642) (xy 369.223272 -226.378334) (xy 369.267734 -226.399432) (xy 369.308237 -226.427388)
			(xy 369.34373 -226.46148) (xy 369.373295 -226.500824) (xy 369.396166 -226.544401) (xy 369.41175 -226.591082)
			(xy 369.419645 -226.639659) (xy 369.42014 -226.664266) (xy 369.738651 -226.664266) (xy 369.742746 -226.613538)
			(xy 369.754925 -226.564124) (xy 369.774873 -226.517304) (xy 369.802074 -226.47429) (xy 369.835822 -226.436196)
			(xy 369.875244 -226.404009) (xy 369.919318 -226.378563) (xy 369.966904 -226.360516) (xy 370.016768 -226.350336)
			(xy 370.06762 -226.348287) (xy 370.118141 -226.354421) (xy 370.167025 -226.368581) (xy 370.213004 -226.390398)
			(xy 370.254888 -226.419308) (xy 370.291592 -226.454563) (xy 370.322165 -226.495249) (xy 370.345816 -226.540312)
			(xy 370.361932 -226.588586) (xy 370.370096 -226.63882) (xy 370.370608 -226.664266) (xy 370.678451 -226.664266)
			(xy 370.682546 -226.613538) (xy 370.694725 -226.564124) (xy 370.714673 -226.517304) (xy 370.741874 -226.47429)
			(xy 370.775622 -226.436196) (xy 370.815044 -226.404009) (xy 370.859118 -226.378563) (xy 370.906704 -226.360516)
			(xy 370.956568 -226.350336) (xy 371.00742 -226.348287) (xy 371.057941 -226.354421) (xy 371.106825 -226.368581)
			(xy 371.152804 -226.390398) (xy 371.194688 -226.419308) (xy 371.231392 -226.454563) (xy 371.261965 -226.495249)
			(xy 371.285616 -226.540312) (xy 371.301732 -226.588586) (xy 371.309896 -226.63882) (xy 371.310408 -226.664266)
			(xy 371.628936 -226.664266) (xy 371.632896 -226.615212) (xy 371.644673 -226.567428) (xy 371.663964 -226.522152)
			(xy 371.690267 -226.480556) (xy 371.722902 -226.443719) (xy 371.761023 -226.412594) (xy 371.803644 -226.387987)
			(xy 371.84966 -226.370535) (xy 371.897879 -226.360691) (xy 371.947054 -226.35871) (xy 371.995909 -226.364642)
			(xy 372.04318 -226.378334) (xy 372.087642 -226.399432) (xy 372.128145 -226.427388) (xy 372.163638 -226.46148)
			(xy 372.193203 -226.500824) (xy 372.216074 -226.544401) (xy 372.231658 -226.591082) (xy 372.239553 -226.639659)
			(xy 372.240048 -226.664266) (xy 372.558559 -226.664266) (xy 372.562654 -226.613538) (xy 372.574833 -226.564124)
			(xy 372.594781 -226.517304) (xy 372.621982 -226.47429) (xy 372.65573 -226.436196) (xy 372.695152 -226.404009)
			(xy 372.739226 -226.378563) (xy 372.786812 -226.360516) (xy 372.836676 -226.350336) (xy 372.887528 -226.348287)
			(xy 372.938049 -226.354421) (xy 372.986933 -226.368581) (xy 373.032912 -226.390398) (xy 373.074796 -226.419308)
			(xy 373.1115 -226.454563) (xy 373.142073 -226.495249) (xy 373.165724 -226.540312) (xy 373.18184 -226.588586)
			(xy 373.190004 -226.63882) (xy 373.190516 -226.664266) (xy 373.498613 -226.664266) (xy 373.502708 -226.613538)
			(xy 373.514887 -226.564124) (xy 373.534835 -226.517304) (xy 373.562036 -226.47429) (xy 373.595784 -226.436196)
			(xy 373.635206 -226.404009) (xy 373.67928 -226.378563) (xy 373.726866 -226.360516) (xy 373.77673 -226.350336)
			(xy 373.827582 -226.348287) (xy 373.878103 -226.354421) (xy 373.926987 -226.368581) (xy 373.972966 -226.390398)
			(xy 374.01485 -226.419308) (xy 374.051554 -226.454563) (xy 374.082127 -226.495249) (xy 374.105778 -226.540312)
			(xy 374.121894 -226.588586) (xy 374.130058 -226.63882) (xy 374.13057 -226.664266) (xy 374.449098 -226.664266)
			(xy 374.453058 -226.615212) (xy 374.464835 -226.567428) (xy 374.484126 -226.522152) (xy 374.510429 -226.480556)
			(xy 374.543064 -226.443719) (xy 374.581185 -226.412594) (xy 374.623806 -226.387987) (xy 374.669822 -226.370535)
			(xy 374.718041 -226.360691) (xy 374.767216 -226.35871) (xy 374.816071 -226.364642) (xy 374.863342 -226.378334)
			(xy 374.907804 -226.399432) (xy 374.948307 -226.427388) (xy 374.9838 -226.46148) (xy 375.013365 -226.500824)
			(xy 375.036236 -226.544401) (xy 375.05182 -226.591082) (xy 375.059715 -226.639659) (xy 375.06021 -226.664266)
			(xy 375.378467 -226.664266) (xy 375.382562 -226.613538) (xy 375.394741 -226.564124) (xy 375.414689 -226.517304)
			(xy 375.44189 -226.47429) (xy 375.475638 -226.436196) (xy 375.51506 -226.404009) (xy 375.559134 -226.378563)
			(xy 375.60672 -226.360516) (xy 375.656584 -226.350336) (xy 375.707436 -226.348287) (xy 375.757957 -226.354421)
			(xy 375.806841 -226.368581) (xy 375.85282 -226.390398) (xy 375.894704 -226.419308) (xy 375.931408 -226.454563)
			(xy 375.961981 -226.495249) (xy 375.985632 -226.540312) (xy 376.001748 -226.588586) (xy 376.009912 -226.63882)
			(xy 376.010424 -226.664266) (xy 376.009912 -226.689712) (xy 376.001748 -226.739946) (xy 375.985632 -226.78822)
			(xy 375.961981 -226.833283) (xy 375.931408 -226.873969) (xy 375.894704 -226.909224) (xy 375.85282 -226.938134)
			(xy 375.806841 -226.959951) (xy 375.757957 -226.974111) (xy 375.707436 -226.980245) (xy 375.656584 -226.978196)
			(xy 375.60672 -226.968016) (xy 375.559134 -226.949969) (xy 375.51506 -226.924523) (xy 375.475638 -226.892336)
			(xy 375.44189 -226.854242) (xy 375.414689 -226.811228) (xy 375.394741 -226.764408) (xy 375.382562 -226.714994)
			(xy 375.378467 -226.664266) (xy 375.06021 -226.664266) (xy 375.059715 -226.688873) (xy 375.05182 -226.73745)
			(xy 375.036236 -226.784131) (xy 375.013365 -226.827708) (xy 374.9838 -226.867052) (xy 374.948307 -226.901144)
			(xy 374.907804 -226.9291) (xy 374.863342 -226.950198) (xy 374.816071 -226.96389) (xy 374.767216 -226.969822)
			(xy 374.718041 -226.967841) (xy 374.669822 -226.957997) (xy 374.623806 -226.940545) (xy 374.581185 -226.915938)
			(xy 374.543064 -226.884813) (xy 374.510429 -226.847976) (xy 374.484126 -226.80638) (xy 374.464835 -226.761104)
			(xy 374.453058 -226.71332) (xy 374.449098 -226.664266) (xy 374.13057 -226.664266) (xy 374.130058 -226.689712)
			(xy 374.121894 -226.739946) (xy 374.105778 -226.78822) (xy 374.082127 -226.833283) (xy 374.051554 -226.873969)
			(xy 374.01485 -226.909224) (xy 373.972966 -226.938134) (xy 373.926987 -226.959951) (xy 373.878103 -226.974111)
			(xy 373.827582 -226.980245) (xy 373.77673 -226.978196) (xy 373.726866 -226.968016) (xy 373.67928 -226.949969)
			(xy 373.635206 -226.924523) (xy 373.595784 -226.892336) (xy 373.562036 -226.854242) (xy 373.534835 -226.811228)
			(xy 373.514887 -226.764408) (xy 373.502708 -226.714994) (xy 373.498613 -226.664266) (xy 373.190516 -226.664266)
			(xy 373.190004 -226.689712) (xy 373.18184 -226.739946) (xy 373.165724 -226.78822) (xy 373.142073 -226.833283)
			(xy 373.1115 -226.873969) (xy 373.074796 -226.909224) (xy 373.032912 -226.938134) (xy 372.986933 -226.959951)
			(xy 372.938049 -226.974111) (xy 372.887528 -226.980245) (xy 372.836676 -226.978196) (xy 372.786812 -226.968016)
			(xy 372.739226 -226.949969) (xy 372.695152 -226.924523) (xy 372.65573 -226.892336) (xy 372.621982 -226.854242)
			(xy 372.594781 -226.811228) (xy 372.574833 -226.764408) (xy 372.562654 -226.714994) (xy 372.558559 -226.664266)
			(xy 372.240048 -226.664266) (xy 372.239553 -226.688873) (xy 372.231658 -226.73745) (xy 372.216074 -226.784131)
			(xy 372.193203 -226.827708) (xy 372.163638 -226.867052) (xy 372.128145 -226.901144) (xy 372.087642 -226.9291)
			(xy 372.04318 -226.950198) (xy 371.995909 -226.96389) (xy 371.947054 -226.969822) (xy 371.897879 -226.967841)
			(xy 371.84966 -226.957997) (xy 371.803644 -226.940545) (xy 371.761023 -226.915938) (xy 371.722902 -226.884813)
			(xy 371.690267 -226.847976) (xy 371.663964 -226.80638) (xy 371.644673 -226.761104) (xy 371.632896 -226.71332)
			(xy 371.628936 -226.664266) (xy 371.310408 -226.664266) (xy 371.309896 -226.689712) (xy 371.301732 -226.739946)
			(xy 371.285616 -226.78822) (xy 371.261965 -226.833283) (xy 371.231392 -226.873969) (xy 371.194688 -226.909224)
			(xy 371.152804 -226.938134) (xy 371.106825 -226.959951) (xy 371.057941 -226.974111) (xy 371.00742 -226.980245)
			(xy 370.956568 -226.978196) (xy 370.906704 -226.968016) (xy 370.859118 -226.949969) (xy 370.815044 -226.924523)
			(xy 370.775622 -226.892336) (xy 370.741874 -226.854242) (xy 370.714673 -226.811228) (xy 370.694725 -226.764408)
			(xy 370.682546 -226.714994) (xy 370.678451 -226.664266) (xy 370.370608 -226.664266) (xy 370.370096 -226.689712)
			(xy 370.361932 -226.739946) (xy 370.345816 -226.78822) (xy 370.322165 -226.833283) (xy 370.291592 -226.873969)
			(xy 370.254888 -226.909224) (xy 370.213004 -226.938134) (xy 370.167025 -226.959951) (xy 370.118141 -226.974111)
			(xy 370.06762 -226.980245) (xy 370.016768 -226.978196) (xy 369.966904 -226.968016) (xy 369.919318 -226.949969)
			(xy 369.875244 -226.924523) (xy 369.835822 -226.892336) (xy 369.802074 -226.854242) (xy 369.774873 -226.811228)
			(xy 369.754925 -226.764408) (xy 369.742746 -226.714994) (xy 369.738651 -226.664266) (xy 369.42014 -226.664266)
			(xy 369.419645 -226.688873) (xy 369.41175 -226.73745) (xy 369.396166 -226.784131) (xy 369.373295 -226.827708)
			(xy 369.34373 -226.867052) (xy 369.308237 -226.901144) (xy 369.267734 -226.9291) (xy 369.223272 -226.950198)
			(xy 369.176001 -226.96389) (xy 369.127146 -226.969822) (xy 369.077971 -226.967841) (xy 369.029752 -226.957997)
			(xy 368.983736 -226.940545) (xy 368.941115 -226.915938) (xy 368.902994 -226.884813) (xy 368.870359 -226.847976)
			(xy 368.844056 -226.80638) (xy 368.824765 -226.761104) (xy 368.812988 -226.71332) (xy 368.809028 -226.664266)
			(xy 368.4905 -226.664266) (xy 368.489988 -226.689712) (xy 368.481824 -226.739946) (xy 368.465708 -226.78822)
			(xy 368.442057 -226.833283) (xy 368.411484 -226.873969) (xy 368.37478 -226.909224) (xy 368.332896 -226.938134)
			(xy 368.286917 -226.959951) (xy 368.238033 -226.974111) (xy 368.187512 -226.980245) (xy 368.13666 -226.978196)
			(xy 368.086796 -226.968016) (xy 368.03921 -226.949969) (xy 367.995136 -226.924523) (xy 367.955714 -226.892336)
			(xy 367.921966 -226.854242) (xy 367.894765 -226.811228) (xy 367.874817 -226.764408) (xy 367.862638 -226.714994)
			(xy 367.858543 -226.664266) (xy 367.550446 -226.664266) (xy 367.549934 -226.689712) (xy 367.54177 -226.739946)
			(xy 367.525654 -226.78822) (xy 367.502003 -226.833283) (xy 367.47143 -226.873969) (xy 367.434726 -226.909224)
			(xy 367.392842 -226.938134) (xy 367.346863 -226.959951) (xy 367.297979 -226.974111) (xy 367.247458 -226.980245)
			(xy 367.196606 -226.978196) (xy 367.146742 -226.968016) (xy 367.099156 -226.949969) (xy 367.055082 -226.924523)
			(xy 367.01566 -226.892336) (xy 366.981912 -226.854242) (xy 366.954711 -226.811228) (xy 366.934763 -226.764408)
			(xy 366.922584 -226.714994) (xy 366.918489 -226.664266) (xy 366.600232 -226.664266) (xy 366.599737 -226.688873)
			(xy 366.591842 -226.73745) (xy 366.576258 -226.784131) (xy 366.553387 -226.827708) (xy 366.523822 -226.867052)
			(xy 366.488329 -226.901144) (xy 366.447826 -226.9291) (xy 366.403364 -226.950198) (xy 366.356093 -226.96389)
			(xy 366.307238 -226.969822) (xy 366.258063 -226.967841) (xy 366.209844 -226.957997) (xy 366.163828 -226.940545)
			(xy 366.121207 -226.915938) (xy 366.083086 -226.884813) (xy 366.050451 -226.847976) (xy 366.024148 -226.80638)
			(xy 366.004857 -226.761104) (xy 365.99308 -226.71332) (xy 365.98912 -226.664266) (xy 365.670592 -226.664266)
			(xy 365.67008 -226.689712) (xy 365.661916 -226.739946) (xy 365.6458 -226.78822) (xy 365.622149 -226.833283)
			(xy 365.591576 -226.873969) (xy 365.554872 -226.909224) (xy 365.512988 -226.938134) (xy 365.467009 -226.959951)
			(xy 365.418125 -226.974111) (xy 365.367604 -226.980245) (xy 365.316752 -226.978196) (xy 365.266888 -226.968016)
			(xy 365.219302 -226.949969) (xy 365.175228 -226.924523) (xy 365.135806 -226.892336) (xy 365.102058 -226.854242)
			(xy 365.074857 -226.811228) (xy 365.054909 -226.764408) (xy 365.04273 -226.714994) (xy 365.038635 -226.664266)
			(xy 364.730538 -226.664266) (xy 364.730026 -226.689712) (xy 364.721862 -226.739946) (xy 364.705746 -226.78822)
			(xy 364.682095 -226.833283) (xy 364.651522 -226.873969) (xy 364.614818 -226.909224) (xy 364.572934 -226.938134)
			(xy 364.526955 -226.959951) (xy 364.478071 -226.974111) (xy 364.42755 -226.980245) (xy 364.376698 -226.978196)
			(xy 364.326834 -226.968016) (xy 364.279248 -226.949969) (xy 364.235174 -226.924523) (xy 364.195752 -226.892336)
			(xy 364.162004 -226.854242) (xy 364.134803 -226.811228) (xy 364.114855 -226.764408) (xy 364.102676 -226.714994)
			(xy 364.098581 -226.664266) (xy 363.78007 -226.664266) (xy 363.779575 -226.688873) (xy 363.77168 -226.73745)
			(xy 363.756096 -226.784131) (xy 363.733225 -226.827708) (xy 363.70366 -226.867052) (xy 363.668167 -226.901144)
			(xy 363.627664 -226.9291) (xy 363.583202 -226.950198) (xy 363.535931 -226.96389) (xy 363.487076 -226.969822)
			(xy 363.437901 -226.967841) (xy 363.389682 -226.957997) (xy 363.343666 -226.940545) (xy 363.301045 -226.915938)
			(xy 363.262924 -226.884813) (xy 363.230289 -226.847976) (xy 363.203986 -226.80638) (xy 363.184695 -226.761104)
			(xy 363.172918 -226.71332) (xy 363.168958 -226.664266) (xy 360.27868 -226.664266) (xy 360.27868 -227.474272)
			(xy 360.81895 -227.474272) (xy 360.82291 -227.425218) (xy 360.834687 -227.377434) (xy 360.853978 -227.332158)
			(xy 360.880281 -227.290562) (xy 360.912916 -227.253725) (xy 360.951037 -227.2226) (xy 360.993658 -227.197993)
			(xy 361.039674 -227.180541) (xy 361.087893 -227.170697) (xy 361.137068 -227.168716) (xy 361.185923 -227.174648)
			(xy 361.233194 -227.18834) (xy 361.277656 -227.209438) (xy 361.318159 -227.237394) (xy 361.353652 -227.271486)
			(xy 361.383217 -227.31083) (xy 361.406088 -227.354407) (xy 361.421672 -227.401088) (xy 361.429567 -227.449665)
			(xy 361.430062 -227.474272) (xy 361.748573 -227.474272) (xy 361.752668 -227.423544) (xy 361.764847 -227.37413)
			(xy 361.784795 -227.32731) (xy 361.811996 -227.284296) (xy 361.845744 -227.246202) (xy 361.885166 -227.214015)
			(xy 361.92924 -227.188569) (xy 361.976826 -227.170522) (xy 362.02669 -227.160342) (xy 362.077542 -227.158293)
			(xy 362.128063 -227.164427) (xy 362.176947 -227.178587) (xy 362.222926 -227.200404) (xy 362.26481 -227.229314)
			(xy 362.301514 -227.264569) (xy 362.332087 -227.305255) (xy 362.355738 -227.350318) (xy 362.371854 -227.398592)
			(xy 362.380018 -227.448826) (xy 362.38053 -227.474272) (xy 362.688627 -227.474272) (xy 362.692722 -227.423544)
			(xy 362.704901 -227.37413) (xy 362.724849 -227.32731) (xy 362.75205 -227.284296) (xy 362.785798 -227.246202)
			(xy 362.82522 -227.214015) (xy 362.869294 -227.188569) (xy 362.91688 -227.170522) (xy 362.966744 -227.160342)
			(xy 363.017596 -227.158293) (xy 363.068117 -227.164427) (xy 363.117001 -227.178587) (xy 363.16298 -227.200404)
			(xy 363.204864 -227.229314) (xy 363.241568 -227.264569) (xy 363.272141 -227.305255) (xy 363.295792 -227.350318)
			(xy 363.311908 -227.398592) (xy 363.320072 -227.448826) (xy 363.320584 -227.474272) (xy 363.639112 -227.474272)
			(xy 363.643072 -227.425218) (xy 363.654849 -227.377434) (xy 363.67414 -227.332158) (xy 363.700443 -227.290562)
			(xy 363.733078 -227.253725) (xy 363.771199 -227.2226) (xy 363.81382 -227.197993) (xy 363.859836 -227.180541)
			(xy 363.908055 -227.170697) (xy 363.95723 -227.168716) (xy 364.006085 -227.174648) (xy 364.053356 -227.18834)
			(xy 364.097818 -227.209438) (xy 364.138321 -227.237394) (xy 364.173814 -227.271486) (xy 364.203379 -227.31083)
			(xy 364.22625 -227.354407) (xy 364.241834 -227.401088) (xy 364.249729 -227.449665) (xy 364.250224 -227.474272)
			(xy 366.45902 -227.474272) (xy 366.46298 -227.425218) (xy 366.474757 -227.377434) (xy 366.494048 -227.332158)
			(xy 366.520351 -227.290562) (xy 366.552986 -227.253725) (xy 366.591107 -227.2226) (xy 366.633728 -227.197993)
			(xy 366.679744 -227.180541) (xy 366.727963 -227.170697) (xy 366.777138 -227.168716) (xy 366.825993 -227.174648)
			(xy 366.873264 -227.18834) (xy 366.917726 -227.209438) (xy 366.958229 -227.237394) (xy 366.993722 -227.271486)
			(xy 367.023287 -227.31083) (xy 367.046158 -227.354407) (xy 367.061742 -227.401088) (xy 367.069637 -227.449665)
			(xy 367.070132 -227.474272) (xy 369.278928 -227.474272) (xy 369.282888 -227.425218) (xy 369.294665 -227.377434)
			(xy 369.313956 -227.332158) (xy 369.340259 -227.290562) (xy 369.372894 -227.253725) (xy 369.411015 -227.2226)
			(xy 369.453636 -227.197993) (xy 369.499652 -227.180541) (xy 369.547871 -227.170697) (xy 369.597046 -227.168716)
			(xy 369.645901 -227.174648) (xy 369.693172 -227.18834) (xy 369.737634 -227.209438) (xy 369.778137 -227.237394)
			(xy 369.81363 -227.271486) (xy 369.843195 -227.31083) (xy 369.866066 -227.354407) (xy 369.88165 -227.401088)
			(xy 369.889545 -227.449665) (xy 369.89004 -227.474272) (xy 372.09909 -227.474272) (xy 372.10305 -227.425218)
			(xy 372.114827 -227.377434) (xy 372.134118 -227.332158) (xy 372.160421 -227.290562) (xy 372.193056 -227.253725)
			(xy 372.231177 -227.2226) (xy 372.273798 -227.197993) (xy 372.319814 -227.180541) (xy 372.368033 -227.170697)
			(xy 372.417208 -227.168716) (xy 372.466063 -227.174648) (xy 372.513334 -227.18834) (xy 372.557796 -227.209438)
			(xy 372.598299 -227.237394) (xy 372.633792 -227.271486) (xy 372.663357 -227.31083) (xy 372.686228 -227.354407)
			(xy 372.701812 -227.401088) (xy 372.709707 -227.449665) (xy 372.710202 -227.474272) (xy 372.709707 -227.498879)
			(xy 372.701812 -227.547456) (xy 372.686228 -227.594137) (xy 372.663357 -227.637714) (xy 372.633792 -227.677058)
			(xy 372.598299 -227.71115) (xy 372.557796 -227.739106) (xy 372.513334 -227.760204) (xy 372.466063 -227.773896)
			(xy 372.417208 -227.779828) (xy 372.368033 -227.777847) (xy 372.319814 -227.768003) (xy 372.273798 -227.750551)
			(xy 372.231177 -227.725944) (xy 372.193056 -227.694819) (xy 372.160421 -227.657982) (xy 372.134118 -227.616386)
			(xy 372.114827 -227.57111) (xy 372.10305 -227.523326) (xy 372.09909 -227.474272) (xy 369.89004 -227.474272)
			(xy 369.889545 -227.498879) (xy 369.88165 -227.547456) (xy 369.866066 -227.594137) (xy 369.843195 -227.637714)
			(xy 369.81363 -227.677058) (xy 369.778137 -227.71115) (xy 369.737634 -227.739106) (xy 369.693172 -227.760204)
			(xy 369.645901 -227.773896) (xy 369.597046 -227.779828) (xy 369.547871 -227.777847) (xy 369.499652 -227.768003)
			(xy 369.453636 -227.750551) (xy 369.411015 -227.725944) (xy 369.372894 -227.694819) (xy 369.340259 -227.657982)
			(xy 369.313956 -227.616386) (xy 369.294665 -227.57111) (xy 369.282888 -227.523326) (xy 369.278928 -227.474272)
			(xy 367.070132 -227.474272) (xy 367.069637 -227.498879) (xy 367.061742 -227.547456) (xy 367.046158 -227.594137)
			(xy 367.023287 -227.637714) (xy 366.993722 -227.677058) (xy 366.958229 -227.71115) (xy 366.917726 -227.739106)
			(xy 366.873264 -227.760204) (xy 366.825993 -227.773896) (xy 366.777138 -227.779828) (xy 366.727963 -227.777847)
			(xy 366.679744 -227.768003) (xy 366.633728 -227.750551) (xy 366.591107 -227.725944) (xy 366.552986 -227.694819)
			(xy 366.520351 -227.657982) (xy 366.494048 -227.616386) (xy 366.474757 -227.57111) (xy 366.46298 -227.523326)
			(xy 366.45902 -227.474272) (xy 364.250224 -227.474272) (xy 364.249729 -227.498879) (xy 364.241834 -227.547456)
			(xy 364.22625 -227.594137) (xy 364.203379 -227.637714) (xy 364.173814 -227.677058) (xy 364.138321 -227.71115)
			(xy 364.097818 -227.739106) (xy 364.053356 -227.760204) (xy 364.006085 -227.773896) (xy 363.95723 -227.779828)
			(xy 363.908055 -227.777847) (xy 363.859836 -227.768003) (xy 363.81382 -227.750551) (xy 363.771199 -227.725944)
			(xy 363.733078 -227.694819) (xy 363.700443 -227.657982) (xy 363.67414 -227.616386) (xy 363.654849 -227.57111)
			(xy 363.643072 -227.523326) (xy 363.639112 -227.474272) (xy 363.320584 -227.474272) (xy 363.320072 -227.499718)
			(xy 363.311908 -227.549952) (xy 363.295792 -227.598226) (xy 363.272141 -227.643289) (xy 363.241568 -227.683975)
			(xy 363.204864 -227.71923) (xy 363.16298 -227.74814) (xy 363.117001 -227.769957) (xy 363.068117 -227.784117)
			(xy 363.017596 -227.790251) (xy 362.966744 -227.788202) (xy 362.91688 -227.778022) (xy 362.869294 -227.759975)
			(xy 362.82522 -227.734529) (xy 362.785798 -227.702342) (xy 362.75205 -227.664248) (xy 362.724849 -227.621234)
			(xy 362.704901 -227.574414) (xy 362.692722 -227.525) (xy 362.688627 -227.474272) (xy 362.38053 -227.474272)
			(xy 362.380018 -227.499718) (xy 362.371854 -227.549952) (xy 362.355738 -227.598226) (xy 362.332087 -227.643289)
			(xy 362.301514 -227.683975) (xy 362.26481 -227.71923) (xy 362.222926 -227.74814) (xy 362.176947 -227.769957)
			(xy 362.128063 -227.784117) (xy 362.077542 -227.790251) (xy 362.02669 -227.788202) (xy 361.976826 -227.778022)
			(xy 361.92924 -227.759975) (xy 361.885166 -227.734529) (xy 361.845744 -227.702342) (xy 361.811996 -227.664248)
			(xy 361.784795 -227.621234) (xy 361.764847 -227.574414) (xy 361.752668 -227.525) (xy 361.748573 -227.474272)
			(xy 361.430062 -227.474272) (xy 361.429567 -227.498879) (xy 361.421672 -227.547456) (xy 361.406088 -227.594137)
			(xy 361.383217 -227.637714) (xy 361.353652 -227.677058) (xy 361.318159 -227.71115) (xy 361.277656 -227.739106)
			(xy 361.233194 -227.760204) (xy 361.185923 -227.773896) (xy 361.137068 -227.779828) (xy 361.087893 -227.777847)
			(xy 361.039674 -227.768003) (xy 360.993658 -227.750551) (xy 360.951037 -227.725944) (xy 360.912916 -227.694819)
			(xy 360.880281 -227.657982) (xy 360.853978 -227.616386) (xy 360.834687 -227.57111) (xy 360.82291 -227.523326)
			(xy 360.81895 -227.474272) (xy 360.27868 -227.474272) (xy 360.27868 -228.284278) (xy 363.168958 -228.284278)
			(xy 363.172918 -228.235224) (xy 363.184695 -228.18744) (xy 363.203986 -228.142164) (xy 363.230289 -228.100568)
			(xy 363.262924 -228.063731) (xy 363.301045 -228.032606) (xy 363.343666 -228.007999) (xy 363.389682 -227.990547)
			(xy 363.437901 -227.980703) (xy 363.487076 -227.978722) (xy 363.535931 -227.984654) (xy 363.583202 -227.998346)
			(xy 363.627664 -228.019444) (xy 363.668167 -228.0474) (xy 363.70366 -228.081492) (xy 363.733225 -228.120836)
			(xy 363.756096 -228.164413) (xy 363.77168 -228.211094) (xy 363.779575 -228.259671) (xy 363.78007 -228.284278)
			(xy 364.098581 -228.284278) (xy 364.102676 -228.23355) (xy 364.114855 -228.184136) (xy 364.134803 -228.137316)
			(xy 364.162004 -228.094302) (xy 364.195752 -228.056208) (xy 364.235174 -228.024021) (xy 364.279248 -227.998575)
			(xy 364.326834 -227.980528) (xy 364.376698 -227.970348) (xy 364.42755 -227.968299) (xy 364.478071 -227.974433)
			(xy 364.526955 -227.988593) (xy 364.572934 -228.01041) (xy 364.614818 -228.03932) (xy 364.651522 -228.074575)
			(xy 364.682095 -228.115261) (xy 364.705746 -228.160324) (xy 364.721862 -228.208598) (xy 364.730026 -228.258832)
			(xy 364.730538 -228.284278) (xy 365.038635 -228.284278) (xy 365.04273 -228.23355) (xy 365.054909 -228.184136)
			(xy 365.074857 -228.137316) (xy 365.102058 -228.094302) (xy 365.135806 -228.056208) (xy 365.175228 -228.024021)
			(xy 365.219302 -227.998575) (xy 365.266888 -227.980528) (xy 365.316752 -227.970348) (xy 365.367604 -227.968299)
			(xy 365.418125 -227.974433) (xy 365.467009 -227.988593) (xy 365.512988 -228.01041) (xy 365.554872 -228.03932)
			(xy 365.591576 -228.074575) (xy 365.622149 -228.115261) (xy 365.6458 -228.160324) (xy 365.661916 -228.208598)
			(xy 365.67008 -228.258832) (xy 365.670592 -228.284278) (xy 365.98912 -228.284278) (xy 365.99308 -228.235224)
			(xy 366.004857 -228.18744) (xy 366.024148 -228.142164) (xy 366.050451 -228.100568) (xy 366.083086 -228.063731)
			(xy 366.121207 -228.032606) (xy 366.163828 -228.007999) (xy 366.209844 -227.990547) (xy 366.258063 -227.980703)
			(xy 366.307238 -227.978722) (xy 366.356093 -227.984654) (xy 366.403364 -227.998346) (xy 366.447826 -228.019444)
			(xy 366.488329 -228.0474) (xy 366.523822 -228.081492) (xy 366.553387 -228.120836) (xy 366.576258 -228.164413)
			(xy 366.591842 -228.211094) (xy 366.599737 -228.259671) (xy 366.600232 -228.284278) (xy 366.918489 -228.284278)
			(xy 366.922584 -228.23355) (xy 366.934763 -228.184136) (xy 366.954711 -228.137316) (xy 366.981912 -228.094302)
			(xy 367.01566 -228.056208) (xy 367.055082 -228.024021) (xy 367.099156 -227.998575) (xy 367.146742 -227.980528)
			(xy 367.196606 -227.970348) (xy 367.247458 -227.968299) (xy 367.297979 -227.974433) (xy 367.346863 -227.988593)
			(xy 367.392842 -228.01041) (xy 367.434726 -228.03932) (xy 367.47143 -228.074575) (xy 367.502003 -228.115261)
			(xy 367.525654 -228.160324) (xy 367.54177 -228.208598) (xy 367.549934 -228.258832) (xy 367.550446 -228.284278)
			(xy 367.858543 -228.284278) (xy 367.862638 -228.23355) (xy 367.874817 -228.184136) (xy 367.894765 -228.137316)
			(xy 367.921966 -228.094302) (xy 367.955714 -228.056208) (xy 367.995136 -228.024021) (xy 368.03921 -227.998575)
			(xy 368.086796 -227.980528) (xy 368.13666 -227.970348) (xy 368.187512 -227.968299) (xy 368.238033 -227.974433)
			(xy 368.286917 -227.988593) (xy 368.332896 -228.01041) (xy 368.37478 -228.03932) (xy 368.411484 -228.074575)
			(xy 368.442057 -228.115261) (xy 368.465708 -228.160324) (xy 368.481824 -228.208598) (xy 368.489988 -228.258832)
			(xy 368.4905 -228.284278) (xy 368.809028 -228.284278) (xy 368.812988 -228.235224) (xy 368.824765 -228.18744)
			(xy 368.844056 -228.142164) (xy 368.870359 -228.100568) (xy 368.902994 -228.063731) (xy 368.941115 -228.032606)
			(xy 368.983736 -228.007999) (xy 369.029752 -227.990547) (xy 369.077971 -227.980703) (xy 369.127146 -227.978722)
			(xy 369.176001 -227.984654) (xy 369.223272 -227.998346) (xy 369.267734 -228.019444) (xy 369.308237 -228.0474)
			(xy 369.34373 -228.081492) (xy 369.373295 -228.120836) (xy 369.396166 -228.164413) (xy 369.41175 -228.211094)
			(xy 369.419645 -228.259671) (xy 369.42014 -228.284278) (xy 369.738651 -228.284278) (xy 369.742746 -228.23355)
			(xy 369.754925 -228.184136) (xy 369.774873 -228.137316) (xy 369.802074 -228.094302) (xy 369.835822 -228.056208)
			(xy 369.875244 -228.024021) (xy 369.919318 -227.998575) (xy 369.966904 -227.980528) (xy 370.016768 -227.970348)
			(xy 370.06762 -227.968299) (xy 370.118141 -227.974433) (xy 370.167025 -227.988593) (xy 370.213004 -228.01041)
			(xy 370.254888 -228.03932) (xy 370.291592 -228.074575) (xy 370.322165 -228.115261) (xy 370.345816 -228.160324)
			(xy 370.361932 -228.208598) (xy 370.370096 -228.258832) (xy 370.370608 -228.284278) (xy 370.678451 -228.284278)
			(xy 370.682546 -228.23355) (xy 370.694725 -228.184136) (xy 370.714673 -228.137316) (xy 370.741874 -228.094302)
			(xy 370.775622 -228.056208) (xy 370.815044 -228.024021) (xy 370.859118 -227.998575) (xy 370.906704 -227.980528)
			(xy 370.956568 -227.970348) (xy 371.00742 -227.968299) (xy 371.057941 -227.974433) (xy 371.106825 -227.988593)
			(xy 371.152804 -228.01041) (xy 371.194688 -228.03932) (xy 371.231392 -228.074575) (xy 371.261965 -228.115261)
			(xy 371.285616 -228.160324) (xy 371.301732 -228.208598) (xy 371.309896 -228.258832) (xy 371.310408 -228.284278)
			(xy 371.628936 -228.284278) (xy 371.632896 -228.235224) (xy 371.644673 -228.18744) (xy 371.663964 -228.142164)
			(xy 371.690267 -228.100568) (xy 371.722902 -228.063731) (xy 371.761023 -228.032606) (xy 371.803644 -228.007999)
			(xy 371.84966 -227.990547) (xy 371.897879 -227.980703) (xy 371.947054 -227.978722) (xy 371.995909 -227.984654)
			(xy 372.04318 -227.998346) (xy 372.087642 -228.019444) (xy 372.128145 -228.0474) (xy 372.163638 -228.081492)
			(xy 372.193203 -228.120836) (xy 372.216074 -228.164413) (xy 372.231658 -228.211094) (xy 372.239553 -228.259671)
			(xy 372.240048 -228.284278) (xy 372.558559 -228.284278) (xy 372.562654 -228.23355) (xy 372.574833 -228.184136)
			(xy 372.594781 -228.137316) (xy 372.621982 -228.094302) (xy 372.65573 -228.056208) (xy 372.695152 -228.024021)
			(xy 372.739226 -227.998575) (xy 372.786812 -227.980528) (xy 372.836676 -227.970348) (xy 372.887528 -227.968299)
			(xy 372.938049 -227.974433) (xy 372.986933 -227.988593) (xy 373.032912 -228.01041) (xy 373.074796 -228.03932)
			(xy 373.1115 -228.074575) (xy 373.142073 -228.115261) (xy 373.165724 -228.160324) (xy 373.18184 -228.208598)
			(xy 373.190004 -228.258832) (xy 373.190516 -228.284278) (xy 373.498613 -228.284278) (xy 373.502708 -228.23355)
			(xy 373.514887 -228.184136) (xy 373.534835 -228.137316) (xy 373.562036 -228.094302) (xy 373.595784 -228.056208)
			(xy 373.635206 -228.024021) (xy 373.67928 -227.998575) (xy 373.726866 -227.980528) (xy 373.77673 -227.970348)
			(xy 373.827582 -227.968299) (xy 373.878103 -227.974433) (xy 373.926987 -227.988593) (xy 373.972966 -228.01041)
			(xy 374.01485 -228.03932) (xy 374.051554 -228.074575) (xy 374.082127 -228.115261) (xy 374.105778 -228.160324)
			(xy 374.121894 -228.208598) (xy 374.130058 -228.258832) (xy 374.13057 -228.284278) (xy 374.130058 -228.309724)
			(xy 374.121894 -228.359958) (xy 374.105778 -228.408232) (xy 374.082127 -228.453295) (xy 374.051554 -228.493981)
			(xy 374.01485 -228.529236) (xy 373.972966 -228.558146) (xy 373.926987 -228.579963) (xy 373.878103 -228.594123)
			(xy 373.827582 -228.600257) (xy 373.77673 -228.598208) (xy 373.726866 -228.588028) (xy 373.67928 -228.569981)
			(xy 373.635206 -228.544535) (xy 373.595784 -228.512348) (xy 373.562036 -228.474254) (xy 373.534835 -228.43124)
			(xy 373.514887 -228.38442) (xy 373.502708 -228.335006) (xy 373.498613 -228.284278) (xy 373.190516 -228.284278)
			(xy 373.190004 -228.309724) (xy 373.18184 -228.359958) (xy 373.165724 -228.408232) (xy 373.142073 -228.453295)
			(xy 373.1115 -228.493981) (xy 373.074796 -228.529236) (xy 373.032912 -228.558146) (xy 372.986933 -228.579963)
			(xy 372.938049 -228.594123) (xy 372.887528 -228.600257) (xy 372.836676 -228.598208) (xy 372.786812 -228.588028)
			(xy 372.739226 -228.569981) (xy 372.695152 -228.544535) (xy 372.65573 -228.512348) (xy 372.621982 -228.474254)
			(xy 372.594781 -228.43124) (xy 372.574833 -228.38442) (xy 372.562654 -228.335006) (xy 372.558559 -228.284278)
			(xy 372.240048 -228.284278) (xy 372.239553 -228.308885) (xy 372.231658 -228.357462) (xy 372.216074 -228.404143)
			(xy 372.193203 -228.44772) (xy 372.163638 -228.487064) (xy 372.128145 -228.521156) (xy 372.087642 -228.549112)
			(xy 372.04318 -228.57021) (xy 371.995909 -228.583902) (xy 371.947054 -228.589834) (xy 371.897879 -228.587853)
			(xy 371.84966 -228.578009) (xy 371.803644 -228.560557) (xy 371.761023 -228.53595) (xy 371.722902 -228.504825)
			(xy 371.690267 -228.467988) (xy 371.663964 -228.426392) (xy 371.644673 -228.381116) (xy 371.632896 -228.333332)
			(xy 371.628936 -228.284278) (xy 371.310408 -228.284278) (xy 371.309896 -228.309724) (xy 371.301732 -228.359958)
			(xy 371.285616 -228.408232) (xy 371.261965 -228.453295) (xy 371.231392 -228.493981) (xy 371.194688 -228.529236)
			(xy 371.152804 -228.558146) (xy 371.106825 -228.579963) (xy 371.057941 -228.594123) (xy 371.00742 -228.600257)
			(xy 370.956568 -228.598208) (xy 370.906704 -228.588028) (xy 370.859118 -228.569981) (xy 370.815044 -228.544535)
			(xy 370.775622 -228.512348) (xy 370.741874 -228.474254) (xy 370.714673 -228.43124) (xy 370.694725 -228.38442)
			(xy 370.682546 -228.335006) (xy 370.678451 -228.284278) (xy 370.370608 -228.284278) (xy 370.370096 -228.309724)
			(xy 370.361932 -228.359958) (xy 370.345816 -228.408232) (xy 370.322165 -228.453295) (xy 370.291592 -228.493981)
			(xy 370.254888 -228.529236) (xy 370.213004 -228.558146) (xy 370.167025 -228.579963) (xy 370.118141 -228.594123)
			(xy 370.06762 -228.600257) (xy 370.016768 -228.598208) (xy 369.966904 -228.588028) (xy 369.919318 -228.569981)
			(xy 369.875244 -228.544535) (xy 369.835822 -228.512348) (xy 369.802074 -228.474254) (xy 369.774873 -228.43124)
			(xy 369.754925 -228.38442) (xy 369.742746 -228.335006) (xy 369.738651 -228.284278) (xy 369.42014 -228.284278)
			(xy 369.419645 -228.308885) (xy 369.41175 -228.357462) (xy 369.396166 -228.404143) (xy 369.373295 -228.44772)
			(xy 369.34373 -228.487064) (xy 369.308237 -228.521156) (xy 369.267734 -228.549112) (xy 369.223272 -228.57021)
			(xy 369.176001 -228.583902) (xy 369.127146 -228.589834) (xy 369.077971 -228.587853) (xy 369.029752 -228.578009)
			(xy 368.983736 -228.560557) (xy 368.941115 -228.53595) (xy 368.902994 -228.504825) (xy 368.870359 -228.467988)
			(xy 368.844056 -228.426392) (xy 368.824765 -228.381116) (xy 368.812988 -228.333332) (xy 368.809028 -228.284278)
			(xy 368.4905 -228.284278) (xy 368.489988 -228.309724) (xy 368.481824 -228.359958) (xy 368.465708 -228.408232)
			(xy 368.442057 -228.453295) (xy 368.411484 -228.493981) (xy 368.37478 -228.529236) (xy 368.332896 -228.558146)
			(xy 368.286917 -228.579963) (xy 368.238033 -228.594123) (xy 368.187512 -228.600257) (xy 368.13666 -228.598208)
			(xy 368.086796 -228.588028) (xy 368.03921 -228.569981) (xy 367.995136 -228.544535) (xy 367.955714 -228.512348)
			(xy 367.921966 -228.474254) (xy 367.894765 -228.43124) (xy 367.874817 -228.38442) (xy 367.862638 -228.335006)
			(xy 367.858543 -228.284278) (xy 367.550446 -228.284278) (xy 367.549934 -228.309724) (xy 367.54177 -228.359958)
			(xy 367.525654 -228.408232) (xy 367.502003 -228.453295) (xy 367.47143 -228.493981) (xy 367.434726 -228.529236)
			(xy 367.392842 -228.558146) (xy 367.346863 -228.579963) (xy 367.297979 -228.594123) (xy 367.247458 -228.600257)
			(xy 367.196606 -228.598208) (xy 367.146742 -228.588028) (xy 367.099156 -228.569981) (xy 367.055082 -228.544535)
			(xy 367.01566 -228.512348) (xy 366.981912 -228.474254) (xy 366.954711 -228.43124) (xy 366.934763 -228.38442)
			(xy 366.922584 -228.335006) (xy 366.918489 -228.284278) (xy 366.600232 -228.284278) (xy 366.599737 -228.308885)
			(xy 366.591842 -228.357462) (xy 366.576258 -228.404143) (xy 366.553387 -228.44772) (xy 366.523822 -228.487064)
			(xy 366.488329 -228.521156) (xy 366.447826 -228.549112) (xy 366.403364 -228.57021) (xy 366.356093 -228.583902)
			(xy 366.307238 -228.589834) (xy 366.258063 -228.587853) (xy 366.209844 -228.578009) (xy 366.163828 -228.560557)
			(xy 366.121207 -228.53595) (xy 366.083086 -228.504825) (xy 366.050451 -228.467988) (xy 366.024148 -228.426392)
			(xy 366.004857 -228.381116) (xy 365.99308 -228.333332) (xy 365.98912 -228.284278) (xy 365.670592 -228.284278)
			(xy 365.67008 -228.309724) (xy 365.661916 -228.359958) (xy 365.6458 -228.408232) (xy 365.622149 -228.453295)
			(xy 365.591576 -228.493981) (xy 365.554872 -228.529236) (xy 365.512988 -228.558146) (xy 365.467009 -228.579963)
			(xy 365.418125 -228.594123) (xy 365.367604 -228.600257) (xy 365.316752 -228.598208) (xy 365.266888 -228.588028)
			(xy 365.219302 -228.569981) (xy 365.175228 -228.544535) (xy 365.135806 -228.512348) (xy 365.102058 -228.474254)
			(xy 365.074857 -228.43124) (xy 365.054909 -228.38442) (xy 365.04273 -228.335006) (xy 365.038635 -228.284278)
			(xy 364.730538 -228.284278) (xy 364.730026 -228.309724) (xy 364.721862 -228.359958) (xy 364.705746 -228.408232)
			(xy 364.682095 -228.453295) (xy 364.651522 -228.493981) (xy 364.614818 -228.529236) (xy 364.572934 -228.558146)
			(xy 364.526955 -228.579963) (xy 364.478071 -228.594123) (xy 364.42755 -228.600257) (xy 364.376698 -228.598208)
			(xy 364.326834 -228.588028) (xy 364.279248 -228.569981) (xy 364.235174 -228.544535) (xy 364.195752 -228.512348)
			(xy 364.162004 -228.474254) (xy 364.134803 -228.43124) (xy 364.114855 -228.38442) (xy 364.102676 -228.335006)
			(xy 364.098581 -228.284278) (xy 363.78007 -228.284278) (xy 363.779575 -228.308885) (xy 363.77168 -228.357462)
			(xy 363.756096 -228.404143) (xy 363.733225 -228.44772) (xy 363.70366 -228.487064) (xy 363.668167 -228.521156)
			(xy 363.627664 -228.549112) (xy 363.583202 -228.57021) (xy 363.535931 -228.583902) (xy 363.487076 -228.589834)
			(xy 363.437901 -228.587853) (xy 363.389682 -228.578009) (xy 363.343666 -228.560557) (xy 363.301045 -228.53595)
			(xy 363.262924 -228.504825) (xy 363.230289 -228.467988) (xy 363.203986 -228.426392) (xy 363.184695 -228.381116)
			(xy 363.172918 -228.333332) (xy 363.168958 -228.284278) (xy 360.27868 -228.284278) (xy 360.27868 -229.094284)
			(xy 360.81895 -229.094284) (xy 360.82291 -229.04523) (xy 360.834687 -228.997446) (xy 360.853978 -228.95217)
			(xy 360.880281 -228.910574) (xy 360.912916 -228.873737) (xy 360.951037 -228.842612) (xy 360.993658 -228.818005)
			(xy 361.039674 -228.800553) (xy 361.087893 -228.790709) (xy 361.137068 -228.788728) (xy 361.185923 -228.79466)
			(xy 361.233194 -228.808352) (xy 361.277656 -228.82945) (xy 361.318159 -228.857406) (xy 361.353652 -228.891498)
			(xy 361.383217 -228.930842) (xy 361.406088 -228.974419) (xy 361.421672 -229.0211) (xy 361.429567 -229.069677)
			(xy 361.430062 -229.094284) (xy 361.748573 -229.094284) (xy 361.752668 -229.043556) (xy 361.764847 -228.994142)
			(xy 361.784795 -228.947322) (xy 361.811996 -228.904308) (xy 361.845744 -228.866214) (xy 361.885166 -228.834027)
			(xy 361.92924 -228.808581) (xy 361.976826 -228.790534) (xy 362.02669 -228.780354) (xy 362.077542 -228.778305)
			(xy 362.128063 -228.784439) (xy 362.176947 -228.798599) (xy 362.222926 -228.820416) (xy 362.26481 -228.849326)
			(xy 362.301514 -228.884581) (xy 362.332087 -228.925267) (xy 362.355738 -228.97033) (xy 362.371854 -229.018604)
			(xy 362.380018 -229.068838) (xy 362.38053 -229.094284) (xy 362.688627 -229.094284) (xy 362.692722 -229.043556)
			(xy 362.704901 -228.994142) (xy 362.724849 -228.947322) (xy 362.75205 -228.904308) (xy 362.785798 -228.866214)
			(xy 362.82522 -228.834027) (xy 362.869294 -228.808581) (xy 362.91688 -228.790534) (xy 362.966744 -228.780354)
			(xy 363.017596 -228.778305) (xy 363.068117 -228.784439) (xy 363.117001 -228.798599) (xy 363.16298 -228.820416)
			(xy 363.204864 -228.849326) (xy 363.241568 -228.884581) (xy 363.272141 -228.925267) (xy 363.295792 -228.97033)
			(xy 363.311908 -229.018604) (xy 363.320072 -229.068838) (xy 363.320584 -229.094284) (xy 363.639112 -229.094284)
			(xy 363.643072 -229.04523) (xy 363.654849 -228.997446) (xy 363.67414 -228.95217) (xy 363.700443 -228.910574)
			(xy 363.733078 -228.873737) (xy 363.771199 -228.842612) (xy 363.81382 -228.818005) (xy 363.859836 -228.800553)
			(xy 363.908055 -228.790709) (xy 363.95723 -228.788728) (xy 364.006085 -228.79466) (xy 364.053356 -228.808352)
			(xy 364.097818 -228.82945) (xy 364.138321 -228.857406) (xy 364.173814 -228.891498) (xy 364.203379 -228.930842)
			(xy 364.22625 -228.974419) (xy 364.241834 -229.0211) (xy 364.249729 -229.069677) (xy 364.250224 -229.094284)
			(xy 364.578912 -229.094284) (xy 364.582872 -229.04523) (xy 364.594649 -228.997446) (xy 364.61394 -228.95217)
			(xy 364.640243 -228.910574) (xy 364.672878 -228.873737) (xy 364.710999 -228.842612) (xy 364.75362 -228.818005)
			(xy 364.799636 -228.800553) (xy 364.847855 -228.790709) (xy 364.89703 -228.788728) (xy 364.945885 -228.79466)
			(xy 364.993156 -228.808352) (xy 365.037618 -228.82945) (xy 365.078121 -228.857406) (xy 365.113614 -228.891498)
			(xy 365.143179 -228.930842) (xy 365.16605 -228.974419) (xy 365.181634 -229.0211) (xy 365.189529 -229.069677)
			(xy 365.190024 -229.094284) (xy 365.518966 -229.094284) (xy 365.522926 -229.04523) (xy 365.534703 -228.997446)
			(xy 365.553994 -228.95217) (xy 365.580297 -228.910574) (xy 365.612932 -228.873737) (xy 365.651053 -228.842612)
			(xy 365.693674 -228.818005) (xy 365.73969 -228.800553) (xy 365.787909 -228.790709) (xy 365.837084 -228.788728)
			(xy 365.885939 -228.79466) (xy 365.93321 -228.808352) (xy 365.977672 -228.82945) (xy 366.018175 -228.857406)
			(xy 366.053668 -228.891498) (xy 366.083233 -228.930842) (xy 366.106104 -228.974419) (xy 366.121688 -229.0211)
			(xy 366.129583 -229.069677) (xy 366.130078 -229.094284) (xy 366.45902 -229.094284) (xy 366.46298 -229.04523)
			(xy 366.474757 -228.997446) (xy 366.494048 -228.95217) (xy 366.520351 -228.910574) (xy 366.552986 -228.873737)
			(xy 366.591107 -228.842612) (xy 366.633728 -228.818005) (xy 366.679744 -228.800553) (xy 366.727963 -228.790709)
			(xy 366.777138 -228.788728) (xy 366.825993 -228.79466) (xy 366.873264 -228.808352) (xy 366.917726 -228.82945)
			(xy 366.958229 -228.857406) (xy 366.993722 -228.891498) (xy 367.023287 -228.930842) (xy 367.046158 -228.974419)
			(xy 367.061742 -229.0211) (xy 367.069637 -229.069677) (xy 367.070132 -229.094284) (xy 367.399074 -229.094284)
			(xy 367.403034 -229.04523) (xy 367.414811 -228.997446) (xy 367.434102 -228.95217) (xy 367.460405 -228.910574)
			(xy 367.49304 -228.873737) (xy 367.531161 -228.842612) (xy 367.573782 -228.818005) (xy 367.619798 -228.800553)
			(xy 367.668017 -228.790709) (xy 367.717192 -228.788728) (xy 367.766047 -228.79466) (xy 367.813318 -228.808352)
			(xy 367.85778 -228.82945) (xy 367.898283 -228.857406) (xy 367.933776 -228.891498) (xy 367.963341 -228.930842)
			(xy 367.986212 -228.974419) (xy 368.001796 -229.0211) (xy 368.009691 -229.069677) (xy 368.010186 -229.094284)
			(xy 368.339128 -229.094284) (xy 368.343088 -229.04523) (xy 368.354865 -228.997446) (xy 368.374156 -228.95217)
			(xy 368.400459 -228.910574) (xy 368.433094 -228.873737) (xy 368.471215 -228.842612) (xy 368.513836 -228.818005)
			(xy 368.559852 -228.800553) (xy 368.608071 -228.790709) (xy 368.657246 -228.788728) (xy 368.706101 -228.79466)
			(xy 368.753372 -228.808352) (xy 368.797834 -228.82945) (xy 368.838337 -228.857406) (xy 368.87383 -228.891498)
			(xy 368.903395 -228.930842) (xy 368.926266 -228.974419) (xy 368.94185 -229.0211) (xy 368.949745 -229.069677)
			(xy 368.95024 -229.094284) (xy 369.278928 -229.094284) (xy 369.282888 -229.04523) (xy 369.294665 -228.997446)
			(xy 369.313956 -228.95217) (xy 369.340259 -228.910574) (xy 369.372894 -228.873737) (xy 369.411015 -228.842612)
			(xy 369.453636 -228.818005) (xy 369.499652 -228.800553) (xy 369.547871 -228.790709) (xy 369.597046 -228.788728)
			(xy 369.645901 -228.79466) (xy 369.693172 -228.808352) (xy 369.737634 -228.82945) (xy 369.778137 -228.857406)
			(xy 369.81363 -228.891498) (xy 369.843195 -228.930842) (xy 369.866066 -228.974419) (xy 369.88165 -229.0211)
			(xy 369.889545 -229.069677) (xy 369.89004 -229.094284) (xy 370.218982 -229.094284) (xy 370.222942 -229.04523)
			(xy 370.234719 -228.997446) (xy 370.25401 -228.95217) (xy 370.280313 -228.910574) (xy 370.312948 -228.873737)
			(xy 370.351069 -228.842612) (xy 370.39369 -228.818005) (xy 370.439706 -228.800553) (xy 370.487925 -228.790709)
			(xy 370.5371 -228.788728) (xy 370.585955 -228.79466) (xy 370.633226 -228.808352) (xy 370.677688 -228.82945)
			(xy 370.718191 -228.857406) (xy 370.753684 -228.891498) (xy 370.783249 -228.930842) (xy 370.80612 -228.974419)
			(xy 370.821704 -229.0211) (xy 370.829599 -229.069677) (xy 370.830094 -229.094284) (xy 371.159036 -229.094284)
			(xy 371.162996 -229.04523) (xy 371.174773 -228.997446) (xy 371.194064 -228.95217) (xy 371.220367 -228.910574)
			(xy 371.253002 -228.873737) (xy 371.291123 -228.842612) (xy 371.333744 -228.818005) (xy 371.37976 -228.800553)
			(xy 371.427979 -228.790709) (xy 371.477154 -228.788728) (xy 371.526009 -228.79466) (xy 371.57328 -228.808352)
			(xy 371.617742 -228.82945) (xy 371.658245 -228.857406) (xy 371.693738 -228.891498) (xy 371.723303 -228.930842)
			(xy 371.746174 -228.974419) (xy 371.761758 -229.0211) (xy 371.769653 -229.069677) (xy 371.770148 -229.094284)
			(xy 372.09909 -229.094284) (xy 372.10305 -229.04523) (xy 372.114827 -228.997446) (xy 372.134118 -228.95217)
			(xy 372.160421 -228.910574) (xy 372.193056 -228.873737) (xy 372.231177 -228.842612) (xy 372.273798 -228.818005)
			(xy 372.319814 -228.800553) (xy 372.368033 -228.790709) (xy 372.417208 -228.788728) (xy 372.466063 -228.79466)
			(xy 372.513334 -228.808352) (xy 372.557796 -228.82945) (xy 372.598299 -228.857406) (xy 372.633792 -228.891498)
			(xy 372.663357 -228.930842) (xy 372.686228 -228.974419) (xy 372.701812 -229.0211) (xy 372.709707 -229.069677)
			(xy 372.710202 -229.094284) (xy 373.03889 -229.094284) (xy 373.04285 -229.04523) (xy 373.054627 -228.997446)
			(xy 373.073918 -228.95217) (xy 373.100221 -228.910574) (xy 373.132856 -228.873737) (xy 373.170977 -228.842612)
			(xy 373.213598 -228.818005) (xy 373.259614 -228.800553) (xy 373.307833 -228.790709) (xy 373.357008 -228.788728)
			(xy 373.405863 -228.79466) (xy 373.453134 -228.808352) (xy 373.497596 -228.82945) (xy 373.538099 -228.857406)
			(xy 373.573592 -228.891498) (xy 373.603157 -228.930842) (xy 373.626028 -228.974419) (xy 373.641612 -229.0211)
			(xy 373.649507 -229.069677) (xy 373.650002 -229.094284) (xy 373.649507 -229.118891) (xy 373.641612 -229.167468)
			(xy 373.626028 -229.214149) (xy 373.603157 -229.257726) (xy 373.573592 -229.29707) (xy 373.538099 -229.331162)
			(xy 373.497596 -229.359118) (xy 373.453134 -229.380216) (xy 373.405863 -229.393908) (xy 373.357008 -229.39984)
			(xy 373.307833 -229.397859) (xy 373.259614 -229.388015) (xy 373.213598 -229.370563) (xy 373.170977 -229.345956)
			(xy 373.132856 -229.314831) (xy 373.100221 -229.277994) (xy 373.073918 -229.236398) (xy 373.054627 -229.191122)
			(xy 373.04285 -229.143338) (xy 373.03889 -229.094284) (xy 372.710202 -229.094284) (xy 372.709707 -229.118891)
			(xy 372.701812 -229.167468) (xy 372.686228 -229.214149) (xy 372.663357 -229.257726) (xy 372.633792 -229.29707)
			(xy 372.598299 -229.331162) (xy 372.557796 -229.359118) (xy 372.513334 -229.380216) (xy 372.466063 -229.393908)
			(xy 372.417208 -229.39984) (xy 372.368033 -229.397859) (xy 372.319814 -229.388015) (xy 372.273798 -229.370563)
			(xy 372.231177 -229.345956) (xy 372.193056 -229.314831) (xy 372.160421 -229.277994) (xy 372.134118 -229.236398)
			(xy 372.114827 -229.191122) (xy 372.10305 -229.143338) (xy 372.09909 -229.094284) (xy 371.770148 -229.094284)
			(xy 371.769653 -229.118891) (xy 371.761758 -229.167468) (xy 371.746174 -229.214149) (xy 371.723303 -229.257726)
			(xy 371.693738 -229.29707) (xy 371.658245 -229.331162) (xy 371.617742 -229.359118) (xy 371.57328 -229.380216)
			(xy 371.526009 -229.393908) (xy 371.477154 -229.39984) (xy 371.427979 -229.397859) (xy 371.37976 -229.388015)
			(xy 371.333744 -229.370563) (xy 371.291123 -229.345956) (xy 371.253002 -229.314831) (xy 371.220367 -229.277994)
			(xy 371.194064 -229.236398) (xy 371.174773 -229.191122) (xy 371.162996 -229.143338) (xy 371.159036 -229.094284)
			(xy 370.830094 -229.094284) (xy 370.829599 -229.118891) (xy 370.821704 -229.167468) (xy 370.80612 -229.214149)
			(xy 370.783249 -229.257726) (xy 370.753684 -229.29707) (xy 370.718191 -229.331162) (xy 370.677688 -229.359118)
			(xy 370.633226 -229.380216) (xy 370.585955 -229.393908) (xy 370.5371 -229.39984) (xy 370.487925 -229.397859)
			(xy 370.439706 -229.388015) (xy 370.39369 -229.370563) (xy 370.351069 -229.345956) (xy 370.312948 -229.314831)
			(xy 370.280313 -229.277994) (xy 370.25401 -229.236398) (xy 370.234719 -229.191122) (xy 370.222942 -229.143338)
			(xy 370.218982 -229.094284) (xy 369.89004 -229.094284) (xy 369.889545 -229.118891) (xy 369.88165 -229.167468)
			(xy 369.866066 -229.214149) (xy 369.843195 -229.257726) (xy 369.81363 -229.29707) (xy 369.778137 -229.331162)
			(xy 369.737634 -229.359118) (xy 369.693172 -229.380216) (xy 369.645901 -229.393908) (xy 369.597046 -229.39984)
			(xy 369.547871 -229.397859) (xy 369.499652 -229.388015) (xy 369.453636 -229.370563) (xy 369.411015 -229.345956)
			(xy 369.372894 -229.314831) (xy 369.340259 -229.277994) (xy 369.313956 -229.236398) (xy 369.294665 -229.191122)
			(xy 369.282888 -229.143338) (xy 369.278928 -229.094284) (xy 368.95024 -229.094284) (xy 368.949745 -229.118891)
			(xy 368.94185 -229.167468) (xy 368.926266 -229.214149) (xy 368.903395 -229.257726) (xy 368.87383 -229.29707)
			(xy 368.838337 -229.331162) (xy 368.797834 -229.359118) (xy 368.753372 -229.380216) (xy 368.706101 -229.393908)
			(xy 368.657246 -229.39984) (xy 368.608071 -229.397859) (xy 368.559852 -229.388015) (xy 368.513836 -229.370563)
			(xy 368.471215 -229.345956) (xy 368.433094 -229.314831) (xy 368.400459 -229.277994) (xy 368.374156 -229.236398)
			(xy 368.354865 -229.191122) (xy 368.343088 -229.143338) (xy 368.339128 -229.094284) (xy 368.010186 -229.094284)
			(xy 368.009691 -229.118891) (xy 368.001796 -229.167468) (xy 367.986212 -229.214149) (xy 367.963341 -229.257726)
			(xy 367.933776 -229.29707) (xy 367.898283 -229.331162) (xy 367.85778 -229.359118) (xy 367.813318 -229.380216)
			(xy 367.766047 -229.393908) (xy 367.717192 -229.39984) (xy 367.668017 -229.397859) (xy 367.619798 -229.388015)
			(xy 367.573782 -229.370563) (xy 367.531161 -229.345956) (xy 367.49304 -229.314831) (xy 367.460405 -229.277994)
			(xy 367.434102 -229.236398) (xy 367.414811 -229.191122) (xy 367.403034 -229.143338) (xy 367.399074 -229.094284)
			(xy 367.070132 -229.094284) (xy 367.069637 -229.118891) (xy 367.061742 -229.167468) (xy 367.046158 -229.214149)
			(xy 367.023287 -229.257726) (xy 366.993722 -229.29707) (xy 366.958229 -229.331162) (xy 366.917726 -229.359118)
			(xy 366.873264 -229.380216) (xy 366.825993 -229.393908) (xy 366.777138 -229.39984) (xy 366.727963 -229.397859)
			(xy 366.679744 -229.388015) (xy 366.633728 -229.370563) (xy 366.591107 -229.345956) (xy 366.552986 -229.314831)
			(xy 366.520351 -229.277994) (xy 366.494048 -229.236398) (xy 366.474757 -229.191122) (xy 366.46298 -229.143338)
			(xy 366.45902 -229.094284) (xy 366.130078 -229.094284) (xy 366.129583 -229.118891) (xy 366.121688 -229.167468)
			(xy 366.106104 -229.214149) (xy 366.083233 -229.257726) (xy 366.053668 -229.29707) (xy 366.018175 -229.331162)
			(xy 365.977672 -229.359118) (xy 365.93321 -229.380216) (xy 365.885939 -229.393908) (xy 365.837084 -229.39984)
			(xy 365.787909 -229.397859) (xy 365.73969 -229.388015) (xy 365.693674 -229.370563) (xy 365.651053 -229.345956)
			(xy 365.612932 -229.314831) (xy 365.580297 -229.277994) (xy 365.553994 -229.236398) (xy 365.534703 -229.191122)
			(xy 365.522926 -229.143338) (xy 365.518966 -229.094284) (xy 365.190024 -229.094284) (xy 365.189529 -229.118891)
			(xy 365.181634 -229.167468) (xy 365.16605 -229.214149) (xy 365.143179 -229.257726) (xy 365.113614 -229.29707)
			(xy 365.078121 -229.331162) (xy 365.037618 -229.359118) (xy 364.993156 -229.380216) (xy 364.945885 -229.393908)
			(xy 364.89703 -229.39984) (xy 364.847855 -229.397859) (xy 364.799636 -229.388015) (xy 364.75362 -229.370563)
			(xy 364.710999 -229.345956) (xy 364.672878 -229.314831) (xy 364.640243 -229.277994) (xy 364.61394 -229.236398)
			(xy 364.594649 -229.191122) (xy 364.582872 -229.143338) (xy 364.578912 -229.094284) (xy 364.250224 -229.094284)
			(xy 364.249729 -229.118891) (xy 364.241834 -229.167468) (xy 364.22625 -229.214149) (xy 364.203379 -229.257726)
			(xy 364.173814 -229.29707) (xy 364.138321 -229.331162) (xy 364.097818 -229.359118) (xy 364.053356 -229.380216)
			(xy 364.006085 -229.393908) (xy 363.95723 -229.39984) (xy 363.908055 -229.397859) (xy 363.859836 -229.388015)
			(xy 363.81382 -229.370563) (xy 363.771199 -229.345956) (xy 363.733078 -229.314831) (xy 363.700443 -229.277994)
			(xy 363.67414 -229.236398) (xy 363.654849 -229.191122) (xy 363.643072 -229.143338) (xy 363.639112 -229.094284)
			(xy 363.320584 -229.094284) (xy 363.320072 -229.11973) (xy 363.311908 -229.169964) (xy 363.295792 -229.218238)
			(xy 363.272141 -229.263301) (xy 363.241568 -229.303987) (xy 363.204864 -229.339242) (xy 363.16298 -229.368152)
			(xy 363.117001 -229.389969) (xy 363.068117 -229.404129) (xy 363.017596 -229.410263) (xy 362.966744 -229.408214)
			(xy 362.91688 -229.398034) (xy 362.869294 -229.379987) (xy 362.82522 -229.354541) (xy 362.785798 -229.322354)
			(xy 362.75205 -229.28426) (xy 362.724849 -229.241246) (xy 362.704901 -229.194426) (xy 362.692722 -229.145012)
			(xy 362.688627 -229.094284) (xy 362.38053 -229.094284) (xy 362.380018 -229.11973) (xy 362.371854 -229.169964)
			(xy 362.355738 -229.218238) (xy 362.332087 -229.263301) (xy 362.301514 -229.303987) (xy 362.26481 -229.339242)
			(xy 362.222926 -229.368152) (xy 362.176947 -229.389969) (xy 362.128063 -229.404129) (xy 362.077542 -229.410263)
			(xy 362.02669 -229.408214) (xy 361.976826 -229.398034) (xy 361.92924 -229.379987) (xy 361.885166 -229.354541)
			(xy 361.845744 -229.322354) (xy 361.811996 -229.28426) (xy 361.784795 -229.241246) (xy 361.764847 -229.194426)
			(xy 361.752668 -229.145012) (xy 361.748573 -229.094284) (xy 361.430062 -229.094284) (xy 361.429567 -229.118891)
			(xy 361.421672 -229.167468) (xy 361.406088 -229.214149) (xy 361.383217 -229.257726) (xy 361.353652 -229.29707)
			(xy 361.318159 -229.331162) (xy 361.277656 -229.359118) (xy 361.233194 -229.380216) (xy 361.185923 -229.393908)
			(xy 361.137068 -229.39984) (xy 361.087893 -229.397859) (xy 361.039674 -229.388015) (xy 360.993658 -229.370563)
			(xy 360.951037 -229.345956) (xy 360.912916 -229.314831) (xy 360.880281 -229.277994) (xy 360.853978 -229.236398)
			(xy 360.834687 -229.191122) (xy 360.82291 -229.143338) (xy 360.81895 -229.094284) (xy 360.27868 -229.094284)
			(xy 360.27868 -229.904036) (xy 361.289104 -229.904036) (xy 361.293064 -229.854982) (xy 361.304841 -229.807198)
			(xy 361.324132 -229.761922) (xy 361.350435 -229.720326) (xy 361.38307 -229.683489) (xy 361.421191 -229.652364)
			(xy 361.463812 -229.627757) (xy 361.509828 -229.610305) (xy 361.558047 -229.600461) (xy 361.607222 -229.59848)
			(xy 361.656077 -229.604412) (xy 361.703348 -229.618104) (xy 361.74781 -229.639202) (xy 361.788313 -229.667158)
			(xy 361.823806 -229.70125) (xy 361.853371 -229.740594) (xy 361.876242 -229.784171) (xy 361.891826 -229.830852)
			(xy 361.899721 -229.879429) (xy 361.900216 -229.904036) (xy 362.228904 -229.904036) (xy 362.232864 -229.854982)
			(xy 362.244641 -229.807198) (xy 362.263932 -229.761922) (xy 362.290235 -229.720326) (xy 362.32287 -229.683489)
			(xy 362.360991 -229.652364) (xy 362.403612 -229.627757) (xy 362.449628 -229.610305) (xy 362.497847 -229.600461)
			(xy 362.547022 -229.59848) (xy 362.595877 -229.604412) (xy 362.643148 -229.618104) (xy 362.68761 -229.639202)
			(xy 362.728113 -229.667158) (xy 362.763606 -229.70125) (xy 362.793171 -229.740594) (xy 362.816042 -229.784171)
			(xy 362.831626 -229.830852) (xy 362.839521 -229.879429) (xy 362.840016 -229.904036) (xy 363.168958 -229.904036)
			(xy 363.172918 -229.854982) (xy 363.184695 -229.807198) (xy 363.203986 -229.761922) (xy 363.230289 -229.720326)
			(xy 363.262924 -229.683489) (xy 363.301045 -229.652364) (xy 363.343666 -229.627757) (xy 363.389682 -229.610305)
			(xy 363.437901 -229.600461) (xy 363.487076 -229.59848) (xy 363.535931 -229.604412) (xy 363.583202 -229.618104)
			(xy 363.627664 -229.639202) (xy 363.668167 -229.667158) (xy 363.70366 -229.70125) (xy 363.733225 -229.740594)
			(xy 363.756096 -229.784171) (xy 363.77168 -229.830852) (xy 363.779575 -229.879429) (xy 363.78007 -229.904036)
			(xy 364.098581 -229.904036) (xy 364.102676 -229.853308) (xy 364.114855 -229.803894) (xy 364.134803 -229.757074)
			(xy 364.162004 -229.71406) (xy 364.195752 -229.675966) (xy 364.235174 -229.643779) (xy 364.279248 -229.618333)
			(xy 364.326834 -229.600286) (xy 364.376698 -229.590106) (xy 364.42755 -229.588057) (xy 364.478071 -229.594191)
			(xy 364.526955 -229.608351) (xy 364.572934 -229.630168) (xy 364.614818 -229.659078) (xy 364.651522 -229.694333)
			(xy 364.682095 -229.735019) (xy 364.705746 -229.780082) (xy 364.721862 -229.828356) (xy 364.730026 -229.87859)
			(xy 364.730538 -229.904036) (xy 365.038635 -229.904036) (xy 365.04273 -229.853308) (xy 365.054909 -229.803894)
			(xy 365.074857 -229.757074) (xy 365.102058 -229.71406) (xy 365.135806 -229.675966) (xy 365.175228 -229.643779)
			(xy 365.219302 -229.618333) (xy 365.266888 -229.600286) (xy 365.316752 -229.590106) (xy 365.367604 -229.588057)
			(xy 365.418125 -229.594191) (xy 365.467009 -229.608351) (xy 365.512988 -229.630168) (xy 365.554872 -229.659078)
			(xy 365.591576 -229.694333) (xy 365.622149 -229.735019) (xy 365.6458 -229.780082) (xy 365.661916 -229.828356)
			(xy 365.67008 -229.87859) (xy 365.670592 -229.904036) (xy 365.98912 -229.904036) (xy 365.99308 -229.854982)
			(xy 366.004857 -229.807198) (xy 366.024148 -229.761922) (xy 366.050451 -229.720326) (xy 366.083086 -229.683489)
			(xy 366.121207 -229.652364) (xy 366.163828 -229.627757) (xy 366.209844 -229.610305) (xy 366.258063 -229.600461)
			(xy 366.307238 -229.59848) (xy 366.356093 -229.604412) (xy 366.403364 -229.618104) (xy 366.447826 -229.639202)
			(xy 366.488329 -229.667158) (xy 366.523822 -229.70125) (xy 366.553387 -229.740594) (xy 366.576258 -229.784171)
			(xy 366.591842 -229.830852) (xy 366.599737 -229.879429) (xy 366.600232 -229.904036) (xy 366.918489 -229.904036)
			(xy 366.922584 -229.853308) (xy 366.934763 -229.803894) (xy 366.954711 -229.757074) (xy 366.981912 -229.71406)
			(xy 367.01566 -229.675966) (xy 367.055082 -229.643779) (xy 367.099156 -229.618333) (xy 367.146742 -229.600286)
			(xy 367.196606 -229.590106) (xy 367.247458 -229.588057) (xy 367.297979 -229.594191) (xy 367.346863 -229.608351)
			(xy 367.392842 -229.630168) (xy 367.434726 -229.659078) (xy 367.47143 -229.694333) (xy 367.502003 -229.735019)
			(xy 367.525654 -229.780082) (xy 367.54177 -229.828356) (xy 367.549934 -229.87859) (xy 367.550446 -229.904036)
			(xy 367.858543 -229.904036) (xy 367.862638 -229.853308) (xy 367.874817 -229.803894) (xy 367.894765 -229.757074)
			(xy 367.921966 -229.71406) (xy 367.955714 -229.675966) (xy 367.995136 -229.643779) (xy 368.03921 -229.618333)
			(xy 368.086796 -229.600286) (xy 368.13666 -229.590106) (xy 368.187512 -229.588057) (xy 368.238033 -229.594191)
			(xy 368.286917 -229.608351) (xy 368.332896 -229.630168) (xy 368.37478 -229.659078) (xy 368.411484 -229.694333)
			(xy 368.442057 -229.735019) (xy 368.465708 -229.780082) (xy 368.481824 -229.828356) (xy 368.489988 -229.87859)
			(xy 368.4905 -229.904036) (xy 368.809028 -229.904036) (xy 368.812988 -229.854982) (xy 368.824765 -229.807198)
			(xy 368.844056 -229.761922) (xy 368.870359 -229.720326) (xy 368.902994 -229.683489) (xy 368.941115 -229.652364)
			(xy 368.983736 -229.627757) (xy 369.029752 -229.610305) (xy 369.077971 -229.600461) (xy 369.127146 -229.59848)
			(xy 369.176001 -229.604412) (xy 369.223272 -229.618104) (xy 369.267734 -229.639202) (xy 369.308237 -229.667158)
			(xy 369.34373 -229.70125) (xy 369.373295 -229.740594) (xy 369.396166 -229.784171) (xy 369.41175 -229.830852)
			(xy 369.419645 -229.879429) (xy 369.42014 -229.904036) (xy 369.738651 -229.904036) (xy 369.742746 -229.853308)
			(xy 369.754925 -229.803894) (xy 369.774873 -229.757074) (xy 369.802074 -229.71406) (xy 369.835822 -229.675966)
			(xy 369.875244 -229.643779) (xy 369.919318 -229.618333) (xy 369.966904 -229.600286) (xy 370.016768 -229.590106)
			(xy 370.06762 -229.588057) (xy 370.118141 -229.594191) (xy 370.167025 -229.608351) (xy 370.213004 -229.630168)
			(xy 370.254888 -229.659078) (xy 370.291592 -229.694333) (xy 370.322165 -229.735019) (xy 370.345816 -229.780082)
			(xy 370.361932 -229.828356) (xy 370.370096 -229.87859) (xy 370.370608 -229.904036) (xy 370.678451 -229.904036)
			(xy 370.682546 -229.853308) (xy 370.694725 -229.803894) (xy 370.714673 -229.757074) (xy 370.741874 -229.71406)
			(xy 370.775622 -229.675966) (xy 370.815044 -229.643779) (xy 370.859118 -229.618333) (xy 370.906704 -229.600286)
			(xy 370.956568 -229.590106) (xy 371.00742 -229.588057) (xy 371.057941 -229.594191) (xy 371.106825 -229.608351)
			(xy 371.152804 -229.630168) (xy 371.194688 -229.659078) (xy 371.231392 -229.694333) (xy 371.261965 -229.735019)
			(xy 371.285616 -229.780082) (xy 371.301732 -229.828356) (xy 371.309896 -229.87859) (xy 371.310408 -229.904036)
			(xy 371.628936 -229.904036) (xy 371.632896 -229.854982) (xy 371.644673 -229.807198) (xy 371.663964 -229.761922)
			(xy 371.690267 -229.720326) (xy 371.722902 -229.683489) (xy 371.761023 -229.652364) (xy 371.803644 -229.627757)
			(xy 371.84966 -229.610305) (xy 371.897879 -229.600461) (xy 371.947054 -229.59848) (xy 371.995909 -229.604412)
			(xy 372.04318 -229.618104) (xy 372.087642 -229.639202) (xy 372.128145 -229.667158) (xy 372.163638 -229.70125)
			(xy 372.193203 -229.740594) (xy 372.216074 -229.784171) (xy 372.231658 -229.830852) (xy 372.239553 -229.879429)
			(xy 372.240048 -229.904036) (xy 372.558559 -229.904036) (xy 372.562654 -229.853308) (xy 372.574833 -229.803894)
			(xy 372.594781 -229.757074) (xy 372.621982 -229.71406) (xy 372.65573 -229.675966) (xy 372.695152 -229.643779)
			(xy 372.739226 -229.618333) (xy 372.786812 -229.600286) (xy 372.836676 -229.590106) (xy 372.887528 -229.588057)
			(xy 372.938049 -229.594191) (xy 372.986933 -229.608351) (xy 373.032912 -229.630168) (xy 373.074796 -229.659078)
			(xy 373.1115 -229.694333) (xy 373.142073 -229.735019) (xy 373.165724 -229.780082) (xy 373.18184 -229.828356)
			(xy 373.190004 -229.87859) (xy 373.190516 -229.904036) (xy 373.498613 -229.904036) (xy 373.502708 -229.853308)
			(xy 373.514887 -229.803894) (xy 373.534835 -229.757074) (xy 373.562036 -229.71406) (xy 373.595784 -229.675966)
			(xy 373.635206 -229.643779) (xy 373.67928 -229.618333) (xy 373.726866 -229.600286) (xy 373.77673 -229.590106)
			(xy 373.827582 -229.588057) (xy 373.878103 -229.594191) (xy 373.926987 -229.608351) (xy 373.972966 -229.630168)
			(xy 374.01485 -229.659078) (xy 374.051554 -229.694333) (xy 374.082127 -229.735019) (xy 374.105778 -229.780082)
			(xy 374.121894 -229.828356) (xy 374.130058 -229.87859) (xy 374.13057 -229.904036) (xy 374.130058 -229.929482)
			(xy 374.121894 -229.979716) (xy 374.105778 -230.02799) (xy 374.082127 -230.073053) (xy 374.051554 -230.113739)
			(xy 374.01485 -230.148994) (xy 373.972966 -230.177904) (xy 373.926987 -230.199721) (xy 373.878103 -230.213881)
			(xy 373.827582 -230.220015) (xy 373.77673 -230.217966) (xy 373.726866 -230.207786) (xy 373.67928 -230.189739)
			(xy 373.635206 -230.164293) (xy 373.595784 -230.132106) (xy 373.562036 -230.094012) (xy 373.534835 -230.050998)
			(xy 373.514887 -230.004178) (xy 373.502708 -229.954764) (xy 373.498613 -229.904036) (xy 373.190516 -229.904036)
			(xy 373.190004 -229.929482) (xy 373.18184 -229.979716) (xy 373.165724 -230.02799) (xy 373.142073 -230.073053)
			(xy 373.1115 -230.113739) (xy 373.074796 -230.148994) (xy 373.032912 -230.177904) (xy 372.986933 -230.199721)
			(xy 372.938049 -230.213881) (xy 372.887528 -230.220015) (xy 372.836676 -230.217966) (xy 372.786812 -230.207786)
			(xy 372.739226 -230.189739) (xy 372.695152 -230.164293) (xy 372.65573 -230.132106) (xy 372.621982 -230.094012)
			(xy 372.594781 -230.050998) (xy 372.574833 -230.004178) (xy 372.562654 -229.954764) (xy 372.558559 -229.904036)
			(xy 372.240048 -229.904036) (xy 372.239553 -229.928643) (xy 372.231658 -229.97722) (xy 372.216074 -230.023901)
			(xy 372.193203 -230.067478) (xy 372.163638 -230.106822) (xy 372.128145 -230.140914) (xy 372.087642 -230.16887)
			(xy 372.04318 -230.189968) (xy 371.995909 -230.20366) (xy 371.947054 -230.209592) (xy 371.897879 -230.207611)
			(xy 371.84966 -230.197767) (xy 371.803644 -230.180315) (xy 371.761023 -230.155708) (xy 371.722902 -230.124583)
			(xy 371.690267 -230.087746) (xy 371.663964 -230.04615) (xy 371.644673 -230.000874) (xy 371.632896 -229.95309)
			(xy 371.628936 -229.904036) (xy 371.310408 -229.904036) (xy 371.309896 -229.929482) (xy 371.301732 -229.979716)
			(xy 371.285616 -230.02799) (xy 371.261965 -230.073053) (xy 371.231392 -230.113739) (xy 371.194688 -230.148994)
			(xy 371.152804 -230.177904) (xy 371.106825 -230.199721) (xy 371.057941 -230.213881) (xy 371.00742 -230.220015)
			(xy 370.956568 -230.217966) (xy 370.906704 -230.207786) (xy 370.859118 -230.189739) (xy 370.815044 -230.164293)
			(xy 370.775622 -230.132106) (xy 370.741874 -230.094012) (xy 370.714673 -230.050998) (xy 370.694725 -230.004178)
			(xy 370.682546 -229.954764) (xy 370.678451 -229.904036) (xy 370.370608 -229.904036) (xy 370.370096 -229.929482)
			(xy 370.361932 -229.979716) (xy 370.345816 -230.02799) (xy 370.322165 -230.073053) (xy 370.291592 -230.113739)
			(xy 370.254888 -230.148994) (xy 370.213004 -230.177904) (xy 370.167025 -230.199721) (xy 370.118141 -230.213881)
			(xy 370.06762 -230.220015) (xy 370.016768 -230.217966) (xy 369.966904 -230.207786) (xy 369.919318 -230.189739)
			(xy 369.875244 -230.164293) (xy 369.835822 -230.132106) (xy 369.802074 -230.094012) (xy 369.774873 -230.050998)
			(xy 369.754925 -230.004178) (xy 369.742746 -229.954764) (xy 369.738651 -229.904036) (xy 369.42014 -229.904036)
			(xy 369.419645 -229.928643) (xy 369.41175 -229.97722) (xy 369.396166 -230.023901) (xy 369.373295 -230.067478)
			(xy 369.34373 -230.106822) (xy 369.308237 -230.140914) (xy 369.267734 -230.16887) (xy 369.223272 -230.189968)
			(xy 369.176001 -230.20366) (xy 369.127146 -230.209592) (xy 369.077971 -230.207611) (xy 369.029752 -230.197767)
			(xy 368.983736 -230.180315) (xy 368.941115 -230.155708) (xy 368.902994 -230.124583) (xy 368.870359 -230.087746)
			(xy 368.844056 -230.04615) (xy 368.824765 -230.000874) (xy 368.812988 -229.95309) (xy 368.809028 -229.904036)
			(xy 368.4905 -229.904036) (xy 368.489988 -229.929482) (xy 368.481824 -229.979716) (xy 368.465708 -230.02799)
			(xy 368.442057 -230.073053) (xy 368.411484 -230.113739) (xy 368.37478 -230.148994) (xy 368.332896 -230.177904)
			(xy 368.286917 -230.199721) (xy 368.238033 -230.213881) (xy 368.187512 -230.220015) (xy 368.13666 -230.217966)
			(xy 368.086796 -230.207786) (xy 368.03921 -230.189739) (xy 367.995136 -230.164293) (xy 367.955714 -230.132106)
			(xy 367.921966 -230.094012) (xy 367.894765 -230.050998) (xy 367.874817 -230.004178) (xy 367.862638 -229.954764)
			(xy 367.858543 -229.904036) (xy 367.550446 -229.904036) (xy 367.549934 -229.929482) (xy 367.54177 -229.979716)
			(xy 367.525654 -230.02799) (xy 367.502003 -230.073053) (xy 367.47143 -230.113739) (xy 367.434726 -230.148994)
			(xy 367.392842 -230.177904) (xy 367.346863 -230.199721) (xy 367.297979 -230.213881) (xy 367.247458 -230.220015)
			(xy 367.196606 -230.217966) (xy 367.146742 -230.207786) (xy 367.099156 -230.189739) (xy 367.055082 -230.164293)
			(xy 367.01566 -230.132106) (xy 366.981912 -230.094012) (xy 366.954711 -230.050998) (xy 366.934763 -230.004178)
			(xy 366.922584 -229.954764) (xy 366.918489 -229.904036) (xy 366.600232 -229.904036) (xy 366.599737 -229.928643)
			(xy 366.591842 -229.97722) (xy 366.576258 -230.023901) (xy 366.553387 -230.067478) (xy 366.523822 -230.106822)
			(xy 366.488329 -230.140914) (xy 366.447826 -230.16887) (xy 366.403364 -230.189968) (xy 366.356093 -230.20366)
			(xy 366.307238 -230.209592) (xy 366.258063 -230.207611) (xy 366.209844 -230.197767) (xy 366.163828 -230.180315)
			(xy 366.121207 -230.155708) (xy 366.083086 -230.124583) (xy 366.050451 -230.087746) (xy 366.024148 -230.04615)
			(xy 366.004857 -230.000874) (xy 365.99308 -229.95309) (xy 365.98912 -229.904036) (xy 365.670592 -229.904036)
			(xy 365.67008 -229.929482) (xy 365.661916 -229.979716) (xy 365.6458 -230.02799) (xy 365.622149 -230.073053)
			(xy 365.591576 -230.113739) (xy 365.554872 -230.148994) (xy 365.512988 -230.177904) (xy 365.467009 -230.199721)
			(xy 365.418125 -230.213881) (xy 365.367604 -230.220015) (xy 365.316752 -230.217966) (xy 365.266888 -230.207786)
			(xy 365.219302 -230.189739) (xy 365.175228 -230.164293) (xy 365.135806 -230.132106) (xy 365.102058 -230.094012)
			(xy 365.074857 -230.050998) (xy 365.054909 -230.004178) (xy 365.04273 -229.954764) (xy 365.038635 -229.904036)
			(xy 364.730538 -229.904036) (xy 364.730026 -229.929482) (xy 364.721862 -229.979716) (xy 364.705746 -230.02799)
			(xy 364.682095 -230.073053) (xy 364.651522 -230.113739) (xy 364.614818 -230.148994) (xy 364.572934 -230.177904)
			(xy 364.526955 -230.199721) (xy 364.478071 -230.213881) (xy 364.42755 -230.220015) (xy 364.376698 -230.217966)
			(xy 364.326834 -230.207786) (xy 364.279248 -230.189739) (xy 364.235174 -230.164293) (xy 364.195752 -230.132106)
			(xy 364.162004 -230.094012) (xy 364.134803 -230.050998) (xy 364.114855 -230.004178) (xy 364.102676 -229.954764)
			(xy 364.098581 -229.904036) (xy 363.78007 -229.904036) (xy 363.779575 -229.928643) (xy 363.77168 -229.97722)
			(xy 363.756096 -230.023901) (xy 363.733225 -230.067478) (xy 363.70366 -230.106822) (xy 363.668167 -230.140914)
			(xy 363.627664 -230.16887) (xy 363.583202 -230.189968) (xy 363.535931 -230.20366) (xy 363.487076 -230.209592)
			(xy 363.437901 -230.207611) (xy 363.389682 -230.197767) (xy 363.343666 -230.180315) (xy 363.301045 -230.155708)
			(xy 363.262924 -230.124583) (xy 363.230289 -230.087746) (xy 363.203986 -230.04615) (xy 363.184695 -230.000874)
			(xy 363.172918 -229.95309) (xy 363.168958 -229.904036) (xy 362.840016 -229.904036) (xy 362.839521 -229.928643)
			(xy 362.831626 -229.97722) (xy 362.816042 -230.023901) (xy 362.793171 -230.067478) (xy 362.763606 -230.106822)
			(xy 362.728113 -230.140914) (xy 362.68761 -230.16887) (xy 362.643148 -230.189968) (xy 362.595877 -230.20366)
			(xy 362.547022 -230.209592) (xy 362.497847 -230.207611) (xy 362.449628 -230.197767) (xy 362.403612 -230.180315)
			(xy 362.360991 -230.155708) (xy 362.32287 -230.124583) (xy 362.290235 -230.087746) (xy 362.263932 -230.04615)
			(xy 362.244641 -230.000874) (xy 362.232864 -229.95309) (xy 362.228904 -229.904036) (xy 361.900216 -229.904036)
			(xy 361.899721 -229.928643) (xy 361.891826 -229.97722) (xy 361.876242 -230.023901) (xy 361.853371 -230.067478)
			(xy 361.823806 -230.106822) (xy 361.788313 -230.140914) (xy 361.74781 -230.16887) (xy 361.703348 -230.189968)
			(xy 361.656077 -230.20366) (xy 361.607222 -230.209592) (xy 361.558047 -230.207611) (xy 361.509828 -230.197767)
			(xy 361.463812 -230.180315) (xy 361.421191 -230.155708) (xy 361.38307 -230.124583) (xy 361.350435 -230.087746)
			(xy 361.324132 -230.04615) (xy 361.304841 -230.000874) (xy 361.293064 -229.95309) (xy 361.289104 -229.904036)
			(xy 360.27868 -229.904036) (xy 360.27868 -230.714296) (xy 360.81895 -230.714296) (xy 360.82291 -230.665242)
			(xy 360.834687 -230.617458) (xy 360.853978 -230.572182) (xy 360.880281 -230.530586) (xy 360.912916 -230.493749)
			(xy 360.951037 -230.462624) (xy 360.993658 -230.438017) (xy 361.039674 -230.420565) (xy 361.087893 -230.410721)
			(xy 361.137068 -230.40874) (xy 361.185923 -230.414672) (xy 361.233194 -230.428364) (xy 361.277656 -230.449462)
			(xy 361.318159 -230.477418) (xy 361.353652 -230.51151) (xy 361.383217 -230.550854) (xy 361.406088 -230.594431)
			(xy 361.421672 -230.641112) (xy 361.429567 -230.689689) (xy 361.430062 -230.714296) (xy 361.748573 -230.714296)
			(xy 361.752668 -230.663568) (xy 361.764847 -230.614154) (xy 361.784795 -230.567334) (xy 361.811996 -230.52432)
			(xy 361.845744 -230.486226) (xy 361.885166 -230.454039) (xy 361.92924 -230.428593) (xy 361.976826 -230.410546)
			(xy 362.02669 -230.400366) (xy 362.077542 -230.398317) (xy 362.128063 -230.404451) (xy 362.176947 -230.418611)
			(xy 362.222926 -230.440428) (xy 362.26481 -230.469338) (xy 362.301514 -230.504593) (xy 362.332087 -230.545279)
			(xy 362.355738 -230.590342) (xy 362.371854 -230.638616) (xy 362.380018 -230.68885) (xy 362.38053 -230.714296)
			(xy 362.688627 -230.714296) (xy 362.692722 -230.663568) (xy 362.704901 -230.614154) (xy 362.724849 -230.567334)
			(xy 362.75205 -230.52432) (xy 362.785798 -230.486226) (xy 362.82522 -230.454039) (xy 362.869294 -230.428593)
			(xy 362.91688 -230.410546) (xy 362.966744 -230.400366) (xy 363.017596 -230.398317) (xy 363.068117 -230.404451)
			(xy 363.117001 -230.418611) (xy 363.16298 -230.440428) (xy 363.204864 -230.469338) (xy 363.241568 -230.504593)
			(xy 363.272141 -230.545279) (xy 363.295792 -230.590342) (xy 363.311908 -230.638616) (xy 363.320072 -230.68885)
			(xy 363.320579 -230.714042) (xy 363.639112 -230.714042) (xy 363.643072 -230.664988) (xy 363.654849 -230.617204)
			(xy 363.67414 -230.571928) (xy 363.700443 -230.530332) (xy 363.733078 -230.493495) (xy 363.771199 -230.46237)
			(xy 363.81382 -230.437763) (xy 363.859836 -230.420311) (xy 363.908055 -230.410467) (xy 363.95723 -230.408486)
			(xy 364.006085 -230.414418) (xy 364.053356 -230.42811) (xy 364.097818 -230.449208) (xy 364.138321 -230.477164)
			(xy 364.173814 -230.511256) (xy 364.203379 -230.5506) (xy 364.22625 -230.594177) (xy 364.241834 -230.640858)
			(xy 364.249729 -230.689435) (xy 364.250224 -230.714042) (xy 364.250219 -230.714296) (xy 366.45902 -230.714296)
			(xy 366.46298 -230.665242) (xy 366.474757 -230.617458) (xy 366.494048 -230.572182) (xy 366.520351 -230.530586)
			(xy 366.552986 -230.493749) (xy 366.591107 -230.462624) (xy 366.633728 -230.438017) (xy 366.679744 -230.420565)
			(xy 366.727963 -230.410721) (xy 366.777138 -230.40874) (xy 366.825993 -230.414672) (xy 366.873264 -230.428364)
			(xy 366.917726 -230.449462) (xy 366.958229 -230.477418) (xy 366.993722 -230.51151) (xy 367.023287 -230.550854)
			(xy 367.046158 -230.594431) (xy 367.061742 -230.641112) (xy 367.069637 -230.689689) (xy 367.070132 -230.714296)
			(xy 369.278928 -230.714296) (xy 369.282888 -230.665242) (xy 369.294665 -230.617458) (xy 369.313956 -230.572182)
			(xy 369.340259 -230.530586) (xy 369.372894 -230.493749) (xy 369.411015 -230.462624) (xy 369.453636 -230.438017)
			(xy 369.499652 -230.420565) (xy 369.547871 -230.410721) (xy 369.597046 -230.40874) (xy 369.645901 -230.414672)
			(xy 369.693172 -230.428364) (xy 369.737634 -230.449462) (xy 369.778137 -230.477418) (xy 369.81363 -230.51151)
			(xy 369.843195 -230.550854) (xy 369.866066 -230.594431) (xy 369.88165 -230.641112) (xy 369.889545 -230.689689)
			(xy 369.890035 -230.714042) (xy 372.09909 -230.714042) (xy 372.10305 -230.664988) (xy 372.114827 -230.617204)
			(xy 372.134118 -230.571928) (xy 372.160421 -230.530332) (xy 372.193056 -230.493495) (xy 372.231177 -230.46237)
			(xy 372.273798 -230.437763) (xy 372.319814 -230.420311) (xy 372.368033 -230.410467) (xy 372.417208 -230.408486)
			(xy 372.466063 -230.414418) (xy 372.513334 -230.42811) (xy 372.557796 -230.449208) (xy 372.598299 -230.477164)
			(xy 372.633792 -230.511256) (xy 372.663357 -230.5506) (xy 372.686228 -230.594177) (xy 372.701812 -230.640858)
			(xy 372.709707 -230.689435) (xy 372.710202 -230.714042) (xy 372.709707 -230.738649) (xy 372.701812 -230.787226)
			(xy 372.686228 -230.833907) (xy 372.663357 -230.877484) (xy 372.633792 -230.916828) (xy 372.598299 -230.95092)
			(xy 372.557796 -230.978876) (xy 372.513334 -230.999974) (xy 372.466063 -231.013666) (xy 372.417208 -231.019598)
			(xy 372.368033 -231.017617) (xy 372.319814 -231.007773) (xy 372.273798 -230.990321) (xy 372.231177 -230.965714)
			(xy 372.193056 -230.934589) (xy 372.160421 -230.897752) (xy 372.134118 -230.856156) (xy 372.114827 -230.81088)
			(xy 372.10305 -230.763096) (xy 372.09909 -230.714042) (xy 369.890035 -230.714042) (xy 369.89004 -230.714296)
			(xy 369.889545 -230.738903) (xy 369.88165 -230.78748) (xy 369.866066 -230.834161) (xy 369.843195 -230.877738)
			(xy 369.81363 -230.917082) (xy 369.778137 -230.951174) (xy 369.737634 -230.97913) (xy 369.693172 -231.000228)
			(xy 369.645901 -231.01392) (xy 369.597046 -231.019852) (xy 369.547871 -231.017871) (xy 369.499652 -231.008027)
			(xy 369.453636 -230.990575) (xy 369.411015 -230.965968) (xy 369.372894 -230.934843) (xy 369.340259 -230.898006)
			(xy 369.313956 -230.85641) (xy 369.294665 -230.811134) (xy 369.282888 -230.76335) (xy 369.278928 -230.714296)
			(xy 367.070132 -230.714296) (xy 367.069637 -230.738903) (xy 367.061742 -230.78748) (xy 367.046158 -230.834161)
			(xy 367.023287 -230.877738) (xy 366.993722 -230.917082) (xy 366.958229 -230.951174) (xy 366.917726 -230.97913)
			(xy 366.873264 -231.000228) (xy 366.825993 -231.01392) (xy 366.777138 -231.019852) (xy 366.727963 -231.017871)
			(xy 366.679744 -231.008027) (xy 366.633728 -230.990575) (xy 366.591107 -230.965968) (xy 366.552986 -230.934843)
			(xy 366.520351 -230.898006) (xy 366.494048 -230.85641) (xy 366.474757 -230.811134) (xy 366.46298 -230.76335)
			(xy 366.45902 -230.714296) (xy 364.250219 -230.714296) (xy 364.249729 -230.738649) (xy 364.241834 -230.787226)
			(xy 364.22625 -230.833907) (xy 364.203379 -230.877484) (xy 364.173814 -230.916828) (xy 364.138321 -230.95092)
			(xy 364.097818 -230.978876) (xy 364.053356 -230.999974) (xy 364.006085 -231.013666) (xy 363.95723 -231.019598)
			(xy 363.908055 -231.017617) (xy 363.859836 -231.007773) (xy 363.81382 -230.990321) (xy 363.771199 -230.965714)
			(xy 363.733078 -230.934589) (xy 363.700443 -230.897752) (xy 363.67414 -230.856156) (xy 363.654849 -230.81088)
			(xy 363.643072 -230.763096) (xy 363.639112 -230.714042) (xy 363.320579 -230.714042) (xy 363.320584 -230.714296)
			(xy 363.320072 -230.739742) (xy 363.311908 -230.789976) (xy 363.295792 -230.83825) (xy 363.272141 -230.883313)
			(xy 363.241568 -230.923999) (xy 363.204864 -230.959254) (xy 363.16298 -230.988164) (xy 363.117001 -231.009981)
			(xy 363.068117 -231.024141) (xy 363.017596 -231.030275) (xy 362.966744 -231.028226) (xy 362.91688 -231.018046)
			(xy 362.869294 -230.999999) (xy 362.82522 -230.974553) (xy 362.785798 -230.942366) (xy 362.75205 -230.904272)
			(xy 362.724849 -230.861258) (xy 362.704901 -230.814438) (xy 362.692722 -230.765024) (xy 362.688627 -230.714296)
			(xy 362.38053 -230.714296) (xy 362.380018 -230.739742) (xy 362.371854 -230.789976) (xy 362.355738 -230.83825)
			(xy 362.332087 -230.883313) (xy 362.301514 -230.923999) (xy 362.26481 -230.959254) (xy 362.222926 -230.988164)
			(xy 362.176947 -231.009981) (xy 362.128063 -231.024141) (xy 362.077542 -231.030275) (xy 362.02669 -231.028226)
			(xy 361.976826 -231.018046) (xy 361.92924 -230.999999) (xy 361.885166 -230.974553) (xy 361.845744 -230.942366)
			(xy 361.811996 -230.904272) (xy 361.784795 -230.861258) (xy 361.764847 -230.814438) (xy 361.752668 -230.765024)
			(xy 361.748573 -230.714296) (xy 361.430062 -230.714296) (xy 361.429567 -230.738903) (xy 361.421672 -230.78748)
			(xy 361.406088 -230.834161) (xy 361.383217 -230.877738) (xy 361.353652 -230.917082) (xy 361.318159 -230.951174)
			(xy 361.277656 -230.97913) (xy 361.233194 -231.000228) (xy 361.185923 -231.01392) (xy 361.137068 -231.019852)
			(xy 361.087893 -231.017871) (xy 361.039674 -231.008027) (xy 360.993658 -230.990575) (xy 360.951037 -230.965968)
			(xy 360.912916 -230.934843) (xy 360.880281 -230.898006) (xy 360.853978 -230.85641) (xy 360.834687 -230.811134)
			(xy 360.82291 -230.76335) (xy 360.81895 -230.714296) (xy 360.27868 -230.714296) (xy 360.27868 -231.524048)
			(xy 363.168958 -231.524048) (xy 363.172918 -231.474994) (xy 363.184695 -231.42721) (xy 363.203986 -231.381934)
			(xy 363.230289 -231.340338) (xy 363.262924 -231.303501) (xy 363.301045 -231.272376) (xy 363.343666 -231.247769)
			(xy 363.389682 -231.230317) (xy 363.437901 -231.220473) (xy 363.487076 -231.218492) (xy 363.535931 -231.224424)
			(xy 363.583202 -231.238116) (xy 363.627664 -231.259214) (xy 363.668167 -231.28717) (xy 363.70366 -231.321262)
			(xy 363.733225 -231.360606) (xy 363.756096 -231.404183) (xy 363.77168 -231.450864) (xy 363.779575 -231.499441)
			(xy 363.78007 -231.524048) (xy 364.098581 -231.524048) (xy 364.102676 -231.47332) (xy 364.114855 -231.423906)
			(xy 364.134803 -231.377086) (xy 364.162004 -231.334072) (xy 364.195752 -231.295978) (xy 364.235174 -231.263791)
			(xy 364.279248 -231.238345) (xy 364.326834 -231.220298) (xy 364.376698 -231.210118) (xy 364.42755 -231.208069)
			(xy 364.478071 -231.214203) (xy 364.526955 -231.228363) (xy 364.572934 -231.25018) (xy 364.614818 -231.27909)
			(xy 364.651522 -231.314345) (xy 364.682095 -231.355031) (xy 364.705746 -231.400094) (xy 364.721862 -231.448368)
			(xy 364.730026 -231.498602) (xy 364.730538 -231.524048) (xy 365.038635 -231.524048) (xy 365.04273 -231.47332)
			(xy 365.054909 -231.423906) (xy 365.074857 -231.377086) (xy 365.102058 -231.334072) (xy 365.135806 -231.295978)
			(xy 365.175228 -231.263791) (xy 365.219302 -231.238345) (xy 365.266888 -231.220298) (xy 365.316752 -231.210118)
			(xy 365.367604 -231.208069) (xy 365.418125 -231.214203) (xy 365.467009 -231.228363) (xy 365.512988 -231.25018)
			(xy 365.554872 -231.27909) (xy 365.591576 -231.314345) (xy 365.622149 -231.355031) (xy 365.6458 -231.400094)
			(xy 365.661916 -231.448368) (xy 365.67008 -231.498602) (xy 365.670592 -231.524048) (xy 365.98912 -231.524048)
			(xy 365.99308 -231.474994) (xy 366.004857 -231.42721) (xy 366.024148 -231.381934) (xy 366.050451 -231.340338)
			(xy 366.083086 -231.303501) (xy 366.121207 -231.272376) (xy 366.163828 -231.247769) (xy 366.209844 -231.230317)
			(xy 366.258063 -231.220473) (xy 366.307238 -231.218492) (xy 366.356093 -231.224424) (xy 366.403364 -231.238116)
			(xy 366.447826 -231.259214) (xy 366.488329 -231.28717) (xy 366.523822 -231.321262) (xy 366.553387 -231.360606)
			(xy 366.576258 -231.404183) (xy 366.591842 -231.450864) (xy 366.599737 -231.499441) (xy 366.600232 -231.524048)
			(xy 366.918489 -231.524048) (xy 366.922584 -231.47332) (xy 366.934763 -231.423906) (xy 366.954711 -231.377086)
			(xy 366.981912 -231.334072) (xy 367.01566 -231.295978) (xy 367.055082 -231.263791) (xy 367.099156 -231.238345)
			(xy 367.146742 -231.220298) (xy 367.196606 -231.210118) (xy 367.247458 -231.208069) (xy 367.297979 -231.214203)
			(xy 367.346863 -231.228363) (xy 367.392842 -231.25018) (xy 367.434726 -231.27909) (xy 367.47143 -231.314345)
			(xy 367.502003 -231.355031) (xy 367.525654 -231.400094) (xy 367.54177 -231.448368) (xy 367.549934 -231.498602)
			(xy 367.550446 -231.524048) (xy 367.858543 -231.524048) (xy 367.862638 -231.47332) (xy 367.874817 -231.423906)
			(xy 367.894765 -231.377086) (xy 367.921966 -231.334072) (xy 367.955714 -231.295978) (xy 367.995136 -231.263791)
			(xy 368.03921 -231.238345) (xy 368.086796 -231.220298) (xy 368.13666 -231.210118) (xy 368.187512 -231.208069)
			(xy 368.238033 -231.214203) (xy 368.286917 -231.228363) (xy 368.332896 -231.25018) (xy 368.37478 -231.27909)
			(xy 368.411484 -231.314345) (xy 368.442057 -231.355031) (xy 368.465708 -231.400094) (xy 368.481824 -231.448368)
			(xy 368.489988 -231.498602) (xy 368.4905 -231.524048) (xy 368.809028 -231.524048) (xy 368.812988 -231.474994)
			(xy 368.824765 -231.42721) (xy 368.844056 -231.381934) (xy 368.870359 -231.340338) (xy 368.902994 -231.303501)
			(xy 368.941115 -231.272376) (xy 368.983736 -231.247769) (xy 369.029752 -231.230317) (xy 369.077971 -231.220473)
			(xy 369.127146 -231.218492) (xy 369.176001 -231.224424) (xy 369.223272 -231.238116) (xy 369.267734 -231.259214)
			(xy 369.308237 -231.28717) (xy 369.34373 -231.321262) (xy 369.373295 -231.360606) (xy 369.396166 -231.404183)
			(xy 369.41175 -231.450864) (xy 369.419645 -231.499441) (xy 369.42014 -231.524048) (xy 369.738651 -231.524048)
			(xy 369.742746 -231.47332) (xy 369.754925 -231.423906) (xy 369.774873 -231.377086) (xy 369.802074 -231.334072)
			(xy 369.835822 -231.295978) (xy 369.875244 -231.263791) (xy 369.919318 -231.238345) (xy 369.966904 -231.220298)
			(xy 370.016768 -231.210118) (xy 370.06762 -231.208069) (xy 370.118141 -231.214203) (xy 370.167025 -231.228363)
			(xy 370.213004 -231.25018) (xy 370.254888 -231.27909) (xy 370.291592 -231.314345) (xy 370.322165 -231.355031)
			(xy 370.345816 -231.400094) (xy 370.361932 -231.448368) (xy 370.370096 -231.498602) (xy 370.370608 -231.524048)
			(xy 370.678451 -231.524048) (xy 370.682546 -231.47332) (xy 370.694725 -231.423906) (xy 370.714673 -231.377086)
			(xy 370.741874 -231.334072) (xy 370.775622 -231.295978) (xy 370.815044 -231.263791) (xy 370.859118 -231.238345)
			(xy 370.906704 -231.220298) (xy 370.956568 -231.210118) (xy 371.00742 -231.208069) (xy 371.057941 -231.214203)
			(xy 371.106825 -231.228363) (xy 371.152804 -231.25018) (xy 371.194688 -231.27909) (xy 371.231392 -231.314345)
			(xy 371.261965 -231.355031) (xy 371.285616 -231.400094) (xy 371.301732 -231.448368) (xy 371.309896 -231.498602)
			(xy 371.310408 -231.524048) (xy 371.628936 -231.524048) (xy 371.632896 -231.474994) (xy 371.644673 -231.42721)
			(xy 371.663964 -231.381934) (xy 371.690267 -231.340338) (xy 371.722902 -231.303501) (xy 371.761023 -231.272376)
			(xy 371.803644 -231.247769) (xy 371.84966 -231.230317) (xy 371.897879 -231.220473) (xy 371.947054 -231.218492)
			(xy 371.995909 -231.224424) (xy 372.04318 -231.238116) (xy 372.087642 -231.259214) (xy 372.128145 -231.28717)
			(xy 372.163638 -231.321262) (xy 372.193203 -231.360606) (xy 372.216074 -231.404183) (xy 372.231658 -231.450864)
			(xy 372.239553 -231.499441) (xy 372.240048 -231.524048) (xy 372.558559 -231.524048) (xy 372.562654 -231.47332)
			(xy 372.574833 -231.423906) (xy 372.594781 -231.377086) (xy 372.621982 -231.334072) (xy 372.65573 -231.295978)
			(xy 372.695152 -231.263791) (xy 372.739226 -231.238345) (xy 372.786812 -231.220298) (xy 372.836676 -231.210118)
			(xy 372.887528 -231.208069) (xy 372.938049 -231.214203) (xy 372.986933 -231.228363) (xy 373.032912 -231.25018)
			(xy 373.074796 -231.27909) (xy 373.1115 -231.314345) (xy 373.142073 -231.355031) (xy 373.165724 -231.400094)
			(xy 373.18184 -231.448368) (xy 373.190004 -231.498602) (xy 373.190516 -231.524048) (xy 373.498613 -231.524048)
			(xy 373.502708 -231.47332) (xy 373.514887 -231.423906) (xy 373.534835 -231.377086) (xy 373.562036 -231.334072)
			(xy 373.595784 -231.295978) (xy 373.635206 -231.263791) (xy 373.67928 -231.238345) (xy 373.726866 -231.220298)
			(xy 373.77673 -231.210118) (xy 373.827582 -231.208069) (xy 373.878103 -231.214203) (xy 373.926987 -231.228363)
			(xy 373.972966 -231.25018) (xy 374.01485 -231.27909) (xy 374.051554 -231.314345) (xy 374.082127 -231.355031)
			(xy 374.105778 -231.400094) (xy 374.121894 -231.448368) (xy 374.130058 -231.498602) (xy 374.13057 -231.524048)
			(xy 374.130058 -231.549494) (xy 374.121894 -231.599728) (xy 374.105778 -231.648002) (xy 374.082127 -231.693065)
			(xy 374.051554 -231.733751) (xy 374.01485 -231.769006) (xy 373.972966 -231.797916) (xy 373.926987 -231.819733)
			(xy 373.878103 -231.833893) (xy 373.827582 -231.840027) (xy 373.77673 -231.837978) (xy 373.726866 -231.827798)
			(xy 373.67928 -231.809751) (xy 373.635206 -231.784305) (xy 373.595784 -231.752118) (xy 373.562036 -231.714024)
			(xy 373.534835 -231.67101) (xy 373.514887 -231.62419) (xy 373.502708 -231.574776) (xy 373.498613 -231.524048)
			(xy 373.190516 -231.524048) (xy 373.190004 -231.549494) (xy 373.18184 -231.599728) (xy 373.165724 -231.648002)
			(xy 373.142073 -231.693065) (xy 373.1115 -231.733751) (xy 373.074796 -231.769006) (xy 373.032912 -231.797916)
			(xy 372.986933 -231.819733) (xy 372.938049 -231.833893) (xy 372.887528 -231.840027) (xy 372.836676 -231.837978)
			(xy 372.786812 -231.827798) (xy 372.739226 -231.809751) (xy 372.695152 -231.784305) (xy 372.65573 -231.752118)
			(xy 372.621982 -231.714024) (xy 372.594781 -231.67101) (xy 372.574833 -231.62419) (xy 372.562654 -231.574776)
			(xy 372.558559 -231.524048) (xy 372.240048 -231.524048) (xy 372.239553 -231.548655) (xy 372.231658 -231.597232)
			(xy 372.216074 -231.643913) (xy 372.193203 -231.68749) (xy 372.163638 -231.726834) (xy 372.128145 -231.760926)
			(xy 372.087642 -231.788882) (xy 372.04318 -231.80998) (xy 371.995909 -231.823672) (xy 371.947054 -231.829604)
			(xy 371.897879 -231.827623) (xy 371.84966 -231.817779) (xy 371.803644 -231.800327) (xy 371.761023 -231.77572)
			(xy 371.722902 -231.744595) (xy 371.690267 -231.707758) (xy 371.663964 -231.666162) (xy 371.644673 -231.620886)
			(xy 371.632896 -231.573102) (xy 371.628936 -231.524048) (xy 371.310408 -231.524048) (xy 371.309896 -231.549494)
			(xy 371.301732 -231.599728) (xy 371.285616 -231.648002) (xy 371.261965 -231.693065) (xy 371.231392 -231.733751)
			(xy 371.194688 -231.769006) (xy 371.152804 -231.797916) (xy 371.106825 -231.819733) (xy 371.057941 -231.833893)
			(xy 371.00742 -231.840027) (xy 370.956568 -231.837978) (xy 370.906704 -231.827798) (xy 370.859118 -231.809751)
			(xy 370.815044 -231.784305) (xy 370.775622 -231.752118) (xy 370.741874 -231.714024) (xy 370.714673 -231.67101)
			(xy 370.694725 -231.62419) (xy 370.682546 -231.574776) (xy 370.678451 -231.524048) (xy 370.370608 -231.524048)
			(xy 370.370096 -231.549494) (xy 370.361932 -231.599728) (xy 370.345816 -231.648002) (xy 370.322165 -231.693065)
			(xy 370.291592 -231.733751) (xy 370.254888 -231.769006) (xy 370.213004 -231.797916) (xy 370.167025 -231.819733)
			(xy 370.118141 -231.833893) (xy 370.06762 -231.840027) (xy 370.016768 -231.837978) (xy 369.966904 -231.827798)
			(xy 369.919318 -231.809751) (xy 369.875244 -231.784305) (xy 369.835822 -231.752118) (xy 369.802074 -231.714024)
			(xy 369.774873 -231.67101) (xy 369.754925 -231.62419) (xy 369.742746 -231.574776) (xy 369.738651 -231.524048)
			(xy 369.42014 -231.524048) (xy 369.419645 -231.548655) (xy 369.41175 -231.597232) (xy 369.396166 -231.643913)
			(xy 369.373295 -231.68749) (xy 369.34373 -231.726834) (xy 369.308237 -231.760926) (xy 369.267734 -231.788882)
			(xy 369.223272 -231.80998) (xy 369.176001 -231.823672) (xy 369.127146 -231.829604) (xy 369.077971 -231.827623)
			(xy 369.029752 -231.817779) (xy 368.983736 -231.800327) (xy 368.941115 -231.77572) (xy 368.902994 -231.744595)
			(xy 368.870359 -231.707758) (xy 368.844056 -231.666162) (xy 368.824765 -231.620886) (xy 368.812988 -231.573102)
			(xy 368.809028 -231.524048) (xy 368.4905 -231.524048) (xy 368.489988 -231.549494) (xy 368.481824 -231.599728)
			(xy 368.465708 -231.648002) (xy 368.442057 -231.693065) (xy 368.411484 -231.733751) (xy 368.37478 -231.769006)
			(xy 368.332896 -231.797916) (xy 368.286917 -231.819733) (xy 368.238033 -231.833893) (xy 368.187512 -231.840027)
			(xy 368.13666 -231.837978) (xy 368.086796 -231.827798) (xy 368.03921 -231.809751) (xy 367.995136 -231.784305)
			(xy 367.955714 -231.752118) (xy 367.921966 -231.714024) (xy 367.894765 -231.67101) (xy 367.874817 -231.62419)
			(xy 367.862638 -231.574776) (xy 367.858543 -231.524048) (xy 367.550446 -231.524048) (xy 367.549934 -231.549494)
			(xy 367.54177 -231.599728) (xy 367.525654 -231.648002) (xy 367.502003 -231.693065) (xy 367.47143 -231.733751)
			(xy 367.434726 -231.769006) (xy 367.392842 -231.797916) (xy 367.346863 -231.819733) (xy 367.297979 -231.833893)
			(xy 367.247458 -231.840027) (xy 367.196606 -231.837978) (xy 367.146742 -231.827798) (xy 367.099156 -231.809751)
			(xy 367.055082 -231.784305) (xy 367.01566 -231.752118) (xy 366.981912 -231.714024) (xy 366.954711 -231.67101)
			(xy 366.934763 -231.62419) (xy 366.922584 -231.574776) (xy 366.918489 -231.524048) (xy 366.600232 -231.524048)
			(xy 366.599737 -231.548655) (xy 366.591842 -231.597232) (xy 366.576258 -231.643913) (xy 366.553387 -231.68749)
			(xy 366.523822 -231.726834) (xy 366.488329 -231.760926) (xy 366.447826 -231.788882) (xy 366.403364 -231.80998)
			(xy 366.356093 -231.823672) (xy 366.307238 -231.829604) (xy 366.258063 -231.827623) (xy 366.209844 -231.817779)
			(xy 366.163828 -231.800327) (xy 366.121207 -231.77572) (xy 366.083086 -231.744595) (xy 366.050451 -231.707758)
			(xy 366.024148 -231.666162) (xy 366.004857 -231.620886) (xy 365.99308 -231.573102) (xy 365.98912 -231.524048)
			(xy 365.670592 -231.524048) (xy 365.67008 -231.549494) (xy 365.661916 -231.599728) (xy 365.6458 -231.648002)
			(xy 365.622149 -231.693065) (xy 365.591576 -231.733751) (xy 365.554872 -231.769006) (xy 365.512988 -231.797916)
			(xy 365.467009 -231.819733) (xy 365.418125 -231.833893) (xy 365.367604 -231.840027) (xy 365.316752 -231.837978)
			(xy 365.266888 -231.827798) (xy 365.219302 -231.809751) (xy 365.175228 -231.784305) (xy 365.135806 -231.752118)
			(xy 365.102058 -231.714024) (xy 365.074857 -231.67101) (xy 365.054909 -231.62419) (xy 365.04273 -231.574776)
			(xy 365.038635 -231.524048) (xy 364.730538 -231.524048) (xy 364.730026 -231.549494) (xy 364.721862 -231.599728)
			(xy 364.705746 -231.648002) (xy 364.682095 -231.693065) (xy 364.651522 -231.733751) (xy 364.614818 -231.769006)
			(xy 364.572934 -231.797916) (xy 364.526955 -231.819733) (xy 364.478071 -231.833893) (xy 364.42755 -231.840027)
			(xy 364.376698 -231.837978) (xy 364.326834 -231.827798) (xy 364.279248 -231.809751) (xy 364.235174 -231.784305)
			(xy 364.195752 -231.752118) (xy 364.162004 -231.714024) (xy 364.134803 -231.67101) (xy 364.114855 -231.62419)
			(xy 364.102676 -231.574776) (xy 364.098581 -231.524048) (xy 363.78007 -231.524048) (xy 363.779575 -231.548655)
			(xy 363.77168 -231.597232) (xy 363.756096 -231.643913) (xy 363.733225 -231.68749) (xy 363.70366 -231.726834)
			(xy 363.668167 -231.760926) (xy 363.627664 -231.788882) (xy 363.583202 -231.80998) (xy 363.535931 -231.823672)
			(xy 363.487076 -231.829604) (xy 363.437901 -231.827623) (xy 363.389682 -231.817779) (xy 363.343666 -231.800327)
			(xy 363.301045 -231.77572) (xy 363.262924 -231.744595) (xy 363.230289 -231.707758) (xy 363.203986 -231.666162)
			(xy 363.184695 -231.620886) (xy 363.172918 -231.573102) (xy 363.168958 -231.524048) (xy 360.27868 -231.524048)
			(xy 360.27868 -232.334054) (xy 360.81895 -232.334054) (xy 360.82291 -232.285) (xy 360.834687 -232.237216)
			(xy 360.853978 -232.19194) (xy 360.880281 -232.150344) (xy 360.912916 -232.113507) (xy 360.951037 -232.082382)
			(xy 360.993658 -232.057775) (xy 361.039674 -232.040323) (xy 361.087893 -232.030479) (xy 361.137068 -232.028498)
			(xy 361.185923 -232.03443) (xy 361.233194 -232.048122) (xy 361.277656 -232.06922) (xy 361.318159 -232.097176)
			(xy 361.353652 -232.131268) (xy 361.383217 -232.170612) (xy 361.406088 -232.214189) (xy 361.421672 -232.26087)
			(xy 361.429567 -232.309447) (xy 361.430062 -232.334054) (xy 361.748573 -232.334054) (xy 361.752668 -232.283326)
			(xy 361.764847 -232.233912) (xy 361.784795 -232.187092) (xy 361.811996 -232.144078) (xy 361.845744 -232.105984)
			(xy 361.885166 -232.073797) (xy 361.92924 -232.048351) (xy 361.976826 -232.030304) (xy 362.02669 -232.020124)
			(xy 362.077542 -232.018075) (xy 362.128063 -232.024209) (xy 362.176947 -232.038369) (xy 362.222926 -232.060186)
			(xy 362.26481 -232.089096) (xy 362.301514 -232.124351) (xy 362.332087 -232.165037) (xy 362.355738 -232.2101)
			(xy 362.371854 -232.258374) (xy 362.380018 -232.308608) (xy 362.38053 -232.334054) (xy 362.688627 -232.334054)
			(xy 362.692722 -232.283326) (xy 362.704901 -232.233912) (xy 362.724849 -232.187092) (xy 362.75205 -232.144078)
			(xy 362.785798 -232.105984) (xy 362.82522 -232.073797) (xy 362.869294 -232.048351) (xy 362.91688 -232.030304)
			(xy 362.966744 -232.020124) (xy 363.017596 -232.018075) (xy 363.068117 -232.024209) (xy 363.117001 -232.038369)
			(xy 363.16298 -232.060186) (xy 363.204864 -232.089096) (xy 363.241568 -232.124351) (xy 363.272141 -232.165037)
			(xy 363.295792 -232.2101) (xy 363.311908 -232.258374) (xy 363.320072 -232.308608) (xy 363.320584 -232.334054)
			(xy 363.639112 -232.334054) (xy 363.643072 -232.285) (xy 363.654849 -232.237216) (xy 363.67414 -232.19194)
			(xy 363.700443 -232.150344) (xy 363.733078 -232.113507) (xy 363.771199 -232.082382) (xy 363.81382 -232.057775)
			(xy 363.859836 -232.040323) (xy 363.908055 -232.030479) (xy 363.95723 -232.028498) (xy 364.006085 -232.03443)
			(xy 364.053356 -232.048122) (xy 364.097818 -232.06922) (xy 364.138321 -232.097176) (xy 364.173814 -232.131268)
			(xy 364.203379 -232.170612) (xy 364.22625 -232.214189) (xy 364.241834 -232.26087) (xy 364.249729 -232.309447)
			(xy 364.250224 -232.334054) (xy 364.578912 -232.334054) (xy 364.582872 -232.285) (xy 364.594649 -232.237216)
			(xy 364.61394 -232.19194) (xy 364.640243 -232.150344) (xy 364.672878 -232.113507) (xy 364.710999 -232.082382)
			(xy 364.75362 -232.057775) (xy 364.799636 -232.040323) (xy 364.847855 -232.030479) (xy 364.89703 -232.028498)
			(xy 364.945885 -232.03443) (xy 364.993156 -232.048122) (xy 365.037618 -232.06922) (xy 365.078121 -232.097176)
			(xy 365.113614 -232.131268) (xy 365.143179 -232.170612) (xy 365.16605 -232.214189) (xy 365.181634 -232.26087)
			(xy 365.189529 -232.309447) (xy 365.190024 -232.334054) (xy 365.518966 -232.334054) (xy 365.522926 -232.285)
			(xy 365.534703 -232.237216) (xy 365.553994 -232.19194) (xy 365.580297 -232.150344) (xy 365.612932 -232.113507)
			(xy 365.651053 -232.082382) (xy 365.693674 -232.057775) (xy 365.73969 -232.040323) (xy 365.787909 -232.030479)
			(xy 365.837084 -232.028498) (xy 365.885939 -232.03443) (xy 365.93321 -232.048122) (xy 365.977672 -232.06922)
			(xy 366.018175 -232.097176) (xy 366.053668 -232.131268) (xy 366.083233 -232.170612) (xy 366.106104 -232.214189)
			(xy 366.121688 -232.26087) (xy 366.129583 -232.309447) (xy 366.130078 -232.334054) (xy 366.45902 -232.334054)
			(xy 366.46298 -232.285) (xy 366.474757 -232.237216) (xy 366.494048 -232.19194) (xy 366.520351 -232.150344)
			(xy 366.552986 -232.113507) (xy 366.591107 -232.082382) (xy 366.633728 -232.057775) (xy 366.679744 -232.040323)
			(xy 366.727963 -232.030479) (xy 366.777138 -232.028498) (xy 366.825993 -232.03443) (xy 366.873264 -232.048122)
			(xy 366.917726 -232.06922) (xy 366.958229 -232.097176) (xy 366.993722 -232.131268) (xy 367.023287 -232.170612)
			(xy 367.046158 -232.214189) (xy 367.061742 -232.26087) (xy 367.069637 -232.309447) (xy 367.070132 -232.334054)
			(xy 367.399074 -232.334054) (xy 367.403034 -232.285) (xy 367.414811 -232.237216) (xy 367.434102 -232.19194)
			(xy 367.460405 -232.150344) (xy 367.49304 -232.113507) (xy 367.531161 -232.082382) (xy 367.573782 -232.057775)
			(xy 367.619798 -232.040323) (xy 367.668017 -232.030479) (xy 367.717192 -232.028498) (xy 367.766047 -232.03443)
			(xy 367.813318 -232.048122) (xy 367.85778 -232.06922) (xy 367.898283 -232.097176) (xy 367.933776 -232.131268)
			(xy 367.963341 -232.170612) (xy 367.986212 -232.214189) (xy 368.001796 -232.26087) (xy 368.009691 -232.309447)
			(xy 368.010186 -232.334054) (xy 368.338874 -232.334054) (xy 368.342834 -232.285) (xy 368.354611 -232.237216)
			(xy 368.373902 -232.19194) (xy 368.400205 -232.150344) (xy 368.43284 -232.113507) (xy 368.470961 -232.082382)
			(xy 368.513582 -232.057775) (xy 368.559598 -232.040323) (xy 368.607817 -232.030479) (xy 368.656992 -232.028498)
			(xy 368.705847 -232.03443) (xy 368.753118 -232.048122) (xy 368.79758 -232.06922) (xy 368.838083 -232.097176)
			(xy 368.873576 -232.131268) (xy 368.903141 -232.170612) (xy 368.926012 -232.214189) (xy 368.941596 -232.26087)
			(xy 368.949491 -232.309447) (xy 368.949986 -232.334054) (xy 369.278928 -232.334054) (xy 369.282888 -232.285)
			(xy 369.294665 -232.237216) (xy 369.313956 -232.19194) (xy 369.340259 -232.150344) (xy 369.372894 -232.113507)
			(xy 369.411015 -232.082382) (xy 369.453636 -232.057775) (xy 369.499652 -232.040323) (xy 369.547871 -232.030479)
			(xy 369.597046 -232.028498) (xy 369.645901 -232.03443) (xy 369.693172 -232.048122) (xy 369.737634 -232.06922)
			(xy 369.778137 -232.097176) (xy 369.81363 -232.131268) (xy 369.843195 -232.170612) (xy 369.866066 -232.214189)
			(xy 369.88165 -232.26087) (xy 369.889545 -232.309447) (xy 369.89004 -232.334054) (xy 370.218982 -232.334054)
			(xy 370.222942 -232.285) (xy 370.234719 -232.237216) (xy 370.25401 -232.19194) (xy 370.280313 -232.150344)
			(xy 370.312948 -232.113507) (xy 370.351069 -232.082382) (xy 370.39369 -232.057775) (xy 370.439706 -232.040323)
			(xy 370.487925 -232.030479) (xy 370.5371 -232.028498) (xy 370.585955 -232.03443) (xy 370.633226 -232.048122)
			(xy 370.677688 -232.06922) (xy 370.718191 -232.097176) (xy 370.753684 -232.131268) (xy 370.783249 -232.170612)
			(xy 370.80612 -232.214189) (xy 370.821704 -232.26087) (xy 370.829599 -232.309447) (xy 370.830094 -232.334054)
			(xy 371.159036 -232.334054) (xy 371.162996 -232.285) (xy 371.174773 -232.237216) (xy 371.194064 -232.19194)
			(xy 371.220367 -232.150344) (xy 371.253002 -232.113507) (xy 371.291123 -232.082382) (xy 371.333744 -232.057775)
			(xy 371.37976 -232.040323) (xy 371.427979 -232.030479) (xy 371.477154 -232.028498) (xy 371.526009 -232.03443)
			(xy 371.57328 -232.048122) (xy 371.617742 -232.06922) (xy 371.658245 -232.097176) (xy 371.693738 -232.131268)
			(xy 371.723303 -232.170612) (xy 371.746174 -232.214189) (xy 371.761758 -232.26087) (xy 371.769653 -232.309447)
			(xy 371.770148 -232.334054) (xy 372.09909 -232.334054) (xy 372.10305 -232.285) (xy 372.114827 -232.237216)
			(xy 372.134118 -232.19194) (xy 372.160421 -232.150344) (xy 372.193056 -232.113507) (xy 372.231177 -232.082382)
			(xy 372.273798 -232.057775) (xy 372.319814 -232.040323) (xy 372.368033 -232.030479) (xy 372.417208 -232.028498)
			(xy 372.466063 -232.03443) (xy 372.513334 -232.048122) (xy 372.557796 -232.06922) (xy 372.598299 -232.097176)
			(xy 372.633792 -232.131268) (xy 372.663357 -232.170612) (xy 372.686228 -232.214189) (xy 372.701812 -232.26087)
			(xy 372.709707 -232.309447) (xy 372.710202 -232.334054) (xy 373.03889 -232.334054) (xy 373.04285 -232.285)
			(xy 373.054627 -232.237216) (xy 373.073918 -232.19194) (xy 373.100221 -232.150344) (xy 373.132856 -232.113507)
			(xy 373.170977 -232.082382) (xy 373.213598 -232.057775) (xy 373.259614 -232.040323) (xy 373.307833 -232.030479)
			(xy 373.357008 -232.028498) (xy 373.405863 -232.03443) (xy 373.453134 -232.048122) (xy 373.497596 -232.06922)
			(xy 373.538099 -232.097176) (xy 373.573592 -232.131268) (xy 373.603157 -232.170612) (xy 373.626028 -232.214189)
			(xy 373.641612 -232.26087) (xy 373.649507 -232.309447) (xy 373.650002 -232.334054) (xy 373.649507 -232.358661)
			(xy 373.641612 -232.407238) (xy 373.626028 -232.453919) (xy 373.603157 -232.497496) (xy 373.573592 -232.53684)
			(xy 373.538099 -232.570932) (xy 373.497596 -232.598888) (xy 373.453134 -232.619986) (xy 373.405863 -232.633678)
			(xy 373.357008 -232.63961) (xy 373.307833 -232.637629) (xy 373.259614 -232.627785) (xy 373.213598 -232.610333)
			(xy 373.170977 -232.585726) (xy 373.132856 -232.554601) (xy 373.100221 -232.517764) (xy 373.073918 -232.476168)
			(xy 373.054627 -232.430892) (xy 373.04285 -232.383108) (xy 373.03889 -232.334054) (xy 372.710202 -232.334054)
			(xy 372.709707 -232.358661) (xy 372.701812 -232.407238) (xy 372.686228 -232.453919) (xy 372.663357 -232.497496)
			(xy 372.633792 -232.53684) (xy 372.598299 -232.570932) (xy 372.557796 -232.598888) (xy 372.513334 -232.619986)
			(xy 372.466063 -232.633678) (xy 372.417208 -232.63961) (xy 372.368033 -232.637629) (xy 372.319814 -232.627785)
			(xy 372.273798 -232.610333) (xy 372.231177 -232.585726) (xy 372.193056 -232.554601) (xy 372.160421 -232.517764)
			(xy 372.134118 -232.476168) (xy 372.114827 -232.430892) (xy 372.10305 -232.383108) (xy 372.09909 -232.334054)
			(xy 371.770148 -232.334054) (xy 371.769653 -232.358661) (xy 371.761758 -232.407238) (xy 371.746174 -232.453919)
			(xy 371.723303 -232.497496) (xy 371.693738 -232.53684) (xy 371.658245 -232.570932) (xy 371.617742 -232.598888)
			(xy 371.57328 -232.619986) (xy 371.526009 -232.633678) (xy 371.477154 -232.63961) (xy 371.427979 -232.637629)
			(xy 371.37976 -232.627785) (xy 371.333744 -232.610333) (xy 371.291123 -232.585726) (xy 371.253002 -232.554601)
			(xy 371.220367 -232.517764) (xy 371.194064 -232.476168) (xy 371.174773 -232.430892) (xy 371.162996 -232.383108)
			(xy 371.159036 -232.334054) (xy 370.830094 -232.334054) (xy 370.829599 -232.358661) (xy 370.821704 -232.407238)
			(xy 370.80612 -232.453919) (xy 370.783249 -232.497496) (xy 370.753684 -232.53684) (xy 370.718191 -232.570932)
			(xy 370.677688 -232.598888) (xy 370.633226 -232.619986) (xy 370.585955 -232.633678) (xy 370.5371 -232.63961)
			(xy 370.487925 -232.637629) (xy 370.439706 -232.627785) (xy 370.39369 -232.610333) (xy 370.351069 -232.585726)
			(xy 370.312948 -232.554601) (xy 370.280313 -232.517764) (xy 370.25401 -232.476168) (xy 370.234719 -232.430892)
			(xy 370.222942 -232.383108) (xy 370.218982 -232.334054) (xy 369.89004 -232.334054) (xy 369.889545 -232.358661)
			(xy 369.88165 -232.407238) (xy 369.866066 -232.453919) (xy 369.843195 -232.497496) (xy 369.81363 -232.53684)
			(xy 369.778137 -232.570932) (xy 369.737634 -232.598888) (xy 369.693172 -232.619986) (xy 369.645901 -232.633678)
			(xy 369.597046 -232.63961) (xy 369.547871 -232.637629) (xy 369.499652 -232.627785) (xy 369.453636 -232.610333)
			(xy 369.411015 -232.585726) (xy 369.372894 -232.554601) (xy 369.340259 -232.517764) (xy 369.313956 -232.476168)
			(xy 369.294665 -232.430892) (xy 369.282888 -232.383108) (xy 369.278928 -232.334054) (xy 368.949986 -232.334054)
			(xy 368.949491 -232.358661) (xy 368.941596 -232.407238) (xy 368.926012 -232.453919) (xy 368.903141 -232.497496)
			(xy 368.873576 -232.53684) (xy 368.838083 -232.570932) (xy 368.79758 -232.598888) (xy 368.753118 -232.619986)
			(xy 368.705847 -232.633678) (xy 368.656992 -232.63961) (xy 368.607817 -232.637629) (xy 368.559598 -232.627785)
			(xy 368.513582 -232.610333) (xy 368.470961 -232.585726) (xy 368.43284 -232.554601) (xy 368.400205 -232.517764)
			(xy 368.373902 -232.476168) (xy 368.354611 -232.430892) (xy 368.342834 -232.383108) (xy 368.338874 -232.334054)
			(xy 368.010186 -232.334054) (xy 368.009691 -232.358661) (xy 368.001796 -232.407238) (xy 367.986212 -232.453919)
			(xy 367.963341 -232.497496) (xy 367.933776 -232.53684) (xy 367.898283 -232.570932) (xy 367.85778 -232.598888)
			(xy 367.813318 -232.619986) (xy 367.766047 -232.633678) (xy 367.717192 -232.63961) (xy 367.668017 -232.637629)
			(xy 367.619798 -232.627785) (xy 367.573782 -232.610333) (xy 367.531161 -232.585726) (xy 367.49304 -232.554601)
			(xy 367.460405 -232.517764) (xy 367.434102 -232.476168) (xy 367.414811 -232.430892) (xy 367.403034 -232.383108)
			(xy 367.399074 -232.334054) (xy 367.070132 -232.334054) (xy 367.069637 -232.358661) (xy 367.061742 -232.407238)
			(xy 367.046158 -232.453919) (xy 367.023287 -232.497496) (xy 366.993722 -232.53684) (xy 366.958229 -232.570932)
			(xy 366.917726 -232.598888) (xy 366.873264 -232.619986) (xy 366.825993 -232.633678) (xy 366.777138 -232.63961)
			(xy 366.727963 -232.637629) (xy 366.679744 -232.627785) (xy 366.633728 -232.610333) (xy 366.591107 -232.585726)
			(xy 366.552986 -232.554601) (xy 366.520351 -232.517764) (xy 366.494048 -232.476168) (xy 366.474757 -232.430892)
			(xy 366.46298 -232.383108) (xy 366.45902 -232.334054) (xy 366.130078 -232.334054) (xy 366.129583 -232.358661)
			(xy 366.121688 -232.407238) (xy 366.106104 -232.453919) (xy 366.083233 -232.497496) (xy 366.053668 -232.53684)
			(xy 366.018175 -232.570932) (xy 365.977672 -232.598888) (xy 365.93321 -232.619986) (xy 365.885939 -232.633678)
			(xy 365.837084 -232.63961) (xy 365.787909 -232.637629) (xy 365.73969 -232.627785) (xy 365.693674 -232.610333)
			(xy 365.651053 -232.585726) (xy 365.612932 -232.554601) (xy 365.580297 -232.517764) (xy 365.553994 -232.476168)
			(xy 365.534703 -232.430892) (xy 365.522926 -232.383108) (xy 365.518966 -232.334054) (xy 365.190024 -232.334054)
			(xy 365.189529 -232.358661) (xy 365.181634 -232.407238) (xy 365.16605 -232.453919) (xy 365.143179 -232.497496)
			(xy 365.113614 -232.53684) (xy 365.078121 -232.570932) (xy 365.037618 -232.598888) (xy 364.993156 -232.619986)
			(xy 364.945885 -232.633678) (xy 364.89703 -232.63961) (xy 364.847855 -232.637629) (xy 364.799636 -232.627785)
			(xy 364.75362 -232.610333) (xy 364.710999 -232.585726) (xy 364.672878 -232.554601) (xy 364.640243 -232.517764)
			(xy 364.61394 -232.476168) (xy 364.594649 -232.430892) (xy 364.582872 -232.383108) (xy 364.578912 -232.334054)
			(xy 364.250224 -232.334054) (xy 364.249729 -232.358661) (xy 364.241834 -232.407238) (xy 364.22625 -232.453919)
			(xy 364.203379 -232.497496) (xy 364.173814 -232.53684) (xy 364.138321 -232.570932) (xy 364.097818 -232.598888)
			(xy 364.053356 -232.619986) (xy 364.006085 -232.633678) (xy 363.95723 -232.63961) (xy 363.908055 -232.637629)
			(xy 363.859836 -232.627785) (xy 363.81382 -232.610333) (xy 363.771199 -232.585726) (xy 363.733078 -232.554601)
			(xy 363.700443 -232.517764) (xy 363.67414 -232.476168) (xy 363.654849 -232.430892) (xy 363.643072 -232.383108)
			(xy 363.639112 -232.334054) (xy 363.320584 -232.334054) (xy 363.320072 -232.3595) (xy 363.311908 -232.409734)
			(xy 363.295792 -232.458008) (xy 363.272141 -232.503071) (xy 363.241568 -232.543757) (xy 363.204864 -232.579012)
			(xy 363.16298 -232.607922) (xy 363.117001 -232.629739) (xy 363.068117 -232.643899) (xy 363.017596 -232.650033)
			(xy 362.966744 -232.647984) (xy 362.91688 -232.637804) (xy 362.869294 -232.619757) (xy 362.82522 -232.594311)
			(xy 362.785798 -232.562124) (xy 362.75205 -232.52403) (xy 362.724849 -232.481016) (xy 362.704901 -232.434196)
			(xy 362.692722 -232.384782) (xy 362.688627 -232.334054) (xy 362.38053 -232.334054) (xy 362.380018 -232.3595)
			(xy 362.371854 -232.409734) (xy 362.355738 -232.458008) (xy 362.332087 -232.503071) (xy 362.301514 -232.543757)
			(xy 362.26481 -232.579012) (xy 362.222926 -232.607922) (xy 362.176947 -232.629739) (xy 362.128063 -232.643899)
			(xy 362.077542 -232.650033) (xy 362.02669 -232.647984) (xy 361.976826 -232.637804) (xy 361.92924 -232.619757)
			(xy 361.885166 -232.594311) (xy 361.845744 -232.562124) (xy 361.811996 -232.52403) (xy 361.784795 -232.481016)
			(xy 361.764847 -232.434196) (xy 361.752668 -232.384782) (xy 361.748573 -232.334054) (xy 361.430062 -232.334054)
			(xy 361.429567 -232.358661) (xy 361.421672 -232.407238) (xy 361.406088 -232.453919) (xy 361.383217 -232.497496)
			(xy 361.353652 -232.53684) (xy 361.318159 -232.570932) (xy 361.277656 -232.598888) (xy 361.233194 -232.619986)
			(xy 361.185923 -232.633678) (xy 361.137068 -232.63961) (xy 361.087893 -232.637629) (xy 361.039674 -232.627785)
			(xy 360.993658 -232.610333) (xy 360.951037 -232.585726) (xy 360.912916 -232.554601) (xy 360.880281 -232.517764)
			(xy 360.853978 -232.476168) (xy 360.834687 -232.430892) (xy 360.82291 -232.383108) (xy 360.81895 -232.334054)
			(xy 360.27868 -232.334054) (xy 360.27868 -233.14406) (xy 361.289104 -233.14406) (xy 361.293064 -233.095006)
			(xy 361.304841 -233.047222) (xy 361.324132 -233.001946) (xy 361.350435 -232.96035) (xy 361.38307 -232.923513)
			(xy 361.421191 -232.892388) (xy 361.463812 -232.867781) (xy 361.509828 -232.850329) (xy 361.558047 -232.840485)
			(xy 361.607222 -232.838504) (xy 361.656077 -232.844436) (xy 361.703348 -232.858128) (xy 361.74781 -232.879226)
			(xy 361.788313 -232.907182) (xy 361.823806 -232.941274) (xy 361.853371 -232.980618) (xy 361.876242 -233.024195)
			(xy 361.891826 -233.070876) (xy 361.899721 -233.119453) (xy 361.900216 -233.14406) (xy 362.228904 -233.14406)
			(xy 362.232864 -233.095006) (xy 362.244641 -233.047222) (xy 362.263932 -233.001946) (xy 362.290235 -232.96035)
			(xy 362.32287 -232.923513) (xy 362.360991 -232.892388) (xy 362.403612 -232.867781) (xy 362.449628 -232.850329)
			(xy 362.497847 -232.840485) (xy 362.547022 -232.838504) (xy 362.595877 -232.844436) (xy 362.643148 -232.858128)
			(xy 362.68761 -232.879226) (xy 362.728113 -232.907182) (xy 362.763606 -232.941274) (xy 362.793171 -232.980618)
			(xy 362.816042 -233.024195) (xy 362.831626 -233.070876) (xy 362.839521 -233.119453) (xy 362.840016 -233.14406)
			(xy 363.168958 -233.14406) (xy 363.172918 -233.095006) (xy 363.184695 -233.047222) (xy 363.203986 -233.001946)
			(xy 363.230289 -232.96035) (xy 363.262924 -232.923513) (xy 363.301045 -232.892388) (xy 363.343666 -232.867781)
			(xy 363.389682 -232.850329) (xy 363.437901 -232.840485) (xy 363.487076 -232.838504) (xy 363.535931 -232.844436)
			(xy 363.583202 -232.858128) (xy 363.627664 -232.879226) (xy 363.668167 -232.907182) (xy 363.70366 -232.941274)
			(xy 363.733225 -232.980618) (xy 363.756096 -233.024195) (xy 363.77168 -233.070876) (xy 363.779575 -233.119453)
			(xy 363.78007 -233.14406) (xy 364.098581 -233.14406) (xy 364.102676 -233.093332) (xy 364.114855 -233.043918)
			(xy 364.134803 -232.997098) (xy 364.162004 -232.954084) (xy 364.195752 -232.91599) (xy 364.235174 -232.883803)
			(xy 364.279248 -232.858357) (xy 364.326834 -232.84031) (xy 364.376698 -232.83013) (xy 364.42755 -232.828081)
			(xy 364.478071 -232.834215) (xy 364.526955 -232.848375) (xy 364.572934 -232.870192) (xy 364.614818 -232.899102)
			(xy 364.651522 -232.934357) (xy 364.682095 -232.975043) (xy 364.705746 -233.020106) (xy 364.721862 -233.06838)
			(xy 364.730026 -233.118614) (xy 364.730538 -233.14406) (xy 365.038635 -233.14406) (xy 365.04273 -233.093332)
			(xy 365.054909 -233.043918) (xy 365.074857 -232.997098) (xy 365.102058 -232.954084) (xy 365.135806 -232.91599)
			(xy 365.175228 -232.883803) (xy 365.219302 -232.858357) (xy 365.266888 -232.84031) (xy 365.316752 -232.83013)
			(xy 365.367604 -232.828081) (xy 365.418125 -232.834215) (xy 365.467009 -232.848375) (xy 365.512988 -232.870192)
			(xy 365.554872 -232.899102) (xy 365.591576 -232.934357) (xy 365.622149 -232.975043) (xy 365.6458 -233.020106)
			(xy 365.661916 -233.06838) (xy 365.67008 -233.118614) (xy 365.670592 -233.14406) (xy 365.98912 -233.14406)
			(xy 365.99308 -233.095006) (xy 366.004857 -233.047222) (xy 366.024148 -233.001946) (xy 366.050451 -232.96035)
			(xy 366.083086 -232.923513) (xy 366.121207 -232.892388) (xy 366.163828 -232.867781) (xy 366.209844 -232.850329)
			(xy 366.258063 -232.840485) (xy 366.307238 -232.838504) (xy 366.356093 -232.844436) (xy 366.403364 -232.858128)
			(xy 366.447826 -232.879226) (xy 366.488329 -232.907182) (xy 366.523822 -232.941274) (xy 366.553387 -232.980618)
			(xy 366.576258 -233.024195) (xy 366.591842 -233.070876) (xy 366.599737 -233.119453) (xy 366.600232 -233.14406)
			(xy 366.918489 -233.14406) (xy 366.922584 -233.093332) (xy 366.934763 -233.043918) (xy 366.954711 -232.997098)
			(xy 366.981912 -232.954084) (xy 367.01566 -232.91599) (xy 367.055082 -232.883803) (xy 367.099156 -232.858357)
			(xy 367.146742 -232.84031) (xy 367.196606 -232.83013) (xy 367.247458 -232.828081) (xy 367.297979 -232.834215)
			(xy 367.346863 -232.848375) (xy 367.392842 -232.870192) (xy 367.434726 -232.899102) (xy 367.47143 -232.934357)
			(xy 367.502003 -232.975043) (xy 367.525654 -233.020106) (xy 367.54177 -233.06838) (xy 367.549934 -233.118614)
			(xy 367.550446 -233.14406) (xy 367.858543 -233.14406) (xy 367.862638 -233.093332) (xy 367.874817 -233.043918)
			(xy 367.894765 -232.997098) (xy 367.921966 -232.954084) (xy 367.955714 -232.91599) (xy 367.995136 -232.883803)
			(xy 368.03921 -232.858357) (xy 368.086796 -232.84031) (xy 368.13666 -232.83013) (xy 368.187512 -232.828081)
			(xy 368.238033 -232.834215) (xy 368.286917 -232.848375) (xy 368.332896 -232.870192) (xy 368.37478 -232.899102)
			(xy 368.411484 -232.934357) (xy 368.442057 -232.975043) (xy 368.465708 -233.020106) (xy 368.481824 -233.06838)
			(xy 368.489988 -233.118614) (xy 368.4905 -233.14406) (xy 368.809028 -233.14406) (xy 368.812988 -233.095006)
			(xy 368.824765 -233.047222) (xy 368.844056 -233.001946) (xy 368.870359 -232.96035) (xy 368.902994 -232.923513)
			(xy 368.941115 -232.892388) (xy 368.983736 -232.867781) (xy 369.029752 -232.850329) (xy 369.077971 -232.840485)
			(xy 369.127146 -232.838504) (xy 369.176001 -232.844436) (xy 369.223272 -232.858128) (xy 369.267734 -232.879226)
			(xy 369.308237 -232.907182) (xy 369.34373 -232.941274) (xy 369.373295 -232.980618) (xy 369.396166 -233.024195)
			(xy 369.41175 -233.070876) (xy 369.419645 -233.119453) (xy 369.42014 -233.14406) (xy 369.738651 -233.14406)
			(xy 369.742746 -233.093332) (xy 369.754925 -233.043918) (xy 369.774873 -232.997098) (xy 369.802074 -232.954084)
			(xy 369.835822 -232.91599) (xy 369.875244 -232.883803) (xy 369.919318 -232.858357) (xy 369.966904 -232.84031)
			(xy 370.016768 -232.83013) (xy 370.06762 -232.828081) (xy 370.118141 -232.834215) (xy 370.167025 -232.848375)
			(xy 370.213004 -232.870192) (xy 370.254888 -232.899102) (xy 370.291592 -232.934357) (xy 370.322165 -232.975043)
			(xy 370.345816 -233.020106) (xy 370.361932 -233.06838) (xy 370.370096 -233.118614) (xy 370.370608 -233.14406)
			(xy 370.678451 -233.14406) (xy 370.682546 -233.093332) (xy 370.694725 -233.043918) (xy 370.714673 -232.997098)
			(xy 370.741874 -232.954084) (xy 370.775622 -232.91599) (xy 370.815044 -232.883803) (xy 370.859118 -232.858357)
			(xy 370.906704 -232.84031) (xy 370.956568 -232.83013) (xy 371.00742 -232.828081) (xy 371.057941 -232.834215)
			(xy 371.106825 -232.848375) (xy 371.152804 -232.870192) (xy 371.194688 -232.899102) (xy 371.231392 -232.934357)
			(xy 371.261965 -232.975043) (xy 371.285616 -233.020106) (xy 371.301732 -233.06838) (xy 371.309896 -233.118614)
			(xy 371.310408 -233.14406) (xy 371.628936 -233.14406) (xy 371.632896 -233.095006) (xy 371.644673 -233.047222)
			(xy 371.663964 -233.001946) (xy 371.690267 -232.96035) (xy 371.722902 -232.923513) (xy 371.761023 -232.892388)
			(xy 371.803644 -232.867781) (xy 371.84966 -232.850329) (xy 371.897879 -232.840485) (xy 371.947054 -232.838504)
			(xy 371.995909 -232.844436) (xy 372.04318 -232.858128) (xy 372.087642 -232.879226) (xy 372.128145 -232.907182)
			(xy 372.163638 -232.941274) (xy 372.193203 -232.980618) (xy 372.216074 -233.024195) (xy 372.231658 -233.070876)
			(xy 372.239553 -233.119453) (xy 372.240048 -233.14406) (xy 372.558559 -233.14406) (xy 372.562654 -233.093332)
			(xy 372.574833 -233.043918) (xy 372.594781 -232.997098) (xy 372.621982 -232.954084) (xy 372.65573 -232.91599)
			(xy 372.695152 -232.883803) (xy 372.739226 -232.858357) (xy 372.786812 -232.84031) (xy 372.836676 -232.83013)
			(xy 372.887528 -232.828081) (xy 372.938049 -232.834215) (xy 372.986933 -232.848375) (xy 373.032912 -232.870192)
			(xy 373.074796 -232.899102) (xy 373.1115 -232.934357) (xy 373.142073 -232.975043) (xy 373.165724 -233.020106)
			(xy 373.18184 -233.06838) (xy 373.190004 -233.118614) (xy 373.190516 -233.14406) (xy 373.498613 -233.14406)
			(xy 373.502708 -233.093332) (xy 373.514887 -233.043918) (xy 373.534835 -232.997098) (xy 373.562036 -232.954084)
			(xy 373.595784 -232.91599) (xy 373.635206 -232.883803) (xy 373.67928 -232.858357) (xy 373.726866 -232.84031)
			(xy 373.77673 -232.83013) (xy 373.827582 -232.828081) (xy 373.878103 -232.834215) (xy 373.926987 -232.848375)
			(xy 373.972966 -232.870192) (xy 374.01485 -232.899102) (xy 374.051554 -232.934357) (xy 374.082127 -232.975043)
			(xy 374.105778 -233.020106) (xy 374.121894 -233.06838) (xy 374.130058 -233.118614) (xy 374.13057 -233.14406)
			(xy 374.130058 -233.169506) (xy 374.121894 -233.21974) (xy 374.105778 -233.268014) (xy 374.082127 -233.313077)
			(xy 374.051554 -233.353763) (xy 374.01485 -233.389018) (xy 373.972966 -233.417928) (xy 373.926987 -233.439745)
			(xy 373.878103 -233.453905) (xy 373.827582 -233.460039) (xy 373.77673 -233.45799) (xy 373.726866 -233.44781)
			(xy 373.67928 -233.429763) (xy 373.635206 -233.404317) (xy 373.595784 -233.37213) (xy 373.562036 -233.334036)
			(xy 373.534835 -233.291022) (xy 373.514887 -233.244202) (xy 373.502708 -233.194788) (xy 373.498613 -233.14406)
			(xy 373.190516 -233.14406) (xy 373.190004 -233.169506) (xy 373.18184 -233.21974) (xy 373.165724 -233.268014)
			(xy 373.142073 -233.313077) (xy 373.1115 -233.353763) (xy 373.074796 -233.389018) (xy 373.032912 -233.417928)
			(xy 372.986933 -233.439745) (xy 372.938049 -233.453905) (xy 372.887528 -233.460039) (xy 372.836676 -233.45799)
			(xy 372.786812 -233.44781) (xy 372.739226 -233.429763) (xy 372.695152 -233.404317) (xy 372.65573 -233.37213)
			(xy 372.621982 -233.334036) (xy 372.594781 -233.291022) (xy 372.574833 -233.244202) (xy 372.562654 -233.194788)
			(xy 372.558559 -233.14406) (xy 372.240048 -233.14406) (xy 372.239553 -233.168667) (xy 372.231658 -233.217244)
			(xy 372.216074 -233.263925) (xy 372.193203 -233.307502) (xy 372.163638 -233.346846) (xy 372.128145 -233.380938)
			(xy 372.087642 -233.408894) (xy 372.04318 -233.429992) (xy 371.995909 -233.443684) (xy 371.947054 -233.449616)
			(xy 371.897879 -233.447635) (xy 371.84966 -233.437791) (xy 371.803644 -233.420339) (xy 371.761023 -233.395732)
			(xy 371.722902 -233.364607) (xy 371.690267 -233.32777) (xy 371.663964 -233.286174) (xy 371.644673 -233.240898)
			(xy 371.632896 -233.193114) (xy 371.628936 -233.14406) (xy 371.310408 -233.14406) (xy 371.309896 -233.169506)
			(xy 371.301732 -233.21974) (xy 371.285616 -233.268014) (xy 371.261965 -233.313077) (xy 371.231392 -233.353763)
			(xy 371.194688 -233.389018) (xy 371.152804 -233.417928) (xy 371.106825 -233.439745) (xy 371.057941 -233.453905)
			(xy 371.00742 -233.460039) (xy 370.956568 -233.45799) (xy 370.906704 -233.44781) (xy 370.859118 -233.429763)
			(xy 370.815044 -233.404317) (xy 370.775622 -233.37213) (xy 370.741874 -233.334036) (xy 370.714673 -233.291022)
			(xy 370.694725 -233.244202) (xy 370.682546 -233.194788) (xy 370.678451 -233.14406) (xy 370.370608 -233.14406)
			(xy 370.370096 -233.169506) (xy 370.361932 -233.21974) (xy 370.345816 -233.268014) (xy 370.322165 -233.313077)
			(xy 370.291592 -233.353763) (xy 370.254888 -233.389018) (xy 370.213004 -233.417928) (xy 370.167025 -233.439745)
			(xy 370.118141 -233.453905) (xy 370.06762 -233.460039) (xy 370.016768 -233.45799) (xy 369.966904 -233.44781)
			(xy 369.919318 -233.429763) (xy 369.875244 -233.404317) (xy 369.835822 -233.37213) (xy 369.802074 -233.334036)
			(xy 369.774873 -233.291022) (xy 369.754925 -233.244202) (xy 369.742746 -233.194788) (xy 369.738651 -233.14406)
			(xy 369.42014 -233.14406) (xy 369.419645 -233.168667) (xy 369.41175 -233.217244) (xy 369.396166 -233.263925)
			(xy 369.373295 -233.307502) (xy 369.34373 -233.346846) (xy 369.308237 -233.380938) (xy 369.267734 -233.408894)
			(xy 369.223272 -233.429992) (xy 369.176001 -233.443684) (xy 369.127146 -233.449616) (xy 369.077971 -233.447635)
			(xy 369.029752 -233.437791) (xy 368.983736 -233.420339) (xy 368.941115 -233.395732) (xy 368.902994 -233.364607)
			(xy 368.870359 -233.32777) (xy 368.844056 -233.286174) (xy 368.824765 -233.240898) (xy 368.812988 -233.193114)
			(xy 368.809028 -233.14406) (xy 368.4905 -233.14406) (xy 368.489988 -233.169506) (xy 368.481824 -233.21974)
			(xy 368.465708 -233.268014) (xy 368.442057 -233.313077) (xy 368.411484 -233.353763) (xy 368.37478 -233.389018)
			(xy 368.332896 -233.417928) (xy 368.286917 -233.439745) (xy 368.238033 -233.453905) (xy 368.187512 -233.460039)
			(xy 368.13666 -233.45799) (xy 368.086796 -233.44781) (xy 368.03921 -233.429763) (xy 367.995136 -233.404317)
			(xy 367.955714 -233.37213) (xy 367.921966 -233.334036) (xy 367.894765 -233.291022) (xy 367.874817 -233.244202)
			(xy 367.862638 -233.194788) (xy 367.858543 -233.14406) (xy 367.550446 -233.14406) (xy 367.549934 -233.169506)
			(xy 367.54177 -233.21974) (xy 367.525654 -233.268014) (xy 367.502003 -233.313077) (xy 367.47143 -233.353763)
			(xy 367.434726 -233.389018) (xy 367.392842 -233.417928) (xy 367.346863 -233.439745) (xy 367.297979 -233.453905)
			(xy 367.247458 -233.460039) (xy 367.196606 -233.45799) (xy 367.146742 -233.44781) (xy 367.099156 -233.429763)
			(xy 367.055082 -233.404317) (xy 367.01566 -233.37213) (xy 366.981912 -233.334036) (xy 366.954711 -233.291022)
			(xy 366.934763 -233.244202) (xy 366.922584 -233.194788) (xy 366.918489 -233.14406) (xy 366.600232 -233.14406)
			(xy 366.599737 -233.168667) (xy 366.591842 -233.217244) (xy 366.576258 -233.263925) (xy 366.553387 -233.307502)
			(xy 366.523822 -233.346846) (xy 366.488329 -233.380938) (xy 366.447826 -233.408894) (xy 366.403364 -233.429992)
			(xy 366.356093 -233.443684) (xy 366.307238 -233.449616) (xy 366.258063 -233.447635) (xy 366.209844 -233.437791)
			(xy 366.163828 -233.420339) (xy 366.121207 -233.395732) (xy 366.083086 -233.364607) (xy 366.050451 -233.32777)
			(xy 366.024148 -233.286174) (xy 366.004857 -233.240898) (xy 365.99308 -233.193114) (xy 365.98912 -233.14406)
			(xy 365.670592 -233.14406) (xy 365.67008 -233.169506) (xy 365.661916 -233.21974) (xy 365.6458 -233.268014)
			(xy 365.622149 -233.313077) (xy 365.591576 -233.353763) (xy 365.554872 -233.389018) (xy 365.512988 -233.417928)
			(xy 365.467009 -233.439745) (xy 365.418125 -233.453905) (xy 365.367604 -233.460039) (xy 365.316752 -233.45799)
			(xy 365.266888 -233.44781) (xy 365.219302 -233.429763) (xy 365.175228 -233.404317) (xy 365.135806 -233.37213)
			(xy 365.102058 -233.334036) (xy 365.074857 -233.291022) (xy 365.054909 -233.244202) (xy 365.04273 -233.194788)
			(xy 365.038635 -233.14406) (xy 364.730538 -233.14406) (xy 364.730026 -233.169506) (xy 364.721862 -233.21974)
			(xy 364.705746 -233.268014) (xy 364.682095 -233.313077) (xy 364.651522 -233.353763) (xy 364.614818 -233.389018)
			(xy 364.572934 -233.417928) (xy 364.526955 -233.439745) (xy 364.478071 -233.453905) (xy 364.42755 -233.460039)
			(xy 364.376698 -233.45799) (xy 364.326834 -233.44781) (xy 364.279248 -233.429763) (xy 364.235174 -233.404317)
			(xy 364.195752 -233.37213) (xy 364.162004 -233.334036) (xy 364.134803 -233.291022) (xy 364.114855 -233.244202)
			(xy 364.102676 -233.194788) (xy 364.098581 -233.14406) (xy 363.78007 -233.14406) (xy 363.779575 -233.168667)
			(xy 363.77168 -233.217244) (xy 363.756096 -233.263925) (xy 363.733225 -233.307502) (xy 363.70366 -233.346846)
			(xy 363.668167 -233.380938) (xy 363.627664 -233.408894) (xy 363.583202 -233.429992) (xy 363.535931 -233.443684)
			(xy 363.487076 -233.449616) (xy 363.437901 -233.447635) (xy 363.389682 -233.437791) (xy 363.343666 -233.420339)
			(xy 363.301045 -233.395732) (xy 363.262924 -233.364607) (xy 363.230289 -233.32777) (xy 363.203986 -233.286174)
			(xy 363.184695 -233.240898) (xy 363.172918 -233.193114) (xy 363.168958 -233.14406) (xy 362.840016 -233.14406)
			(xy 362.839521 -233.168667) (xy 362.831626 -233.217244) (xy 362.816042 -233.263925) (xy 362.793171 -233.307502)
			(xy 362.763606 -233.346846) (xy 362.728113 -233.380938) (xy 362.68761 -233.408894) (xy 362.643148 -233.429992)
			(xy 362.595877 -233.443684) (xy 362.547022 -233.449616) (xy 362.497847 -233.447635) (xy 362.449628 -233.437791)
			(xy 362.403612 -233.420339) (xy 362.360991 -233.395732) (xy 362.32287 -233.364607) (xy 362.290235 -233.32777)
			(xy 362.263932 -233.286174) (xy 362.244641 -233.240898) (xy 362.232864 -233.193114) (xy 362.228904 -233.14406)
			(xy 361.900216 -233.14406) (xy 361.899721 -233.168667) (xy 361.891826 -233.217244) (xy 361.876242 -233.263925)
			(xy 361.853371 -233.307502) (xy 361.823806 -233.346846) (xy 361.788313 -233.380938) (xy 361.74781 -233.408894)
			(xy 361.703348 -233.429992) (xy 361.656077 -233.443684) (xy 361.607222 -233.449616) (xy 361.558047 -233.447635)
			(xy 361.509828 -233.437791) (xy 361.463812 -233.420339) (xy 361.421191 -233.395732) (xy 361.38307 -233.364607)
			(xy 361.350435 -233.32777) (xy 361.324132 -233.286174) (xy 361.304841 -233.240898) (xy 361.293064 -233.193114)
			(xy 361.289104 -233.14406) (xy 360.27868 -233.14406) (xy 360.27868 -233.954066) (xy 360.81895 -233.954066)
			(xy 360.82291 -233.905012) (xy 360.834687 -233.857228) (xy 360.853978 -233.811952) (xy 360.880281 -233.770356)
			(xy 360.912916 -233.733519) (xy 360.951037 -233.702394) (xy 360.993658 -233.677787) (xy 361.039674 -233.660335)
			(xy 361.087893 -233.650491) (xy 361.137068 -233.64851) (xy 361.185923 -233.654442) (xy 361.233194 -233.668134)
			(xy 361.277656 -233.689232) (xy 361.318159 -233.717188) (xy 361.353652 -233.75128) (xy 361.383217 -233.790624)
			(xy 361.406088 -233.834201) (xy 361.421672 -233.880882) (xy 361.429567 -233.929459) (xy 361.430062 -233.954066)
			(xy 361.748573 -233.954066) (xy 361.752668 -233.903338) (xy 361.764847 -233.853924) (xy 361.784795 -233.807104)
			(xy 361.811996 -233.76409) (xy 361.845744 -233.725996) (xy 361.885166 -233.693809) (xy 361.92924 -233.668363)
			(xy 361.976826 -233.650316) (xy 362.02669 -233.640136) (xy 362.077542 -233.638087) (xy 362.128063 -233.644221)
			(xy 362.176947 -233.658381) (xy 362.222926 -233.680198) (xy 362.26481 -233.709108) (xy 362.301514 -233.744363)
			(xy 362.332087 -233.785049) (xy 362.355738 -233.830112) (xy 362.371854 -233.878386) (xy 362.380018 -233.92862)
			(xy 362.38053 -233.954066) (xy 362.688627 -233.954066) (xy 362.692722 -233.903338) (xy 362.704901 -233.853924)
			(xy 362.724849 -233.807104) (xy 362.75205 -233.76409) (xy 362.785798 -233.725996) (xy 362.82522 -233.693809)
			(xy 362.869294 -233.668363) (xy 362.91688 -233.650316) (xy 362.966744 -233.640136) (xy 363.017596 -233.638087)
			(xy 363.068117 -233.644221) (xy 363.117001 -233.658381) (xy 363.16298 -233.680198) (xy 363.204864 -233.709108)
			(xy 363.241568 -233.744363) (xy 363.272141 -233.785049) (xy 363.295792 -233.830112) (xy 363.311908 -233.878386)
			(xy 363.320072 -233.92862) (xy 363.320584 -233.954066) (xy 363.639112 -233.954066) (xy 363.643072 -233.905012)
			(xy 363.654849 -233.857228) (xy 363.67414 -233.811952) (xy 363.700443 -233.770356) (xy 363.733078 -233.733519)
			(xy 363.771199 -233.702394) (xy 363.81382 -233.677787) (xy 363.859836 -233.660335) (xy 363.908055 -233.650491)
			(xy 363.95723 -233.64851) (xy 364.006085 -233.654442) (xy 364.053356 -233.668134) (xy 364.097818 -233.689232)
			(xy 364.138321 -233.717188) (xy 364.173814 -233.75128) (xy 364.203379 -233.790624) (xy 364.22625 -233.834201)
			(xy 364.241834 -233.880882) (xy 364.249729 -233.929459) (xy 364.250224 -233.954066) (xy 366.45902 -233.954066)
			(xy 366.46298 -233.905012) (xy 366.474757 -233.857228) (xy 366.494048 -233.811952) (xy 366.520351 -233.770356)
			(xy 366.552986 -233.733519) (xy 366.591107 -233.702394) (xy 366.633728 -233.677787) (xy 366.679744 -233.660335)
			(xy 366.727963 -233.650491) (xy 366.777138 -233.64851) (xy 366.825993 -233.654442) (xy 366.873264 -233.668134)
			(xy 366.917726 -233.689232) (xy 366.958229 -233.717188) (xy 366.993722 -233.75128) (xy 367.023287 -233.790624)
			(xy 367.046158 -233.834201) (xy 367.061742 -233.880882) (xy 367.069637 -233.929459) (xy 367.070132 -233.954066)
			(xy 369.278928 -233.954066) (xy 369.282888 -233.905012) (xy 369.294665 -233.857228) (xy 369.313956 -233.811952)
			(xy 369.340259 -233.770356) (xy 369.372894 -233.733519) (xy 369.411015 -233.702394) (xy 369.453636 -233.677787)
			(xy 369.499652 -233.660335) (xy 369.547871 -233.650491) (xy 369.597046 -233.64851) (xy 369.645901 -233.654442)
			(xy 369.693172 -233.668134) (xy 369.737634 -233.689232) (xy 369.778137 -233.717188) (xy 369.81363 -233.75128)
			(xy 369.843195 -233.790624) (xy 369.866066 -233.834201) (xy 369.88165 -233.880882) (xy 369.889545 -233.929459)
			(xy 369.89004 -233.954066) (xy 372.09909 -233.954066) (xy 372.10305 -233.905012) (xy 372.114827 -233.857228)
			(xy 372.134118 -233.811952) (xy 372.160421 -233.770356) (xy 372.193056 -233.733519) (xy 372.231177 -233.702394)
			(xy 372.273798 -233.677787) (xy 372.319814 -233.660335) (xy 372.368033 -233.650491) (xy 372.417208 -233.64851)
			(xy 372.466063 -233.654442) (xy 372.513334 -233.668134) (xy 372.557796 -233.689232) (xy 372.598299 -233.717188)
			(xy 372.633792 -233.75128) (xy 372.663357 -233.790624) (xy 372.686228 -233.834201) (xy 372.701812 -233.880882)
			(xy 372.709707 -233.929459) (xy 372.710202 -233.954066) (xy 372.709707 -233.978673) (xy 372.701812 -234.02725)
			(xy 372.686228 -234.073931) (xy 372.663357 -234.117508) (xy 372.633792 -234.156852) (xy 372.598299 -234.190944)
			(xy 372.557796 -234.2189) (xy 372.513334 -234.239998) (xy 372.466063 -234.25369) (xy 372.417208 -234.259622)
			(xy 372.368033 -234.257641) (xy 372.319814 -234.247797) (xy 372.273798 -234.230345) (xy 372.231177 -234.205738)
			(xy 372.193056 -234.174613) (xy 372.160421 -234.137776) (xy 372.134118 -234.09618) (xy 372.114827 -234.050904)
			(xy 372.10305 -234.00312) (xy 372.09909 -233.954066) (xy 369.89004 -233.954066) (xy 369.889545 -233.978673)
			(xy 369.88165 -234.02725) (xy 369.866066 -234.073931) (xy 369.843195 -234.117508) (xy 369.81363 -234.156852)
			(xy 369.778137 -234.190944) (xy 369.737634 -234.2189) (xy 369.693172 -234.239998) (xy 369.645901 -234.25369)
			(xy 369.597046 -234.259622) (xy 369.547871 -234.257641) (xy 369.499652 -234.247797) (xy 369.453636 -234.230345)
			(xy 369.411015 -234.205738) (xy 369.372894 -234.174613) (xy 369.340259 -234.137776) (xy 369.313956 -234.09618)
			(xy 369.294665 -234.050904) (xy 369.282888 -234.00312) (xy 369.278928 -233.954066) (xy 367.070132 -233.954066)
			(xy 367.069637 -233.978673) (xy 367.061742 -234.02725) (xy 367.046158 -234.073931) (xy 367.023287 -234.117508)
			(xy 366.993722 -234.156852) (xy 366.958229 -234.190944) (xy 366.917726 -234.2189) (xy 366.873264 -234.239998)
			(xy 366.825993 -234.25369) (xy 366.777138 -234.259622) (xy 366.727963 -234.257641) (xy 366.679744 -234.247797)
			(xy 366.633728 -234.230345) (xy 366.591107 -234.205738) (xy 366.552986 -234.174613) (xy 366.520351 -234.137776)
			(xy 366.494048 -234.09618) (xy 366.474757 -234.050904) (xy 366.46298 -234.00312) (xy 366.45902 -233.954066)
			(xy 364.250224 -233.954066) (xy 364.249729 -233.978673) (xy 364.241834 -234.02725) (xy 364.22625 -234.073931)
			(xy 364.203379 -234.117508) (xy 364.173814 -234.156852) (xy 364.138321 -234.190944) (xy 364.097818 -234.2189)
			(xy 364.053356 -234.239998) (xy 364.006085 -234.25369) (xy 363.95723 -234.259622) (xy 363.908055 -234.257641)
			(xy 363.859836 -234.247797) (xy 363.81382 -234.230345) (xy 363.771199 -234.205738) (xy 363.733078 -234.174613)
			(xy 363.700443 -234.137776) (xy 363.67414 -234.09618) (xy 363.654849 -234.050904) (xy 363.643072 -234.00312)
			(xy 363.639112 -233.954066) (xy 363.320584 -233.954066) (xy 363.320072 -233.979512) (xy 363.311908 -234.029746)
			(xy 363.295792 -234.07802) (xy 363.272141 -234.123083) (xy 363.241568 -234.163769) (xy 363.204864 -234.199024)
			(xy 363.16298 -234.227934) (xy 363.117001 -234.249751) (xy 363.068117 -234.263911) (xy 363.017596 -234.270045)
			(xy 362.966744 -234.267996) (xy 362.91688 -234.257816) (xy 362.869294 -234.239769) (xy 362.82522 -234.214323)
			(xy 362.785798 -234.182136) (xy 362.75205 -234.144042) (xy 362.724849 -234.101028) (xy 362.704901 -234.054208)
			(xy 362.692722 -234.004794) (xy 362.688627 -233.954066) (xy 362.38053 -233.954066) (xy 362.380018 -233.979512)
			(xy 362.371854 -234.029746) (xy 362.355738 -234.07802) (xy 362.332087 -234.123083) (xy 362.301514 -234.163769)
			(xy 362.26481 -234.199024) (xy 362.222926 -234.227934) (xy 362.176947 -234.249751) (xy 362.128063 -234.263911)
			(xy 362.077542 -234.270045) (xy 362.02669 -234.267996) (xy 361.976826 -234.257816) (xy 361.92924 -234.239769)
			(xy 361.885166 -234.214323) (xy 361.845744 -234.182136) (xy 361.811996 -234.144042) (xy 361.784795 -234.101028)
			(xy 361.764847 -234.054208) (xy 361.752668 -234.004794) (xy 361.748573 -233.954066) (xy 361.430062 -233.954066)
			(xy 361.429567 -233.978673) (xy 361.421672 -234.02725) (xy 361.406088 -234.073931) (xy 361.383217 -234.117508)
			(xy 361.353652 -234.156852) (xy 361.318159 -234.190944) (xy 361.277656 -234.2189) (xy 361.233194 -234.239998)
			(xy 361.185923 -234.25369) (xy 361.137068 -234.259622) (xy 361.087893 -234.257641) (xy 361.039674 -234.247797)
			(xy 360.993658 -234.230345) (xy 360.951037 -234.205738) (xy 360.912916 -234.174613) (xy 360.880281 -234.137776)
			(xy 360.853978 -234.09618) (xy 360.834687 -234.050904) (xy 360.82291 -234.00312) (xy 360.81895 -233.954066)
			(xy 360.27868 -233.954066) (xy 360.27868 -234.764072) (xy 363.168958 -234.764072) (xy 363.172918 -234.715018)
			(xy 363.184695 -234.667234) (xy 363.203986 -234.621958) (xy 363.230289 -234.580362) (xy 363.262924 -234.543525)
			(xy 363.301045 -234.5124) (xy 363.343666 -234.487793) (xy 363.389682 -234.470341) (xy 363.437901 -234.460497)
			(xy 363.487076 -234.458516) (xy 363.535931 -234.464448) (xy 363.583202 -234.47814) (xy 363.627664 -234.499238)
			(xy 363.668167 -234.527194) (xy 363.70366 -234.561286) (xy 363.733225 -234.60063) (xy 363.756096 -234.644207)
			(xy 363.77168 -234.690888) (xy 363.779575 -234.739465) (xy 363.78007 -234.764072) (xy 364.098581 -234.764072)
			(xy 364.102676 -234.713344) (xy 364.114855 -234.66393) (xy 364.134803 -234.61711) (xy 364.162004 -234.574096)
			(xy 364.195752 -234.536002) (xy 364.235174 -234.503815) (xy 364.279248 -234.478369) (xy 364.326834 -234.460322)
			(xy 364.376698 -234.450142) (xy 364.42755 -234.448093) (xy 364.478071 -234.454227) (xy 364.526955 -234.468387)
			(xy 364.572934 -234.490204) (xy 364.614818 -234.519114) (xy 364.651522 -234.554369) (xy 364.682095 -234.595055)
			(xy 364.705746 -234.640118) (xy 364.721862 -234.688392) (xy 364.730026 -234.738626) (xy 364.730538 -234.764072)
			(xy 365.038635 -234.764072) (xy 365.04273 -234.713344) (xy 365.054909 -234.66393) (xy 365.074857 -234.61711)
			(xy 365.102058 -234.574096) (xy 365.135806 -234.536002) (xy 365.175228 -234.503815) (xy 365.219302 -234.478369)
			(xy 365.266888 -234.460322) (xy 365.316752 -234.450142) (xy 365.367604 -234.448093) (xy 365.418125 -234.454227)
			(xy 365.467009 -234.468387) (xy 365.512988 -234.490204) (xy 365.554872 -234.519114) (xy 365.591576 -234.554369)
			(xy 365.622149 -234.595055) (xy 365.6458 -234.640118) (xy 365.661916 -234.688392) (xy 365.67008 -234.738626)
			(xy 365.670592 -234.764072) (xy 365.98912 -234.764072) (xy 365.99308 -234.715018) (xy 366.004857 -234.667234)
			(xy 366.024148 -234.621958) (xy 366.050451 -234.580362) (xy 366.083086 -234.543525) (xy 366.121207 -234.5124)
			(xy 366.163828 -234.487793) (xy 366.209844 -234.470341) (xy 366.258063 -234.460497) (xy 366.307238 -234.458516)
			(xy 366.356093 -234.464448) (xy 366.403364 -234.47814) (xy 366.447826 -234.499238) (xy 366.488329 -234.527194)
			(xy 366.523822 -234.561286) (xy 366.553387 -234.60063) (xy 366.576258 -234.644207) (xy 366.591842 -234.690888)
			(xy 366.599737 -234.739465) (xy 366.600232 -234.764072) (xy 366.918489 -234.764072) (xy 366.922584 -234.713344)
			(xy 366.934763 -234.66393) (xy 366.954711 -234.61711) (xy 366.981912 -234.574096) (xy 367.01566 -234.536002)
			(xy 367.055082 -234.503815) (xy 367.099156 -234.478369) (xy 367.146742 -234.460322) (xy 367.196606 -234.450142)
			(xy 367.247458 -234.448093) (xy 367.297979 -234.454227) (xy 367.346863 -234.468387) (xy 367.392842 -234.490204)
			(xy 367.434726 -234.519114) (xy 367.47143 -234.554369) (xy 367.502003 -234.595055) (xy 367.525654 -234.640118)
			(xy 367.54177 -234.688392) (xy 367.549934 -234.738626) (xy 367.550446 -234.764072) (xy 367.858543 -234.764072)
			(xy 367.862638 -234.713344) (xy 367.874817 -234.66393) (xy 367.894765 -234.61711) (xy 367.921966 -234.574096)
			(xy 367.955714 -234.536002) (xy 367.995136 -234.503815) (xy 368.03921 -234.478369) (xy 368.086796 -234.460322)
			(xy 368.13666 -234.450142) (xy 368.187512 -234.448093) (xy 368.238033 -234.454227) (xy 368.286917 -234.468387)
			(xy 368.332896 -234.490204) (xy 368.37478 -234.519114) (xy 368.411484 -234.554369) (xy 368.442057 -234.595055)
			(xy 368.465708 -234.640118) (xy 368.481824 -234.688392) (xy 368.489988 -234.738626) (xy 368.4905 -234.764072)
			(xy 368.809028 -234.764072) (xy 368.812988 -234.715018) (xy 368.824765 -234.667234) (xy 368.844056 -234.621958)
			(xy 368.870359 -234.580362) (xy 368.902994 -234.543525) (xy 368.941115 -234.5124) (xy 368.983736 -234.487793)
			(xy 369.029752 -234.470341) (xy 369.077971 -234.460497) (xy 369.127146 -234.458516) (xy 369.176001 -234.464448)
			(xy 369.223272 -234.47814) (xy 369.267734 -234.499238) (xy 369.308237 -234.527194) (xy 369.34373 -234.561286)
			(xy 369.373295 -234.60063) (xy 369.396166 -234.644207) (xy 369.41175 -234.690888) (xy 369.419645 -234.739465)
			(xy 369.42014 -234.764072) (xy 369.738651 -234.764072) (xy 369.742746 -234.713344) (xy 369.754925 -234.66393)
			(xy 369.774873 -234.61711) (xy 369.802074 -234.574096) (xy 369.835822 -234.536002) (xy 369.875244 -234.503815)
			(xy 369.919318 -234.478369) (xy 369.966904 -234.460322) (xy 370.016768 -234.450142) (xy 370.06762 -234.448093)
			(xy 370.118141 -234.454227) (xy 370.167025 -234.468387) (xy 370.213004 -234.490204) (xy 370.254888 -234.519114)
			(xy 370.291592 -234.554369) (xy 370.322165 -234.595055) (xy 370.345816 -234.640118) (xy 370.361932 -234.688392)
			(xy 370.370096 -234.738626) (xy 370.370608 -234.764072) (xy 370.678451 -234.764072) (xy 370.682546 -234.713344)
			(xy 370.694725 -234.66393) (xy 370.714673 -234.61711) (xy 370.741874 -234.574096) (xy 370.775622 -234.536002)
			(xy 370.815044 -234.503815) (xy 370.859118 -234.478369) (xy 370.906704 -234.460322) (xy 370.956568 -234.450142)
			(xy 371.00742 -234.448093) (xy 371.057941 -234.454227) (xy 371.106825 -234.468387) (xy 371.152804 -234.490204)
			(xy 371.194688 -234.519114) (xy 371.231392 -234.554369) (xy 371.261965 -234.595055) (xy 371.285616 -234.640118)
			(xy 371.301732 -234.688392) (xy 371.309896 -234.738626) (xy 371.310408 -234.764072) (xy 371.628936 -234.764072)
			(xy 371.632896 -234.715018) (xy 371.644673 -234.667234) (xy 371.663964 -234.621958) (xy 371.690267 -234.580362)
			(xy 371.722902 -234.543525) (xy 371.761023 -234.5124) (xy 371.803644 -234.487793) (xy 371.84966 -234.470341)
			(xy 371.897879 -234.460497) (xy 371.947054 -234.458516) (xy 371.995909 -234.464448) (xy 372.04318 -234.47814)
			(xy 372.087642 -234.499238) (xy 372.128145 -234.527194) (xy 372.163638 -234.561286) (xy 372.193203 -234.60063)
			(xy 372.216074 -234.644207) (xy 372.231658 -234.690888) (xy 372.239553 -234.739465) (xy 372.240048 -234.764072)
			(xy 372.558559 -234.764072) (xy 372.562654 -234.713344) (xy 372.574833 -234.66393) (xy 372.594781 -234.61711)
			(xy 372.621982 -234.574096) (xy 372.65573 -234.536002) (xy 372.695152 -234.503815) (xy 372.739226 -234.478369)
			(xy 372.786812 -234.460322) (xy 372.836676 -234.450142) (xy 372.887528 -234.448093) (xy 372.938049 -234.454227)
			(xy 372.986933 -234.468387) (xy 373.032912 -234.490204) (xy 373.074796 -234.519114) (xy 373.1115 -234.554369)
			(xy 373.142073 -234.595055) (xy 373.165724 -234.640118) (xy 373.18184 -234.688392) (xy 373.190004 -234.738626)
			(xy 373.190516 -234.764072) (xy 373.498613 -234.764072) (xy 373.502708 -234.713344) (xy 373.514887 -234.66393)
			(xy 373.534835 -234.61711) (xy 373.562036 -234.574096) (xy 373.595784 -234.536002) (xy 373.635206 -234.503815)
			(xy 373.67928 -234.478369) (xy 373.726866 -234.460322) (xy 373.77673 -234.450142) (xy 373.827582 -234.448093)
			(xy 373.878103 -234.454227) (xy 373.926987 -234.468387) (xy 373.972966 -234.490204) (xy 374.01485 -234.519114)
			(xy 374.051554 -234.554369) (xy 374.082127 -234.595055) (xy 374.105778 -234.640118) (xy 374.121894 -234.688392)
			(xy 374.130058 -234.738626) (xy 374.13057 -234.764072) (xy 374.130058 -234.789518) (xy 374.121894 -234.839752)
			(xy 374.105778 -234.888026) (xy 374.082127 -234.933089) (xy 374.051554 -234.973775) (xy 374.01485 -235.00903)
			(xy 373.972966 -235.03794) (xy 373.926987 -235.059757) (xy 373.878103 -235.073917) (xy 373.827582 -235.080051)
			(xy 373.77673 -235.078002) (xy 373.726866 -235.067822) (xy 373.67928 -235.049775) (xy 373.635206 -235.024329)
			(xy 373.595784 -234.992142) (xy 373.562036 -234.954048) (xy 373.534835 -234.911034) (xy 373.514887 -234.864214)
			(xy 373.502708 -234.8148) (xy 373.498613 -234.764072) (xy 373.190516 -234.764072) (xy 373.190004 -234.789518)
			(xy 373.18184 -234.839752) (xy 373.165724 -234.888026) (xy 373.142073 -234.933089) (xy 373.1115 -234.973775)
			(xy 373.074796 -235.00903) (xy 373.032912 -235.03794) (xy 372.986933 -235.059757) (xy 372.938049 -235.073917)
			(xy 372.887528 -235.080051) (xy 372.836676 -235.078002) (xy 372.786812 -235.067822) (xy 372.739226 -235.049775)
			(xy 372.695152 -235.024329) (xy 372.65573 -234.992142) (xy 372.621982 -234.954048) (xy 372.594781 -234.911034)
			(xy 372.574833 -234.864214) (xy 372.562654 -234.8148) (xy 372.558559 -234.764072) (xy 372.240048 -234.764072)
			(xy 372.239553 -234.788679) (xy 372.231658 -234.837256) (xy 372.216074 -234.883937) (xy 372.193203 -234.927514)
			(xy 372.163638 -234.966858) (xy 372.128145 -235.00095) (xy 372.087642 -235.028906) (xy 372.04318 -235.050004)
			(xy 371.995909 -235.063696) (xy 371.947054 -235.069628) (xy 371.897879 -235.067647) (xy 371.84966 -235.057803)
			(xy 371.803644 -235.040351) (xy 371.761023 -235.015744) (xy 371.722902 -234.984619) (xy 371.690267 -234.947782)
			(xy 371.663964 -234.906186) (xy 371.644673 -234.86091) (xy 371.632896 -234.813126) (xy 371.628936 -234.764072)
			(xy 371.310408 -234.764072) (xy 371.309896 -234.789518) (xy 371.301732 -234.839752) (xy 371.285616 -234.888026)
			(xy 371.261965 -234.933089) (xy 371.231392 -234.973775) (xy 371.194688 -235.00903) (xy 371.152804 -235.03794)
			(xy 371.106825 -235.059757) (xy 371.057941 -235.073917) (xy 371.00742 -235.080051) (xy 370.956568 -235.078002)
			(xy 370.906704 -235.067822) (xy 370.859118 -235.049775) (xy 370.815044 -235.024329) (xy 370.775622 -234.992142)
			(xy 370.741874 -234.954048) (xy 370.714673 -234.911034) (xy 370.694725 -234.864214) (xy 370.682546 -234.8148)
			(xy 370.678451 -234.764072) (xy 370.370608 -234.764072) (xy 370.370096 -234.789518) (xy 370.361932 -234.839752)
			(xy 370.345816 -234.888026) (xy 370.322165 -234.933089) (xy 370.291592 -234.973775) (xy 370.254888 -235.00903)
			(xy 370.213004 -235.03794) (xy 370.167025 -235.059757) (xy 370.118141 -235.073917) (xy 370.06762 -235.080051)
			(xy 370.016768 -235.078002) (xy 369.966904 -235.067822) (xy 369.919318 -235.049775) (xy 369.875244 -235.024329)
			(xy 369.835822 -234.992142) (xy 369.802074 -234.954048) (xy 369.774873 -234.911034) (xy 369.754925 -234.864214)
			(xy 369.742746 -234.8148) (xy 369.738651 -234.764072) (xy 369.42014 -234.764072) (xy 369.419645 -234.788679)
			(xy 369.41175 -234.837256) (xy 369.396166 -234.883937) (xy 369.373295 -234.927514) (xy 369.34373 -234.966858)
			(xy 369.308237 -235.00095) (xy 369.267734 -235.028906) (xy 369.223272 -235.050004) (xy 369.176001 -235.063696)
			(xy 369.127146 -235.069628) (xy 369.077971 -235.067647) (xy 369.029752 -235.057803) (xy 368.983736 -235.040351)
			(xy 368.941115 -235.015744) (xy 368.902994 -234.984619) (xy 368.870359 -234.947782) (xy 368.844056 -234.906186)
			(xy 368.824765 -234.86091) (xy 368.812988 -234.813126) (xy 368.809028 -234.764072) (xy 368.4905 -234.764072)
			(xy 368.489988 -234.789518) (xy 368.481824 -234.839752) (xy 368.465708 -234.888026) (xy 368.442057 -234.933089)
			(xy 368.411484 -234.973775) (xy 368.37478 -235.00903) (xy 368.332896 -235.03794) (xy 368.286917 -235.059757)
			(xy 368.238033 -235.073917) (xy 368.187512 -235.080051) (xy 368.13666 -235.078002) (xy 368.086796 -235.067822)
			(xy 368.03921 -235.049775) (xy 367.995136 -235.024329) (xy 367.955714 -234.992142) (xy 367.921966 -234.954048)
			(xy 367.894765 -234.911034) (xy 367.874817 -234.864214) (xy 367.862638 -234.8148) (xy 367.858543 -234.764072)
			(xy 367.550446 -234.764072) (xy 367.549934 -234.789518) (xy 367.54177 -234.839752) (xy 367.525654 -234.888026)
			(xy 367.502003 -234.933089) (xy 367.47143 -234.973775) (xy 367.434726 -235.00903) (xy 367.392842 -235.03794)
			(xy 367.346863 -235.059757) (xy 367.297979 -235.073917) (xy 367.247458 -235.080051) (xy 367.196606 -235.078002)
			(xy 367.146742 -235.067822) (xy 367.099156 -235.049775) (xy 367.055082 -235.024329) (xy 367.01566 -234.992142)
			(xy 366.981912 -234.954048) (xy 366.954711 -234.911034) (xy 366.934763 -234.864214) (xy 366.922584 -234.8148)
			(xy 366.918489 -234.764072) (xy 366.600232 -234.764072) (xy 366.599737 -234.788679) (xy 366.591842 -234.837256)
			(xy 366.576258 -234.883937) (xy 366.553387 -234.927514) (xy 366.523822 -234.966858) (xy 366.488329 -235.00095)
			(xy 366.447826 -235.028906) (xy 366.403364 -235.050004) (xy 366.356093 -235.063696) (xy 366.307238 -235.069628)
			(xy 366.258063 -235.067647) (xy 366.209844 -235.057803) (xy 366.163828 -235.040351) (xy 366.121207 -235.015744)
			(xy 366.083086 -234.984619) (xy 366.050451 -234.947782) (xy 366.024148 -234.906186) (xy 366.004857 -234.86091)
			(xy 365.99308 -234.813126) (xy 365.98912 -234.764072) (xy 365.670592 -234.764072) (xy 365.67008 -234.789518)
			(xy 365.661916 -234.839752) (xy 365.6458 -234.888026) (xy 365.622149 -234.933089) (xy 365.591576 -234.973775)
			(xy 365.554872 -235.00903) (xy 365.512988 -235.03794) (xy 365.467009 -235.059757) (xy 365.418125 -235.073917)
			(xy 365.367604 -235.080051) (xy 365.316752 -235.078002) (xy 365.266888 -235.067822) (xy 365.219302 -235.049775)
			(xy 365.175228 -235.024329) (xy 365.135806 -234.992142) (xy 365.102058 -234.954048) (xy 365.074857 -234.911034)
			(xy 365.054909 -234.864214) (xy 365.04273 -234.8148) (xy 365.038635 -234.764072) (xy 364.730538 -234.764072)
			(xy 364.730026 -234.789518) (xy 364.721862 -234.839752) (xy 364.705746 -234.888026) (xy 364.682095 -234.933089)
			(xy 364.651522 -234.973775) (xy 364.614818 -235.00903) (xy 364.572934 -235.03794) (xy 364.526955 -235.059757)
			(xy 364.478071 -235.073917) (xy 364.42755 -235.080051) (xy 364.376698 -235.078002) (xy 364.326834 -235.067822)
			(xy 364.279248 -235.049775) (xy 364.235174 -235.024329) (xy 364.195752 -234.992142) (xy 364.162004 -234.954048)
			(xy 364.134803 -234.911034) (xy 364.114855 -234.864214) (xy 364.102676 -234.8148) (xy 364.098581 -234.764072)
			(xy 363.78007 -234.764072) (xy 363.779575 -234.788679) (xy 363.77168 -234.837256) (xy 363.756096 -234.883937)
			(xy 363.733225 -234.927514) (xy 363.70366 -234.966858) (xy 363.668167 -235.00095) (xy 363.627664 -235.028906)
			(xy 363.583202 -235.050004) (xy 363.535931 -235.063696) (xy 363.487076 -235.069628) (xy 363.437901 -235.067647)
			(xy 363.389682 -235.057803) (xy 363.343666 -235.040351) (xy 363.301045 -235.015744) (xy 363.262924 -234.984619)
			(xy 363.230289 -234.947782) (xy 363.203986 -234.906186) (xy 363.184695 -234.86091) (xy 363.172918 -234.813126)
			(xy 363.168958 -234.764072) (xy 360.27868 -234.764072) (xy 360.27868 -235.574078) (xy 360.81895 -235.574078)
			(xy 360.82291 -235.525024) (xy 360.834687 -235.47724) (xy 360.853978 -235.431964) (xy 360.880281 -235.390368)
			(xy 360.912916 -235.353531) (xy 360.951037 -235.322406) (xy 360.993658 -235.297799) (xy 361.039674 -235.280347)
			(xy 361.087893 -235.270503) (xy 361.137068 -235.268522) (xy 361.185923 -235.274454) (xy 361.233194 -235.288146)
			(xy 361.277656 -235.309244) (xy 361.318159 -235.3372) (xy 361.353652 -235.371292) (xy 361.383217 -235.410636)
			(xy 361.406088 -235.454213) (xy 361.421672 -235.500894) (xy 361.429567 -235.549471) (xy 361.430062 -235.574078)
			(xy 361.748573 -235.574078) (xy 361.752668 -235.52335) (xy 361.764847 -235.473936) (xy 361.784795 -235.427116)
			(xy 361.811996 -235.384102) (xy 361.845744 -235.346008) (xy 361.885166 -235.313821) (xy 361.92924 -235.288375)
			(xy 361.976826 -235.270328) (xy 362.02669 -235.260148) (xy 362.077542 -235.258099) (xy 362.128063 -235.264233)
			(xy 362.176947 -235.278393) (xy 362.222926 -235.30021) (xy 362.26481 -235.32912) (xy 362.301514 -235.364375)
			(xy 362.332087 -235.405061) (xy 362.355738 -235.450124) (xy 362.371854 -235.498398) (xy 362.380018 -235.548632)
			(xy 362.38053 -235.574078) (xy 362.688627 -235.574078) (xy 362.692722 -235.52335) (xy 362.704901 -235.473936)
			(xy 362.724849 -235.427116) (xy 362.75205 -235.384102) (xy 362.785798 -235.346008) (xy 362.82522 -235.313821)
			(xy 362.869294 -235.288375) (xy 362.91688 -235.270328) (xy 362.966744 -235.260148) (xy 363.017596 -235.258099)
			(xy 363.068117 -235.264233) (xy 363.117001 -235.278393) (xy 363.16298 -235.30021) (xy 363.204864 -235.32912)
			(xy 363.241568 -235.364375) (xy 363.272141 -235.405061) (xy 363.295792 -235.450124) (xy 363.311908 -235.498398)
			(xy 363.320072 -235.548632) (xy 363.320584 -235.574078) (xy 363.639112 -235.574078) (xy 363.643072 -235.525024)
			(xy 363.654849 -235.47724) (xy 363.67414 -235.431964) (xy 363.700443 -235.390368) (xy 363.733078 -235.353531)
			(xy 363.771199 -235.322406) (xy 363.81382 -235.297799) (xy 363.859836 -235.280347) (xy 363.908055 -235.270503)
			(xy 363.95723 -235.268522) (xy 364.006085 -235.274454) (xy 364.053356 -235.288146) (xy 364.097818 -235.309244)
			(xy 364.138321 -235.3372) (xy 364.173814 -235.371292) (xy 364.203379 -235.410636) (xy 364.22625 -235.454213)
			(xy 364.241834 -235.500894) (xy 364.249729 -235.549471) (xy 364.250224 -235.574078) (xy 364.578912 -235.574078)
			(xy 364.582872 -235.525024) (xy 364.594649 -235.47724) (xy 364.61394 -235.431964) (xy 364.640243 -235.390368)
			(xy 364.672878 -235.353531) (xy 364.710999 -235.322406) (xy 364.75362 -235.297799) (xy 364.799636 -235.280347)
			(xy 364.847855 -235.270503) (xy 364.89703 -235.268522) (xy 364.945885 -235.274454) (xy 364.993156 -235.288146)
			(xy 365.037618 -235.309244) (xy 365.078121 -235.3372) (xy 365.113614 -235.371292) (xy 365.143179 -235.410636)
			(xy 365.16605 -235.454213) (xy 365.181634 -235.500894) (xy 365.189529 -235.549471) (xy 365.190024 -235.574078)
			(xy 365.518966 -235.574078) (xy 365.522926 -235.525024) (xy 365.534703 -235.47724) (xy 365.553994 -235.431964)
			(xy 365.580297 -235.390368) (xy 365.612932 -235.353531) (xy 365.651053 -235.322406) (xy 365.693674 -235.297799)
			(xy 365.73969 -235.280347) (xy 365.787909 -235.270503) (xy 365.837084 -235.268522) (xy 365.885939 -235.274454)
			(xy 365.93321 -235.288146) (xy 365.977672 -235.309244) (xy 366.018175 -235.3372) (xy 366.053668 -235.371292)
			(xy 366.083233 -235.410636) (xy 366.106104 -235.454213) (xy 366.121688 -235.500894) (xy 366.129583 -235.549471)
			(xy 366.130078 -235.574078) (xy 366.45902 -235.574078) (xy 366.46298 -235.525024) (xy 366.474757 -235.47724)
			(xy 366.494048 -235.431964) (xy 366.520351 -235.390368) (xy 366.552986 -235.353531) (xy 366.591107 -235.322406)
			(xy 366.633728 -235.297799) (xy 366.679744 -235.280347) (xy 366.727963 -235.270503) (xy 366.777138 -235.268522)
			(xy 366.825993 -235.274454) (xy 366.873264 -235.288146) (xy 366.917726 -235.309244) (xy 366.958229 -235.3372)
			(xy 366.993722 -235.371292) (xy 367.023287 -235.410636) (xy 367.046158 -235.454213) (xy 367.061742 -235.500894)
			(xy 367.069637 -235.549471) (xy 367.070132 -235.574078) (xy 367.399074 -235.574078) (xy 367.403034 -235.525024)
			(xy 367.414811 -235.47724) (xy 367.434102 -235.431964) (xy 367.460405 -235.390368) (xy 367.49304 -235.353531)
			(xy 367.531161 -235.322406) (xy 367.573782 -235.297799) (xy 367.619798 -235.280347) (xy 367.668017 -235.270503)
			(xy 367.717192 -235.268522) (xy 367.766047 -235.274454) (xy 367.813318 -235.288146) (xy 367.85778 -235.309244)
			(xy 367.898283 -235.3372) (xy 367.933776 -235.371292) (xy 367.963341 -235.410636) (xy 367.986212 -235.454213)
			(xy 368.001796 -235.500894) (xy 368.009691 -235.549471) (xy 368.010186 -235.574078) (xy 368.338874 -235.574078)
			(xy 368.342834 -235.525024) (xy 368.354611 -235.47724) (xy 368.373902 -235.431964) (xy 368.400205 -235.390368)
			(xy 368.43284 -235.353531) (xy 368.470961 -235.322406) (xy 368.513582 -235.297799) (xy 368.559598 -235.280347)
			(xy 368.607817 -235.270503) (xy 368.656992 -235.268522) (xy 368.705847 -235.274454) (xy 368.753118 -235.288146)
			(xy 368.79758 -235.309244) (xy 368.838083 -235.3372) (xy 368.873576 -235.371292) (xy 368.903141 -235.410636)
			(xy 368.926012 -235.454213) (xy 368.941596 -235.500894) (xy 368.949491 -235.549471) (xy 368.949986 -235.574078)
			(xy 369.278928 -235.574078) (xy 369.282888 -235.525024) (xy 369.294665 -235.47724) (xy 369.313956 -235.431964)
			(xy 369.340259 -235.390368) (xy 369.372894 -235.353531) (xy 369.411015 -235.322406) (xy 369.453636 -235.297799)
			(xy 369.499652 -235.280347) (xy 369.547871 -235.270503) (xy 369.597046 -235.268522) (xy 369.645901 -235.274454)
			(xy 369.693172 -235.288146) (xy 369.737634 -235.309244) (xy 369.778137 -235.3372) (xy 369.81363 -235.371292)
			(xy 369.843195 -235.410636) (xy 369.866066 -235.454213) (xy 369.88165 -235.500894) (xy 369.889545 -235.549471)
			(xy 369.89004 -235.574078) (xy 370.218982 -235.574078) (xy 370.222942 -235.525024) (xy 370.234719 -235.47724)
			(xy 370.25401 -235.431964) (xy 370.280313 -235.390368) (xy 370.312948 -235.353531) (xy 370.351069 -235.322406)
			(xy 370.39369 -235.297799) (xy 370.439706 -235.280347) (xy 370.487925 -235.270503) (xy 370.5371 -235.268522)
			(xy 370.585955 -235.274454) (xy 370.633226 -235.288146) (xy 370.677688 -235.309244) (xy 370.718191 -235.3372)
			(xy 370.753684 -235.371292) (xy 370.783249 -235.410636) (xy 370.80612 -235.454213) (xy 370.821704 -235.500894)
			(xy 370.829599 -235.549471) (xy 370.830094 -235.574078) (xy 371.159036 -235.574078) (xy 371.162996 -235.525024)
			(xy 371.174773 -235.47724) (xy 371.194064 -235.431964) (xy 371.220367 -235.390368) (xy 371.253002 -235.353531)
			(xy 371.291123 -235.322406) (xy 371.333744 -235.297799) (xy 371.37976 -235.280347) (xy 371.427979 -235.270503)
			(xy 371.477154 -235.268522) (xy 371.526009 -235.274454) (xy 371.57328 -235.288146) (xy 371.617742 -235.309244)
			(xy 371.658245 -235.3372) (xy 371.693738 -235.371292) (xy 371.723303 -235.410636) (xy 371.746174 -235.454213)
			(xy 371.761758 -235.500894) (xy 371.769653 -235.549471) (xy 371.770148 -235.574078) (xy 372.09909 -235.574078)
			(xy 372.10305 -235.525024) (xy 372.114827 -235.47724) (xy 372.134118 -235.431964) (xy 372.160421 -235.390368)
			(xy 372.193056 -235.353531) (xy 372.231177 -235.322406) (xy 372.273798 -235.297799) (xy 372.319814 -235.280347)
			(xy 372.368033 -235.270503) (xy 372.417208 -235.268522) (xy 372.466063 -235.274454) (xy 372.513334 -235.288146)
			(xy 372.557796 -235.309244) (xy 372.598299 -235.3372) (xy 372.633792 -235.371292) (xy 372.663357 -235.410636)
			(xy 372.686228 -235.454213) (xy 372.701812 -235.500894) (xy 372.709707 -235.549471) (xy 372.710202 -235.574078)
			(xy 373.03889 -235.574078) (xy 373.04285 -235.525024) (xy 373.054627 -235.47724) (xy 373.073918 -235.431964)
			(xy 373.100221 -235.390368) (xy 373.132856 -235.353531) (xy 373.170977 -235.322406) (xy 373.213598 -235.297799)
			(xy 373.259614 -235.280347) (xy 373.307833 -235.270503) (xy 373.357008 -235.268522) (xy 373.405863 -235.274454)
			(xy 373.453134 -235.288146) (xy 373.497596 -235.309244) (xy 373.538099 -235.3372) (xy 373.573592 -235.371292)
			(xy 373.603157 -235.410636) (xy 373.626028 -235.454213) (xy 373.641612 -235.500894) (xy 373.649507 -235.549471)
			(xy 373.650002 -235.574078) (xy 373.649507 -235.598685) (xy 373.641612 -235.647262) (xy 373.626028 -235.693943)
			(xy 373.603157 -235.73752) (xy 373.573592 -235.776864) (xy 373.538099 -235.810956) (xy 373.497596 -235.838912)
			(xy 373.453134 -235.86001) (xy 373.405863 -235.873702) (xy 373.357008 -235.879634) (xy 373.307833 -235.877653)
			(xy 373.259614 -235.867809) (xy 373.213598 -235.850357) (xy 373.170977 -235.82575) (xy 373.132856 -235.794625)
			(xy 373.100221 -235.757788) (xy 373.073918 -235.716192) (xy 373.054627 -235.670916) (xy 373.04285 -235.623132)
			(xy 373.03889 -235.574078) (xy 372.710202 -235.574078) (xy 372.709707 -235.598685) (xy 372.701812 -235.647262)
			(xy 372.686228 -235.693943) (xy 372.663357 -235.73752) (xy 372.633792 -235.776864) (xy 372.598299 -235.810956)
			(xy 372.557796 -235.838912) (xy 372.513334 -235.86001) (xy 372.466063 -235.873702) (xy 372.417208 -235.879634)
			(xy 372.368033 -235.877653) (xy 372.319814 -235.867809) (xy 372.273798 -235.850357) (xy 372.231177 -235.82575)
			(xy 372.193056 -235.794625) (xy 372.160421 -235.757788) (xy 372.134118 -235.716192) (xy 372.114827 -235.670916)
			(xy 372.10305 -235.623132) (xy 372.09909 -235.574078) (xy 371.770148 -235.574078) (xy 371.769653 -235.598685)
			(xy 371.761758 -235.647262) (xy 371.746174 -235.693943) (xy 371.723303 -235.73752) (xy 371.693738 -235.776864)
			(xy 371.658245 -235.810956) (xy 371.617742 -235.838912) (xy 371.57328 -235.86001) (xy 371.526009 -235.873702)
			(xy 371.477154 -235.879634) (xy 371.427979 -235.877653) (xy 371.37976 -235.867809) (xy 371.333744 -235.850357)
			(xy 371.291123 -235.82575) (xy 371.253002 -235.794625) (xy 371.220367 -235.757788) (xy 371.194064 -235.716192)
			(xy 371.174773 -235.670916) (xy 371.162996 -235.623132) (xy 371.159036 -235.574078) (xy 370.830094 -235.574078)
			(xy 370.829599 -235.598685) (xy 370.821704 -235.647262) (xy 370.80612 -235.693943) (xy 370.783249 -235.73752)
			(xy 370.753684 -235.776864) (xy 370.718191 -235.810956) (xy 370.677688 -235.838912) (xy 370.633226 -235.86001)
			(xy 370.585955 -235.873702) (xy 370.5371 -235.879634) (xy 370.487925 -235.877653) (xy 370.439706 -235.867809)
			(xy 370.39369 -235.850357) (xy 370.351069 -235.82575) (xy 370.312948 -235.794625) (xy 370.280313 -235.757788)
			(xy 370.25401 -235.716192) (xy 370.234719 -235.670916) (xy 370.222942 -235.623132) (xy 370.218982 -235.574078)
			(xy 369.89004 -235.574078) (xy 369.889545 -235.598685) (xy 369.88165 -235.647262) (xy 369.866066 -235.693943)
			(xy 369.843195 -235.73752) (xy 369.81363 -235.776864) (xy 369.778137 -235.810956) (xy 369.737634 -235.838912)
			(xy 369.693172 -235.86001) (xy 369.645901 -235.873702) (xy 369.597046 -235.879634) (xy 369.547871 -235.877653)
			(xy 369.499652 -235.867809) (xy 369.453636 -235.850357) (xy 369.411015 -235.82575) (xy 369.372894 -235.794625)
			(xy 369.340259 -235.757788) (xy 369.313956 -235.716192) (xy 369.294665 -235.670916) (xy 369.282888 -235.623132)
			(xy 369.278928 -235.574078) (xy 368.949986 -235.574078) (xy 368.949491 -235.598685) (xy 368.941596 -235.647262)
			(xy 368.926012 -235.693943) (xy 368.903141 -235.73752) (xy 368.873576 -235.776864) (xy 368.838083 -235.810956)
			(xy 368.79758 -235.838912) (xy 368.753118 -235.86001) (xy 368.705847 -235.873702) (xy 368.656992 -235.879634)
			(xy 368.607817 -235.877653) (xy 368.559598 -235.867809) (xy 368.513582 -235.850357) (xy 368.470961 -235.82575)
			(xy 368.43284 -235.794625) (xy 368.400205 -235.757788) (xy 368.373902 -235.716192) (xy 368.354611 -235.670916)
			(xy 368.342834 -235.623132) (xy 368.338874 -235.574078) (xy 368.010186 -235.574078) (xy 368.009691 -235.598685)
			(xy 368.001796 -235.647262) (xy 367.986212 -235.693943) (xy 367.963341 -235.73752) (xy 367.933776 -235.776864)
			(xy 367.898283 -235.810956) (xy 367.85778 -235.838912) (xy 367.813318 -235.86001) (xy 367.766047 -235.873702)
			(xy 367.717192 -235.879634) (xy 367.668017 -235.877653) (xy 367.619798 -235.867809) (xy 367.573782 -235.850357)
			(xy 367.531161 -235.82575) (xy 367.49304 -235.794625) (xy 367.460405 -235.757788) (xy 367.434102 -235.716192)
			(xy 367.414811 -235.670916) (xy 367.403034 -235.623132) (xy 367.399074 -235.574078) (xy 367.070132 -235.574078)
			(xy 367.069637 -235.598685) (xy 367.061742 -235.647262) (xy 367.046158 -235.693943) (xy 367.023287 -235.73752)
			(xy 366.993722 -235.776864) (xy 366.958229 -235.810956) (xy 366.917726 -235.838912) (xy 366.873264 -235.86001)
			(xy 366.825993 -235.873702) (xy 366.777138 -235.879634) (xy 366.727963 -235.877653) (xy 366.679744 -235.867809)
			(xy 366.633728 -235.850357) (xy 366.591107 -235.82575) (xy 366.552986 -235.794625) (xy 366.520351 -235.757788)
			(xy 366.494048 -235.716192) (xy 366.474757 -235.670916) (xy 366.46298 -235.623132) (xy 366.45902 -235.574078)
			(xy 366.130078 -235.574078) (xy 366.129583 -235.598685) (xy 366.121688 -235.647262) (xy 366.106104 -235.693943)
			(xy 366.083233 -235.73752) (xy 366.053668 -235.776864) (xy 366.018175 -235.810956) (xy 365.977672 -235.838912)
			(xy 365.93321 -235.86001) (xy 365.885939 -235.873702) (xy 365.837084 -235.879634) (xy 365.787909 -235.877653)
			(xy 365.73969 -235.867809) (xy 365.693674 -235.850357) (xy 365.651053 -235.82575) (xy 365.612932 -235.794625)
			(xy 365.580297 -235.757788) (xy 365.553994 -235.716192) (xy 365.534703 -235.670916) (xy 365.522926 -235.623132)
			(xy 365.518966 -235.574078) (xy 365.190024 -235.574078) (xy 365.189529 -235.598685) (xy 365.181634 -235.647262)
			(xy 365.16605 -235.693943) (xy 365.143179 -235.73752) (xy 365.113614 -235.776864) (xy 365.078121 -235.810956)
			(xy 365.037618 -235.838912) (xy 364.993156 -235.86001) (xy 364.945885 -235.873702) (xy 364.89703 -235.879634)
			(xy 364.847855 -235.877653) (xy 364.799636 -235.867809) (xy 364.75362 -235.850357) (xy 364.710999 -235.82575)
			(xy 364.672878 -235.794625) (xy 364.640243 -235.757788) (xy 364.61394 -235.716192) (xy 364.594649 -235.670916)
			(xy 364.582872 -235.623132) (xy 364.578912 -235.574078) (xy 364.250224 -235.574078) (xy 364.249729 -235.598685)
			(xy 364.241834 -235.647262) (xy 364.22625 -235.693943) (xy 364.203379 -235.73752) (xy 364.173814 -235.776864)
			(xy 364.138321 -235.810956) (xy 364.097818 -235.838912) (xy 364.053356 -235.86001) (xy 364.006085 -235.873702)
			(xy 363.95723 -235.879634) (xy 363.908055 -235.877653) (xy 363.859836 -235.867809) (xy 363.81382 -235.850357)
			(xy 363.771199 -235.82575) (xy 363.733078 -235.794625) (xy 363.700443 -235.757788) (xy 363.67414 -235.716192)
			(xy 363.654849 -235.670916) (xy 363.643072 -235.623132) (xy 363.639112 -235.574078) (xy 363.320584 -235.574078)
			(xy 363.320072 -235.599524) (xy 363.311908 -235.649758) (xy 363.295792 -235.698032) (xy 363.272141 -235.743095)
			(xy 363.241568 -235.783781) (xy 363.204864 -235.819036) (xy 363.16298 -235.847946) (xy 363.117001 -235.869763)
			(xy 363.068117 -235.883923) (xy 363.017596 -235.890057) (xy 362.966744 -235.888008) (xy 362.91688 -235.877828)
			(xy 362.869294 -235.859781) (xy 362.82522 -235.834335) (xy 362.785798 -235.802148) (xy 362.75205 -235.764054)
			(xy 362.724849 -235.72104) (xy 362.704901 -235.67422) (xy 362.692722 -235.624806) (xy 362.688627 -235.574078)
			(xy 362.38053 -235.574078) (xy 362.380018 -235.599524) (xy 362.371854 -235.649758) (xy 362.355738 -235.698032)
			(xy 362.332087 -235.743095) (xy 362.301514 -235.783781) (xy 362.26481 -235.819036) (xy 362.222926 -235.847946)
			(xy 362.176947 -235.869763) (xy 362.128063 -235.883923) (xy 362.077542 -235.890057) (xy 362.02669 -235.888008)
			(xy 361.976826 -235.877828) (xy 361.92924 -235.859781) (xy 361.885166 -235.834335) (xy 361.845744 -235.802148)
			(xy 361.811996 -235.764054) (xy 361.784795 -235.72104) (xy 361.764847 -235.67422) (xy 361.752668 -235.624806)
			(xy 361.748573 -235.574078) (xy 361.430062 -235.574078) (xy 361.429567 -235.598685) (xy 361.421672 -235.647262)
			(xy 361.406088 -235.693943) (xy 361.383217 -235.73752) (xy 361.353652 -235.776864) (xy 361.318159 -235.810956)
			(xy 361.277656 -235.838912) (xy 361.233194 -235.86001) (xy 361.185923 -235.873702) (xy 361.137068 -235.879634)
			(xy 361.087893 -235.877653) (xy 361.039674 -235.867809) (xy 360.993658 -235.850357) (xy 360.951037 -235.82575)
			(xy 360.912916 -235.794625) (xy 360.880281 -235.757788) (xy 360.853978 -235.716192) (xy 360.834687 -235.670916)
			(xy 360.82291 -235.623132) (xy 360.81895 -235.574078) (xy 360.27868 -235.574078) (xy 360.27868 -236.384084)
			(xy 361.289104 -236.384084) (xy 361.293064 -236.33503) (xy 361.304841 -236.287246) (xy 361.324132 -236.24197)
			(xy 361.350435 -236.200374) (xy 361.38307 -236.163537) (xy 361.421191 -236.132412) (xy 361.463812 -236.107805)
			(xy 361.509828 -236.090353) (xy 361.558047 -236.080509) (xy 361.607222 -236.078528) (xy 361.656077 -236.08446)
			(xy 361.703348 -236.098152) (xy 361.74781 -236.11925) (xy 361.788313 -236.147206) (xy 361.823806 -236.181298)
			(xy 361.853371 -236.220642) (xy 361.876242 -236.264219) (xy 361.891826 -236.3109) (xy 361.899721 -236.359477)
			(xy 361.900216 -236.384084) (xy 362.228904 -236.384084) (xy 362.232864 -236.33503) (xy 362.244641 -236.287246)
			(xy 362.263932 -236.24197) (xy 362.290235 -236.200374) (xy 362.32287 -236.163537) (xy 362.360991 -236.132412)
			(xy 362.403612 -236.107805) (xy 362.449628 -236.090353) (xy 362.497847 -236.080509) (xy 362.547022 -236.078528)
			(xy 362.595877 -236.08446) (xy 362.643148 -236.098152) (xy 362.68761 -236.11925) (xy 362.728113 -236.147206)
			(xy 362.763606 -236.181298) (xy 362.793171 -236.220642) (xy 362.816042 -236.264219) (xy 362.831626 -236.3109)
			(xy 362.839521 -236.359477) (xy 362.840016 -236.384084) (xy 363.168958 -236.384084) (xy 363.172918 -236.33503)
			(xy 363.184695 -236.287246) (xy 363.203986 -236.24197) (xy 363.230289 -236.200374) (xy 363.262924 -236.163537)
			(xy 363.301045 -236.132412) (xy 363.343666 -236.107805) (xy 363.389682 -236.090353) (xy 363.437901 -236.080509)
			(xy 363.487076 -236.078528) (xy 363.535931 -236.08446) (xy 363.583202 -236.098152) (xy 363.627664 -236.11925)
			(xy 363.668167 -236.147206) (xy 363.70366 -236.181298) (xy 363.733225 -236.220642) (xy 363.756096 -236.264219)
			(xy 363.77168 -236.3109) (xy 363.779575 -236.359477) (xy 363.78007 -236.384084) (xy 365.98912 -236.384084)
			(xy 365.99308 -236.33503) (xy 366.004857 -236.287246) (xy 366.024148 -236.24197) (xy 366.050451 -236.200374)
			(xy 366.083086 -236.163537) (xy 366.121207 -236.132412) (xy 366.163828 -236.107805) (xy 366.209844 -236.090353)
			(xy 366.258063 -236.080509) (xy 366.307238 -236.078528) (xy 366.356093 -236.08446) (xy 366.403364 -236.098152)
			(xy 366.447826 -236.11925) (xy 366.488329 -236.147206) (xy 366.523822 -236.181298) (xy 366.553387 -236.220642)
			(xy 366.576258 -236.264219) (xy 366.591842 -236.3109) (xy 366.599737 -236.359477) (xy 366.600232 -236.384084)
			(xy 368.809028 -236.384084) (xy 368.812988 -236.33503) (xy 368.824765 -236.287246) (xy 368.844056 -236.24197)
			(xy 368.870359 -236.200374) (xy 368.902994 -236.163537) (xy 368.941115 -236.132412) (xy 368.983736 -236.107805)
			(xy 369.029752 -236.090353) (xy 369.077971 -236.080509) (xy 369.127146 -236.078528) (xy 369.176001 -236.08446)
			(xy 369.223272 -236.098152) (xy 369.267734 -236.11925) (xy 369.308237 -236.147206) (xy 369.34373 -236.181298)
			(xy 369.373295 -236.220642) (xy 369.396166 -236.264219) (xy 369.41175 -236.3109) (xy 369.419645 -236.359477)
			(xy 369.42014 -236.384084) (xy 369.738651 -236.384084) (xy 369.742746 -236.333356) (xy 369.754925 -236.283942)
			(xy 369.774873 -236.237122) (xy 369.802074 -236.194108) (xy 369.835822 -236.156014) (xy 369.875244 -236.123827)
			(xy 369.919318 -236.098381) (xy 369.966904 -236.080334) (xy 370.016768 -236.070154) (xy 370.06762 -236.068105)
			(xy 370.118141 -236.074239) (xy 370.167025 -236.088399) (xy 370.213004 -236.110216) (xy 370.254888 -236.139126)
			(xy 370.291592 -236.174381) (xy 370.322165 -236.215067) (xy 370.345816 -236.26013) (xy 370.361932 -236.308404)
			(xy 370.370096 -236.358638) (xy 370.370608 -236.384084) (xy 370.678451 -236.384084) (xy 370.682546 -236.333356)
			(xy 370.694725 -236.283942) (xy 370.714673 -236.237122) (xy 370.741874 -236.194108) (xy 370.775622 -236.156014)
			(xy 370.815044 -236.123827) (xy 370.859118 -236.098381) (xy 370.906704 -236.080334) (xy 370.956568 -236.070154)
			(xy 371.00742 -236.068105) (xy 371.057941 -236.074239) (xy 371.106825 -236.088399) (xy 371.152804 -236.110216)
			(xy 371.194688 -236.139126) (xy 371.231392 -236.174381) (xy 371.261965 -236.215067) (xy 371.285616 -236.26013)
			(xy 371.301732 -236.308404) (xy 371.309896 -236.358638) (xy 371.310408 -236.384084) (xy 371.628936 -236.384084)
			(xy 371.632896 -236.33503) (xy 371.644673 -236.287246) (xy 371.663964 -236.24197) (xy 371.690267 -236.200374)
			(xy 371.722902 -236.163537) (xy 371.761023 -236.132412) (xy 371.803644 -236.107805) (xy 371.84966 -236.090353)
			(xy 371.897879 -236.080509) (xy 371.947054 -236.078528) (xy 371.995909 -236.08446) (xy 372.04318 -236.098152)
			(xy 372.087642 -236.11925) (xy 372.128145 -236.147206) (xy 372.163638 -236.181298) (xy 372.193203 -236.220642)
			(xy 372.216074 -236.264219) (xy 372.231658 -236.3109) (xy 372.239553 -236.359477) (xy 372.240048 -236.384084)
			(xy 372.558559 -236.384084) (xy 372.562654 -236.333356) (xy 372.574833 -236.283942) (xy 372.594781 -236.237122)
			(xy 372.621982 -236.194108) (xy 372.65573 -236.156014) (xy 372.695152 -236.123827) (xy 372.739226 -236.098381)
			(xy 372.786812 -236.080334) (xy 372.836676 -236.070154) (xy 372.887528 -236.068105) (xy 372.938049 -236.074239)
			(xy 372.986933 -236.088399) (xy 373.032912 -236.110216) (xy 373.074796 -236.139126) (xy 373.1115 -236.174381)
			(xy 373.142073 -236.215067) (xy 373.165724 -236.26013) (xy 373.18184 -236.308404) (xy 373.190004 -236.358638)
			(xy 373.190516 -236.384084) (xy 373.498613 -236.384084) (xy 373.502708 -236.333356) (xy 373.514887 -236.283942)
			(xy 373.534835 -236.237122) (xy 373.562036 -236.194108) (xy 373.595784 -236.156014) (xy 373.635206 -236.123827)
			(xy 373.67928 -236.098381) (xy 373.726866 -236.080334) (xy 373.77673 -236.070154) (xy 373.827582 -236.068105)
			(xy 373.878103 -236.074239) (xy 373.926987 -236.088399) (xy 373.972966 -236.110216) (xy 374.01485 -236.139126)
			(xy 374.051554 -236.174381) (xy 374.082127 -236.215067) (xy 374.105778 -236.26013) (xy 374.121894 -236.308404)
			(xy 374.130058 -236.358638) (xy 374.13057 -236.384084) (xy 374.130058 -236.40953) (xy 374.121894 -236.459764)
			(xy 374.105778 -236.508038) (xy 374.082127 -236.553101) (xy 374.051554 -236.593787) (xy 374.01485 -236.629042)
			(xy 373.972966 -236.657952) (xy 373.926987 -236.679769) (xy 373.878103 -236.693929) (xy 373.827582 -236.700063)
			(xy 373.77673 -236.698014) (xy 373.726866 -236.687834) (xy 373.67928 -236.669787) (xy 373.635206 -236.644341)
			(xy 373.595784 -236.612154) (xy 373.562036 -236.57406) (xy 373.534835 -236.531046) (xy 373.514887 -236.484226)
			(xy 373.502708 -236.434812) (xy 373.498613 -236.384084) (xy 373.190516 -236.384084) (xy 373.190004 -236.40953)
			(xy 373.18184 -236.459764) (xy 373.165724 -236.508038) (xy 373.142073 -236.553101) (xy 373.1115 -236.593787)
			(xy 373.074796 -236.629042) (xy 373.032912 -236.657952) (xy 372.986933 -236.679769) (xy 372.938049 -236.693929)
			(xy 372.887528 -236.700063) (xy 372.836676 -236.698014) (xy 372.786812 -236.687834) (xy 372.739226 -236.669787)
			(xy 372.695152 -236.644341) (xy 372.65573 -236.612154) (xy 372.621982 -236.57406) (xy 372.594781 -236.531046)
			(xy 372.574833 -236.484226) (xy 372.562654 -236.434812) (xy 372.558559 -236.384084) (xy 372.240048 -236.384084)
			(xy 372.239553 -236.408691) (xy 372.231658 -236.457268) (xy 372.216074 -236.503949) (xy 372.193203 -236.547526)
			(xy 372.163638 -236.58687) (xy 372.128145 -236.620962) (xy 372.087642 -236.648918) (xy 372.04318 -236.670016)
			(xy 371.995909 -236.683708) (xy 371.947054 -236.68964) (xy 371.897879 -236.687659) (xy 371.84966 -236.677815)
			(xy 371.803644 -236.660363) (xy 371.761023 -236.635756) (xy 371.722902 -236.604631) (xy 371.690267 -236.567794)
			(xy 371.663964 -236.526198) (xy 371.644673 -236.480922) (xy 371.632896 -236.433138) (xy 371.628936 -236.384084)
			(xy 371.310408 -236.384084) (xy 371.309896 -236.40953) (xy 371.301732 -236.459764) (xy 371.285616 -236.508038)
			(xy 371.261965 -236.553101) (xy 371.231392 -236.593787) (xy 371.194688 -236.629042) (xy 371.152804 -236.657952)
			(xy 371.106825 -236.679769) (xy 371.057941 -236.693929) (xy 371.00742 -236.700063) (xy 370.956568 -236.698014)
			(xy 370.906704 -236.687834) (xy 370.859118 -236.669787) (xy 370.815044 -236.644341) (xy 370.775622 -236.612154)
			(xy 370.741874 -236.57406) (xy 370.714673 -236.531046) (xy 370.694725 -236.484226) (xy 370.682546 -236.434812)
			(xy 370.678451 -236.384084) (xy 370.370608 -236.384084) (xy 370.370096 -236.40953) (xy 370.361932 -236.459764)
			(xy 370.345816 -236.508038) (xy 370.322165 -236.553101) (xy 370.291592 -236.593787) (xy 370.254888 -236.629042)
			(xy 370.213004 -236.657952) (xy 370.167025 -236.679769) (xy 370.118141 -236.693929) (xy 370.06762 -236.700063)
			(xy 370.016768 -236.698014) (xy 369.966904 -236.687834) (xy 369.919318 -236.669787) (xy 369.875244 -236.644341)
			(xy 369.835822 -236.612154) (xy 369.802074 -236.57406) (xy 369.774873 -236.531046) (xy 369.754925 -236.484226)
			(xy 369.742746 -236.434812) (xy 369.738651 -236.384084) (xy 369.42014 -236.384084) (xy 369.419645 -236.408691)
			(xy 369.41175 -236.457268) (xy 369.396166 -236.503949) (xy 369.373295 -236.547526) (xy 369.34373 -236.58687)
			(xy 369.308237 -236.620962) (xy 369.267734 -236.648918) (xy 369.223272 -236.670016) (xy 369.176001 -236.683708)
			(xy 369.127146 -236.68964) (xy 369.077971 -236.687659) (xy 369.029752 -236.677815) (xy 368.983736 -236.660363)
			(xy 368.941115 -236.635756) (xy 368.902994 -236.604631) (xy 368.870359 -236.567794) (xy 368.844056 -236.526198)
			(xy 368.824765 -236.480922) (xy 368.812988 -236.433138) (xy 368.809028 -236.384084) (xy 366.600232 -236.384084)
			(xy 366.599737 -236.408691) (xy 366.591842 -236.457268) (xy 366.576258 -236.503949) (xy 366.553387 -236.547526)
			(xy 366.523822 -236.58687) (xy 366.488329 -236.620962) (xy 366.447826 -236.648918) (xy 366.403364 -236.670016)
			(xy 366.356093 -236.683708) (xy 366.307238 -236.68964) (xy 366.258063 -236.687659) (xy 366.209844 -236.677815)
			(xy 366.163828 -236.660363) (xy 366.121207 -236.635756) (xy 366.083086 -236.604631) (xy 366.050451 -236.567794)
			(xy 366.024148 -236.526198) (xy 366.004857 -236.480922) (xy 365.99308 -236.433138) (xy 365.98912 -236.384084)
			(xy 363.78007 -236.384084) (xy 363.779575 -236.408691) (xy 363.77168 -236.457268) (xy 363.756096 -236.503949)
			(xy 363.733225 -236.547526) (xy 363.70366 -236.58687) (xy 363.668167 -236.620962) (xy 363.627664 -236.648918)
			(xy 363.583202 -236.670016) (xy 363.535931 -236.683708) (xy 363.487076 -236.68964) (xy 363.437901 -236.687659)
			(xy 363.389682 -236.677815) (xy 363.343666 -236.660363) (xy 363.301045 -236.635756) (xy 363.262924 -236.604631)
			(xy 363.230289 -236.567794) (xy 363.203986 -236.526198) (xy 363.184695 -236.480922) (xy 363.172918 -236.433138)
			(xy 363.168958 -236.384084) (xy 362.840016 -236.384084) (xy 362.839521 -236.408691) (xy 362.831626 -236.457268)
			(xy 362.816042 -236.503949) (xy 362.793171 -236.547526) (xy 362.763606 -236.58687) (xy 362.728113 -236.620962)
			(xy 362.68761 -236.648918) (xy 362.643148 -236.670016) (xy 362.595877 -236.683708) (xy 362.547022 -236.68964)
			(xy 362.497847 -236.687659) (xy 362.449628 -236.677815) (xy 362.403612 -236.660363) (xy 362.360991 -236.635756)
			(xy 362.32287 -236.604631) (xy 362.290235 -236.567794) (xy 362.263932 -236.526198) (xy 362.244641 -236.480922)
			(xy 362.232864 -236.433138) (xy 362.228904 -236.384084) (xy 361.900216 -236.384084) (xy 361.899721 -236.408691)
			(xy 361.891826 -236.457268) (xy 361.876242 -236.503949) (xy 361.853371 -236.547526) (xy 361.823806 -236.58687)
			(xy 361.788313 -236.620962) (xy 361.74781 -236.648918) (xy 361.703348 -236.670016) (xy 361.656077 -236.683708)
			(xy 361.607222 -236.68964) (xy 361.558047 -236.687659) (xy 361.509828 -236.677815) (xy 361.463812 -236.660363)
			(xy 361.421191 -236.635756) (xy 361.38307 -236.604631) (xy 361.350435 -236.567794) (xy 361.324132 -236.526198)
			(xy 361.304841 -236.480922) (xy 361.293064 -236.433138) (xy 361.289104 -236.384084) (xy 360.27868 -236.384084)
			(xy 360.27868 -237.19409) (xy 360.81895 -237.19409) (xy 360.82291 -237.145036) (xy 360.834687 -237.097252)
			(xy 360.853978 -237.051976) (xy 360.880281 -237.01038) (xy 360.912916 -236.973543) (xy 360.951037 -236.942418)
			(xy 360.993658 -236.917811) (xy 361.039674 -236.900359) (xy 361.087893 -236.890515) (xy 361.137068 -236.888534)
			(xy 361.185923 -236.894466) (xy 361.233194 -236.908158) (xy 361.277656 -236.929256) (xy 361.318159 -236.957212)
			(xy 361.353652 -236.991304) (xy 361.383217 -237.030648) (xy 361.406088 -237.074225) (xy 361.421672 -237.120906)
			(xy 361.429567 -237.169483) (xy 361.430062 -237.19409) (xy 363.639112 -237.19409) (xy 363.643072 -237.145036)
			(xy 363.654849 -237.097252) (xy 363.67414 -237.051976) (xy 363.700443 -237.01038) (xy 363.733078 -236.973543)
			(xy 363.771199 -236.942418) (xy 363.81382 -236.917811) (xy 363.859836 -236.900359) (xy 363.908055 -236.890515)
			(xy 363.95723 -236.888534) (xy 364.006085 -236.894466) (xy 364.053356 -236.908158) (xy 364.097818 -236.929256)
			(xy 364.138321 -236.957212) (xy 364.173814 -236.991304) (xy 364.203379 -237.030648) (xy 364.22625 -237.074225)
			(xy 364.241834 -237.120906) (xy 364.249729 -237.169483) (xy 364.250224 -237.19409) (xy 364.578912 -237.19409)
			(xy 364.582872 -237.145036) (xy 364.594649 -237.097252) (xy 364.61394 -237.051976) (xy 364.640243 -237.01038)
			(xy 364.672878 -236.973543) (xy 364.710999 -236.942418) (xy 364.75362 -236.917811) (xy 364.799636 -236.900359)
			(xy 364.847855 -236.890515) (xy 364.89703 -236.888534) (xy 364.945885 -236.894466) (xy 364.993156 -236.908158)
			(xy 365.037618 -236.929256) (xy 365.078121 -236.957212) (xy 365.113614 -236.991304) (xy 365.143179 -237.030648)
			(xy 365.16605 -237.074225) (xy 365.181634 -237.120906) (xy 365.189529 -237.169483) (xy 365.190024 -237.19409)
			(xy 365.518966 -237.19409) (xy 365.522926 -237.145036) (xy 365.534703 -237.097252) (xy 365.553994 -237.051976)
			(xy 365.580297 -237.01038) (xy 365.612932 -236.973543) (xy 365.651053 -236.942418) (xy 365.693674 -236.917811)
			(xy 365.73969 -236.900359) (xy 365.787909 -236.890515) (xy 365.837084 -236.888534) (xy 365.885939 -236.894466)
			(xy 365.93321 -236.908158) (xy 365.977672 -236.929256) (xy 366.018175 -236.957212) (xy 366.053668 -236.991304)
			(xy 366.083233 -237.030648) (xy 366.106104 -237.074225) (xy 366.121688 -237.120906) (xy 366.129583 -237.169483)
			(xy 366.130078 -237.19409) (xy 366.45902 -237.19409) (xy 366.46298 -237.145036) (xy 366.474757 -237.097252)
			(xy 366.494048 -237.051976) (xy 366.520351 -237.01038) (xy 366.552986 -236.973543) (xy 366.591107 -236.942418)
			(xy 366.633728 -236.917811) (xy 366.679744 -236.900359) (xy 366.727963 -236.890515) (xy 366.777138 -236.888534)
			(xy 366.825993 -236.894466) (xy 366.873264 -236.908158) (xy 366.917726 -236.929256) (xy 366.958229 -236.957212)
			(xy 366.993722 -236.991304) (xy 367.023287 -237.030648) (xy 367.046158 -237.074225) (xy 367.061742 -237.120906)
			(xy 367.069637 -237.169483) (xy 367.070132 -237.19409) (xy 367.399074 -237.19409) (xy 367.403034 -237.145036)
			(xy 367.414811 -237.097252) (xy 367.434102 -237.051976) (xy 367.460405 -237.01038) (xy 367.49304 -236.973543)
			(xy 367.531161 -236.942418) (xy 367.573782 -236.917811) (xy 367.619798 -236.900359) (xy 367.668017 -236.890515)
			(xy 367.717192 -236.888534) (xy 367.766047 -236.894466) (xy 367.813318 -236.908158) (xy 367.85778 -236.929256)
			(xy 367.898283 -236.957212) (xy 367.933776 -236.991304) (xy 367.963341 -237.030648) (xy 367.986212 -237.074225)
			(xy 368.001796 -237.120906) (xy 368.009691 -237.169483) (xy 368.010186 -237.19409) (xy 368.338874 -237.19409)
			(xy 368.342834 -237.145036) (xy 368.354611 -237.097252) (xy 368.373902 -237.051976) (xy 368.400205 -237.01038)
			(xy 368.43284 -236.973543) (xy 368.470961 -236.942418) (xy 368.513582 -236.917811) (xy 368.559598 -236.900359)
			(xy 368.607817 -236.890515) (xy 368.656992 -236.888534) (xy 368.705847 -236.894466) (xy 368.753118 -236.908158)
			(xy 368.79758 -236.929256) (xy 368.838083 -236.957212) (xy 368.873576 -236.991304) (xy 368.903141 -237.030648)
			(xy 368.926012 -237.074225) (xy 368.941596 -237.120906) (xy 368.949491 -237.169483) (xy 368.949986 -237.19409)
			(xy 369.278928 -237.19409) (xy 369.282888 -237.145036) (xy 369.294665 -237.097252) (xy 369.313956 -237.051976)
			(xy 369.340259 -237.01038) (xy 369.372894 -236.973543) (xy 369.411015 -236.942418) (xy 369.453636 -236.917811)
			(xy 369.499652 -236.900359) (xy 369.547871 -236.890515) (xy 369.597046 -236.888534) (xy 369.645901 -236.894466)
			(xy 369.693172 -236.908158) (xy 369.737634 -236.929256) (xy 369.778137 -236.957212) (xy 369.81363 -236.991304)
			(xy 369.843195 -237.030648) (xy 369.866066 -237.074225) (xy 369.88165 -237.120906) (xy 369.889545 -237.169483)
			(xy 369.89004 -237.19409) (xy 370.218982 -237.19409) (xy 370.222942 -237.145036) (xy 370.234719 -237.097252)
			(xy 370.25401 -237.051976) (xy 370.280313 -237.01038) (xy 370.312948 -236.973543) (xy 370.351069 -236.942418)
			(xy 370.39369 -236.917811) (xy 370.439706 -236.900359) (xy 370.487925 -236.890515) (xy 370.5371 -236.888534)
			(xy 370.585955 -236.894466) (xy 370.633226 -236.908158) (xy 370.677688 -236.929256) (xy 370.718191 -236.957212)
			(xy 370.753684 -236.991304) (xy 370.783249 -237.030648) (xy 370.80612 -237.074225) (xy 370.821704 -237.120906)
			(xy 370.829599 -237.169483) (xy 370.830094 -237.19409) (xy 371.159036 -237.19409) (xy 371.162996 -237.145036)
			(xy 371.174773 -237.097252) (xy 371.194064 -237.051976) (xy 371.220367 -237.01038) (xy 371.253002 -236.973543)
			(xy 371.291123 -236.942418) (xy 371.333744 -236.917811) (xy 371.37976 -236.900359) (xy 371.427979 -236.890515)
			(xy 371.477154 -236.888534) (xy 371.526009 -236.894466) (xy 371.57328 -236.908158) (xy 371.617742 -236.929256)
			(xy 371.658245 -236.957212) (xy 371.693738 -236.991304) (xy 371.723303 -237.030648) (xy 371.746174 -237.074225)
			(xy 371.761758 -237.120906) (xy 371.769653 -237.169483) (xy 371.770148 -237.19409) (xy 372.09909 -237.19409)
			(xy 372.10305 -237.145036) (xy 372.114827 -237.097252) (xy 372.134118 -237.051976) (xy 372.160421 -237.01038)
			(xy 372.193056 -236.973543) (xy 372.231177 -236.942418) (xy 372.273798 -236.917811) (xy 372.319814 -236.900359)
			(xy 372.368033 -236.890515) (xy 372.417208 -236.888534) (xy 372.466063 -236.894466) (xy 372.513334 -236.908158)
			(xy 372.557796 -236.929256) (xy 372.598299 -236.957212) (xy 372.633792 -236.991304) (xy 372.663357 -237.030648)
			(xy 372.686228 -237.074225) (xy 372.701812 -237.120906) (xy 372.709707 -237.169483) (xy 372.710202 -237.19409)
			(xy 373.03889 -237.19409) (xy 373.04285 -237.145036) (xy 373.054627 -237.097252) (xy 373.073918 -237.051976)
			(xy 373.100221 -237.01038) (xy 373.132856 -236.973543) (xy 373.170977 -236.942418) (xy 373.213598 -236.917811)
			(xy 373.259614 -236.900359) (xy 373.307833 -236.890515) (xy 373.357008 -236.888534) (xy 373.405863 -236.894466)
			(xy 373.453134 -236.908158) (xy 373.497596 -236.929256) (xy 373.538099 -236.957212) (xy 373.573592 -236.991304)
			(xy 373.603157 -237.030648) (xy 373.626028 -237.074225) (xy 373.641612 -237.120906) (xy 373.649507 -237.169483)
			(xy 373.650002 -237.19409) (xy 373.649507 -237.218697) (xy 373.641612 -237.267274) (xy 373.626028 -237.313955)
			(xy 373.603157 -237.357532) (xy 373.573592 -237.396876) (xy 373.538099 -237.430968) (xy 373.497596 -237.458924)
			(xy 373.453134 -237.480022) (xy 373.405863 -237.493714) (xy 373.357008 -237.499646) (xy 373.307833 -237.497665)
			(xy 373.259614 -237.487821) (xy 373.213598 -237.470369) (xy 373.170977 -237.445762) (xy 373.132856 -237.414637)
			(xy 373.100221 -237.3778) (xy 373.073918 -237.336204) (xy 373.054627 -237.290928) (xy 373.04285 -237.243144)
			(xy 373.03889 -237.19409) (xy 372.710202 -237.19409) (xy 372.709707 -237.218697) (xy 372.701812 -237.267274)
			(xy 372.686228 -237.313955) (xy 372.663357 -237.357532) (xy 372.633792 -237.396876) (xy 372.598299 -237.430968)
			(xy 372.557796 -237.458924) (xy 372.513334 -237.480022) (xy 372.466063 -237.493714) (xy 372.417208 -237.499646)
			(xy 372.368033 -237.497665) (xy 372.319814 -237.487821) (xy 372.273798 -237.470369) (xy 372.231177 -237.445762)
			(xy 372.193056 -237.414637) (xy 372.160421 -237.3778) (xy 372.134118 -237.336204) (xy 372.114827 -237.290928)
			(xy 372.10305 -237.243144) (xy 372.09909 -237.19409) (xy 371.770148 -237.19409) (xy 371.769653 -237.218697)
			(xy 371.761758 -237.267274) (xy 371.746174 -237.313955) (xy 371.723303 -237.357532) (xy 371.693738 -237.396876)
			(xy 371.658245 -237.430968) (xy 371.617742 -237.458924) (xy 371.57328 -237.480022) (xy 371.526009 -237.493714)
			(xy 371.477154 -237.499646) (xy 371.427979 -237.497665) (xy 371.37976 -237.487821) (xy 371.333744 -237.470369)
			(xy 371.291123 -237.445762) (xy 371.253002 -237.414637) (xy 371.220367 -237.3778) (xy 371.194064 -237.336204)
			(xy 371.174773 -237.290928) (xy 371.162996 -237.243144) (xy 371.159036 -237.19409) (xy 370.830094 -237.19409)
			(xy 370.829599 -237.218697) (xy 370.821704 -237.267274) (xy 370.80612 -237.313955) (xy 370.783249 -237.357532)
			(xy 370.753684 -237.396876) (xy 370.718191 -237.430968) (xy 370.677688 -237.458924) (xy 370.633226 -237.480022)
			(xy 370.585955 -237.493714) (xy 370.5371 -237.499646) (xy 370.487925 -237.497665) (xy 370.439706 -237.487821)
			(xy 370.39369 -237.470369) (xy 370.351069 -237.445762) (xy 370.312948 -237.414637) (xy 370.280313 -237.3778)
			(xy 370.25401 -237.336204) (xy 370.234719 -237.290928) (xy 370.222942 -237.243144) (xy 370.218982 -237.19409)
			(xy 369.89004 -237.19409) (xy 369.889545 -237.218697) (xy 369.88165 -237.267274) (xy 369.866066 -237.313955)
			(xy 369.843195 -237.357532) (xy 369.81363 -237.396876) (xy 369.778137 -237.430968) (xy 369.737634 -237.458924)
			(xy 369.693172 -237.480022) (xy 369.645901 -237.493714) (xy 369.597046 -237.499646) (xy 369.547871 -237.497665)
			(xy 369.499652 -237.487821) (xy 369.453636 -237.470369) (xy 369.411015 -237.445762) (xy 369.372894 -237.414637)
			(xy 369.340259 -237.3778) (xy 369.313956 -237.336204) (xy 369.294665 -237.290928) (xy 369.282888 -237.243144)
			(xy 369.278928 -237.19409) (xy 368.949986 -237.19409) (xy 368.949491 -237.218697) (xy 368.941596 -237.267274)
			(xy 368.926012 -237.313955) (xy 368.903141 -237.357532) (xy 368.873576 -237.396876) (xy 368.838083 -237.430968)
			(xy 368.79758 -237.458924) (xy 368.753118 -237.480022) (xy 368.705847 -237.493714) (xy 368.656992 -237.499646)
			(xy 368.607817 -237.497665) (xy 368.559598 -237.487821) (xy 368.513582 -237.470369) (xy 368.470961 -237.445762)
			(xy 368.43284 -237.414637) (xy 368.400205 -237.3778) (xy 368.373902 -237.336204) (xy 368.354611 -237.290928)
			(xy 368.342834 -237.243144) (xy 368.338874 -237.19409) (xy 368.010186 -237.19409) (xy 368.009691 -237.218697)
			(xy 368.001796 -237.267274) (xy 367.986212 -237.313955) (xy 367.963341 -237.357532) (xy 367.933776 -237.396876)
			(xy 367.898283 -237.430968) (xy 367.85778 -237.458924) (xy 367.813318 -237.480022) (xy 367.766047 -237.493714)
			(xy 367.717192 -237.499646) (xy 367.668017 -237.497665) (xy 367.619798 -237.487821) (xy 367.573782 -237.470369)
			(xy 367.531161 -237.445762) (xy 367.49304 -237.414637) (xy 367.460405 -237.3778) (xy 367.434102 -237.336204)
			(xy 367.414811 -237.290928) (xy 367.403034 -237.243144) (xy 367.399074 -237.19409) (xy 367.070132 -237.19409)
			(xy 367.069637 -237.218697) (xy 367.061742 -237.267274) (xy 367.046158 -237.313955) (xy 367.023287 -237.357532)
			(xy 366.993722 -237.396876) (xy 366.958229 -237.430968) (xy 366.917726 -237.458924) (xy 366.873264 -237.480022)
			(xy 366.825993 -237.493714) (xy 366.777138 -237.499646) (xy 366.727963 -237.497665) (xy 366.679744 -237.487821)
			(xy 366.633728 -237.470369) (xy 366.591107 -237.445762) (xy 366.552986 -237.414637) (xy 366.520351 -237.3778)
			(xy 366.494048 -237.336204) (xy 366.474757 -237.290928) (xy 366.46298 -237.243144) (xy 366.45902 -237.19409)
			(xy 366.130078 -237.19409) (xy 366.129583 -237.218697) (xy 366.121688 -237.267274) (xy 366.106104 -237.313955)
			(xy 366.083233 -237.357532) (xy 366.053668 -237.396876) (xy 366.018175 -237.430968) (xy 365.977672 -237.458924)
			(xy 365.93321 -237.480022) (xy 365.885939 -237.493714) (xy 365.837084 -237.499646) (xy 365.787909 -237.497665)
			(xy 365.73969 -237.487821) (xy 365.693674 -237.470369) (xy 365.651053 -237.445762) (xy 365.612932 -237.414637)
			(xy 365.580297 -237.3778) (xy 365.553994 -237.336204) (xy 365.534703 -237.290928) (xy 365.522926 -237.243144)
			(xy 365.518966 -237.19409) (xy 365.190024 -237.19409) (xy 365.189529 -237.218697) (xy 365.181634 -237.267274)
			(xy 365.16605 -237.313955) (xy 365.143179 -237.357532) (xy 365.113614 -237.396876) (xy 365.078121 -237.430968)
			(xy 365.037618 -237.458924) (xy 364.993156 -237.480022) (xy 364.945885 -237.493714) (xy 364.89703 -237.499646)
			(xy 364.847855 -237.497665) (xy 364.799636 -237.487821) (xy 364.75362 -237.470369) (xy 364.710999 -237.445762)
			(xy 364.672878 -237.414637) (xy 364.640243 -237.3778) (xy 364.61394 -237.336204) (xy 364.594649 -237.290928)
			(xy 364.582872 -237.243144) (xy 364.578912 -237.19409) (xy 364.250224 -237.19409) (xy 364.249729 -237.218697)
			(xy 364.241834 -237.267274) (xy 364.22625 -237.313955) (xy 364.203379 -237.357532) (xy 364.173814 -237.396876)
			(xy 364.138321 -237.430968) (xy 364.097818 -237.458924) (xy 364.053356 -237.480022) (xy 364.006085 -237.493714)
			(xy 363.95723 -237.499646) (xy 363.908055 -237.497665) (xy 363.859836 -237.487821) (xy 363.81382 -237.470369)
			(xy 363.771199 -237.445762) (xy 363.733078 -237.414637) (xy 363.700443 -237.3778) (xy 363.67414 -237.336204)
			(xy 363.654849 -237.290928) (xy 363.643072 -237.243144) (xy 363.639112 -237.19409) (xy 361.430062 -237.19409)
			(xy 361.429567 -237.218697) (xy 361.421672 -237.267274) (xy 361.406088 -237.313955) (xy 361.383217 -237.357532)
			(xy 361.353652 -237.396876) (xy 361.318159 -237.430968) (xy 361.277656 -237.458924) (xy 361.233194 -237.480022)
			(xy 361.185923 -237.493714) (xy 361.137068 -237.499646) (xy 361.087893 -237.497665) (xy 361.039674 -237.487821)
			(xy 360.993658 -237.470369) (xy 360.951037 -237.445762) (xy 360.912916 -237.414637) (xy 360.880281 -237.3778)
			(xy 360.853978 -237.336204) (xy 360.834687 -237.290928) (xy 360.82291 -237.243144) (xy 360.81895 -237.19409)
			(xy 360.27868 -237.19409) (xy 360.27868 -238.004096) (xy 361.289104 -238.004096) (xy 361.293064 -237.955042)
			(xy 361.304841 -237.907258) (xy 361.324132 -237.861982) (xy 361.350435 -237.820386) (xy 361.38307 -237.783549)
			(xy 361.421191 -237.752424) (xy 361.463812 -237.727817) (xy 361.509828 -237.710365) (xy 361.558047 -237.700521)
			(xy 361.607222 -237.69854) (xy 361.656077 -237.704472) (xy 361.703348 -237.718164) (xy 361.74781 -237.739262)
			(xy 361.788313 -237.767218) (xy 361.823806 -237.80131) (xy 361.853371 -237.840654) (xy 361.876242 -237.884231)
			(xy 361.891826 -237.930912) (xy 361.899721 -237.979489) (xy 361.900216 -238.004096) (xy 362.228904 -238.004096)
			(xy 362.232864 -237.955042) (xy 362.244641 -237.907258) (xy 362.263932 -237.861982) (xy 362.290235 -237.820386)
			(xy 362.32287 -237.783549) (xy 362.360991 -237.752424) (xy 362.403612 -237.727817) (xy 362.449628 -237.710365)
			(xy 362.497847 -237.700521) (xy 362.547022 -237.69854) (xy 362.595877 -237.704472) (xy 362.643148 -237.718164)
			(xy 362.68761 -237.739262) (xy 362.728113 -237.767218) (xy 362.763606 -237.80131) (xy 362.793171 -237.840654)
			(xy 362.816042 -237.884231) (xy 362.831626 -237.930912) (xy 362.839521 -237.979489) (xy 362.840016 -238.004096)
			(xy 363.168958 -238.004096) (xy 363.172918 -237.955042) (xy 363.184695 -237.907258) (xy 363.203986 -237.861982)
			(xy 363.230289 -237.820386) (xy 363.262924 -237.783549) (xy 363.301045 -237.752424) (xy 363.343666 -237.727817)
			(xy 363.389682 -237.710365) (xy 363.437901 -237.700521) (xy 363.487076 -237.69854) (xy 363.535931 -237.704472)
			(xy 363.583202 -237.718164) (xy 363.627664 -237.739262) (xy 363.668167 -237.767218) (xy 363.70366 -237.80131)
			(xy 363.733225 -237.840654) (xy 363.756096 -237.884231) (xy 363.77168 -237.930912) (xy 363.779575 -237.979489)
			(xy 363.78007 -238.004096) (xy 364.098581 -238.004096) (xy 364.102676 -237.953368) (xy 364.114855 -237.903954)
			(xy 364.134803 -237.857134) (xy 364.162004 -237.81412) (xy 364.195752 -237.776026) (xy 364.235174 -237.743839)
			(xy 364.279248 -237.718393) (xy 364.326834 -237.700346) (xy 364.376698 -237.690166) (xy 364.42755 -237.688117)
			(xy 364.478071 -237.694251) (xy 364.526955 -237.708411) (xy 364.572934 -237.730228) (xy 364.614818 -237.759138)
			(xy 364.651522 -237.794393) (xy 364.682095 -237.835079) (xy 364.705746 -237.880142) (xy 364.721862 -237.928416)
			(xy 364.730026 -237.97865) (xy 364.730538 -238.004096) (xy 365.038635 -238.004096) (xy 365.04273 -237.953368)
			(xy 365.054909 -237.903954) (xy 365.074857 -237.857134) (xy 365.102058 -237.81412) (xy 365.135806 -237.776026)
			(xy 365.175228 -237.743839) (xy 365.219302 -237.718393) (xy 365.266888 -237.700346) (xy 365.316752 -237.690166)
			(xy 365.367604 -237.688117) (xy 365.418125 -237.694251) (xy 365.467009 -237.708411) (xy 365.512988 -237.730228)
			(xy 365.554872 -237.759138) (xy 365.591576 -237.794393) (xy 365.622149 -237.835079) (xy 365.6458 -237.880142)
			(xy 365.661916 -237.928416) (xy 365.67008 -237.97865) (xy 365.670592 -238.004096) (xy 365.98912 -238.004096)
			(xy 365.99308 -237.955042) (xy 366.004857 -237.907258) (xy 366.024148 -237.861982) (xy 366.050451 -237.820386)
			(xy 366.083086 -237.783549) (xy 366.121207 -237.752424) (xy 366.163828 -237.727817) (xy 366.209844 -237.710365)
			(xy 366.258063 -237.700521) (xy 366.307238 -237.69854) (xy 366.356093 -237.704472) (xy 366.403364 -237.718164)
			(xy 366.447826 -237.739262) (xy 366.488329 -237.767218) (xy 366.523822 -237.80131) (xy 366.553387 -237.840654)
			(xy 366.576258 -237.884231) (xy 366.591842 -237.930912) (xy 366.599737 -237.979489) (xy 366.600232 -238.004096)
			(xy 366.92892 -238.004096) (xy 366.93288 -237.955042) (xy 366.944657 -237.907258) (xy 366.963948 -237.861982)
			(xy 366.990251 -237.820386) (xy 367.022886 -237.783549) (xy 367.061007 -237.752424) (xy 367.103628 -237.727817)
			(xy 367.149644 -237.710365) (xy 367.197863 -237.700521) (xy 367.247038 -237.69854) (xy 367.295893 -237.704472)
			(xy 367.343164 -237.718164) (xy 367.387626 -237.739262) (xy 367.428129 -237.767218) (xy 367.463622 -237.80131)
			(xy 367.493187 -237.840654) (xy 367.516058 -237.884231) (xy 367.531642 -237.930912) (xy 367.539537 -237.979489)
			(xy 367.540032 -238.004096) (xy 367.868974 -238.004096) (xy 367.872934 -237.955042) (xy 367.884711 -237.907258)
			(xy 367.904002 -237.861982) (xy 367.930305 -237.820386) (xy 367.96294 -237.783549) (xy 368.001061 -237.752424)
			(xy 368.043682 -237.727817) (xy 368.089698 -237.710365) (xy 368.137917 -237.700521) (xy 368.187092 -237.69854)
			(xy 368.235947 -237.704472) (xy 368.283218 -237.718164) (xy 368.32768 -237.739262) (xy 368.368183 -237.767218)
			(xy 368.403676 -237.80131) (xy 368.433241 -237.840654) (xy 368.456112 -237.884231) (xy 368.471696 -237.930912)
			(xy 368.479591 -237.979489) (xy 368.480086 -238.004096) (xy 368.809028 -238.004096) (xy 368.812988 -237.955042)
			(xy 368.824765 -237.907258) (xy 368.844056 -237.861982) (xy 368.870359 -237.820386) (xy 368.902994 -237.783549)
			(xy 368.941115 -237.752424) (xy 368.983736 -237.727817) (xy 369.029752 -237.710365) (xy 369.077971 -237.700521)
			(xy 369.127146 -237.69854) (xy 369.176001 -237.704472) (xy 369.223272 -237.718164) (xy 369.267734 -237.739262)
			(xy 369.308237 -237.767218) (xy 369.34373 -237.80131) (xy 369.373295 -237.840654) (xy 369.396166 -237.884231)
			(xy 369.41175 -237.930912) (xy 369.419645 -237.979489) (xy 369.42014 -238.004096) (xy 369.749082 -238.004096)
			(xy 369.753042 -237.955042) (xy 369.764819 -237.907258) (xy 369.78411 -237.861982) (xy 369.810413 -237.820386)
			(xy 369.843048 -237.783549) (xy 369.881169 -237.752424) (xy 369.92379 -237.727817) (xy 369.969806 -237.710365)
			(xy 370.018025 -237.700521) (xy 370.0672 -237.69854) (xy 370.116055 -237.704472) (xy 370.163326 -237.718164)
			(xy 370.207788 -237.739262) (xy 370.248291 -237.767218) (xy 370.283784 -237.80131) (xy 370.313349 -237.840654)
			(xy 370.33622 -237.884231) (xy 370.351804 -237.930912) (xy 370.359699 -237.979489) (xy 370.360194 -238.004096)
			(xy 370.688882 -238.004096) (xy 370.692842 -237.955042) (xy 370.704619 -237.907258) (xy 370.72391 -237.861982)
			(xy 370.750213 -237.820386) (xy 370.782848 -237.783549) (xy 370.820969 -237.752424) (xy 370.86359 -237.727817)
			(xy 370.909606 -237.710365) (xy 370.957825 -237.700521) (xy 371.007 -237.69854) (xy 371.055855 -237.704472)
			(xy 371.103126 -237.718164) (xy 371.147588 -237.739262) (xy 371.188091 -237.767218) (xy 371.223584 -237.80131)
			(xy 371.253149 -237.840654) (xy 371.27602 -237.884231) (xy 371.291604 -237.930912) (xy 371.299499 -237.979489)
			(xy 371.299994 -238.004096) (xy 371.628936 -238.004096) (xy 371.632896 -237.955042) (xy 371.644673 -237.907258)
			(xy 371.663964 -237.861982) (xy 371.690267 -237.820386) (xy 371.722902 -237.783549) (xy 371.761023 -237.752424)
			(xy 371.803644 -237.727817) (xy 371.84966 -237.710365) (xy 371.897879 -237.700521) (xy 371.947054 -237.69854)
			(xy 371.995909 -237.704472) (xy 372.04318 -237.718164) (xy 372.087642 -237.739262) (xy 372.128145 -237.767218)
			(xy 372.163638 -237.80131) (xy 372.193203 -237.840654) (xy 372.216074 -237.884231) (xy 372.231658 -237.930912)
			(xy 372.239553 -237.979489) (xy 372.240048 -238.004096) (xy 372.56899 -238.004096) (xy 372.57295 -237.955042)
			(xy 372.584727 -237.907258) (xy 372.604018 -237.861982) (xy 372.630321 -237.820386) (xy 372.662956 -237.783549)
			(xy 372.701077 -237.752424) (xy 372.743698 -237.727817) (xy 372.789714 -237.710365) (xy 372.837933 -237.700521)
			(xy 372.887108 -237.69854) (xy 372.935963 -237.704472) (xy 372.983234 -237.718164) (xy 373.027696 -237.739262)
			(xy 373.068199 -237.767218) (xy 373.103692 -237.80131) (xy 373.133257 -237.840654) (xy 373.156128 -237.884231)
			(xy 373.171712 -237.930912) (xy 373.179607 -237.979489) (xy 373.180102 -238.004096) (xy 373.509044 -238.004096)
			(xy 373.513004 -237.955042) (xy 373.524781 -237.907258) (xy 373.544072 -237.861982) (xy 373.570375 -237.820386)
			(xy 373.60301 -237.783549) (xy 373.641131 -237.752424) (xy 373.683752 -237.727817) (xy 373.729768 -237.710365)
			(xy 373.777987 -237.700521) (xy 373.827162 -237.69854) (xy 373.876017 -237.704472) (xy 373.923288 -237.718164)
			(xy 373.96775 -237.739262) (xy 374.008253 -237.767218) (xy 374.043746 -237.80131) (xy 374.073311 -237.840654)
			(xy 374.096182 -237.884231) (xy 374.111766 -237.930912) (xy 374.119661 -237.979489) (xy 374.120156 -238.004096)
			(xy 374.119661 -238.028703) (xy 374.111766 -238.07728) (xy 374.096182 -238.123961) (xy 374.073311 -238.167538)
			(xy 374.043746 -238.206882) (xy 374.008253 -238.240974) (xy 373.96775 -238.26893) (xy 373.923288 -238.290028)
			(xy 373.876017 -238.30372) (xy 373.827162 -238.309652) (xy 373.777987 -238.307671) (xy 373.729768 -238.297827)
			(xy 373.683752 -238.280375) (xy 373.641131 -238.255768) (xy 373.60301 -238.224643) (xy 373.570375 -238.187806)
			(xy 373.544072 -238.14621) (xy 373.524781 -238.100934) (xy 373.513004 -238.05315) (xy 373.509044 -238.004096)
			(xy 373.180102 -238.004096) (xy 373.179607 -238.028703) (xy 373.171712 -238.07728) (xy 373.156128 -238.123961)
			(xy 373.133257 -238.167538) (xy 373.103692 -238.206882) (xy 373.068199 -238.240974) (xy 373.027696 -238.26893)
			(xy 372.983234 -238.290028) (xy 372.935963 -238.30372) (xy 372.887108 -238.309652) (xy 372.837933 -238.307671)
			(xy 372.789714 -238.297827) (xy 372.743698 -238.280375) (xy 372.701077 -238.255768) (xy 372.662956 -238.224643)
			(xy 372.630321 -238.187806) (xy 372.604018 -238.14621) (xy 372.584727 -238.100934) (xy 372.57295 -238.05315)
			(xy 372.56899 -238.004096) (xy 372.240048 -238.004096) (xy 372.239553 -238.028703) (xy 372.231658 -238.07728)
			(xy 372.216074 -238.123961) (xy 372.193203 -238.167538) (xy 372.163638 -238.206882) (xy 372.128145 -238.240974)
			(xy 372.087642 -238.26893) (xy 372.04318 -238.290028) (xy 371.995909 -238.30372) (xy 371.947054 -238.309652)
			(xy 371.897879 -238.307671) (xy 371.84966 -238.297827) (xy 371.803644 -238.280375) (xy 371.761023 -238.255768)
			(xy 371.722902 -238.224643) (xy 371.690267 -238.187806) (xy 371.663964 -238.14621) (xy 371.644673 -238.100934)
			(xy 371.632896 -238.05315) (xy 371.628936 -238.004096) (xy 371.299994 -238.004096) (xy 371.299499 -238.028703)
			(xy 371.291604 -238.07728) (xy 371.27602 -238.123961) (xy 371.253149 -238.167538) (xy 371.223584 -238.206882)
			(xy 371.188091 -238.240974) (xy 371.147588 -238.26893) (xy 371.103126 -238.290028) (xy 371.055855 -238.30372)
			(xy 371.007 -238.309652) (xy 370.957825 -238.307671) (xy 370.909606 -238.297827) (xy 370.86359 -238.280375)
			(xy 370.820969 -238.255768) (xy 370.782848 -238.224643) (xy 370.750213 -238.187806) (xy 370.72391 -238.14621)
			(xy 370.704619 -238.100934) (xy 370.692842 -238.05315) (xy 370.688882 -238.004096) (xy 370.360194 -238.004096)
			(xy 370.359699 -238.028703) (xy 370.351804 -238.07728) (xy 370.33622 -238.123961) (xy 370.313349 -238.167538)
			(xy 370.283784 -238.206882) (xy 370.248291 -238.240974) (xy 370.207788 -238.26893) (xy 370.163326 -238.290028)
			(xy 370.116055 -238.30372) (xy 370.0672 -238.309652) (xy 370.018025 -238.307671) (xy 369.969806 -238.297827)
			(xy 369.92379 -238.280375) (xy 369.881169 -238.255768) (xy 369.843048 -238.224643) (xy 369.810413 -238.187806)
			(xy 369.78411 -238.14621) (xy 369.764819 -238.100934) (xy 369.753042 -238.05315) (xy 369.749082 -238.004096)
			(xy 369.42014 -238.004096) (xy 369.419645 -238.028703) (xy 369.41175 -238.07728) (xy 369.396166 -238.123961)
			(xy 369.373295 -238.167538) (xy 369.34373 -238.206882) (xy 369.308237 -238.240974) (xy 369.267734 -238.26893)
			(xy 369.223272 -238.290028) (xy 369.176001 -238.30372) (xy 369.127146 -238.309652) (xy 369.077971 -238.307671)
			(xy 369.029752 -238.297827) (xy 368.983736 -238.280375) (xy 368.941115 -238.255768) (xy 368.902994 -238.224643)
			(xy 368.870359 -238.187806) (xy 368.844056 -238.14621) (xy 368.824765 -238.100934) (xy 368.812988 -238.05315)
			(xy 368.809028 -238.004096) (xy 368.480086 -238.004096) (xy 368.479591 -238.028703) (xy 368.471696 -238.07728)
			(xy 368.456112 -238.123961) (xy 368.433241 -238.167538) (xy 368.403676 -238.206882) (xy 368.368183 -238.240974)
			(xy 368.32768 -238.26893) (xy 368.283218 -238.290028) (xy 368.235947 -238.30372) (xy 368.187092 -238.309652)
			(xy 368.137917 -238.307671) (xy 368.089698 -238.297827) (xy 368.043682 -238.280375) (xy 368.001061 -238.255768)
			(xy 367.96294 -238.224643) (xy 367.930305 -238.187806) (xy 367.904002 -238.14621) (xy 367.884711 -238.100934)
			(xy 367.872934 -238.05315) (xy 367.868974 -238.004096) (xy 367.540032 -238.004096) (xy 367.539537 -238.028703)
			(xy 367.531642 -238.07728) (xy 367.516058 -238.123961) (xy 367.493187 -238.167538) (xy 367.463622 -238.206882)
			(xy 367.428129 -238.240974) (xy 367.387626 -238.26893) (xy 367.343164 -238.290028) (xy 367.295893 -238.30372)
			(xy 367.247038 -238.309652) (xy 367.197863 -238.307671) (xy 367.149644 -238.297827) (xy 367.103628 -238.280375)
			(xy 367.061007 -238.255768) (xy 367.022886 -238.224643) (xy 366.990251 -238.187806) (xy 366.963948 -238.14621)
			(xy 366.944657 -238.100934) (xy 366.93288 -238.05315) (xy 366.92892 -238.004096) (xy 366.600232 -238.004096)
			(xy 366.599737 -238.028703) (xy 366.591842 -238.07728) (xy 366.576258 -238.123961) (xy 366.553387 -238.167538)
			(xy 366.523822 -238.206882) (xy 366.488329 -238.240974) (xy 366.447826 -238.26893) (xy 366.403364 -238.290028)
			(xy 366.356093 -238.30372) (xy 366.307238 -238.309652) (xy 366.258063 -238.307671) (xy 366.209844 -238.297827)
			(xy 366.163828 -238.280375) (xy 366.121207 -238.255768) (xy 366.083086 -238.224643) (xy 366.050451 -238.187806)
			(xy 366.024148 -238.14621) (xy 366.004857 -238.100934) (xy 365.99308 -238.05315) (xy 365.98912 -238.004096)
			(xy 365.670592 -238.004096) (xy 365.67008 -238.029542) (xy 365.661916 -238.079776) (xy 365.6458 -238.12805)
			(xy 365.622149 -238.173113) (xy 365.591576 -238.213799) (xy 365.554872 -238.249054) (xy 365.512988 -238.277964)
			(xy 365.467009 -238.299781) (xy 365.418125 -238.313941) (xy 365.367604 -238.320075) (xy 365.316752 -238.318026)
			(xy 365.266888 -238.307846) (xy 365.219302 -238.289799) (xy 365.175228 -238.264353) (xy 365.135806 -238.232166)
			(xy 365.102058 -238.194072) (xy 365.074857 -238.151058) (xy 365.054909 -238.104238) (xy 365.04273 -238.054824)
			(xy 365.038635 -238.004096) (xy 364.730538 -238.004096) (xy 364.730026 -238.029542) (xy 364.721862 -238.079776)
			(xy 364.705746 -238.12805) (xy 364.682095 -238.173113) (xy 364.651522 -238.213799) (xy 364.614818 -238.249054)
			(xy 364.572934 -238.277964) (xy 364.526955 -238.299781) (xy 364.478071 -238.313941) (xy 364.42755 -238.320075)
			(xy 364.376698 -238.318026) (xy 364.326834 -238.307846) (xy 364.279248 -238.289799) (xy 364.235174 -238.264353)
			(xy 364.195752 -238.232166) (xy 364.162004 -238.194072) (xy 364.134803 -238.151058) (xy 364.114855 -238.104238)
			(xy 364.102676 -238.054824) (xy 364.098581 -238.004096) (xy 363.78007 -238.004096) (xy 363.779575 -238.028703)
			(xy 363.77168 -238.07728) (xy 363.756096 -238.123961) (xy 363.733225 -238.167538) (xy 363.70366 -238.206882)
			(xy 363.668167 -238.240974) (xy 363.627664 -238.26893) (xy 363.583202 -238.290028) (xy 363.535931 -238.30372)
			(xy 363.487076 -238.309652) (xy 363.437901 -238.307671) (xy 363.389682 -238.297827) (xy 363.343666 -238.280375)
			(xy 363.301045 -238.255768) (xy 363.262924 -238.224643) (xy 363.230289 -238.187806) (xy 363.203986 -238.14621)
			(xy 363.184695 -238.100934) (xy 363.172918 -238.05315) (xy 363.168958 -238.004096) (xy 362.840016 -238.004096)
			(xy 362.839521 -238.028703) (xy 362.831626 -238.07728) (xy 362.816042 -238.123961) (xy 362.793171 -238.167538)
			(xy 362.763606 -238.206882) (xy 362.728113 -238.240974) (xy 362.68761 -238.26893) (xy 362.643148 -238.290028)
			(xy 362.595877 -238.30372) (xy 362.547022 -238.309652) (xy 362.497847 -238.307671) (xy 362.449628 -238.297827)
			(xy 362.403612 -238.280375) (xy 362.360991 -238.255768) (xy 362.32287 -238.224643) (xy 362.290235 -238.187806)
			(xy 362.263932 -238.14621) (xy 362.244641 -238.100934) (xy 362.232864 -238.05315) (xy 362.228904 -238.004096)
			(xy 361.900216 -238.004096) (xy 361.899721 -238.028703) (xy 361.891826 -238.07728) (xy 361.876242 -238.123961)
			(xy 361.853371 -238.167538) (xy 361.823806 -238.206882) (xy 361.788313 -238.240974) (xy 361.74781 -238.26893)
			(xy 361.703348 -238.290028) (xy 361.656077 -238.30372) (xy 361.607222 -238.309652) (xy 361.558047 -238.307671)
			(xy 361.509828 -238.297827) (xy 361.463812 -238.280375) (xy 361.421191 -238.255768) (xy 361.38307 -238.224643)
			(xy 361.350435 -238.187806) (xy 361.324132 -238.14621) (xy 361.304841 -238.100934) (xy 361.293064 -238.05315)
			(xy 361.289104 -238.004096) (xy 360.27868 -238.004096) (xy 360.27868 -238.814102) (xy 360.81895 -238.814102)
			(xy 360.82291 -238.765048) (xy 360.834687 -238.717264) (xy 360.853978 -238.671988) (xy 360.880281 -238.630392)
			(xy 360.912916 -238.593555) (xy 360.951037 -238.56243) (xy 360.993658 -238.537823) (xy 361.039674 -238.520371)
			(xy 361.087893 -238.510527) (xy 361.137068 -238.508546) (xy 361.185923 -238.514478) (xy 361.233194 -238.52817)
			(xy 361.277656 -238.549268) (xy 361.318159 -238.577224) (xy 361.353652 -238.611316) (xy 361.383217 -238.65066)
			(xy 361.406088 -238.694237) (xy 361.421672 -238.740918) (xy 361.429567 -238.789495) (xy 361.430062 -238.814102)
			(xy 361.748573 -238.814102) (xy 361.752668 -238.763374) (xy 361.764847 -238.71396) (xy 361.784795 -238.66714)
			(xy 361.811996 -238.624126) (xy 361.845744 -238.586032) (xy 361.885166 -238.553845) (xy 361.92924 -238.528399)
			(xy 361.976826 -238.510352) (xy 362.02669 -238.500172) (xy 362.077542 -238.498123) (xy 362.128063 -238.504257)
			(xy 362.176947 -238.518417) (xy 362.222926 -238.540234) (xy 362.26481 -238.569144) (xy 362.301514 -238.604399)
			(xy 362.332087 -238.645085) (xy 362.355738 -238.690148) (xy 362.371854 -238.738422) (xy 362.380018 -238.788656)
			(xy 362.38053 -238.814102) (xy 362.688627 -238.814102) (xy 362.692722 -238.763374) (xy 362.704901 -238.71396)
			(xy 362.724849 -238.66714) (xy 362.75205 -238.624126) (xy 362.785798 -238.586032) (xy 362.82522 -238.553845)
			(xy 362.869294 -238.528399) (xy 362.91688 -238.510352) (xy 362.966744 -238.500172) (xy 363.017596 -238.498123)
			(xy 363.068117 -238.504257) (xy 363.117001 -238.518417) (xy 363.16298 -238.540234) (xy 363.204864 -238.569144)
			(xy 363.241568 -238.604399) (xy 363.272141 -238.645085) (xy 363.295792 -238.690148) (xy 363.311908 -238.738422)
			(xy 363.320072 -238.788656) (xy 363.320584 -238.814102) (xy 363.639112 -238.814102) (xy 363.643072 -238.765048)
			(xy 363.654849 -238.717264) (xy 363.67414 -238.671988) (xy 363.700443 -238.630392) (xy 363.733078 -238.593555)
			(xy 363.771199 -238.56243) (xy 363.81382 -238.537823) (xy 363.859836 -238.520371) (xy 363.908055 -238.510527)
			(xy 363.95723 -238.508546) (xy 364.006085 -238.514478) (xy 364.053356 -238.52817) (xy 364.097818 -238.549268)
			(xy 364.138321 -238.577224) (xy 364.173814 -238.611316) (xy 364.203379 -238.65066) (xy 364.22625 -238.694237)
			(xy 364.241834 -238.740918) (xy 364.249729 -238.789495) (xy 364.250224 -238.814102) (xy 366.45902 -238.814102)
			(xy 366.46298 -238.765048) (xy 366.474757 -238.717264) (xy 366.494048 -238.671988) (xy 366.520351 -238.630392)
			(xy 366.552986 -238.593555) (xy 366.591107 -238.56243) (xy 366.633728 -238.537823) (xy 366.679744 -238.520371)
			(xy 366.727963 -238.510527) (xy 366.777138 -238.508546) (xy 366.825993 -238.514478) (xy 366.873264 -238.52817)
			(xy 366.917726 -238.549268) (xy 366.958229 -238.577224) (xy 366.993722 -238.611316) (xy 367.023287 -238.65066)
			(xy 367.046158 -238.694237) (xy 367.061742 -238.740918) (xy 367.069637 -238.789495) (xy 367.070132 -238.814102)
			(xy 369.278928 -238.814102) (xy 369.282888 -238.765048) (xy 369.294665 -238.717264) (xy 369.313956 -238.671988)
			(xy 369.340259 -238.630392) (xy 369.372894 -238.593555) (xy 369.411015 -238.56243) (xy 369.453636 -238.537823)
			(xy 369.499652 -238.520371) (xy 369.547871 -238.510527) (xy 369.597046 -238.508546) (xy 369.645901 -238.514478)
			(xy 369.693172 -238.52817) (xy 369.737634 -238.549268) (xy 369.778137 -238.577224) (xy 369.81363 -238.611316)
			(xy 369.843195 -238.65066) (xy 369.866066 -238.694237) (xy 369.88165 -238.740918) (xy 369.889545 -238.789495)
			(xy 369.89004 -238.814102) (xy 372.09909 -238.814102) (xy 372.10305 -238.765048) (xy 372.114827 -238.717264)
			(xy 372.134118 -238.671988) (xy 372.160421 -238.630392) (xy 372.193056 -238.593555) (xy 372.231177 -238.56243)
			(xy 372.273798 -238.537823) (xy 372.319814 -238.520371) (xy 372.368033 -238.510527) (xy 372.417208 -238.508546)
			(xy 372.466063 -238.514478) (xy 372.513334 -238.52817) (xy 372.557796 -238.549268) (xy 372.598299 -238.577224)
			(xy 372.633792 -238.611316) (xy 372.663357 -238.65066) (xy 372.686228 -238.694237) (xy 372.701812 -238.740918)
			(xy 372.709707 -238.789495) (xy 372.710202 -238.814102) (xy 372.709707 -238.838709) (xy 372.701812 -238.887286)
			(xy 372.686228 -238.933967) (xy 372.663357 -238.977544) (xy 372.633792 -239.016888) (xy 372.598299 -239.05098)
			(xy 372.557796 -239.078936) (xy 372.513334 -239.100034) (xy 372.466063 -239.113726) (xy 372.417208 -239.119658)
			(xy 372.368033 -239.117677) (xy 372.319814 -239.107833) (xy 372.273798 -239.090381) (xy 372.231177 -239.065774)
			(xy 372.193056 -239.034649) (xy 372.160421 -238.997812) (xy 372.134118 -238.956216) (xy 372.114827 -238.91094)
			(xy 372.10305 -238.863156) (xy 372.09909 -238.814102) (xy 369.89004 -238.814102) (xy 369.889545 -238.838709)
			(xy 369.88165 -238.887286) (xy 369.866066 -238.933967) (xy 369.843195 -238.977544) (xy 369.81363 -239.016888)
			(xy 369.778137 -239.05098) (xy 369.737634 -239.078936) (xy 369.693172 -239.100034) (xy 369.645901 -239.113726)
			(xy 369.597046 -239.119658) (xy 369.547871 -239.117677) (xy 369.499652 -239.107833) (xy 369.453636 -239.090381)
			(xy 369.411015 -239.065774) (xy 369.372894 -239.034649) (xy 369.340259 -238.997812) (xy 369.313956 -238.956216)
			(xy 369.294665 -238.91094) (xy 369.282888 -238.863156) (xy 369.278928 -238.814102) (xy 367.070132 -238.814102)
			(xy 367.069637 -238.838709) (xy 367.061742 -238.887286) (xy 367.046158 -238.933967) (xy 367.023287 -238.977544)
			(xy 366.993722 -239.016888) (xy 366.958229 -239.05098) (xy 366.917726 -239.078936) (xy 366.873264 -239.100034)
			(xy 366.825993 -239.113726) (xy 366.777138 -239.119658) (xy 366.727963 -239.117677) (xy 366.679744 -239.107833)
			(xy 366.633728 -239.090381) (xy 366.591107 -239.065774) (xy 366.552986 -239.034649) (xy 366.520351 -238.997812)
			(xy 366.494048 -238.956216) (xy 366.474757 -238.91094) (xy 366.46298 -238.863156) (xy 366.45902 -238.814102)
			(xy 364.250224 -238.814102) (xy 364.249729 -238.838709) (xy 364.241834 -238.887286) (xy 364.22625 -238.933967)
			(xy 364.203379 -238.977544) (xy 364.173814 -239.016888) (xy 364.138321 -239.05098) (xy 364.097818 -239.078936)
			(xy 364.053356 -239.100034) (xy 364.006085 -239.113726) (xy 363.95723 -239.119658) (xy 363.908055 -239.117677)
			(xy 363.859836 -239.107833) (xy 363.81382 -239.090381) (xy 363.771199 -239.065774) (xy 363.733078 -239.034649)
			(xy 363.700443 -238.997812) (xy 363.67414 -238.956216) (xy 363.654849 -238.91094) (xy 363.643072 -238.863156)
			(xy 363.639112 -238.814102) (xy 363.320584 -238.814102) (xy 363.320072 -238.839548) (xy 363.311908 -238.889782)
			(xy 363.295792 -238.938056) (xy 363.272141 -238.983119) (xy 363.241568 -239.023805) (xy 363.204864 -239.05906)
			(xy 363.16298 -239.08797) (xy 363.117001 -239.109787) (xy 363.068117 -239.123947) (xy 363.017596 -239.130081)
			(xy 362.966744 -239.128032) (xy 362.91688 -239.117852) (xy 362.869294 -239.099805) (xy 362.82522 -239.074359)
			(xy 362.785798 -239.042172) (xy 362.75205 -239.004078) (xy 362.724849 -238.961064) (xy 362.704901 -238.914244)
			(xy 362.692722 -238.86483) (xy 362.688627 -238.814102) (xy 362.38053 -238.814102) (xy 362.380018 -238.839548)
			(xy 362.371854 -238.889782) (xy 362.355738 -238.938056) (xy 362.332087 -238.983119) (xy 362.301514 -239.023805)
			(xy 362.26481 -239.05906) (xy 362.222926 -239.08797) (xy 362.176947 -239.109787) (xy 362.128063 -239.123947)
			(xy 362.077542 -239.130081) (xy 362.02669 -239.128032) (xy 361.976826 -239.117852) (xy 361.92924 -239.099805)
			(xy 361.885166 -239.074359) (xy 361.845744 -239.042172) (xy 361.811996 -239.004078) (xy 361.784795 -238.961064)
			(xy 361.764847 -238.914244) (xy 361.752668 -238.86483) (xy 361.748573 -238.814102) (xy 361.430062 -238.814102)
			(xy 361.429567 -238.838709) (xy 361.421672 -238.887286) (xy 361.406088 -238.933967) (xy 361.383217 -238.977544)
			(xy 361.353652 -239.016888) (xy 361.318159 -239.05098) (xy 361.277656 -239.078936) (xy 361.233194 -239.100034)
			(xy 361.185923 -239.113726) (xy 361.137068 -239.119658) (xy 361.087893 -239.117677) (xy 361.039674 -239.107833)
			(xy 360.993658 -239.090381) (xy 360.951037 -239.065774) (xy 360.912916 -239.034649) (xy 360.880281 -238.997812)
			(xy 360.853978 -238.956216) (xy 360.834687 -238.91094) (xy 360.82291 -238.863156) (xy 360.81895 -238.814102)
			(xy 360.27868 -238.814102) (xy 360.27868 -239.624108) (xy 363.168958 -239.624108) (xy 363.172918 -239.575054)
			(xy 363.184695 -239.52727) (xy 363.203986 -239.481994) (xy 363.230289 -239.440398) (xy 363.262924 -239.403561)
			(xy 363.301045 -239.372436) (xy 363.343666 -239.347829) (xy 363.389682 -239.330377) (xy 363.437901 -239.320533)
			(xy 363.487076 -239.318552) (xy 363.535931 -239.324484) (xy 363.583202 -239.338176) (xy 363.627664 -239.359274)
			(xy 363.668167 -239.38723) (xy 363.70366 -239.421322) (xy 363.733225 -239.460666) (xy 363.756096 -239.504243)
			(xy 363.77168 -239.550924) (xy 363.779575 -239.599501) (xy 363.78007 -239.624108) (xy 364.098581 -239.624108)
			(xy 364.102676 -239.57338) (xy 364.114855 -239.523966) (xy 364.134803 -239.477146) (xy 364.162004 -239.434132)
			(xy 364.195752 -239.396038) (xy 364.235174 -239.363851) (xy 364.279248 -239.338405) (xy 364.326834 -239.320358)
			(xy 364.376698 -239.310178) (xy 364.42755 -239.308129) (xy 364.478071 -239.314263) (xy 364.526955 -239.328423)
			(xy 364.572934 -239.35024) (xy 364.614818 -239.37915) (xy 364.651522 -239.414405) (xy 364.682095 -239.455091)
			(xy 364.705746 -239.500154) (xy 364.721862 -239.548428) (xy 364.730026 -239.598662) (xy 364.730538 -239.624108)
			(xy 365.038635 -239.624108) (xy 365.04273 -239.57338) (xy 365.054909 -239.523966) (xy 365.074857 -239.477146)
			(xy 365.102058 -239.434132) (xy 365.135806 -239.396038) (xy 365.175228 -239.363851) (xy 365.219302 -239.338405)
			(xy 365.266888 -239.320358) (xy 365.316752 -239.310178) (xy 365.367604 -239.308129) (xy 365.418125 -239.314263)
			(xy 365.467009 -239.328423) (xy 365.512988 -239.35024) (xy 365.554872 -239.37915) (xy 365.591576 -239.414405)
			(xy 365.622149 -239.455091) (xy 365.6458 -239.500154) (xy 365.661916 -239.548428) (xy 365.67008 -239.598662)
			(xy 365.670592 -239.624108) (xy 365.98912 -239.624108) (xy 365.99308 -239.575054) (xy 366.004857 -239.52727)
			(xy 366.024148 -239.481994) (xy 366.050451 -239.440398) (xy 366.083086 -239.403561) (xy 366.121207 -239.372436)
			(xy 366.163828 -239.347829) (xy 366.209844 -239.330377) (xy 366.258063 -239.320533) (xy 366.307238 -239.318552)
			(xy 366.356093 -239.324484) (xy 366.403364 -239.338176) (xy 366.447826 -239.359274) (xy 366.488329 -239.38723)
			(xy 366.523822 -239.421322) (xy 366.553387 -239.460666) (xy 366.576258 -239.504243) (xy 366.591842 -239.550924)
			(xy 366.599737 -239.599501) (xy 366.600232 -239.624108) (xy 366.918489 -239.624108) (xy 366.922584 -239.57338)
			(xy 366.934763 -239.523966) (xy 366.954711 -239.477146) (xy 366.981912 -239.434132) (xy 367.01566 -239.396038)
			(xy 367.055082 -239.363851) (xy 367.099156 -239.338405) (xy 367.146742 -239.320358) (xy 367.196606 -239.310178)
			(xy 367.247458 -239.308129) (xy 367.297979 -239.314263) (xy 367.346863 -239.328423) (xy 367.392842 -239.35024)
			(xy 367.434726 -239.37915) (xy 367.47143 -239.414405) (xy 367.502003 -239.455091) (xy 367.525654 -239.500154)
			(xy 367.54177 -239.548428) (xy 367.549934 -239.598662) (xy 367.550446 -239.624108) (xy 367.858543 -239.624108)
			(xy 367.862638 -239.57338) (xy 367.874817 -239.523966) (xy 367.894765 -239.477146) (xy 367.921966 -239.434132)
			(xy 367.955714 -239.396038) (xy 367.995136 -239.363851) (xy 368.03921 -239.338405) (xy 368.086796 -239.320358)
			(xy 368.13666 -239.310178) (xy 368.187512 -239.308129) (xy 368.238033 -239.314263) (xy 368.286917 -239.328423)
			(xy 368.332896 -239.35024) (xy 368.37478 -239.37915) (xy 368.411484 -239.414405) (xy 368.442057 -239.455091)
			(xy 368.465708 -239.500154) (xy 368.481824 -239.548428) (xy 368.489988 -239.598662) (xy 368.4905 -239.624108)
			(xy 368.809028 -239.624108) (xy 368.812988 -239.575054) (xy 368.824765 -239.52727) (xy 368.844056 -239.481994)
			(xy 368.870359 -239.440398) (xy 368.902994 -239.403561) (xy 368.941115 -239.372436) (xy 368.983736 -239.347829)
			(xy 369.029752 -239.330377) (xy 369.077971 -239.320533) (xy 369.127146 -239.318552) (xy 369.176001 -239.324484)
			(xy 369.223272 -239.338176) (xy 369.267734 -239.359274) (xy 369.308237 -239.38723) (xy 369.34373 -239.421322)
			(xy 369.373295 -239.460666) (xy 369.396166 -239.504243) (xy 369.41175 -239.550924) (xy 369.419645 -239.599501)
			(xy 369.42014 -239.624108) (xy 369.738651 -239.624108) (xy 369.742746 -239.57338) (xy 369.754925 -239.523966)
			(xy 369.774873 -239.477146) (xy 369.802074 -239.434132) (xy 369.835822 -239.396038) (xy 369.875244 -239.363851)
			(xy 369.919318 -239.338405) (xy 369.966904 -239.320358) (xy 370.016768 -239.310178) (xy 370.06762 -239.308129)
			(xy 370.118141 -239.314263) (xy 370.167025 -239.328423) (xy 370.213004 -239.35024) (xy 370.254888 -239.37915)
			(xy 370.291592 -239.414405) (xy 370.322165 -239.455091) (xy 370.345816 -239.500154) (xy 370.361932 -239.548428)
			(xy 370.370096 -239.598662) (xy 370.370608 -239.624108) (xy 370.678451 -239.624108) (xy 370.682546 -239.57338)
			(xy 370.694725 -239.523966) (xy 370.714673 -239.477146) (xy 370.741874 -239.434132) (xy 370.775622 -239.396038)
			(xy 370.815044 -239.363851) (xy 370.859118 -239.338405) (xy 370.906704 -239.320358) (xy 370.956568 -239.310178)
			(xy 371.00742 -239.308129) (xy 371.057941 -239.314263) (xy 371.106825 -239.328423) (xy 371.152804 -239.35024)
			(xy 371.194688 -239.37915) (xy 371.231392 -239.414405) (xy 371.261965 -239.455091) (xy 371.285616 -239.500154)
			(xy 371.301732 -239.548428) (xy 371.309896 -239.598662) (xy 371.310408 -239.624108) (xy 371.628936 -239.624108)
			(xy 371.632896 -239.575054) (xy 371.644673 -239.52727) (xy 371.663964 -239.481994) (xy 371.690267 -239.440398)
			(xy 371.722902 -239.403561) (xy 371.761023 -239.372436) (xy 371.803644 -239.347829) (xy 371.84966 -239.330377)
			(xy 371.897879 -239.320533) (xy 371.947054 -239.318552) (xy 371.995909 -239.324484) (xy 372.04318 -239.338176)
			(xy 372.087642 -239.359274) (xy 372.128145 -239.38723) (xy 372.163638 -239.421322) (xy 372.193203 -239.460666)
			(xy 372.216074 -239.504243) (xy 372.231658 -239.550924) (xy 372.239553 -239.599501) (xy 372.240048 -239.624108)
			(xy 372.558559 -239.624108) (xy 372.562654 -239.57338) (xy 372.574833 -239.523966) (xy 372.594781 -239.477146)
			(xy 372.621982 -239.434132) (xy 372.65573 -239.396038) (xy 372.695152 -239.363851) (xy 372.739226 -239.338405)
			(xy 372.786812 -239.320358) (xy 372.836676 -239.310178) (xy 372.887528 -239.308129) (xy 372.938049 -239.314263)
			(xy 372.986933 -239.328423) (xy 373.032912 -239.35024) (xy 373.074796 -239.37915) (xy 373.1115 -239.414405)
			(xy 373.142073 -239.455091) (xy 373.165724 -239.500154) (xy 373.18184 -239.548428) (xy 373.190004 -239.598662)
			(xy 373.190516 -239.624108) (xy 373.498613 -239.624108) (xy 373.502708 -239.57338) (xy 373.514887 -239.523966)
			(xy 373.534835 -239.477146) (xy 373.562036 -239.434132) (xy 373.595784 -239.396038) (xy 373.635206 -239.363851)
			(xy 373.67928 -239.338405) (xy 373.726866 -239.320358) (xy 373.77673 -239.310178) (xy 373.827582 -239.308129)
			(xy 373.878103 -239.314263) (xy 373.926987 -239.328423) (xy 373.972966 -239.35024) (xy 374.01485 -239.37915)
			(xy 374.051554 -239.414405) (xy 374.082127 -239.455091) (xy 374.105778 -239.500154) (xy 374.121894 -239.548428)
			(xy 374.130058 -239.598662) (xy 374.13057 -239.624108) (xy 374.130058 -239.649554) (xy 374.121894 -239.699788)
			(xy 374.105778 -239.748062) (xy 374.082127 -239.793125) (xy 374.051554 -239.833811) (xy 374.01485 -239.869066)
			(xy 373.972966 -239.897976) (xy 373.926987 -239.919793) (xy 373.878103 -239.933953) (xy 373.827582 -239.940087)
			(xy 373.77673 -239.938038) (xy 373.726866 -239.927858) (xy 373.67928 -239.909811) (xy 373.635206 -239.884365)
			(xy 373.595784 -239.852178) (xy 373.562036 -239.814084) (xy 373.534835 -239.77107) (xy 373.514887 -239.72425)
			(xy 373.502708 -239.674836) (xy 373.498613 -239.624108) (xy 373.190516 -239.624108) (xy 373.190004 -239.649554)
			(xy 373.18184 -239.699788) (xy 373.165724 -239.748062) (xy 373.142073 -239.793125) (xy 373.1115 -239.833811)
			(xy 373.074796 -239.869066) (xy 373.032912 -239.897976) (xy 372.986933 -239.919793) (xy 372.938049 -239.933953)
			(xy 372.887528 -239.940087) (xy 372.836676 -239.938038) (xy 372.786812 -239.927858) (xy 372.739226 -239.909811)
			(xy 372.695152 -239.884365) (xy 372.65573 -239.852178) (xy 372.621982 -239.814084) (xy 372.594781 -239.77107)
			(xy 372.574833 -239.72425) (xy 372.562654 -239.674836) (xy 372.558559 -239.624108) (xy 372.240048 -239.624108)
			(xy 372.239553 -239.648715) (xy 372.231658 -239.697292) (xy 372.216074 -239.743973) (xy 372.193203 -239.78755)
			(xy 372.163638 -239.826894) (xy 372.128145 -239.860986) (xy 372.087642 -239.888942) (xy 372.04318 -239.91004)
			(xy 371.995909 -239.923732) (xy 371.947054 -239.929664) (xy 371.897879 -239.927683) (xy 371.84966 -239.917839)
			(xy 371.803644 -239.900387) (xy 371.761023 -239.87578) (xy 371.722902 -239.844655) (xy 371.690267 -239.807818)
			(xy 371.663964 -239.766222) (xy 371.644673 -239.720946) (xy 371.632896 -239.673162) (xy 371.628936 -239.624108)
			(xy 371.310408 -239.624108) (xy 371.309896 -239.649554) (xy 371.301732 -239.699788) (xy 371.285616 -239.748062)
			(xy 371.261965 -239.793125) (xy 371.231392 -239.833811) (xy 371.194688 -239.869066) (xy 371.152804 -239.897976)
			(xy 371.106825 -239.919793) (xy 371.057941 -239.933953) (xy 371.00742 -239.940087) (xy 370.956568 -239.938038)
			(xy 370.906704 -239.927858) (xy 370.859118 -239.909811) (xy 370.815044 -239.884365) (xy 370.775622 -239.852178)
			(xy 370.741874 -239.814084) (xy 370.714673 -239.77107) (xy 370.694725 -239.72425) (xy 370.682546 -239.674836)
			(xy 370.678451 -239.624108) (xy 370.370608 -239.624108) (xy 370.370096 -239.649554) (xy 370.361932 -239.699788)
			(xy 370.345816 -239.748062) (xy 370.322165 -239.793125) (xy 370.291592 -239.833811) (xy 370.254888 -239.869066)
			(xy 370.213004 -239.897976) (xy 370.167025 -239.919793) (xy 370.118141 -239.933953) (xy 370.06762 -239.940087)
			(xy 370.016768 -239.938038) (xy 369.966904 -239.927858) (xy 369.919318 -239.909811) (xy 369.875244 -239.884365)
			(xy 369.835822 -239.852178) (xy 369.802074 -239.814084) (xy 369.774873 -239.77107) (xy 369.754925 -239.72425)
			(xy 369.742746 -239.674836) (xy 369.738651 -239.624108) (xy 369.42014 -239.624108) (xy 369.419645 -239.648715)
			(xy 369.41175 -239.697292) (xy 369.396166 -239.743973) (xy 369.373295 -239.78755) (xy 369.34373 -239.826894)
			(xy 369.308237 -239.860986) (xy 369.267734 -239.888942) (xy 369.223272 -239.91004) (xy 369.176001 -239.923732)
			(xy 369.127146 -239.929664) (xy 369.077971 -239.927683) (xy 369.029752 -239.917839) (xy 368.983736 -239.900387)
			(xy 368.941115 -239.87578) (xy 368.902994 -239.844655) (xy 368.870359 -239.807818) (xy 368.844056 -239.766222)
			(xy 368.824765 -239.720946) (xy 368.812988 -239.673162) (xy 368.809028 -239.624108) (xy 368.4905 -239.624108)
			(xy 368.489988 -239.649554) (xy 368.481824 -239.699788) (xy 368.465708 -239.748062) (xy 368.442057 -239.793125)
			(xy 368.411484 -239.833811) (xy 368.37478 -239.869066) (xy 368.332896 -239.897976) (xy 368.286917 -239.919793)
			(xy 368.238033 -239.933953) (xy 368.187512 -239.940087) (xy 368.13666 -239.938038) (xy 368.086796 -239.927858)
			(xy 368.03921 -239.909811) (xy 367.995136 -239.884365) (xy 367.955714 -239.852178) (xy 367.921966 -239.814084)
			(xy 367.894765 -239.77107) (xy 367.874817 -239.72425) (xy 367.862638 -239.674836) (xy 367.858543 -239.624108)
			(xy 367.550446 -239.624108) (xy 367.549934 -239.649554) (xy 367.54177 -239.699788) (xy 367.525654 -239.748062)
			(xy 367.502003 -239.793125) (xy 367.47143 -239.833811) (xy 367.434726 -239.869066) (xy 367.392842 -239.897976)
			(xy 367.346863 -239.919793) (xy 367.297979 -239.933953) (xy 367.247458 -239.940087) (xy 367.196606 -239.938038)
			(xy 367.146742 -239.927858) (xy 367.099156 -239.909811) (xy 367.055082 -239.884365) (xy 367.01566 -239.852178)
			(xy 366.981912 -239.814084) (xy 366.954711 -239.77107) (xy 366.934763 -239.72425) (xy 366.922584 -239.674836)
			(xy 366.918489 -239.624108) (xy 366.600232 -239.624108) (xy 366.599737 -239.648715) (xy 366.591842 -239.697292)
			(xy 366.576258 -239.743973) (xy 366.553387 -239.78755) (xy 366.523822 -239.826894) (xy 366.488329 -239.860986)
			(xy 366.447826 -239.888942) (xy 366.403364 -239.91004) (xy 366.356093 -239.923732) (xy 366.307238 -239.929664)
			(xy 366.258063 -239.927683) (xy 366.209844 -239.917839) (xy 366.163828 -239.900387) (xy 366.121207 -239.87578)
			(xy 366.083086 -239.844655) (xy 366.050451 -239.807818) (xy 366.024148 -239.766222) (xy 366.004857 -239.720946)
			(xy 365.99308 -239.673162) (xy 365.98912 -239.624108) (xy 365.670592 -239.624108) (xy 365.67008 -239.649554)
			(xy 365.661916 -239.699788) (xy 365.6458 -239.748062) (xy 365.622149 -239.793125) (xy 365.591576 -239.833811)
			(xy 365.554872 -239.869066) (xy 365.512988 -239.897976) (xy 365.467009 -239.919793) (xy 365.418125 -239.933953)
			(xy 365.367604 -239.940087) (xy 365.316752 -239.938038) (xy 365.266888 -239.927858) (xy 365.219302 -239.909811)
			(xy 365.175228 -239.884365) (xy 365.135806 -239.852178) (xy 365.102058 -239.814084) (xy 365.074857 -239.77107)
			(xy 365.054909 -239.72425) (xy 365.04273 -239.674836) (xy 365.038635 -239.624108) (xy 364.730538 -239.624108)
			(xy 364.730026 -239.649554) (xy 364.721862 -239.699788) (xy 364.705746 -239.748062) (xy 364.682095 -239.793125)
			(xy 364.651522 -239.833811) (xy 364.614818 -239.869066) (xy 364.572934 -239.897976) (xy 364.526955 -239.919793)
			(xy 364.478071 -239.933953) (xy 364.42755 -239.940087) (xy 364.376698 -239.938038) (xy 364.326834 -239.927858)
			(xy 364.279248 -239.909811) (xy 364.235174 -239.884365) (xy 364.195752 -239.852178) (xy 364.162004 -239.814084)
			(xy 364.134803 -239.77107) (xy 364.114855 -239.72425) (xy 364.102676 -239.674836) (xy 364.098581 -239.624108)
			(xy 363.78007 -239.624108) (xy 363.779575 -239.648715) (xy 363.77168 -239.697292) (xy 363.756096 -239.743973)
			(xy 363.733225 -239.78755) (xy 363.70366 -239.826894) (xy 363.668167 -239.860986) (xy 363.627664 -239.888942)
			(xy 363.583202 -239.91004) (xy 363.535931 -239.923732) (xy 363.487076 -239.929664) (xy 363.437901 -239.927683)
			(xy 363.389682 -239.917839) (xy 363.343666 -239.900387) (xy 363.301045 -239.87578) (xy 363.262924 -239.844655)
			(xy 363.230289 -239.807818) (xy 363.203986 -239.766222) (xy 363.184695 -239.720946) (xy 363.172918 -239.673162)
			(xy 363.168958 -239.624108) (xy 360.27868 -239.624108) (xy 360.27868 -240.434114) (xy 360.81895 -240.434114)
			(xy 360.82291 -240.38506) (xy 360.834687 -240.337276) (xy 360.853978 -240.292) (xy 360.880281 -240.250404)
			(xy 360.912916 -240.213567) (xy 360.951037 -240.182442) (xy 360.993658 -240.157835) (xy 361.039674 -240.140383)
			(xy 361.087893 -240.130539) (xy 361.137068 -240.128558) (xy 361.185923 -240.13449) (xy 361.233194 -240.148182)
			(xy 361.277656 -240.16928) (xy 361.318159 -240.197236) (xy 361.353652 -240.231328) (xy 361.383217 -240.270672)
			(xy 361.406088 -240.314249) (xy 361.421672 -240.36093) (xy 361.429567 -240.409507) (xy 361.430062 -240.434114)
			(xy 361.748573 -240.434114) (xy 361.752668 -240.383386) (xy 361.764847 -240.333972) (xy 361.784795 -240.287152)
			(xy 361.811996 -240.244138) (xy 361.845744 -240.206044) (xy 361.885166 -240.173857) (xy 361.92924 -240.148411)
			(xy 361.976826 -240.130364) (xy 362.02669 -240.120184) (xy 362.077542 -240.118135) (xy 362.128063 -240.124269)
			(xy 362.176947 -240.138429) (xy 362.222926 -240.160246) (xy 362.26481 -240.189156) (xy 362.301514 -240.224411)
			(xy 362.332087 -240.265097) (xy 362.355738 -240.31016) (xy 362.371854 -240.358434) (xy 362.380018 -240.408668)
			(xy 362.38053 -240.434114) (xy 362.688627 -240.434114) (xy 362.692722 -240.383386) (xy 362.704901 -240.333972)
			(xy 362.724849 -240.287152) (xy 362.75205 -240.244138) (xy 362.785798 -240.206044) (xy 362.82522 -240.173857)
			(xy 362.869294 -240.148411) (xy 362.91688 -240.130364) (xy 362.966744 -240.120184) (xy 363.017596 -240.118135)
			(xy 363.068117 -240.124269) (xy 363.117001 -240.138429) (xy 363.16298 -240.160246) (xy 363.204864 -240.189156)
			(xy 363.241568 -240.224411) (xy 363.272141 -240.265097) (xy 363.295792 -240.31016) (xy 363.311908 -240.358434)
			(xy 363.320072 -240.408668) (xy 363.320584 -240.434114) (xy 363.639112 -240.434114) (xy 363.643072 -240.38506)
			(xy 363.654849 -240.337276) (xy 363.67414 -240.292) (xy 363.700443 -240.250404) (xy 363.733078 -240.213567)
			(xy 363.771199 -240.182442) (xy 363.81382 -240.157835) (xy 363.859836 -240.140383) (xy 363.908055 -240.130539)
			(xy 363.95723 -240.128558) (xy 364.006085 -240.13449) (xy 364.053356 -240.148182) (xy 364.097818 -240.16928)
			(xy 364.138321 -240.197236) (xy 364.173814 -240.231328) (xy 364.203379 -240.270672) (xy 364.22625 -240.314249)
			(xy 364.241834 -240.36093) (xy 364.249729 -240.409507) (xy 364.250224 -240.434114) (xy 364.578912 -240.434114)
			(xy 364.582872 -240.38506) (xy 364.594649 -240.337276) (xy 364.61394 -240.292) (xy 364.640243 -240.250404)
			(xy 364.672878 -240.213567) (xy 364.710999 -240.182442) (xy 364.75362 -240.157835) (xy 364.799636 -240.140383)
			(xy 364.847855 -240.130539) (xy 364.89703 -240.128558) (xy 364.945885 -240.13449) (xy 364.993156 -240.148182)
			(xy 365.037618 -240.16928) (xy 365.078121 -240.197236) (xy 365.113614 -240.231328) (xy 365.143179 -240.270672)
			(xy 365.16605 -240.314249) (xy 365.181634 -240.36093) (xy 365.189529 -240.409507) (xy 365.190024 -240.434114)
			(xy 365.518966 -240.434114) (xy 365.522926 -240.38506) (xy 365.534703 -240.337276) (xy 365.553994 -240.292)
			(xy 365.580297 -240.250404) (xy 365.612932 -240.213567) (xy 365.651053 -240.182442) (xy 365.693674 -240.157835)
			(xy 365.73969 -240.140383) (xy 365.787909 -240.130539) (xy 365.837084 -240.128558) (xy 365.885939 -240.13449)
			(xy 365.93321 -240.148182) (xy 365.977672 -240.16928) (xy 366.018175 -240.197236) (xy 366.053668 -240.231328)
			(xy 366.083233 -240.270672) (xy 366.106104 -240.314249) (xy 366.121688 -240.36093) (xy 366.129583 -240.409507)
			(xy 366.130078 -240.434114) (xy 366.45902 -240.434114) (xy 366.46298 -240.38506) (xy 366.474757 -240.337276)
			(xy 366.494048 -240.292) (xy 366.520351 -240.250404) (xy 366.552986 -240.213567) (xy 366.591107 -240.182442)
			(xy 366.633728 -240.157835) (xy 366.679744 -240.140383) (xy 366.727963 -240.130539) (xy 366.777138 -240.128558)
			(xy 366.825993 -240.13449) (xy 366.873264 -240.148182) (xy 366.917726 -240.16928) (xy 366.958229 -240.197236)
			(xy 366.993722 -240.231328) (xy 367.023287 -240.270672) (xy 367.046158 -240.314249) (xy 367.061742 -240.36093)
			(xy 367.069637 -240.409507) (xy 367.070132 -240.434114) (xy 367.399074 -240.434114) (xy 367.403034 -240.38506)
			(xy 367.414811 -240.337276) (xy 367.434102 -240.292) (xy 367.460405 -240.250404) (xy 367.49304 -240.213567)
			(xy 367.531161 -240.182442) (xy 367.573782 -240.157835) (xy 367.619798 -240.140383) (xy 367.668017 -240.130539)
			(xy 367.717192 -240.128558) (xy 367.766047 -240.13449) (xy 367.813318 -240.148182) (xy 367.85778 -240.16928)
			(xy 367.898283 -240.197236) (xy 367.933776 -240.231328) (xy 367.963341 -240.270672) (xy 367.986212 -240.314249)
			(xy 368.001796 -240.36093) (xy 368.009691 -240.409507) (xy 368.010186 -240.434114) (xy 368.338874 -240.434114)
			(xy 368.342834 -240.38506) (xy 368.354611 -240.337276) (xy 368.373902 -240.292) (xy 368.400205 -240.250404)
			(xy 368.43284 -240.213567) (xy 368.470961 -240.182442) (xy 368.513582 -240.157835) (xy 368.559598 -240.140383)
			(xy 368.607817 -240.130539) (xy 368.656992 -240.128558) (xy 368.705847 -240.13449) (xy 368.753118 -240.148182)
			(xy 368.79758 -240.16928) (xy 368.838083 -240.197236) (xy 368.873576 -240.231328) (xy 368.903141 -240.270672)
			(xy 368.926012 -240.314249) (xy 368.941596 -240.36093) (xy 368.949491 -240.409507) (xy 368.949986 -240.434114)
			(xy 369.278928 -240.434114) (xy 369.282888 -240.38506) (xy 369.294665 -240.337276) (xy 369.313956 -240.292)
			(xy 369.340259 -240.250404) (xy 369.372894 -240.213567) (xy 369.411015 -240.182442) (xy 369.453636 -240.157835)
			(xy 369.499652 -240.140383) (xy 369.547871 -240.130539) (xy 369.597046 -240.128558) (xy 369.645901 -240.13449)
			(xy 369.693172 -240.148182) (xy 369.737634 -240.16928) (xy 369.778137 -240.197236) (xy 369.81363 -240.231328)
			(xy 369.843195 -240.270672) (xy 369.866066 -240.314249) (xy 369.88165 -240.36093) (xy 369.889545 -240.409507)
			(xy 369.89004 -240.434114) (xy 370.218982 -240.434114) (xy 370.222942 -240.38506) (xy 370.234719 -240.337276)
			(xy 370.25401 -240.292) (xy 370.280313 -240.250404) (xy 370.312948 -240.213567) (xy 370.351069 -240.182442)
			(xy 370.39369 -240.157835) (xy 370.439706 -240.140383) (xy 370.487925 -240.130539) (xy 370.5371 -240.128558)
			(xy 370.585955 -240.13449) (xy 370.633226 -240.148182) (xy 370.677688 -240.16928) (xy 370.718191 -240.197236)
			(xy 370.753684 -240.231328) (xy 370.783249 -240.270672) (xy 370.80612 -240.314249) (xy 370.821704 -240.36093)
			(xy 370.829599 -240.409507) (xy 370.830094 -240.434114) (xy 371.159036 -240.434114) (xy 371.162996 -240.38506)
			(xy 371.174773 -240.337276) (xy 371.194064 -240.292) (xy 371.220367 -240.250404) (xy 371.253002 -240.213567)
			(xy 371.291123 -240.182442) (xy 371.333744 -240.157835) (xy 371.37976 -240.140383) (xy 371.427979 -240.130539)
			(xy 371.477154 -240.128558) (xy 371.526009 -240.13449) (xy 371.57328 -240.148182) (xy 371.617742 -240.16928)
			(xy 371.658245 -240.197236) (xy 371.693738 -240.231328) (xy 371.723303 -240.270672) (xy 371.746174 -240.314249)
			(xy 371.761758 -240.36093) (xy 371.769653 -240.409507) (xy 371.770148 -240.434114) (xy 372.09909 -240.434114)
			(xy 372.10305 -240.38506) (xy 372.114827 -240.337276) (xy 372.134118 -240.292) (xy 372.160421 -240.250404)
			(xy 372.193056 -240.213567) (xy 372.231177 -240.182442) (xy 372.273798 -240.157835) (xy 372.319814 -240.140383)
			(xy 372.368033 -240.130539) (xy 372.417208 -240.128558) (xy 372.466063 -240.13449) (xy 372.513334 -240.148182)
			(xy 372.557796 -240.16928) (xy 372.598299 -240.197236) (xy 372.633792 -240.231328) (xy 372.663357 -240.270672)
			(xy 372.686228 -240.314249) (xy 372.701812 -240.36093) (xy 372.709707 -240.409507) (xy 372.710202 -240.434114)
			(xy 373.03889 -240.434114) (xy 373.04285 -240.38506) (xy 373.054627 -240.337276) (xy 373.073918 -240.292)
			(xy 373.100221 -240.250404) (xy 373.132856 -240.213567) (xy 373.170977 -240.182442) (xy 373.213598 -240.157835)
			(xy 373.259614 -240.140383) (xy 373.307833 -240.130539) (xy 373.357008 -240.128558) (xy 373.405863 -240.13449)
			(xy 373.453134 -240.148182) (xy 373.497596 -240.16928) (xy 373.538099 -240.197236) (xy 373.573592 -240.231328)
			(xy 373.603157 -240.270672) (xy 373.626028 -240.314249) (xy 373.641612 -240.36093) (xy 373.649507 -240.409507)
			(xy 373.650002 -240.434114) (xy 373.649507 -240.458721) (xy 373.641612 -240.507298) (xy 373.626028 -240.553979)
			(xy 373.603157 -240.597556) (xy 373.573592 -240.6369) (xy 373.538099 -240.670992) (xy 373.497596 -240.698948)
			(xy 373.453134 -240.720046) (xy 373.405863 -240.733738) (xy 373.357008 -240.73967) (xy 373.307833 -240.737689)
			(xy 373.259614 -240.727845) (xy 373.213598 -240.710393) (xy 373.170977 -240.685786) (xy 373.132856 -240.654661)
			(xy 373.100221 -240.617824) (xy 373.073918 -240.576228) (xy 373.054627 -240.530952) (xy 373.04285 -240.483168)
			(xy 373.03889 -240.434114) (xy 372.710202 -240.434114) (xy 372.709707 -240.458721) (xy 372.701812 -240.507298)
			(xy 372.686228 -240.553979) (xy 372.663357 -240.597556) (xy 372.633792 -240.6369) (xy 372.598299 -240.670992)
			(xy 372.557796 -240.698948) (xy 372.513334 -240.720046) (xy 372.466063 -240.733738) (xy 372.417208 -240.73967)
			(xy 372.368033 -240.737689) (xy 372.319814 -240.727845) (xy 372.273798 -240.710393) (xy 372.231177 -240.685786)
			(xy 372.193056 -240.654661) (xy 372.160421 -240.617824) (xy 372.134118 -240.576228) (xy 372.114827 -240.530952)
			(xy 372.10305 -240.483168) (xy 372.09909 -240.434114) (xy 371.770148 -240.434114) (xy 371.769653 -240.458721)
			(xy 371.761758 -240.507298) (xy 371.746174 -240.553979) (xy 371.723303 -240.597556) (xy 371.693738 -240.6369)
			(xy 371.658245 -240.670992) (xy 371.617742 -240.698948) (xy 371.57328 -240.720046) (xy 371.526009 -240.733738)
			(xy 371.477154 -240.73967) (xy 371.427979 -240.737689) (xy 371.37976 -240.727845) (xy 371.333744 -240.710393)
			(xy 371.291123 -240.685786) (xy 371.253002 -240.654661) (xy 371.220367 -240.617824) (xy 371.194064 -240.576228)
			(xy 371.174773 -240.530952) (xy 371.162996 -240.483168) (xy 371.159036 -240.434114) (xy 370.830094 -240.434114)
			(xy 370.829599 -240.458721) (xy 370.821704 -240.507298) (xy 370.80612 -240.553979) (xy 370.783249 -240.597556)
			(xy 370.753684 -240.6369) (xy 370.718191 -240.670992) (xy 370.677688 -240.698948) (xy 370.633226 -240.720046)
			(xy 370.585955 -240.733738) (xy 370.5371 -240.73967) (xy 370.487925 -240.737689) (xy 370.439706 -240.727845)
			(xy 370.39369 -240.710393) (xy 370.351069 -240.685786) (xy 370.312948 -240.654661) (xy 370.280313 -240.617824)
			(xy 370.25401 -240.576228) (xy 370.234719 -240.530952) (xy 370.222942 -240.483168) (xy 370.218982 -240.434114)
			(xy 369.89004 -240.434114) (xy 369.889545 -240.458721) (xy 369.88165 -240.507298) (xy 369.866066 -240.553979)
			(xy 369.843195 -240.597556) (xy 369.81363 -240.6369) (xy 369.778137 -240.670992) (xy 369.737634 -240.698948)
			(xy 369.693172 -240.720046) (xy 369.645901 -240.733738) (xy 369.597046 -240.73967) (xy 369.547871 -240.737689)
			(xy 369.499652 -240.727845) (xy 369.453636 -240.710393) (xy 369.411015 -240.685786) (xy 369.372894 -240.654661)
			(xy 369.340259 -240.617824) (xy 369.313956 -240.576228) (xy 369.294665 -240.530952) (xy 369.282888 -240.483168)
			(xy 369.278928 -240.434114) (xy 368.949986 -240.434114) (xy 368.949491 -240.458721) (xy 368.941596 -240.507298)
			(xy 368.926012 -240.553979) (xy 368.903141 -240.597556) (xy 368.873576 -240.6369) (xy 368.838083 -240.670992)
			(xy 368.79758 -240.698948) (xy 368.753118 -240.720046) (xy 368.705847 -240.733738) (xy 368.656992 -240.73967)
			(xy 368.607817 -240.737689) (xy 368.559598 -240.727845) (xy 368.513582 -240.710393) (xy 368.470961 -240.685786)
			(xy 368.43284 -240.654661) (xy 368.400205 -240.617824) (xy 368.373902 -240.576228) (xy 368.354611 -240.530952)
			(xy 368.342834 -240.483168) (xy 368.338874 -240.434114) (xy 368.010186 -240.434114) (xy 368.009691 -240.458721)
			(xy 368.001796 -240.507298) (xy 367.986212 -240.553979) (xy 367.963341 -240.597556) (xy 367.933776 -240.6369)
			(xy 367.898283 -240.670992) (xy 367.85778 -240.698948) (xy 367.813318 -240.720046) (xy 367.766047 -240.733738)
			(xy 367.717192 -240.73967) (xy 367.668017 -240.737689) (xy 367.619798 -240.727845) (xy 367.573782 -240.710393)
			(xy 367.531161 -240.685786) (xy 367.49304 -240.654661) (xy 367.460405 -240.617824) (xy 367.434102 -240.576228)
			(xy 367.414811 -240.530952) (xy 367.403034 -240.483168) (xy 367.399074 -240.434114) (xy 367.070132 -240.434114)
			(xy 367.069637 -240.458721) (xy 367.061742 -240.507298) (xy 367.046158 -240.553979) (xy 367.023287 -240.597556)
			(xy 366.993722 -240.6369) (xy 366.958229 -240.670992) (xy 366.917726 -240.698948) (xy 366.873264 -240.720046)
			(xy 366.825993 -240.733738) (xy 366.777138 -240.73967) (xy 366.727963 -240.737689) (xy 366.679744 -240.727845)
			(xy 366.633728 -240.710393) (xy 366.591107 -240.685786) (xy 366.552986 -240.654661) (xy 366.520351 -240.617824)
			(xy 366.494048 -240.576228) (xy 366.474757 -240.530952) (xy 366.46298 -240.483168) (xy 366.45902 -240.434114)
			(xy 366.130078 -240.434114) (xy 366.129583 -240.458721) (xy 366.121688 -240.507298) (xy 366.106104 -240.553979)
			(xy 366.083233 -240.597556) (xy 366.053668 -240.6369) (xy 366.018175 -240.670992) (xy 365.977672 -240.698948)
			(xy 365.93321 -240.720046) (xy 365.885939 -240.733738) (xy 365.837084 -240.73967) (xy 365.787909 -240.737689)
			(xy 365.73969 -240.727845) (xy 365.693674 -240.710393) (xy 365.651053 -240.685786) (xy 365.612932 -240.654661)
			(xy 365.580297 -240.617824) (xy 365.553994 -240.576228) (xy 365.534703 -240.530952) (xy 365.522926 -240.483168)
			(xy 365.518966 -240.434114) (xy 365.190024 -240.434114) (xy 365.189529 -240.458721) (xy 365.181634 -240.507298)
			(xy 365.16605 -240.553979) (xy 365.143179 -240.597556) (xy 365.113614 -240.6369) (xy 365.078121 -240.670992)
			(xy 365.037618 -240.698948) (xy 364.993156 -240.720046) (xy 364.945885 -240.733738) (xy 364.89703 -240.73967)
			(xy 364.847855 -240.737689) (xy 364.799636 -240.727845) (xy 364.75362 -240.710393) (xy 364.710999 -240.685786)
			(xy 364.672878 -240.654661) (xy 364.640243 -240.617824) (xy 364.61394 -240.576228) (xy 364.594649 -240.530952)
			(xy 364.582872 -240.483168) (xy 364.578912 -240.434114) (xy 364.250224 -240.434114) (xy 364.249729 -240.458721)
			(xy 364.241834 -240.507298) (xy 364.22625 -240.553979) (xy 364.203379 -240.597556) (xy 364.173814 -240.6369)
			(xy 364.138321 -240.670992) (xy 364.097818 -240.698948) (xy 364.053356 -240.720046) (xy 364.006085 -240.733738)
			(xy 363.95723 -240.73967) (xy 363.908055 -240.737689) (xy 363.859836 -240.727845) (xy 363.81382 -240.710393)
			(xy 363.771199 -240.685786) (xy 363.733078 -240.654661) (xy 363.700443 -240.617824) (xy 363.67414 -240.576228)
			(xy 363.654849 -240.530952) (xy 363.643072 -240.483168) (xy 363.639112 -240.434114) (xy 363.320584 -240.434114)
			(xy 363.320072 -240.45956) (xy 363.311908 -240.509794) (xy 363.295792 -240.558068) (xy 363.272141 -240.603131)
			(xy 363.241568 -240.643817) (xy 363.204864 -240.679072) (xy 363.16298 -240.707982) (xy 363.117001 -240.729799)
			(xy 363.068117 -240.743959) (xy 363.017596 -240.750093) (xy 362.966744 -240.748044) (xy 362.91688 -240.737864)
			(xy 362.869294 -240.719817) (xy 362.82522 -240.694371) (xy 362.785798 -240.662184) (xy 362.75205 -240.62409)
			(xy 362.724849 -240.581076) (xy 362.704901 -240.534256) (xy 362.692722 -240.484842) (xy 362.688627 -240.434114)
			(xy 362.38053 -240.434114) (xy 362.380018 -240.45956) (xy 362.371854 -240.509794) (xy 362.355738 -240.558068)
			(xy 362.332087 -240.603131) (xy 362.301514 -240.643817) (xy 362.26481 -240.679072) (xy 362.222926 -240.707982)
			(xy 362.176947 -240.729799) (xy 362.128063 -240.743959) (xy 362.077542 -240.750093) (xy 362.02669 -240.748044)
			(xy 361.976826 -240.737864) (xy 361.92924 -240.719817) (xy 361.885166 -240.694371) (xy 361.845744 -240.662184)
			(xy 361.811996 -240.62409) (xy 361.784795 -240.581076) (xy 361.764847 -240.534256) (xy 361.752668 -240.484842)
			(xy 361.748573 -240.434114) (xy 361.430062 -240.434114) (xy 361.429567 -240.458721) (xy 361.421672 -240.507298)
			(xy 361.406088 -240.553979) (xy 361.383217 -240.597556) (xy 361.353652 -240.6369) (xy 361.318159 -240.670992)
			(xy 361.277656 -240.698948) (xy 361.233194 -240.720046) (xy 361.185923 -240.733738) (xy 361.137068 -240.73967)
			(xy 361.087893 -240.737689) (xy 361.039674 -240.727845) (xy 360.993658 -240.710393) (xy 360.951037 -240.685786)
			(xy 360.912916 -240.654661) (xy 360.880281 -240.617824) (xy 360.853978 -240.576228) (xy 360.834687 -240.530952)
			(xy 360.82291 -240.483168) (xy 360.81895 -240.434114) (xy 360.27868 -240.434114) (xy 360.27868 -241.24412)
			(xy 361.289104 -241.24412) (xy 361.293064 -241.195066) (xy 361.304841 -241.147282) (xy 361.324132 -241.102006)
			(xy 361.350435 -241.06041) (xy 361.38307 -241.023573) (xy 361.421191 -240.992448) (xy 361.463812 -240.967841)
			(xy 361.509828 -240.950389) (xy 361.558047 -240.940545) (xy 361.607222 -240.938564) (xy 361.656077 -240.944496)
			(xy 361.703348 -240.958188) (xy 361.74781 -240.979286) (xy 361.788313 -241.007242) (xy 361.823806 -241.041334)
			(xy 361.853371 -241.080678) (xy 361.876242 -241.124255) (xy 361.891826 -241.170936) (xy 361.899721 -241.219513)
			(xy 361.900216 -241.24412) (xy 362.228904 -241.24412) (xy 362.232864 -241.195066) (xy 362.244641 -241.147282)
			(xy 362.263932 -241.102006) (xy 362.290235 -241.06041) (xy 362.32287 -241.023573) (xy 362.360991 -240.992448)
			(xy 362.403612 -240.967841) (xy 362.449628 -240.950389) (xy 362.497847 -240.940545) (xy 362.547022 -240.938564)
			(xy 362.595877 -240.944496) (xy 362.643148 -240.958188) (xy 362.68761 -240.979286) (xy 362.728113 -241.007242)
			(xy 362.763606 -241.041334) (xy 362.793171 -241.080678) (xy 362.816042 -241.124255) (xy 362.831626 -241.170936)
			(xy 362.839521 -241.219513) (xy 362.840016 -241.24412) (xy 363.168958 -241.24412) (xy 363.172918 -241.195066)
			(xy 363.184695 -241.147282) (xy 363.203986 -241.102006) (xy 363.230289 -241.06041) (xy 363.262924 -241.023573)
			(xy 363.301045 -240.992448) (xy 363.343666 -240.967841) (xy 363.389682 -240.950389) (xy 363.437901 -240.940545)
			(xy 363.487076 -240.938564) (xy 363.535931 -240.944496) (xy 363.583202 -240.958188) (xy 363.627664 -240.979286)
			(xy 363.668167 -241.007242) (xy 363.70366 -241.041334) (xy 363.733225 -241.080678) (xy 363.756096 -241.124255)
			(xy 363.77168 -241.170936) (xy 363.779575 -241.219513) (xy 363.78007 -241.24412) (xy 364.098581 -241.24412)
			(xy 364.102676 -241.193392) (xy 364.114855 -241.143978) (xy 364.134803 -241.097158) (xy 364.162004 -241.054144)
			(xy 364.195752 -241.01605) (xy 364.235174 -240.983863) (xy 364.279248 -240.958417) (xy 364.326834 -240.94037)
			(xy 364.376698 -240.93019) (xy 364.42755 -240.928141) (xy 364.478071 -240.934275) (xy 364.526955 -240.948435)
			(xy 364.572934 -240.970252) (xy 364.614818 -240.999162) (xy 364.651522 -241.034417) (xy 364.682095 -241.075103)
			(xy 364.705746 -241.120166) (xy 364.721862 -241.16844) (xy 364.730026 -241.218674) (xy 364.730538 -241.24412)
			(xy 365.038635 -241.24412) (xy 365.04273 -241.193392) (xy 365.054909 -241.143978) (xy 365.074857 -241.097158)
			(xy 365.102058 -241.054144) (xy 365.135806 -241.01605) (xy 365.175228 -240.983863) (xy 365.219302 -240.958417)
			(xy 365.266888 -240.94037) (xy 365.316752 -240.93019) (xy 365.367604 -240.928141) (xy 365.418125 -240.934275)
			(xy 365.467009 -240.948435) (xy 365.512988 -240.970252) (xy 365.554872 -240.999162) (xy 365.591576 -241.034417)
			(xy 365.622149 -241.075103) (xy 365.6458 -241.120166) (xy 365.661916 -241.16844) (xy 365.67008 -241.218674)
			(xy 365.670592 -241.24412) (xy 365.98912 -241.24412) (xy 365.99308 -241.195066) (xy 366.004857 -241.147282)
			(xy 366.024148 -241.102006) (xy 366.050451 -241.06041) (xy 366.083086 -241.023573) (xy 366.121207 -240.992448)
			(xy 366.163828 -240.967841) (xy 366.209844 -240.950389) (xy 366.258063 -240.940545) (xy 366.307238 -240.938564)
			(xy 366.356093 -240.944496) (xy 366.403364 -240.958188) (xy 366.447826 -240.979286) (xy 366.488329 -241.007242)
			(xy 366.523822 -241.041334) (xy 366.553387 -241.080678) (xy 366.576258 -241.124255) (xy 366.591842 -241.170936)
			(xy 366.599737 -241.219513) (xy 366.600232 -241.24412) (xy 366.918489 -241.24412) (xy 366.922584 -241.193392)
			(xy 366.934763 -241.143978) (xy 366.954711 -241.097158) (xy 366.981912 -241.054144) (xy 367.01566 -241.01605)
			(xy 367.055082 -240.983863) (xy 367.099156 -240.958417) (xy 367.146742 -240.94037) (xy 367.196606 -240.93019)
			(xy 367.247458 -240.928141) (xy 367.297979 -240.934275) (xy 367.346863 -240.948435) (xy 367.392842 -240.970252)
			(xy 367.434726 -240.999162) (xy 367.47143 -241.034417) (xy 367.502003 -241.075103) (xy 367.525654 -241.120166)
			(xy 367.54177 -241.16844) (xy 367.549934 -241.218674) (xy 367.550446 -241.24412) (xy 367.858543 -241.24412)
			(xy 367.862638 -241.193392) (xy 367.874817 -241.143978) (xy 367.894765 -241.097158) (xy 367.921966 -241.054144)
			(xy 367.955714 -241.01605) (xy 367.995136 -240.983863) (xy 368.03921 -240.958417) (xy 368.086796 -240.94037)
			(xy 368.13666 -240.93019) (xy 368.187512 -240.928141) (xy 368.238033 -240.934275) (xy 368.286917 -240.948435)
			(xy 368.332896 -240.970252) (xy 368.37478 -240.999162) (xy 368.411484 -241.034417) (xy 368.442057 -241.075103)
			(xy 368.465708 -241.120166) (xy 368.481824 -241.16844) (xy 368.489988 -241.218674) (xy 368.4905 -241.24412)
			(xy 368.809028 -241.24412) (xy 368.812988 -241.195066) (xy 368.824765 -241.147282) (xy 368.844056 -241.102006)
			(xy 368.870359 -241.06041) (xy 368.902994 -241.023573) (xy 368.941115 -240.992448) (xy 368.983736 -240.967841)
			(xy 369.029752 -240.950389) (xy 369.077971 -240.940545) (xy 369.127146 -240.938564) (xy 369.176001 -240.944496)
			(xy 369.223272 -240.958188) (xy 369.267734 -240.979286) (xy 369.308237 -241.007242) (xy 369.34373 -241.041334)
			(xy 369.373295 -241.080678) (xy 369.396166 -241.124255) (xy 369.41175 -241.170936) (xy 369.419645 -241.219513)
			(xy 369.42014 -241.24412) (xy 369.738651 -241.24412) (xy 369.742746 -241.193392) (xy 369.754925 -241.143978)
			(xy 369.774873 -241.097158) (xy 369.802074 -241.054144) (xy 369.835822 -241.01605) (xy 369.875244 -240.983863)
			(xy 369.919318 -240.958417) (xy 369.966904 -240.94037) (xy 370.016768 -240.93019) (xy 370.06762 -240.928141)
			(xy 370.118141 -240.934275) (xy 370.167025 -240.948435) (xy 370.213004 -240.970252) (xy 370.254888 -240.999162)
			(xy 370.291592 -241.034417) (xy 370.322165 -241.075103) (xy 370.345816 -241.120166) (xy 370.361932 -241.16844)
			(xy 370.370096 -241.218674) (xy 370.370608 -241.24412) (xy 370.678451 -241.24412) (xy 370.682546 -241.193392)
			(xy 370.694725 -241.143978) (xy 370.714673 -241.097158) (xy 370.741874 -241.054144) (xy 370.775622 -241.01605)
			(xy 370.815044 -240.983863) (xy 370.859118 -240.958417) (xy 370.906704 -240.94037) (xy 370.956568 -240.93019)
			(xy 371.00742 -240.928141) (xy 371.057941 -240.934275) (xy 371.106825 -240.948435) (xy 371.152804 -240.970252)
			(xy 371.194688 -240.999162) (xy 371.231392 -241.034417) (xy 371.261965 -241.075103) (xy 371.285616 -241.120166)
			(xy 371.301732 -241.16844) (xy 371.309896 -241.218674) (xy 371.310408 -241.24412) (xy 371.628936 -241.24412)
			(xy 371.632896 -241.195066) (xy 371.644673 -241.147282) (xy 371.663964 -241.102006) (xy 371.690267 -241.06041)
			(xy 371.722902 -241.023573) (xy 371.761023 -240.992448) (xy 371.803644 -240.967841) (xy 371.84966 -240.950389)
			(xy 371.897879 -240.940545) (xy 371.947054 -240.938564) (xy 371.995909 -240.944496) (xy 372.04318 -240.958188)
			(xy 372.087642 -240.979286) (xy 372.128145 -241.007242) (xy 372.163638 -241.041334) (xy 372.193203 -241.080678)
			(xy 372.216074 -241.124255) (xy 372.231658 -241.170936) (xy 372.239553 -241.219513) (xy 372.240048 -241.24412)
			(xy 372.558559 -241.24412) (xy 372.562654 -241.193392) (xy 372.574833 -241.143978) (xy 372.594781 -241.097158)
			(xy 372.621982 -241.054144) (xy 372.65573 -241.01605) (xy 372.695152 -240.983863) (xy 372.739226 -240.958417)
			(xy 372.786812 -240.94037) (xy 372.836676 -240.93019) (xy 372.887528 -240.928141) (xy 372.938049 -240.934275)
			(xy 372.986933 -240.948435) (xy 373.032912 -240.970252) (xy 373.074796 -240.999162) (xy 373.1115 -241.034417)
			(xy 373.142073 -241.075103) (xy 373.165724 -241.120166) (xy 373.18184 -241.16844) (xy 373.190004 -241.218674)
			(xy 373.190516 -241.24412) (xy 373.498613 -241.24412) (xy 373.502708 -241.193392) (xy 373.514887 -241.143978)
			(xy 373.534835 -241.097158) (xy 373.562036 -241.054144) (xy 373.595784 -241.01605) (xy 373.635206 -240.983863)
			(xy 373.67928 -240.958417) (xy 373.726866 -240.94037) (xy 373.77673 -240.93019) (xy 373.827582 -240.928141)
			(xy 373.878103 -240.934275) (xy 373.926987 -240.948435) (xy 373.972966 -240.970252) (xy 374.01485 -240.999162)
			(xy 374.051554 -241.034417) (xy 374.082127 -241.075103) (xy 374.105778 -241.120166) (xy 374.121894 -241.16844)
			(xy 374.130058 -241.218674) (xy 374.13057 -241.24412) (xy 374.130058 -241.269566) (xy 374.121894 -241.3198)
			(xy 374.105778 -241.368074) (xy 374.082127 -241.413137) (xy 374.051554 -241.453823) (xy 374.01485 -241.489078)
			(xy 373.972966 -241.517988) (xy 373.926987 -241.539805) (xy 373.878103 -241.553965) (xy 373.827582 -241.560099)
			(xy 373.77673 -241.55805) (xy 373.726866 -241.54787) (xy 373.67928 -241.529823) (xy 373.635206 -241.504377)
			(xy 373.595784 -241.47219) (xy 373.562036 -241.434096) (xy 373.534835 -241.391082) (xy 373.514887 -241.344262)
			(xy 373.502708 -241.294848) (xy 373.498613 -241.24412) (xy 373.190516 -241.24412) (xy 373.190004 -241.269566)
			(xy 373.18184 -241.3198) (xy 373.165724 -241.368074) (xy 373.142073 -241.413137) (xy 373.1115 -241.453823)
			(xy 373.074796 -241.489078) (xy 373.032912 -241.517988) (xy 372.986933 -241.539805) (xy 372.938049 -241.553965)
			(xy 372.887528 -241.560099) (xy 372.836676 -241.55805) (xy 372.786812 -241.54787) (xy 372.739226 -241.529823)
			(xy 372.695152 -241.504377) (xy 372.65573 -241.47219) (xy 372.621982 -241.434096) (xy 372.594781 -241.391082)
			(xy 372.574833 -241.344262) (xy 372.562654 -241.294848) (xy 372.558559 -241.24412) (xy 372.240048 -241.24412)
			(xy 372.239553 -241.268727) (xy 372.231658 -241.317304) (xy 372.216074 -241.363985) (xy 372.193203 -241.407562)
			(xy 372.163638 -241.446906) (xy 372.128145 -241.480998) (xy 372.087642 -241.508954) (xy 372.04318 -241.530052)
			(xy 371.995909 -241.543744) (xy 371.947054 -241.549676) (xy 371.897879 -241.547695) (xy 371.84966 -241.537851)
			(xy 371.803644 -241.520399) (xy 371.761023 -241.495792) (xy 371.722902 -241.464667) (xy 371.690267 -241.42783)
			(xy 371.663964 -241.386234) (xy 371.644673 -241.340958) (xy 371.632896 -241.293174) (xy 371.628936 -241.24412)
			(xy 371.310408 -241.24412) (xy 371.309896 -241.269566) (xy 371.301732 -241.3198) (xy 371.285616 -241.368074)
			(xy 371.261965 -241.413137) (xy 371.231392 -241.453823) (xy 371.194688 -241.489078) (xy 371.152804 -241.517988)
			(xy 371.106825 -241.539805) (xy 371.057941 -241.553965) (xy 371.00742 -241.560099) (xy 370.956568 -241.55805)
			(xy 370.906704 -241.54787) (xy 370.859118 -241.529823) (xy 370.815044 -241.504377) (xy 370.775622 -241.47219)
			(xy 370.741874 -241.434096) (xy 370.714673 -241.391082) (xy 370.694725 -241.344262) (xy 370.682546 -241.294848)
			(xy 370.678451 -241.24412) (xy 370.370608 -241.24412) (xy 370.370096 -241.269566) (xy 370.361932 -241.3198)
			(xy 370.345816 -241.368074) (xy 370.322165 -241.413137) (xy 370.291592 -241.453823) (xy 370.254888 -241.489078)
			(xy 370.213004 -241.517988) (xy 370.167025 -241.539805) (xy 370.118141 -241.553965) (xy 370.06762 -241.560099)
			(xy 370.016768 -241.55805) (xy 369.966904 -241.54787) (xy 369.919318 -241.529823) (xy 369.875244 -241.504377)
			(xy 369.835822 -241.47219) (xy 369.802074 -241.434096) (xy 369.774873 -241.391082) (xy 369.754925 -241.344262)
			(xy 369.742746 -241.294848) (xy 369.738651 -241.24412) (xy 369.42014 -241.24412) (xy 369.419645 -241.268727)
			(xy 369.41175 -241.317304) (xy 369.396166 -241.363985) (xy 369.373295 -241.407562) (xy 369.34373 -241.446906)
			(xy 369.308237 -241.480998) (xy 369.267734 -241.508954) (xy 369.223272 -241.530052) (xy 369.176001 -241.543744)
			(xy 369.127146 -241.549676) (xy 369.077971 -241.547695) (xy 369.029752 -241.537851) (xy 368.983736 -241.520399)
			(xy 368.941115 -241.495792) (xy 368.902994 -241.464667) (xy 368.870359 -241.42783) (xy 368.844056 -241.386234)
			(xy 368.824765 -241.340958) (xy 368.812988 -241.293174) (xy 368.809028 -241.24412) (xy 368.4905 -241.24412)
			(xy 368.489988 -241.269566) (xy 368.481824 -241.3198) (xy 368.465708 -241.368074) (xy 368.442057 -241.413137)
			(xy 368.411484 -241.453823) (xy 368.37478 -241.489078) (xy 368.332896 -241.517988) (xy 368.286917 -241.539805)
			(xy 368.238033 -241.553965) (xy 368.187512 -241.560099) (xy 368.13666 -241.55805) (xy 368.086796 -241.54787)
			(xy 368.03921 -241.529823) (xy 367.995136 -241.504377) (xy 367.955714 -241.47219) (xy 367.921966 -241.434096)
			(xy 367.894765 -241.391082) (xy 367.874817 -241.344262) (xy 367.862638 -241.294848) (xy 367.858543 -241.24412)
			(xy 367.550446 -241.24412) (xy 367.549934 -241.269566) (xy 367.54177 -241.3198) (xy 367.525654 -241.368074)
			(xy 367.502003 -241.413137) (xy 367.47143 -241.453823) (xy 367.434726 -241.489078) (xy 367.392842 -241.517988)
			(xy 367.346863 -241.539805) (xy 367.297979 -241.553965) (xy 367.247458 -241.560099) (xy 367.196606 -241.55805)
			(xy 367.146742 -241.54787) (xy 367.099156 -241.529823) (xy 367.055082 -241.504377) (xy 367.01566 -241.47219)
			(xy 366.981912 -241.434096) (xy 366.954711 -241.391082) (xy 366.934763 -241.344262) (xy 366.922584 -241.294848)
			(xy 366.918489 -241.24412) (xy 366.600232 -241.24412) (xy 366.599737 -241.268727) (xy 366.591842 -241.317304)
			(xy 366.576258 -241.363985) (xy 366.553387 -241.407562) (xy 366.523822 -241.446906) (xy 366.488329 -241.480998)
			(xy 366.447826 -241.508954) (xy 366.403364 -241.530052) (xy 366.356093 -241.543744) (xy 366.307238 -241.549676)
			(xy 366.258063 -241.547695) (xy 366.209844 -241.537851) (xy 366.163828 -241.520399) (xy 366.121207 -241.495792)
			(xy 366.083086 -241.464667) (xy 366.050451 -241.42783) (xy 366.024148 -241.386234) (xy 366.004857 -241.340958)
			(xy 365.99308 -241.293174) (xy 365.98912 -241.24412) (xy 365.670592 -241.24412) (xy 365.67008 -241.269566)
			(xy 365.661916 -241.3198) (xy 365.6458 -241.368074) (xy 365.622149 -241.413137) (xy 365.591576 -241.453823)
			(xy 365.554872 -241.489078) (xy 365.512988 -241.517988) (xy 365.467009 -241.539805) (xy 365.418125 -241.553965)
			(xy 365.367604 -241.560099) (xy 365.316752 -241.55805) (xy 365.266888 -241.54787) (xy 365.219302 -241.529823)
			(xy 365.175228 -241.504377) (xy 365.135806 -241.47219) (xy 365.102058 -241.434096) (xy 365.074857 -241.391082)
			(xy 365.054909 -241.344262) (xy 365.04273 -241.294848) (xy 365.038635 -241.24412) (xy 364.730538 -241.24412)
			(xy 364.730026 -241.269566) (xy 364.721862 -241.3198) (xy 364.705746 -241.368074) (xy 364.682095 -241.413137)
			(xy 364.651522 -241.453823) (xy 364.614818 -241.489078) (xy 364.572934 -241.517988) (xy 364.526955 -241.539805)
			(xy 364.478071 -241.553965) (xy 364.42755 -241.560099) (xy 364.376698 -241.55805) (xy 364.326834 -241.54787)
			(xy 364.279248 -241.529823) (xy 364.235174 -241.504377) (xy 364.195752 -241.47219) (xy 364.162004 -241.434096)
			(xy 364.134803 -241.391082) (xy 364.114855 -241.344262) (xy 364.102676 -241.294848) (xy 364.098581 -241.24412)
			(xy 363.78007 -241.24412) (xy 363.779575 -241.268727) (xy 363.77168 -241.317304) (xy 363.756096 -241.363985)
			(xy 363.733225 -241.407562) (xy 363.70366 -241.446906) (xy 363.668167 -241.480998) (xy 363.627664 -241.508954)
			(xy 363.583202 -241.530052) (xy 363.535931 -241.543744) (xy 363.487076 -241.549676) (xy 363.437901 -241.547695)
			(xy 363.389682 -241.537851) (xy 363.343666 -241.520399) (xy 363.301045 -241.495792) (xy 363.262924 -241.464667)
			(xy 363.230289 -241.42783) (xy 363.203986 -241.386234) (xy 363.184695 -241.340958) (xy 363.172918 -241.293174)
			(xy 363.168958 -241.24412) (xy 362.840016 -241.24412) (xy 362.839521 -241.268727) (xy 362.831626 -241.317304)
			(xy 362.816042 -241.363985) (xy 362.793171 -241.407562) (xy 362.763606 -241.446906) (xy 362.728113 -241.480998)
			(xy 362.68761 -241.508954) (xy 362.643148 -241.530052) (xy 362.595877 -241.543744) (xy 362.547022 -241.549676)
			(xy 362.497847 -241.547695) (xy 362.449628 -241.537851) (xy 362.403612 -241.520399) (xy 362.360991 -241.495792)
			(xy 362.32287 -241.464667) (xy 362.290235 -241.42783) (xy 362.263932 -241.386234) (xy 362.244641 -241.340958)
			(xy 362.232864 -241.293174) (xy 362.228904 -241.24412) (xy 361.900216 -241.24412) (xy 361.899721 -241.268727)
			(xy 361.891826 -241.317304) (xy 361.876242 -241.363985) (xy 361.853371 -241.407562) (xy 361.823806 -241.446906)
			(xy 361.788313 -241.480998) (xy 361.74781 -241.508954) (xy 361.703348 -241.530052) (xy 361.656077 -241.543744)
			(xy 361.607222 -241.549676) (xy 361.558047 -241.547695) (xy 361.509828 -241.537851) (xy 361.463812 -241.520399)
			(xy 361.421191 -241.495792) (xy 361.38307 -241.464667) (xy 361.350435 -241.42783) (xy 361.324132 -241.386234)
			(xy 361.304841 -241.340958) (xy 361.293064 -241.293174) (xy 361.289104 -241.24412) (xy 360.27868 -241.24412)
			(xy 360.27868 -242.054126) (xy 360.81895 -242.054126) (xy 360.82291 -242.005072) (xy 360.834687 -241.957288)
			(xy 360.853978 -241.912012) (xy 360.880281 -241.870416) (xy 360.912916 -241.833579) (xy 360.951037 -241.802454)
			(xy 360.993658 -241.777847) (xy 361.039674 -241.760395) (xy 361.087893 -241.750551) (xy 361.137068 -241.74857)
			(xy 361.185923 -241.754502) (xy 361.233194 -241.768194) (xy 361.277656 -241.789292) (xy 361.318159 -241.817248)
			(xy 361.353652 -241.85134) (xy 361.383217 -241.890684) (xy 361.406088 -241.934261) (xy 361.421672 -241.980942)
			(xy 361.429567 -242.029519) (xy 361.430062 -242.054126) (xy 361.748573 -242.054126) (xy 361.752668 -242.003398)
			(xy 361.764847 -241.953984) (xy 361.784795 -241.907164) (xy 361.811996 -241.86415) (xy 361.845744 -241.826056)
			(xy 361.885166 -241.793869) (xy 361.92924 -241.768423) (xy 361.976826 -241.750376) (xy 362.02669 -241.740196)
			(xy 362.077542 -241.738147) (xy 362.128063 -241.744281) (xy 362.176947 -241.758441) (xy 362.222926 -241.780258)
			(xy 362.26481 -241.809168) (xy 362.301514 -241.844423) (xy 362.332087 -241.885109) (xy 362.355738 -241.930172)
			(xy 362.371854 -241.978446) (xy 362.380018 -242.02868) (xy 362.38053 -242.054126) (xy 362.688627 -242.054126)
			(xy 362.692722 -242.003398) (xy 362.704901 -241.953984) (xy 362.724849 -241.907164) (xy 362.75205 -241.86415)
			(xy 362.785798 -241.826056) (xy 362.82522 -241.793869) (xy 362.869294 -241.768423) (xy 362.91688 -241.750376)
			(xy 362.966744 -241.740196) (xy 363.017596 -241.738147) (xy 363.068117 -241.744281) (xy 363.117001 -241.758441)
			(xy 363.16298 -241.780258) (xy 363.204864 -241.809168) (xy 363.241568 -241.844423) (xy 363.272141 -241.885109)
			(xy 363.295792 -241.930172) (xy 363.311908 -241.978446) (xy 363.320072 -242.02868) (xy 363.320584 -242.054126)
			(xy 363.639112 -242.054126) (xy 363.643072 -242.005072) (xy 363.654849 -241.957288) (xy 363.67414 -241.912012)
			(xy 363.700443 -241.870416) (xy 363.733078 -241.833579) (xy 363.771199 -241.802454) (xy 363.81382 -241.777847)
			(xy 363.859836 -241.760395) (xy 363.908055 -241.750551) (xy 363.95723 -241.74857) (xy 364.006085 -241.754502)
			(xy 364.053356 -241.768194) (xy 364.097818 -241.789292) (xy 364.138321 -241.817248) (xy 364.173814 -241.85134)
			(xy 364.203379 -241.890684) (xy 364.22625 -241.934261) (xy 364.241834 -241.980942) (xy 364.249729 -242.029519)
			(xy 364.250224 -242.054126) (xy 366.45902 -242.054126) (xy 366.46298 -242.005072) (xy 366.474757 -241.957288)
			(xy 366.494048 -241.912012) (xy 366.520351 -241.870416) (xy 366.552986 -241.833579) (xy 366.591107 -241.802454)
			(xy 366.633728 -241.777847) (xy 366.679744 -241.760395) (xy 366.727963 -241.750551) (xy 366.777138 -241.74857)
			(xy 366.825993 -241.754502) (xy 366.873264 -241.768194) (xy 366.917726 -241.789292) (xy 366.958229 -241.817248)
			(xy 366.993722 -241.85134) (xy 367.023287 -241.890684) (xy 367.046158 -241.934261) (xy 367.061742 -241.980942)
			(xy 367.069637 -242.029519) (xy 367.070132 -242.054126) (xy 369.278928 -242.054126) (xy 369.282888 -242.005072)
			(xy 369.294665 -241.957288) (xy 369.313956 -241.912012) (xy 369.340259 -241.870416) (xy 369.372894 -241.833579)
			(xy 369.411015 -241.802454) (xy 369.453636 -241.777847) (xy 369.499652 -241.760395) (xy 369.547871 -241.750551)
			(xy 369.597046 -241.74857) (xy 369.645901 -241.754502) (xy 369.693172 -241.768194) (xy 369.737634 -241.789292)
			(xy 369.778137 -241.817248) (xy 369.81363 -241.85134) (xy 369.843195 -241.890684) (xy 369.866066 -241.934261)
			(xy 369.88165 -241.980942) (xy 369.889545 -242.029519) (xy 369.89004 -242.054126) (xy 372.09909 -242.054126)
			(xy 372.10305 -242.005072) (xy 372.114827 -241.957288) (xy 372.134118 -241.912012) (xy 372.160421 -241.870416)
			(xy 372.193056 -241.833579) (xy 372.231177 -241.802454) (xy 372.273798 -241.777847) (xy 372.319814 -241.760395)
			(xy 372.368033 -241.750551) (xy 372.417208 -241.74857) (xy 372.466063 -241.754502) (xy 372.513334 -241.768194)
			(xy 372.557796 -241.789292) (xy 372.598299 -241.817248) (xy 372.633792 -241.85134) (xy 372.663357 -241.890684)
			(xy 372.686228 -241.934261) (xy 372.701812 -241.980942) (xy 372.709707 -242.029519) (xy 372.710202 -242.054126)
			(xy 372.709707 -242.078733) (xy 372.701812 -242.12731) (xy 372.686228 -242.173991) (xy 372.663357 -242.217568)
			(xy 372.633792 -242.256912) (xy 372.598299 -242.291004) (xy 372.557796 -242.31896) (xy 372.513334 -242.340058)
			(xy 372.466063 -242.35375) (xy 372.417208 -242.359682) (xy 372.368033 -242.357701) (xy 372.319814 -242.347857)
			(xy 372.273798 -242.330405) (xy 372.231177 -242.305798) (xy 372.193056 -242.274673) (xy 372.160421 -242.237836)
			(xy 372.134118 -242.19624) (xy 372.114827 -242.150964) (xy 372.10305 -242.10318) (xy 372.09909 -242.054126)
			(xy 369.89004 -242.054126) (xy 369.889545 -242.078733) (xy 369.88165 -242.12731) (xy 369.866066 -242.173991)
			(xy 369.843195 -242.217568) (xy 369.81363 -242.256912) (xy 369.778137 -242.291004) (xy 369.737634 -242.31896)
			(xy 369.693172 -242.340058) (xy 369.645901 -242.35375) (xy 369.597046 -242.359682) (xy 369.547871 -242.357701)
			(xy 369.499652 -242.347857) (xy 369.453636 -242.330405) (xy 369.411015 -242.305798) (xy 369.372894 -242.274673)
			(xy 369.340259 -242.237836) (xy 369.313956 -242.19624) (xy 369.294665 -242.150964) (xy 369.282888 -242.10318)
			(xy 369.278928 -242.054126) (xy 367.070132 -242.054126) (xy 367.069637 -242.078733) (xy 367.061742 -242.12731)
			(xy 367.046158 -242.173991) (xy 367.023287 -242.217568) (xy 366.993722 -242.256912) (xy 366.958229 -242.291004)
			(xy 366.917726 -242.31896) (xy 366.873264 -242.340058) (xy 366.825993 -242.35375) (xy 366.777138 -242.359682)
			(xy 366.727963 -242.357701) (xy 366.679744 -242.347857) (xy 366.633728 -242.330405) (xy 366.591107 -242.305798)
			(xy 366.552986 -242.274673) (xy 366.520351 -242.237836) (xy 366.494048 -242.19624) (xy 366.474757 -242.150964)
			(xy 366.46298 -242.10318) (xy 366.45902 -242.054126) (xy 364.250224 -242.054126) (xy 364.249729 -242.078733)
			(xy 364.241834 -242.12731) (xy 364.22625 -242.173991) (xy 364.203379 -242.217568) (xy 364.173814 -242.256912)
			(xy 364.138321 -242.291004) (xy 364.097818 -242.31896) (xy 364.053356 -242.340058) (xy 364.006085 -242.35375)
			(xy 363.95723 -242.359682) (xy 363.908055 -242.357701) (xy 363.859836 -242.347857) (xy 363.81382 -242.330405)
			(xy 363.771199 -242.305798) (xy 363.733078 -242.274673) (xy 363.700443 -242.237836) (xy 363.67414 -242.19624)
			(xy 363.654849 -242.150964) (xy 363.643072 -242.10318) (xy 363.639112 -242.054126) (xy 363.320584 -242.054126)
			(xy 363.320072 -242.079572) (xy 363.311908 -242.129806) (xy 363.295792 -242.17808) (xy 363.272141 -242.223143)
			(xy 363.241568 -242.263829) (xy 363.204864 -242.299084) (xy 363.16298 -242.327994) (xy 363.117001 -242.349811)
			(xy 363.068117 -242.363971) (xy 363.017596 -242.370105) (xy 362.966744 -242.368056) (xy 362.91688 -242.357876)
			(xy 362.869294 -242.339829) (xy 362.82522 -242.314383) (xy 362.785798 -242.282196) (xy 362.75205 -242.244102)
			(xy 362.724849 -242.201088) (xy 362.704901 -242.154268) (xy 362.692722 -242.104854) (xy 362.688627 -242.054126)
			(xy 362.38053 -242.054126) (xy 362.380018 -242.079572) (xy 362.371854 -242.129806) (xy 362.355738 -242.17808)
			(xy 362.332087 -242.223143) (xy 362.301514 -242.263829) (xy 362.26481 -242.299084) (xy 362.222926 -242.327994)
			(xy 362.176947 -242.349811) (xy 362.128063 -242.363971) (xy 362.077542 -242.370105) (xy 362.02669 -242.368056)
			(xy 361.976826 -242.357876) (xy 361.92924 -242.339829) (xy 361.885166 -242.314383) (xy 361.845744 -242.282196)
			(xy 361.811996 -242.244102) (xy 361.784795 -242.201088) (xy 361.764847 -242.154268) (xy 361.752668 -242.104854)
			(xy 361.748573 -242.054126) (xy 361.430062 -242.054126) (xy 361.429567 -242.078733) (xy 361.421672 -242.12731)
			(xy 361.406088 -242.173991) (xy 361.383217 -242.217568) (xy 361.353652 -242.256912) (xy 361.318159 -242.291004)
			(xy 361.277656 -242.31896) (xy 361.233194 -242.340058) (xy 361.185923 -242.35375) (xy 361.137068 -242.359682)
			(xy 361.087893 -242.357701) (xy 361.039674 -242.347857) (xy 360.993658 -242.330405) (xy 360.951037 -242.305798)
			(xy 360.912916 -242.274673) (xy 360.880281 -242.237836) (xy 360.853978 -242.19624) (xy 360.834687 -242.150964)
			(xy 360.82291 -242.10318) (xy 360.81895 -242.054126) (xy 360.27868 -242.054126) (xy 360.27868 -242.864132)
			(xy 363.168958 -242.864132) (xy 363.172918 -242.815078) (xy 363.184695 -242.767294) (xy 363.203986 -242.722018)
			(xy 363.230289 -242.680422) (xy 363.262924 -242.643585) (xy 363.301045 -242.61246) (xy 363.343666 -242.587853)
			(xy 363.389682 -242.570401) (xy 363.437901 -242.560557) (xy 363.487076 -242.558576) (xy 363.535931 -242.564508)
			(xy 363.583202 -242.5782) (xy 363.627664 -242.599298) (xy 363.668167 -242.627254) (xy 363.70366 -242.661346)
			(xy 363.733225 -242.70069) (xy 363.756096 -242.744267) (xy 363.77168 -242.790948) (xy 363.779575 -242.839525)
			(xy 363.78007 -242.864132) (xy 364.098581 -242.864132) (xy 364.102676 -242.813404) (xy 364.114855 -242.76399)
			(xy 364.134803 -242.71717) (xy 364.162004 -242.674156) (xy 364.195752 -242.636062) (xy 364.235174 -242.603875)
			(xy 364.279248 -242.578429) (xy 364.326834 -242.560382) (xy 364.376698 -242.550202) (xy 364.42755 -242.548153)
			(xy 364.478071 -242.554287) (xy 364.526955 -242.568447) (xy 364.572934 -242.590264) (xy 364.614818 -242.619174)
			(xy 364.651522 -242.654429) (xy 364.682095 -242.695115) (xy 364.705746 -242.740178) (xy 364.721862 -242.788452)
			(xy 364.730026 -242.838686) (xy 364.730538 -242.864132) (xy 365.038635 -242.864132) (xy 365.04273 -242.813404)
			(xy 365.054909 -242.76399) (xy 365.074857 -242.71717) (xy 365.102058 -242.674156) (xy 365.135806 -242.636062)
			(xy 365.175228 -242.603875) (xy 365.219302 -242.578429) (xy 365.266888 -242.560382) (xy 365.316752 -242.550202)
			(xy 365.367604 -242.548153) (xy 365.418125 -242.554287) (xy 365.467009 -242.568447) (xy 365.512988 -242.590264)
			(xy 365.554872 -242.619174) (xy 365.591576 -242.654429) (xy 365.622149 -242.695115) (xy 365.6458 -242.740178)
			(xy 365.661916 -242.788452) (xy 365.67008 -242.838686) (xy 365.670592 -242.864132) (xy 365.98912 -242.864132)
			(xy 365.99308 -242.815078) (xy 366.004857 -242.767294) (xy 366.024148 -242.722018) (xy 366.050451 -242.680422)
			(xy 366.083086 -242.643585) (xy 366.121207 -242.61246) (xy 366.163828 -242.587853) (xy 366.209844 -242.570401)
			(xy 366.258063 -242.560557) (xy 366.307238 -242.558576) (xy 366.356093 -242.564508) (xy 366.403364 -242.5782)
			(xy 366.447826 -242.599298) (xy 366.488329 -242.627254) (xy 366.523822 -242.661346) (xy 366.553387 -242.70069)
			(xy 366.576258 -242.744267) (xy 366.591842 -242.790948) (xy 366.599737 -242.839525) (xy 366.600232 -242.864132)
			(xy 366.918489 -242.864132) (xy 366.922584 -242.813404) (xy 366.934763 -242.76399) (xy 366.954711 -242.71717)
			(xy 366.981912 -242.674156) (xy 367.01566 -242.636062) (xy 367.055082 -242.603875) (xy 367.099156 -242.578429)
			(xy 367.146742 -242.560382) (xy 367.196606 -242.550202) (xy 367.247458 -242.548153) (xy 367.297979 -242.554287)
			(xy 367.346863 -242.568447) (xy 367.392842 -242.590264) (xy 367.434726 -242.619174) (xy 367.47143 -242.654429)
			(xy 367.502003 -242.695115) (xy 367.525654 -242.740178) (xy 367.54177 -242.788452) (xy 367.549934 -242.838686)
			(xy 367.550446 -242.864132) (xy 367.858543 -242.864132) (xy 367.862638 -242.813404) (xy 367.874817 -242.76399)
			(xy 367.894765 -242.71717) (xy 367.921966 -242.674156) (xy 367.955714 -242.636062) (xy 367.995136 -242.603875)
			(xy 368.03921 -242.578429) (xy 368.086796 -242.560382) (xy 368.13666 -242.550202) (xy 368.187512 -242.548153)
			(xy 368.238033 -242.554287) (xy 368.286917 -242.568447) (xy 368.332896 -242.590264) (xy 368.37478 -242.619174)
			(xy 368.411484 -242.654429) (xy 368.442057 -242.695115) (xy 368.465708 -242.740178) (xy 368.481824 -242.788452)
			(xy 368.489988 -242.838686) (xy 368.4905 -242.864132) (xy 368.809028 -242.864132) (xy 368.812988 -242.815078)
			(xy 368.824765 -242.767294) (xy 368.844056 -242.722018) (xy 368.870359 -242.680422) (xy 368.902994 -242.643585)
			(xy 368.941115 -242.61246) (xy 368.983736 -242.587853) (xy 369.029752 -242.570401) (xy 369.077971 -242.560557)
			(xy 369.127146 -242.558576) (xy 369.176001 -242.564508) (xy 369.223272 -242.5782) (xy 369.267734 -242.599298)
			(xy 369.308237 -242.627254) (xy 369.34373 -242.661346) (xy 369.373295 -242.70069) (xy 369.396166 -242.744267)
			(xy 369.41175 -242.790948) (xy 369.419645 -242.839525) (xy 369.42014 -242.864132) (xy 369.738651 -242.864132)
			(xy 369.742746 -242.813404) (xy 369.754925 -242.76399) (xy 369.774873 -242.71717) (xy 369.802074 -242.674156)
			(xy 369.835822 -242.636062) (xy 369.875244 -242.603875) (xy 369.919318 -242.578429) (xy 369.966904 -242.560382)
			(xy 370.016768 -242.550202) (xy 370.06762 -242.548153) (xy 370.118141 -242.554287) (xy 370.167025 -242.568447)
			(xy 370.213004 -242.590264) (xy 370.254888 -242.619174) (xy 370.291592 -242.654429) (xy 370.322165 -242.695115)
			(xy 370.345816 -242.740178) (xy 370.361932 -242.788452) (xy 370.370096 -242.838686) (xy 370.370608 -242.864132)
			(xy 370.678451 -242.864132) (xy 370.682546 -242.813404) (xy 370.694725 -242.76399) (xy 370.714673 -242.71717)
			(xy 370.741874 -242.674156) (xy 370.775622 -242.636062) (xy 370.815044 -242.603875) (xy 370.859118 -242.578429)
			(xy 370.906704 -242.560382) (xy 370.956568 -242.550202) (xy 371.00742 -242.548153) (xy 371.057941 -242.554287)
			(xy 371.106825 -242.568447) (xy 371.152804 -242.590264) (xy 371.194688 -242.619174) (xy 371.231392 -242.654429)
			(xy 371.261965 -242.695115) (xy 371.285616 -242.740178) (xy 371.301732 -242.788452) (xy 371.309896 -242.838686)
			(xy 371.310408 -242.864132) (xy 371.628936 -242.864132) (xy 371.632896 -242.815078) (xy 371.644673 -242.767294)
			(xy 371.663964 -242.722018) (xy 371.690267 -242.680422) (xy 371.722902 -242.643585) (xy 371.761023 -242.61246)
			(xy 371.803644 -242.587853) (xy 371.84966 -242.570401) (xy 371.897879 -242.560557) (xy 371.947054 -242.558576)
			(xy 371.995909 -242.564508) (xy 372.04318 -242.5782) (xy 372.087642 -242.599298) (xy 372.128145 -242.627254)
			(xy 372.163638 -242.661346) (xy 372.193203 -242.70069) (xy 372.216074 -242.744267) (xy 372.231658 -242.790948)
			(xy 372.239553 -242.839525) (xy 372.240048 -242.864132) (xy 372.558559 -242.864132) (xy 372.562654 -242.813404)
			(xy 372.574833 -242.76399) (xy 372.594781 -242.71717) (xy 372.621982 -242.674156) (xy 372.65573 -242.636062)
			(xy 372.695152 -242.603875) (xy 372.739226 -242.578429) (xy 372.786812 -242.560382) (xy 372.836676 -242.550202)
			(xy 372.887528 -242.548153) (xy 372.938049 -242.554287) (xy 372.986933 -242.568447) (xy 373.032912 -242.590264)
			(xy 373.074796 -242.619174) (xy 373.1115 -242.654429) (xy 373.142073 -242.695115) (xy 373.165724 -242.740178)
			(xy 373.18184 -242.788452) (xy 373.190004 -242.838686) (xy 373.190516 -242.864132) (xy 373.498613 -242.864132)
			(xy 373.502708 -242.813404) (xy 373.514887 -242.76399) (xy 373.534835 -242.71717) (xy 373.562036 -242.674156)
			(xy 373.595784 -242.636062) (xy 373.635206 -242.603875) (xy 373.67928 -242.578429) (xy 373.726866 -242.560382)
			(xy 373.77673 -242.550202) (xy 373.827582 -242.548153) (xy 373.878103 -242.554287) (xy 373.926987 -242.568447)
			(xy 373.972966 -242.590264) (xy 374.01485 -242.619174) (xy 374.051554 -242.654429) (xy 374.082127 -242.695115)
			(xy 374.105778 -242.740178) (xy 374.121894 -242.788452) (xy 374.130058 -242.838686) (xy 374.13057 -242.864132)
			(xy 374.130058 -242.889578) (xy 374.121894 -242.939812) (xy 374.105778 -242.988086) (xy 374.082127 -243.033149)
			(xy 374.051554 -243.073835) (xy 374.01485 -243.10909) (xy 373.972966 -243.138) (xy 373.926987 -243.159817)
			(xy 373.878103 -243.173977) (xy 373.827582 -243.180111) (xy 373.77673 -243.178062) (xy 373.726866 -243.167882)
			(xy 373.67928 -243.149835) (xy 373.635206 -243.124389) (xy 373.595784 -243.092202) (xy 373.562036 -243.054108)
			(xy 373.534835 -243.011094) (xy 373.514887 -242.964274) (xy 373.502708 -242.91486) (xy 373.498613 -242.864132)
			(xy 373.190516 -242.864132) (xy 373.190004 -242.889578) (xy 373.18184 -242.939812) (xy 373.165724 -242.988086)
			(xy 373.142073 -243.033149) (xy 373.1115 -243.073835) (xy 373.074796 -243.10909) (xy 373.032912 -243.138)
			(xy 372.986933 -243.159817) (xy 372.938049 -243.173977) (xy 372.887528 -243.180111) (xy 372.836676 -243.178062)
			(xy 372.786812 -243.167882) (xy 372.739226 -243.149835) (xy 372.695152 -243.124389) (xy 372.65573 -243.092202)
			(xy 372.621982 -243.054108) (xy 372.594781 -243.011094) (xy 372.574833 -242.964274) (xy 372.562654 -242.91486)
			(xy 372.558559 -242.864132) (xy 372.240048 -242.864132) (xy 372.239553 -242.888739) (xy 372.231658 -242.937316)
			(xy 372.216074 -242.983997) (xy 372.193203 -243.027574) (xy 372.163638 -243.066918) (xy 372.128145 -243.10101)
			(xy 372.087642 -243.128966) (xy 372.04318 -243.150064) (xy 371.995909 -243.163756) (xy 371.947054 -243.169688)
			(xy 371.897879 -243.167707) (xy 371.84966 -243.157863) (xy 371.803644 -243.140411) (xy 371.761023 -243.115804)
			(xy 371.722902 -243.084679) (xy 371.690267 -243.047842) (xy 371.663964 -243.006246) (xy 371.644673 -242.96097)
			(xy 371.632896 -242.913186) (xy 371.628936 -242.864132) (xy 371.310408 -242.864132) (xy 371.309896 -242.889578)
			(xy 371.301732 -242.939812) (xy 371.285616 -242.988086) (xy 371.261965 -243.033149) (xy 371.231392 -243.073835)
			(xy 371.194688 -243.10909) (xy 371.152804 -243.138) (xy 371.106825 -243.159817) (xy 371.057941 -243.173977)
			(xy 371.00742 -243.180111) (xy 370.956568 -243.178062) (xy 370.906704 -243.167882) (xy 370.859118 -243.149835)
			(xy 370.815044 -243.124389) (xy 370.775622 -243.092202) (xy 370.741874 -243.054108) (xy 370.714673 -243.011094)
			(xy 370.694725 -242.964274) (xy 370.682546 -242.91486) (xy 370.678451 -242.864132) (xy 370.370608 -242.864132)
			(xy 370.370096 -242.889578) (xy 370.361932 -242.939812) (xy 370.345816 -242.988086) (xy 370.322165 -243.033149)
			(xy 370.291592 -243.073835) (xy 370.254888 -243.10909) (xy 370.213004 -243.138) (xy 370.167025 -243.159817)
			(xy 370.118141 -243.173977) (xy 370.06762 -243.180111) (xy 370.016768 -243.178062) (xy 369.966904 -243.167882)
			(xy 369.919318 -243.149835) (xy 369.875244 -243.124389) (xy 369.835822 -243.092202) (xy 369.802074 -243.054108)
			(xy 369.774873 -243.011094) (xy 369.754925 -242.964274) (xy 369.742746 -242.91486) (xy 369.738651 -242.864132)
			(xy 369.42014 -242.864132) (xy 369.419645 -242.888739) (xy 369.41175 -242.937316) (xy 369.396166 -242.983997)
			(xy 369.373295 -243.027574) (xy 369.34373 -243.066918) (xy 369.308237 -243.10101) (xy 369.267734 -243.128966)
			(xy 369.223272 -243.150064) (xy 369.176001 -243.163756) (xy 369.127146 -243.169688) (xy 369.077971 -243.167707)
			(xy 369.029752 -243.157863) (xy 368.983736 -243.140411) (xy 368.941115 -243.115804) (xy 368.902994 -243.084679)
			(xy 368.870359 -243.047842) (xy 368.844056 -243.006246) (xy 368.824765 -242.96097) (xy 368.812988 -242.913186)
			(xy 368.809028 -242.864132) (xy 368.4905 -242.864132) (xy 368.489988 -242.889578) (xy 368.481824 -242.939812)
			(xy 368.465708 -242.988086) (xy 368.442057 -243.033149) (xy 368.411484 -243.073835) (xy 368.37478 -243.10909)
			(xy 368.332896 -243.138) (xy 368.286917 -243.159817) (xy 368.238033 -243.173977) (xy 368.187512 -243.180111)
			(xy 368.13666 -243.178062) (xy 368.086796 -243.167882) (xy 368.03921 -243.149835) (xy 367.995136 -243.124389)
			(xy 367.955714 -243.092202) (xy 367.921966 -243.054108) (xy 367.894765 -243.011094) (xy 367.874817 -242.964274)
			(xy 367.862638 -242.91486) (xy 367.858543 -242.864132) (xy 367.550446 -242.864132) (xy 367.549934 -242.889578)
			(xy 367.54177 -242.939812) (xy 367.525654 -242.988086) (xy 367.502003 -243.033149) (xy 367.47143 -243.073835)
			(xy 367.434726 -243.10909) (xy 367.392842 -243.138) (xy 367.346863 -243.159817) (xy 367.297979 -243.173977)
			(xy 367.247458 -243.180111) (xy 367.196606 -243.178062) (xy 367.146742 -243.167882) (xy 367.099156 -243.149835)
			(xy 367.055082 -243.124389) (xy 367.01566 -243.092202) (xy 366.981912 -243.054108) (xy 366.954711 -243.011094)
			(xy 366.934763 -242.964274) (xy 366.922584 -242.91486) (xy 366.918489 -242.864132) (xy 366.600232 -242.864132)
			(xy 366.599737 -242.888739) (xy 366.591842 -242.937316) (xy 366.576258 -242.983997) (xy 366.553387 -243.027574)
			(xy 366.523822 -243.066918) (xy 366.488329 -243.10101) (xy 366.447826 -243.128966) (xy 366.403364 -243.150064)
			(xy 366.356093 -243.163756) (xy 366.307238 -243.169688) (xy 366.258063 -243.167707) (xy 366.209844 -243.157863)
			(xy 366.163828 -243.140411) (xy 366.121207 -243.115804) (xy 366.083086 -243.084679) (xy 366.050451 -243.047842)
			(xy 366.024148 -243.006246) (xy 366.004857 -242.96097) (xy 365.99308 -242.913186) (xy 365.98912 -242.864132)
			(xy 365.670592 -242.864132) (xy 365.67008 -242.889578) (xy 365.661916 -242.939812) (xy 365.6458 -242.988086)
			(xy 365.622149 -243.033149) (xy 365.591576 -243.073835) (xy 365.554872 -243.10909) (xy 365.512988 -243.138)
			(xy 365.467009 -243.159817) (xy 365.418125 -243.173977) (xy 365.367604 -243.180111) (xy 365.316752 -243.178062)
			(xy 365.266888 -243.167882) (xy 365.219302 -243.149835) (xy 365.175228 -243.124389) (xy 365.135806 -243.092202)
			(xy 365.102058 -243.054108) (xy 365.074857 -243.011094) (xy 365.054909 -242.964274) (xy 365.04273 -242.91486)
			(xy 365.038635 -242.864132) (xy 364.730538 -242.864132) (xy 364.730026 -242.889578) (xy 364.721862 -242.939812)
			(xy 364.705746 -242.988086) (xy 364.682095 -243.033149) (xy 364.651522 -243.073835) (xy 364.614818 -243.10909)
			(xy 364.572934 -243.138) (xy 364.526955 -243.159817) (xy 364.478071 -243.173977) (xy 364.42755 -243.180111)
			(xy 364.376698 -243.178062) (xy 364.326834 -243.167882) (xy 364.279248 -243.149835) (xy 364.235174 -243.124389)
			(xy 364.195752 -243.092202) (xy 364.162004 -243.054108) (xy 364.134803 -243.011094) (xy 364.114855 -242.964274)
			(xy 364.102676 -242.91486) (xy 364.098581 -242.864132) (xy 363.78007 -242.864132) (xy 363.779575 -242.888739)
			(xy 363.77168 -242.937316) (xy 363.756096 -242.983997) (xy 363.733225 -243.027574) (xy 363.70366 -243.066918)
			(xy 363.668167 -243.10101) (xy 363.627664 -243.128966) (xy 363.583202 -243.150064) (xy 363.535931 -243.163756)
			(xy 363.487076 -243.169688) (xy 363.437901 -243.167707) (xy 363.389682 -243.157863) (xy 363.343666 -243.140411)
			(xy 363.301045 -243.115804) (xy 363.262924 -243.084679) (xy 363.230289 -243.047842) (xy 363.203986 -243.006246)
			(xy 363.184695 -242.96097) (xy 363.172918 -242.913186) (xy 363.168958 -242.864132) (xy 360.27868 -242.864132)
			(xy 360.27868 -243.674138) (xy 360.81895 -243.674138) (xy 360.82291 -243.625084) (xy 360.834687 -243.5773)
			(xy 360.853978 -243.532024) (xy 360.880281 -243.490428) (xy 360.912916 -243.453591) (xy 360.951037 -243.422466)
			(xy 360.993658 -243.397859) (xy 361.039674 -243.380407) (xy 361.087893 -243.370563) (xy 361.137068 -243.368582)
			(xy 361.185923 -243.374514) (xy 361.233194 -243.388206) (xy 361.277656 -243.409304) (xy 361.318159 -243.43726)
			(xy 361.353652 -243.471352) (xy 361.383217 -243.510696) (xy 361.406088 -243.554273) (xy 361.421672 -243.600954)
			(xy 361.429567 -243.649531) (xy 361.430062 -243.674138) (xy 361.748573 -243.674138) (xy 361.752668 -243.62341)
			(xy 361.764847 -243.573996) (xy 361.784795 -243.527176) (xy 361.811996 -243.484162) (xy 361.845744 -243.446068)
			(xy 361.885166 -243.413881) (xy 361.92924 -243.388435) (xy 361.976826 -243.370388) (xy 362.02669 -243.360208)
			(xy 362.077542 -243.358159) (xy 362.128063 -243.364293) (xy 362.176947 -243.378453) (xy 362.222926 -243.40027)
			(xy 362.26481 -243.42918) (xy 362.301514 -243.464435) (xy 362.332087 -243.505121) (xy 362.355738 -243.550184)
			(xy 362.371854 -243.598458) (xy 362.380018 -243.648692) (xy 362.38053 -243.674138) (xy 362.688627 -243.674138)
			(xy 362.692722 -243.62341) (xy 362.704901 -243.573996) (xy 362.724849 -243.527176) (xy 362.75205 -243.484162)
			(xy 362.785798 -243.446068) (xy 362.82522 -243.413881) (xy 362.869294 -243.388435) (xy 362.91688 -243.370388)
			(xy 362.966744 -243.360208) (xy 363.017596 -243.358159) (xy 363.068117 -243.364293) (xy 363.117001 -243.378453)
			(xy 363.16298 -243.40027) (xy 363.204864 -243.42918) (xy 363.241568 -243.464435) (xy 363.272141 -243.505121)
			(xy 363.295792 -243.550184) (xy 363.311908 -243.598458) (xy 363.320072 -243.648692) (xy 363.320584 -243.674138)
			(xy 363.639112 -243.674138) (xy 363.643072 -243.625084) (xy 363.654849 -243.5773) (xy 363.67414 -243.532024)
			(xy 363.700443 -243.490428) (xy 363.733078 -243.453591) (xy 363.771199 -243.422466) (xy 363.81382 -243.397859)
			(xy 363.859836 -243.380407) (xy 363.908055 -243.370563) (xy 363.95723 -243.368582) (xy 364.006085 -243.374514)
			(xy 364.053356 -243.388206) (xy 364.097818 -243.409304) (xy 364.138321 -243.43726) (xy 364.173814 -243.471352)
			(xy 364.203379 -243.510696) (xy 364.22625 -243.554273) (xy 364.241834 -243.600954) (xy 364.249729 -243.649531)
			(xy 364.250224 -243.674138) (xy 364.578912 -243.674138) (xy 364.582872 -243.625084) (xy 364.594649 -243.5773)
			(xy 364.61394 -243.532024) (xy 364.640243 -243.490428) (xy 364.672878 -243.453591) (xy 364.710999 -243.422466)
			(xy 364.75362 -243.397859) (xy 364.799636 -243.380407) (xy 364.847855 -243.370563) (xy 364.89703 -243.368582)
			(xy 364.945885 -243.374514) (xy 364.993156 -243.388206) (xy 365.037618 -243.409304) (xy 365.078121 -243.43726)
			(xy 365.113614 -243.471352) (xy 365.143179 -243.510696) (xy 365.16605 -243.554273) (xy 365.181634 -243.600954)
			(xy 365.189529 -243.649531) (xy 365.190024 -243.674138) (xy 365.518966 -243.674138) (xy 365.522926 -243.625084)
			(xy 365.534703 -243.5773) (xy 365.553994 -243.532024) (xy 365.580297 -243.490428) (xy 365.612932 -243.453591)
			(xy 365.651053 -243.422466) (xy 365.693674 -243.397859) (xy 365.73969 -243.380407) (xy 365.787909 -243.370563)
			(xy 365.837084 -243.368582) (xy 365.885939 -243.374514) (xy 365.93321 -243.388206) (xy 365.977672 -243.409304)
			(xy 366.018175 -243.43726) (xy 366.053668 -243.471352) (xy 366.083233 -243.510696) (xy 366.106104 -243.554273)
			(xy 366.121688 -243.600954) (xy 366.129583 -243.649531) (xy 366.130078 -243.674138) (xy 366.45902 -243.674138)
			(xy 366.46298 -243.625084) (xy 366.474757 -243.5773) (xy 366.494048 -243.532024) (xy 366.520351 -243.490428)
			(xy 366.552986 -243.453591) (xy 366.591107 -243.422466) (xy 366.633728 -243.397859) (xy 366.679744 -243.380407)
			(xy 366.727963 -243.370563) (xy 366.777138 -243.368582) (xy 366.825993 -243.374514) (xy 366.873264 -243.388206)
			(xy 366.917726 -243.409304) (xy 366.958229 -243.43726) (xy 366.993722 -243.471352) (xy 367.023287 -243.510696)
			(xy 367.046158 -243.554273) (xy 367.061742 -243.600954) (xy 367.069637 -243.649531) (xy 367.070132 -243.674138)
			(xy 367.399074 -243.674138) (xy 367.403034 -243.625084) (xy 367.414811 -243.5773) (xy 367.434102 -243.532024)
			(xy 367.460405 -243.490428) (xy 367.49304 -243.453591) (xy 367.531161 -243.422466) (xy 367.573782 -243.397859)
			(xy 367.619798 -243.380407) (xy 367.668017 -243.370563) (xy 367.717192 -243.368582) (xy 367.766047 -243.374514)
			(xy 367.813318 -243.388206) (xy 367.85778 -243.409304) (xy 367.898283 -243.43726) (xy 367.933776 -243.471352)
			(xy 367.963341 -243.510696) (xy 367.986212 -243.554273) (xy 368.001796 -243.600954) (xy 368.009691 -243.649531)
			(xy 368.010186 -243.674138) (xy 368.338874 -243.674138) (xy 368.342834 -243.625084) (xy 368.354611 -243.5773)
			(xy 368.373902 -243.532024) (xy 368.400205 -243.490428) (xy 368.43284 -243.453591) (xy 368.470961 -243.422466)
			(xy 368.513582 -243.397859) (xy 368.559598 -243.380407) (xy 368.607817 -243.370563) (xy 368.656992 -243.368582)
			(xy 368.705847 -243.374514) (xy 368.753118 -243.388206) (xy 368.79758 -243.409304) (xy 368.838083 -243.43726)
			(xy 368.873576 -243.471352) (xy 368.903141 -243.510696) (xy 368.926012 -243.554273) (xy 368.941596 -243.600954)
			(xy 368.949491 -243.649531) (xy 368.949986 -243.674138) (xy 369.278928 -243.674138) (xy 369.282888 -243.625084)
			(xy 369.294665 -243.5773) (xy 369.313956 -243.532024) (xy 369.340259 -243.490428) (xy 369.372894 -243.453591)
			(xy 369.411015 -243.422466) (xy 369.453636 -243.397859) (xy 369.499652 -243.380407) (xy 369.547871 -243.370563)
			(xy 369.597046 -243.368582) (xy 369.645901 -243.374514) (xy 369.693172 -243.388206) (xy 369.737634 -243.409304)
			(xy 369.778137 -243.43726) (xy 369.81363 -243.471352) (xy 369.843195 -243.510696) (xy 369.866066 -243.554273)
			(xy 369.88165 -243.600954) (xy 369.889545 -243.649531) (xy 369.89004 -243.674138) (xy 370.218982 -243.674138)
			(xy 370.222942 -243.625084) (xy 370.234719 -243.5773) (xy 370.25401 -243.532024) (xy 370.280313 -243.490428)
			(xy 370.312948 -243.453591) (xy 370.351069 -243.422466) (xy 370.39369 -243.397859) (xy 370.439706 -243.380407)
			(xy 370.487925 -243.370563) (xy 370.5371 -243.368582) (xy 370.585955 -243.374514) (xy 370.633226 -243.388206)
			(xy 370.677688 -243.409304) (xy 370.718191 -243.43726) (xy 370.753684 -243.471352) (xy 370.783249 -243.510696)
			(xy 370.80612 -243.554273) (xy 370.821704 -243.600954) (xy 370.829599 -243.649531) (xy 370.830094 -243.674138)
			(xy 371.159036 -243.674138) (xy 371.162996 -243.625084) (xy 371.174773 -243.5773) (xy 371.194064 -243.532024)
			(xy 371.220367 -243.490428) (xy 371.253002 -243.453591) (xy 371.291123 -243.422466) (xy 371.333744 -243.397859)
			(xy 371.37976 -243.380407) (xy 371.427979 -243.370563) (xy 371.477154 -243.368582) (xy 371.526009 -243.374514)
			(xy 371.57328 -243.388206) (xy 371.617742 -243.409304) (xy 371.658245 -243.43726) (xy 371.693738 -243.471352)
			(xy 371.723303 -243.510696) (xy 371.746174 -243.554273) (xy 371.761758 -243.600954) (xy 371.769653 -243.649531)
			(xy 371.770148 -243.674138) (xy 372.09909 -243.674138) (xy 372.10305 -243.625084) (xy 372.114827 -243.5773)
			(xy 372.134118 -243.532024) (xy 372.160421 -243.490428) (xy 372.193056 -243.453591) (xy 372.231177 -243.422466)
			(xy 372.273798 -243.397859) (xy 372.319814 -243.380407) (xy 372.368033 -243.370563) (xy 372.417208 -243.368582)
			(xy 372.466063 -243.374514) (xy 372.513334 -243.388206) (xy 372.557796 -243.409304) (xy 372.598299 -243.43726)
			(xy 372.633792 -243.471352) (xy 372.663357 -243.510696) (xy 372.686228 -243.554273) (xy 372.701812 -243.600954)
			(xy 372.709707 -243.649531) (xy 372.710202 -243.674138) (xy 373.03889 -243.674138) (xy 373.04285 -243.625084)
			(xy 373.054627 -243.5773) (xy 373.073918 -243.532024) (xy 373.100221 -243.490428) (xy 373.132856 -243.453591)
			(xy 373.170977 -243.422466) (xy 373.213598 -243.397859) (xy 373.259614 -243.380407) (xy 373.307833 -243.370563)
			(xy 373.357008 -243.368582) (xy 373.405863 -243.374514) (xy 373.453134 -243.388206) (xy 373.497596 -243.409304)
			(xy 373.538099 -243.43726) (xy 373.573592 -243.471352) (xy 373.603157 -243.510696) (xy 373.626028 -243.554273)
			(xy 373.641612 -243.600954) (xy 373.649507 -243.649531) (xy 373.650002 -243.674138) (xy 373.649507 -243.698745)
			(xy 373.641612 -243.747322) (xy 373.626028 -243.794003) (xy 373.603157 -243.83758) (xy 373.573592 -243.876924)
			(xy 373.538099 -243.911016) (xy 373.497596 -243.938972) (xy 373.453134 -243.96007) (xy 373.405863 -243.973762)
			(xy 373.357008 -243.979694) (xy 373.307833 -243.977713) (xy 373.259614 -243.967869) (xy 373.213598 -243.950417)
			(xy 373.170977 -243.92581) (xy 373.132856 -243.894685) (xy 373.100221 -243.857848) (xy 373.073918 -243.816252)
			(xy 373.054627 -243.770976) (xy 373.04285 -243.723192) (xy 373.03889 -243.674138) (xy 372.710202 -243.674138)
			(xy 372.709707 -243.698745) (xy 372.701812 -243.747322) (xy 372.686228 -243.794003) (xy 372.663357 -243.83758)
			(xy 372.633792 -243.876924) (xy 372.598299 -243.911016) (xy 372.557796 -243.938972) (xy 372.513334 -243.96007)
			(xy 372.466063 -243.973762) (xy 372.417208 -243.979694) (xy 372.368033 -243.977713) (xy 372.319814 -243.967869)
			(xy 372.273798 -243.950417) (xy 372.231177 -243.92581) (xy 372.193056 -243.894685) (xy 372.160421 -243.857848)
			(xy 372.134118 -243.816252) (xy 372.114827 -243.770976) (xy 372.10305 -243.723192) (xy 372.09909 -243.674138)
			(xy 371.770148 -243.674138) (xy 371.769653 -243.698745) (xy 371.761758 -243.747322) (xy 371.746174 -243.794003)
			(xy 371.723303 -243.83758) (xy 371.693738 -243.876924) (xy 371.658245 -243.911016) (xy 371.617742 -243.938972)
			(xy 371.57328 -243.96007) (xy 371.526009 -243.973762) (xy 371.477154 -243.979694) (xy 371.427979 -243.977713)
			(xy 371.37976 -243.967869) (xy 371.333744 -243.950417) (xy 371.291123 -243.92581) (xy 371.253002 -243.894685)
			(xy 371.220367 -243.857848) (xy 371.194064 -243.816252) (xy 371.174773 -243.770976) (xy 371.162996 -243.723192)
			(xy 371.159036 -243.674138) (xy 370.830094 -243.674138) (xy 370.829599 -243.698745) (xy 370.821704 -243.747322)
			(xy 370.80612 -243.794003) (xy 370.783249 -243.83758) (xy 370.753684 -243.876924) (xy 370.718191 -243.911016)
			(xy 370.677688 -243.938972) (xy 370.633226 -243.96007) (xy 370.585955 -243.973762) (xy 370.5371 -243.979694)
			(xy 370.487925 -243.977713) (xy 370.439706 -243.967869) (xy 370.39369 -243.950417) (xy 370.351069 -243.92581)
			(xy 370.312948 -243.894685) (xy 370.280313 -243.857848) (xy 370.25401 -243.816252) (xy 370.234719 -243.770976)
			(xy 370.222942 -243.723192) (xy 370.218982 -243.674138) (xy 369.89004 -243.674138) (xy 369.889545 -243.698745)
			(xy 369.88165 -243.747322) (xy 369.866066 -243.794003) (xy 369.843195 -243.83758) (xy 369.81363 -243.876924)
			(xy 369.778137 -243.911016) (xy 369.737634 -243.938972) (xy 369.693172 -243.96007) (xy 369.645901 -243.973762)
			(xy 369.597046 -243.979694) (xy 369.547871 -243.977713) (xy 369.499652 -243.967869) (xy 369.453636 -243.950417)
			(xy 369.411015 -243.92581) (xy 369.372894 -243.894685) (xy 369.340259 -243.857848) (xy 369.313956 -243.816252)
			(xy 369.294665 -243.770976) (xy 369.282888 -243.723192) (xy 369.278928 -243.674138) (xy 368.949986 -243.674138)
			(xy 368.949491 -243.698745) (xy 368.941596 -243.747322) (xy 368.926012 -243.794003) (xy 368.903141 -243.83758)
			(xy 368.873576 -243.876924) (xy 368.838083 -243.911016) (xy 368.79758 -243.938972) (xy 368.753118 -243.96007)
			(xy 368.705847 -243.973762) (xy 368.656992 -243.979694) (xy 368.607817 -243.977713) (xy 368.559598 -243.967869)
			(xy 368.513582 -243.950417) (xy 368.470961 -243.92581) (xy 368.43284 -243.894685) (xy 368.400205 -243.857848)
			(xy 368.373902 -243.816252) (xy 368.354611 -243.770976) (xy 368.342834 -243.723192) (xy 368.338874 -243.674138)
			(xy 368.010186 -243.674138) (xy 368.009691 -243.698745) (xy 368.001796 -243.747322) (xy 367.986212 -243.794003)
			(xy 367.963341 -243.83758) (xy 367.933776 -243.876924) (xy 367.898283 -243.911016) (xy 367.85778 -243.938972)
			(xy 367.813318 -243.96007) (xy 367.766047 -243.973762) (xy 367.717192 -243.979694) (xy 367.668017 -243.977713)
			(xy 367.619798 -243.967869) (xy 367.573782 -243.950417) (xy 367.531161 -243.92581) (xy 367.49304 -243.894685)
			(xy 367.460405 -243.857848) (xy 367.434102 -243.816252) (xy 367.414811 -243.770976) (xy 367.403034 -243.723192)
			(xy 367.399074 -243.674138) (xy 367.070132 -243.674138) (xy 367.069637 -243.698745) (xy 367.061742 -243.747322)
			(xy 367.046158 -243.794003) (xy 367.023287 -243.83758) (xy 366.993722 -243.876924) (xy 366.958229 -243.911016)
			(xy 366.917726 -243.938972) (xy 366.873264 -243.96007) (xy 366.825993 -243.973762) (xy 366.777138 -243.979694)
			(xy 366.727963 -243.977713) (xy 366.679744 -243.967869) (xy 366.633728 -243.950417) (xy 366.591107 -243.92581)
			(xy 366.552986 -243.894685) (xy 366.520351 -243.857848) (xy 366.494048 -243.816252) (xy 366.474757 -243.770976)
			(xy 366.46298 -243.723192) (xy 366.45902 -243.674138) (xy 366.130078 -243.674138) (xy 366.129583 -243.698745)
			(xy 366.121688 -243.747322) (xy 366.106104 -243.794003) (xy 366.083233 -243.83758) (xy 366.053668 -243.876924)
			(xy 366.018175 -243.911016) (xy 365.977672 -243.938972) (xy 365.93321 -243.96007) (xy 365.885939 -243.973762)
			(xy 365.837084 -243.979694) (xy 365.787909 -243.977713) (xy 365.73969 -243.967869) (xy 365.693674 -243.950417)
			(xy 365.651053 -243.92581) (xy 365.612932 -243.894685) (xy 365.580297 -243.857848) (xy 365.553994 -243.816252)
			(xy 365.534703 -243.770976) (xy 365.522926 -243.723192) (xy 365.518966 -243.674138) (xy 365.190024 -243.674138)
			(xy 365.189529 -243.698745) (xy 365.181634 -243.747322) (xy 365.16605 -243.794003) (xy 365.143179 -243.83758)
			(xy 365.113614 -243.876924) (xy 365.078121 -243.911016) (xy 365.037618 -243.938972) (xy 364.993156 -243.96007)
			(xy 364.945885 -243.973762) (xy 364.89703 -243.979694) (xy 364.847855 -243.977713) (xy 364.799636 -243.967869)
			(xy 364.75362 -243.950417) (xy 364.710999 -243.92581) (xy 364.672878 -243.894685) (xy 364.640243 -243.857848)
			(xy 364.61394 -243.816252) (xy 364.594649 -243.770976) (xy 364.582872 -243.723192) (xy 364.578912 -243.674138)
			(xy 364.250224 -243.674138) (xy 364.249729 -243.698745) (xy 364.241834 -243.747322) (xy 364.22625 -243.794003)
			(xy 364.203379 -243.83758) (xy 364.173814 -243.876924) (xy 364.138321 -243.911016) (xy 364.097818 -243.938972)
			(xy 364.053356 -243.96007) (xy 364.006085 -243.973762) (xy 363.95723 -243.979694) (xy 363.908055 -243.977713)
			(xy 363.859836 -243.967869) (xy 363.81382 -243.950417) (xy 363.771199 -243.92581) (xy 363.733078 -243.894685)
			(xy 363.700443 -243.857848) (xy 363.67414 -243.816252) (xy 363.654849 -243.770976) (xy 363.643072 -243.723192)
			(xy 363.639112 -243.674138) (xy 363.320584 -243.674138) (xy 363.320072 -243.699584) (xy 363.311908 -243.749818)
			(xy 363.295792 -243.798092) (xy 363.272141 -243.843155) (xy 363.241568 -243.883841) (xy 363.204864 -243.919096)
			(xy 363.16298 -243.948006) (xy 363.117001 -243.969823) (xy 363.068117 -243.983983) (xy 363.017596 -243.990117)
			(xy 362.966744 -243.988068) (xy 362.91688 -243.977888) (xy 362.869294 -243.959841) (xy 362.82522 -243.934395)
			(xy 362.785798 -243.902208) (xy 362.75205 -243.864114) (xy 362.724849 -243.8211) (xy 362.704901 -243.77428)
			(xy 362.692722 -243.724866) (xy 362.688627 -243.674138) (xy 362.38053 -243.674138) (xy 362.380018 -243.699584)
			(xy 362.371854 -243.749818) (xy 362.355738 -243.798092) (xy 362.332087 -243.843155) (xy 362.301514 -243.883841)
			(xy 362.26481 -243.919096) (xy 362.222926 -243.948006) (xy 362.176947 -243.969823) (xy 362.128063 -243.983983)
			(xy 362.077542 -243.990117) (xy 362.02669 -243.988068) (xy 361.976826 -243.977888) (xy 361.92924 -243.959841)
			(xy 361.885166 -243.934395) (xy 361.845744 -243.902208) (xy 361.811996 -243.864114) (xy 361.784795 -243.8211)
			(xy 361.764847 -243.77428) (xy 361.752668 -243.724866) (xy 361.748573 -243.674138) (xy 361.430062 -243.674138)
			(xy 361.429567 -243.698745) (xy 361.421672 -243.747322) (xy 361.406088 -243.794003) (xy 361.383217 -243.83758)
			(xy 361.353652 -243.876924) (xy 361.318159 -243.911016) (xy 361.277656 -243.938972) (xy 361.233194 -243.96007)
			(xy 361.185923 -243.973762) (xy 361.137068 -243.979694) (xy 361.087893 -243.977713) (xy 361.039674 -243.967869)
			(xy 360.993658 -243.950417) (xy 360.951037 -243.92581) (xy 360.912916 -243.894685) (xy 360.880281 -243.857848)
			(xy 360.853978 -243.816252) (xy 360.834687 -243.770976) (xy 360.82291 -243.723192) (xy 360.81895 -243.674138)
			(xy 360.27868 -243.674138) (xy 360.27868 -244.484144) (xy 361.289104 -244.484144) (xy 361.293064 -244.43509)
			(xy 361.304841 -244.387306) (xy 361.324132 -244.34203) (xy 361.350435 -244.300434) (xy 361.38307 -244.263597)
			(xy 361.421191 -244.232472) (xy 361.463812 -244.207865) (xy 361.509828 -244.190413) (xy 361.558047 -244.180569)
			(xy 361.607222 -244.178588) (xy 361.656077 -244.18452) (xy 361.703348 -244.198212) (xy 361.74781 -244.21931)
			(xy 361.788313 -244.247266) (xy 361.823806 -244.281358) (xy 361.853371 -244.320702) (xy 361.876242 -244.364279)
			(xy 361.891826 -244.41096) (xy 361.899721 -244.459537) (xy 361.900216 -244.484144) (xy 362.228904 -244.484144)
			(xy 362.232864 -244.43509) (xy 362.244641 -244.387306) (xy 362.263932 -244.34203) (xy 362.290235 -244.300434)
			(xy 362.32287 -244.263597) (xy 362.360991 -244.232472) (xy 362.403612 -244.207865) (xy 362.449628 -244.190413)
			(xy 362.497847 -244.180569) (xy 362.547022 -244.178588) (xy 362.595877 -244.18452) (xy 362.643148 -244.198212)
			(xy 362.68761 -244.21931) (xy 362.728113 -244.247266) (xy 362.763606 -244.281358) (xy 362.793171 -244.320702)
			(xy 362.816042 -244.364279) (xy 362.831626 -244.41096) (xy 362.839521 -244.459537) (xy 362.840016 -244.484144)
			(xy 363.168958 -244.484144) (xy 363.172918 -244.43509) (xy 363.184695 -244.387306) (xy 363.203986 -244.34203)
			(xy 363.230289 -244.300434) (xy 363.262924 -244.263597) (xy 363.301045 -244.232472) (xy 363.343666 -244.207865)
			(xy 363.389682 -244.190413) (xy 363.437901 -244.180569) (xy 363.487076 -244.178588) (xy 363.535931 -244.18452)
			(xy 363.583202 -244.198212) (xy 363.627664 -244.21931) (xy 363.668167 -244.247266) (xy 363.70366 -244.281358)
			(xy 363.733225 -244.320702) (xy 363.756096 -244.364279) (xy 363.77168 -244.41096) (xy 363.779575 -244.459537)
			(xy 363.78007 -244.484144) (xy 364.098581 -244.484144) (xy 364.102676 -244.433416) (xy 364.114855 -244.384002)
			(xy 364.134803 -244.337182) (xy 364.162004 -244.294168) (xy 364.195752 -244.256074) (xy 364.235174 -244.223887)
			(xy 364.279248 -244.198441) (xy 364.326834 -244.180394) (xy 364.376698 -244.170214) (xy 364.42755 -244.168165)
			(xy 364.478071 -244.174299) (xy 364.526955 -244.188459) (xy 364.572934 -244.210276) (xy 364.614818 -244.239186)
			(xy 364.651522 -244.274441) (xy 364.682095 -244.315127) (xy 364.705746 -244.36019) (xy 364.721862 -244.408464)
			(xy 364.730026 -244.458698) (xy 364.730538 -244.484144) (xy 365.038635 -244.484144) (xy 365.04273 -244.433416)
			(xy 365.054909 -244.384002) (xy 365.074857 -244.337182) (xy 365.102058 -244.294168) (xy 365.135806 -244.256074)
			(xy 365.175228 -244.223887) (xy 365.219302 -244.198441) (xy 365.266888 -244.180394) (xy 365.316752 -244.170214)
			(xy 365.367604 -244.168165) (xy 365.418125 -244.174299) (xy 365.467009 -244.188459) (xy 365.512988 -244.210276)
			(xy 365.554872 -244.239186) (xy 365.591576 -244.274441) (xy 365.622149 -244.315127) (xy 365.6458 -244.36019)
			(xy 365.661916 -244.408464) (xy 365.67008 -244.458698) (xy 365.670592 -244.484144) (xy 365.98912 -244.484144)
			(xy 365.99308 -244.43509) (xy 366.004857 -244.387306) (xy 366.024148 -244.34203) (xy 366.050451 -244.300434)
			(xy 366.083086 -244.263597) (xy 366.121207 -244.232472) (xy 366.163828 -244.207865) (xy 366.209844 -244.190413)
			(xy 366.258063 -244.180569) (xy 366.307238 -244.178588) (xy 366.356093 -244.18452) (xy 366.403364 -244.198212)
			(xy 366.447826 -244.21931) (xy 366.488329 -244.247266) (xy 366.523822 -244.281358) (xy 366.553387 -244.320702)
			(xy 366.576258 -244.364279) (xy 366.591842 -244.41096) (xy 366.599737 -244.459537) (xy 366.600232 -244.484144)
			(xy 366.918489 -244.484144) (xy 366.922584 -244.433416) (xy 366.934763 -244.384002) (xy 366.954711 -244.337182)
			(xy 366.981912 -244.294168) (xy 367.01566 -244.256074) (xy 367.055082 -244.223887) (xy 367.099156 -244.198441)
			(xy 367.146742 -244.180394) (xy 367.196606 -244.170214) (xy 367.247458 -244.168165) (xy 367.297979 -244.174299)
			(xy 367.346863 -244.188459) (xy 367.392842 -244.210276) (xy 367.434726 -244.239186) (xy 367.47143 -244.274441)
			(xy 367.502003 -244.315127) (xy 367.525654 -244.36019) (xy 367.54177 -244.408464) (xy 367.549934 -244.458698)
			(xy 367.550446 -244.484144) (xy 367.858543 -244.484144) (xy 367.862638 -244.433416) (xy 367.874817 -244.384002)
			(xy 367.894765 -244.337182) (xy 367.921966 -244.294168) (xy 367.955714 -244.256074) (xy 367.995136 -244.223887)
			(xy 368.03921 -244.198441) (xy 368.086796 -244.180394) (xy 368.13666 -244.170214) (xy 368.187512 -244.168165)
			(xy 368.238033 -244.174299) (xy 368.286917 -244.188459) (xy 368.332896 -244.210276) (xy 368.37478 -244.239186)
			(xy 368.411484 -244.274441) (xy 368.442057 -244.315127) (xy 368.465708 -244.36019) (xy 368.481824 -244.408464)
			(xy 368.489988 -244.458698) (xy 368.4905 -244.484144) (xy 368.809028 -244.484144) (xy 368.812988 -244.43509)
			(xy 368.824765 -244.387306) (xy 368.844056 -244.34203) (xy 368.870359 -244.300434) (xy 368.902994 -244.263597)
			(xy 368.941115 -244.232472) (xy 368.983736 -244.207865) (xy 369.029752 -244.190413) (xy 369.077971 -244.180569)
			(xy 369.127146 -244.178588) (xy 369.176001 -244.18452) (xy 369.223272 -244.198212) (xy 369.267734 -244.21931)
			(xy 369.308237 -244.247266) (xy 369.34373 -244.281358) (xy 369.373295 -244.320702) (xy 369.396166 -244.364279)
			(xy 369.41175 -244.41096) (xy 369.419645 -244.459537) (xy 369.42014 -244.484144) (xy 369.738651 -244.484144)
			(xy 369.742746 -244.433416) (xy 369.754925 -244.384002) (xy 369.774873 -244.337182) (xy 369.802074 -244.294168)
			(xy 369.835822 -244.256074) (xy 369.875244 -244.223887) (xy 369.919318 -244.198441) (xy 369.966904 -244.180394)
			(xy 370.016768 -244.170214) (xy 370.06762 -244.168165) (xy 370.118141 -244.174299) (xy 370.167025 -244.188459)
			(xy 370.213004 -244.210276) (xy 370.254888 -244.239186) (xy 370.291592 -244.274441) (xy 370.322165 -244.315127)
			(xy 370.345816 -244.36019) (xy 370.361932 -244.408464) (xy 370.370096 -244.458698) (xy 370.370608 -244.484144)
			(xy 370.678451 -244.484144) (xy 370.682546 -244.433416) (xy 370.694725 -244.384002) (xy 370.714673 -244.337182)
			(xy 370.741874 -244.294168) (xy 370.775622 -244.256074) (xy 370.815044 -244.223887) (xy 370.859118 -244.198441)
			(xy 370.906704 -244.180394) (xy 370.956568 -244.170214) (xy 371.00742 -244.168165) (xy 371.057941 -244.174299)
			(xy 371.106825 -244.188459) (xy 371.152804 -244.210276) (xy 371.194688 -244.239186) (xy 371.231392 -244.274441)
			(xy 371.261965 -244.315127) (xy 371.285616 -244.36019) (xy 371.301732 -244.408464) (xy 371.309896 -244.458698)
			(xy 371.310408 -244.484144) (xy 371.628936 -244.484144) (xy 371.632896 -244.43509) (xy 371.644673 -244.387306)
			(xy 371.663964 -244.34203) (xy 371.690267 -244.300434) (xy 371.722902 -244.263597) (xy 371.761023 -244.232472)
			(xy 371.803644 -244.207865) (xy 371.84966 -244.190413) (xy 371.897879 -244.180569) (xy 371.947054 -244.178588)
			(xy 371.995909 -244.18452) (xy 372.04318 -244.198212) (xy 372.087642 -244.21931) (xy 372.128145 -244.247266)
			(xy 372.163638 -244.281358) (xy 372.193203 -244.320702) (xy 372.216074 -244.364279) (xy 372.231658 -244.41096)
			(xy 372.239553 -244.459537) (xy 372.240048 -244.484144) (xy 372.558559 -244.484144) (xy 372.562654 -244.433416)
			(xy 372.574833 -244.384002) (xy 372.594781 -244.337182) (xy 372.621982 -244.294168) (xy 372.65573 -244.256074)
			(xy 372.695152 -244.223887) (xy 372.739226 -244.198441) (xy 372.786812 -244.180394) (xy 372.836676 -244.170214)
			(xy 372.887528 -244.168165) (xy 372.938049 -244.174299) (xy 372.986933 -244.188459) (xy 373.032912 -244.210276)
			(xy 373.074796 -244.239186) (xy 373.1115 -244.274441) (xy 373.142073 -244.315127) (xy 373.165724 -244.36019)
			(xy 373.18184 -244.408464) (xy 373.190004 -244.458698) (xy 373.190516 -244.484144) (xy 373.498613 -244.484144)
			(xy 373.502708 -244.433416) (xy 373.514887 -244.384002) (xy 373.534835 -244.337182) (xy 373.562036 -244.294168)
			(xy 373.595784 -244.256074) (xy 373.635206 -244.223887) (xy 373.67928 -244.198441) (xy 373.726866 -244.180394)
			(xy 373.77673 -244.170214) (xy 373.827582 -244.168165) (xy 373.878103 -244.174299) (xy 373.926987 -244.188459)
			(xy 373.972966 -244.210276) (xy 374.01485 -244.239186) (xy 374.051554 -244.274441) (xy 374.082127 -244.315127)
			(xy 374.105778 -244.36019) (xy 374.121894 -244.408464) (xy 374.130058 -244.458698) (xy 374.13057 -244.484144)
			(xy 374.130058 -244.50959) (xy 374.121894 -244.559824) (xy 374.105778 -244.608098) (xy 374.082127 -244.653161)
			(xy 374.051554 -244.693847) (xy 374.01485 -244.729102) (xy 373.972966 -244.758012) (xy 373.926987 -244.779829)
			(xy 373.878103 -244.793989) (xy 373.827582 -244.800123) (xy 373.77673 -244.798074) (xy 373.726866 -244.787894)
			(xy 373.67928 -244.769847) (xy 373.635206 -244.744401) (xy 373.595784 -244.712214) (xy 373.562036 -244.67412)
			(xy 373.534835 -244.631106) (xy 373.514887 -244.584286) (xy 373.502708 -244.534872) (xy 373.498613 -244.484144)
			(xy 373.190516 -244.484144) (xy 373.190004 -244.50959) (xy 373.18184 -244.559824) (xy 373.165724 -244.608098)
			(xy 373.142073 -244.653161) (xy 373.1115 -244.693847) (xy 373.074796 -244.729102) (xy 373.032912 -244.758012)
			(xy 372.986933 -244.779829) (xy 372.938049 -244.793989) (xy 372.887528 -244.800123) (xy 372.836676 -244.798074)
			(xy 372.786812 -244.787894) (xy 372.739226 -244.769847) (xy 372.695152 -244.744401) (xy 372.65573 -244.712214)
			(xy 372.621982 -244.67412) (xy 372.594781 -244.631106) (xy 372.574833 -244.584286) (xy 372.562654 -244.534872)
			(xy 372.558559 -244.484144) (xy 372.240048 -244.484144) (xy 372.239553 -244.508751) (xy 372.231658 -244.557328)
			(xy 372.216074 -244.604009) (xy 372.193203 -244.647586) (xy 372.163638 -244.68693) (xy 372.128145 -244.721022)
			(xy 372.087642 -244.748978) (xy 372.04318 -244.770076) (xy 371.995909 -244.783768) (xy 371.947054 -244.7897)
			(xy 371.897879 -244.787719) (xy 371.84966 -244.777875) (xy 371.803644 -244.760423) (xy 371.761023 -244.735816)
			(xy 371.722902 -244.704691) (xy 371.690267 -244.667854) (xy 371.663964 -244.626258) (xy 371.644673 -244.580982)
			(xy 371.632896 -244.533198) (xy 371.628936 -244.484144) (xy 371.310408 -244.484144) (xy 371.309896 -244.50959)
			(xy 371.301732 -244.559824) (xy 371.285616 -244.608098) (xy 371.261965 -244.653161) (xy 371.231392 -244.693847)
			(xy 371.194688 -244.729102) (xy 371.152804 -244.758012) (xy 371.106825 -244.779829) (xy 371.057941 -244.793989)
			(xy 371.00742 -244.800123) (xy 370.956568 -244.798074) (xy 370.906704 -244.787894) (xy 370.859118 -244.769847)
			(xy 370.815044 -244.744401) (xy 370.775622 -244.712214) (xy 370.741874 -244.67412) (xy 370.714673 -244.631106)
			(xy 370.694725 -244.584286) (xy 370.682546 -244.534872) (xy 370.678451 -244.484144) (xy 370.370608 -244.484144)
			(xy 370.370096 -244.50959) (xy 370.361932 -244.559824) (xy 370.345816 -244.608098) (xy 370.322165 -244.653161)
			(xy 370.291592 -244.693847) (xy 370.254888 -244.729102) (xy 370.213004 -244.758012) (xy 370.167025 -244.779829)
			(xy 370.118141 -244.793989) (xy 370.06762 -244.800123) (xy 370.016768 -244.798074) (xy 369.966904 -244.787894)
			(xy 369.919318 -244.769847) (xy 369.875244 -244.744401) (xy 369.835822 -244.712214) (xy 369.802074 -244.67412)
			(xy 369.774873 -244.631106) (xy 369.754925 -244.584286) (xy 369.742746 -244.534872) (xy 369.738651 -244.484144)
			(xy 369.42014 -244.484144) (xy 369.419645 -244.508751) (xy 369.41175 -244.557328) (xy 369.396166 -244.604009)
			(xy 369.373295 -244.647586) (xy 369.34373 -244.68693) (xy 369.308237 -244.721022) (xy 369.267734 -244.748978)
			(xy 369.223272 -244.770076) (xy 369.176001 -244.783768) (xy 369.127146 -244.7897) (xy 369.077971 -244.787719)
			(xy 369.029752 -244.777875) (xy 368.983736 -244.760423) (xy 368.941115 -244.735816) (xy 368.902994 -244.704691)
			(xy 368.870359 -244.667854) (xy 368.844056 -244.626258) (xy 368.824765 -244.580982) (xy 368.812988 -244.533198)
			(xy 368.809028 -244.484144) (xy 368.4905 -244.484144) (xy 368.489988 -244.50959) (xy 368.481824 -244.559824)
			(xy 368.465708 -244.608098) (xy 368.442057 -244.653161) (xy 368.411484 -244.693847) (xy 368.37478 -244.729102)
			(xy 368.332896 -244.758012) (xy 368.286917 -244.779829) (xy 368.238033 -244.793989) (xy 368.187512 -244.800123)
			(xy 368.13666 -244.798074) (xy 368.086796 -244.787894) (xy 368.03921 -244.769847) (xy 367.995136 -244.744401)
			(xy 367.955714 -244.712214) (xy 367.921966 -244.67412) (xy 367.894765 -244.631106) (xy 367.874817 -244.584286)
			(xy 367.862638 -244.534872) (xy 367.858543 -244.484144) (xy 367.550446 -244.484144) (xy 367.549934 -244.50959)
			(xy 367.54177 -244.559824) (xy 367.525654 -244.608098) (xy 367.502003 -244.653161) (xy 367.47143 -244.693847)
			(xy 367.434726 -244.729102) (xy 367.392842 -244.758012) (xy 367.346863 -244.779829) (xy 367.297979 -244.793989)
			(xy 367.247458 -244.800123) (xy 367.196606 -244.798074) (xy 367.146742 -244.787894) (xy 367.099156 -244.769847)
			(xy 367.055082 -244.744401) (xy 367.01566 -244.712214) (xy 366.981912 -244.67412) (xy 366.954711 -244.631106)
			(xy 366.934763 -244.584286) (xy 366.922584 -244.534872) (xy 366.918489 -244.484144) (xy 366.600232 -244.484144)
			(xy 366.599737 -244.508751) (xy 366.591842 -244.557328) (xy 366.576258 -244.604009) (xy 366.553387 -244.647586)
			(xy 366.523822 -244.68693) (xy 366.488329 -244.721022) (xy 366.447826 -244.748978) (xy 366.403364 -244.770076)
			(xy 366.356093 -244.783768) (xy 366.307238 -244.7897) (xy 366.258063 -244.787719) (xy 366.209844 -244.777875)
			(xy 366.163828 -244.760423) (xy 366.121207 -244.735816) (xy 366.083086 -244.704691) (xy 366.050451 -244.667854)
			(xy 366.024148 -244.626258) (xy 366.004857 -244.580982) (xy 365.99308 -244.533198) (xy 365.98912 -244.484144)
			(xy 365.670592 -244.484144) (xy 365.67008 -244.50959) (xy 365.661916 -244.559824) (xy 365.6458 -244.608098)
			(xy 365.622149 -244.653161) (xy 365.591576 -244.693847) (xy 365.554872 -244.729102) (xy 365.512988 -244.758012)
			(xy 365.467009 -244.779829) (xy 365.418125 -244.793989) (xy 365.367604 -244.800123) (xy 365.316752 -244.798074)
			(xy 365.266888 -244.787894) (xy 365.219302 -244.769847) (xy 365.175228 -244.744401) (xy 365.135806 -244.712214)
			(xy 365.102058 -244.67412) (xy 365.074857 -244.631106) (xy 365.054909 -244.584286) (xy 365.04273 -244.534872)
			(xy 365.038635 -244.484144) (xy 364.730538 -244.484144) (xy 364.730026 -244.50959) (xy 364.721862 -244.559824)
			(xy 364.705746 -244.608098) (xy 364.682095 -244.653161) (xy 364.651522 -244.693847) (xy 364.614818 -244.729102)
			(xy 364.572934 -244.758012) (xy 364.526955 -244.779829) (xy 364.478071 -244.793989) (xy 364.42755 -244.800123)
			(xy 364.376698 -244.798074) (xy 364.326834 -244.787894) (xy 364.279248 -244.769847) (xy 364.235174 -244.744401)
			(xy 364.195752 -244.712214) (xy 364.162004 -244.67412) (xy 364.134803 -244.631106) (xy 364.114855 -244.584286)
			(xy 364.102676 -244.534872) (xy 364.098581 -244.484144) (xy 363.78007 -244.484144) (xy 363.779575 -244.508751)
			(xy 363.77168 -244.557328) (xy 363.756096 -244.604009) (xy 363.733225 -244.647586) (xy 363.70366 -244.68693)
			(xy 363.668167 -244.721022) (xy 363.627664 -244.748978) (xy 363.583202 -244.770076) (xy 363.535931 -244.783768)
			(xy 363.487076 -244.7897) (xy 363.437901 -244.787719) (xy 363.389682 -244.777875) (xy 363.343666 -244.760423)
			(xy 363.301045 -244.735816) (xy 363.262924 -244.704691) (xy 363.230289 -244.667854) (xy 363.203986 -244.626258)
			(xy 363.184695 -244.580982) (xy 363.172918 -244.533198) (xy 363.168958 -244.484144) (xy 362.840016 -244.484144)
			(xy 362.839521 -244.508751) (xy 362.831626 -244.557328) (xy 362.816042 -244.604009) (xy 362.793171 -244.647586)
			(xy 362.763606 -244.68693) (xy 362.728113 -244.721022) (xy 362.68761 -244.748978) (xy 362.643148 -244.770076)
			(xy 362.595877 -244.783768) (xy 362.547022 -244.7897) (xy 362.497847 -244.787719) (xy 362.449628 -244.777875)
			(xy 362.403612 -244.760423) (xy 362.360991 -244.735816) (xy 362.32287 -244.704691) (xy 362.290235 -244.667854)
			(xy 362.263932 -244.626258) (xy 362.244641 -244.580982) (xy 362.232864 -244.533198) (xy 362.228904 -244.484144)
			(xy 361.900216 -244.484144) (xy 361.899721 -244.508751) (xy 361.891826 -244.557328) (xy 361.876242 -244.604009)
			(xy 361.853371 -244.647586) (xy 361.823806 -244.68693) (xy 361.788313 -244.721022) (xy 361.74781 -244.748978)
			(xy 361.703348 -244.770076) (xy 361.656077 -244.783768) (xy 361.607222 -244.7897) (xy 361.558047 -244.787719)
			(xy 361.509828 -244.777875) (xy 361.463812 -244.760423) (xy 361.421191 -244.735816) (xy 361.38307 -244.704691)
			(xy 361.350435 -244.667854) (xy 361.324132 -244.626258) (xy 361.304841 -244.580982) (xy 361.293064 -244.533198)
			(xy 361.289104 -244.484144) (xy 360.27868 -244.484144) (xy 360.27868 -245.29415) (xy 360.81895 -245.29415)
			(xy 360.82291 -245.245096) (xy 360.834687 -245.197312) (xy 360.853978 -245.152036) (xy 360.880281 -245.11044)
			(xy 360.912916 -245.073603) (xy 360.951037 -245.042478) (xy 360.993658 -245.017871) (xy 361.039674 -245.000419)
			(xy 361.087893 -244.990575) (xy 361.137068 -244.988594) (xy 361.185923 -244.994526) (xy 361.233194 -245.008218)
			(xy 361.277656 -245.029316) (xy 361.318159 -245.057272) (xy 361.353652 -245.091364) (xy 361.383217 -245.130708)
			(xy 361.406088 -245.174285) (xy 361.421672 -245.220966) (xy 361.429567 -245.269543) (xy 361.430062 -245.29415)
			(xy 361.748573 -245.29415) (xy 361.752668 -245.243422) (xy 361.764847 -245.194008) (xy 361.784795 -245.147188)
			(xy 361.811996 -245.104174) (xy 361.845744 -245.06608) (xy 361.885166 -245.033893) (xy 361.92924 -245.008447)
			(xy 361.976826 -244.9904) (xy 362.02669 -244.98022) (xy 362.077542 -244.978171) (xy 362.128063 -244.984305)
			(xy 362.176947 -244.998465) (xy 362.222926 -245.020282) (xy 362.26481 -245.049192) (xy 362.301514 -245.084447)
			(xy 362.332087 -245.125133) (xy 362.355738 -245.170196) (xy 362.371854 -245.21847) (xy 362.380018 -245.268704)
			(xy 362.38053 -245.29415) (xy 362.688627 -245.29415) (xy 362.692722 -245.243422) (xy 362.704901 -245.194008)
			(xy 362.724849 -245.147188) (xy 362.75205 -245.104174) (xy 362.785798 -245.06608) (xy 362.82522 -245.033893)
			(xy 362.869294 -245.008447) (xy 362.91688 -244.9904) (xy 362.966744 -244.98022) (xy 363.017596 -244.978171)
			(xy 363.068117 -244.984305) (xy 363.117001 -244.998465) (xy 363.16298 -245.020282) (xy 363.204864 -245.049192)
			(xy 363.241568 -245.084447) (xy 363.272141 -245.125133) (xy 363.295792 -245.170196) (xy 363.311908 -245.21847)
			(xy 363.320072 -245.268704) (xy 363.320584 -245.29415) (xy 363.639112 -245.29415) (xy 363.643072 -245.245096)
			(xy 363.654849 -245.197312) (xy 363.67414 -245.152036) (xy 363.700443 -245.11044) (xy 363.733078 -245.073603)
			(xy 363.771199 -245.042478) (xy 363.81382 -245.017871) (xy 363.859836 -245.000419) (xy 363.908055 -244.990575)
			(xy 363.95723 -244.988594) (xy 364.006085 -244.994526) (xy 364.053356 -245.008218) (xy 364.097818 -245.029316)
			(xy 364.138321 -245.057272) (xy 364.173814 -245.091364) (xy 364.203379 -245.130708) (xy 364.22625 -245.174285)
			(xy 364.241834 -245.220966) (xy 364.249729 -245.269543) (xy 364.250224 -245.29415) (xy 366.45902 -245.29415)
			(xy 366.46298 -245.245096) (xy 366.474757 -245.197312) (xy 366.494048 -245.152036) (xy 366.520351 -245.11044)
			(xy 366.552986 -245.073603) (xy 366.591107 -245.042478) (xy 366.633728 -245.017871) (xy 366.679744 -245.000419)
			(xy 366.727963 -244.990575) (xy 366.777138 -244.988594) (xy 366.825993 -244.994526) (xy 366.873264 -245.008218)
			(xy 366.917726 -245.029316) (xy 366.958229 -245.057272) (xy 366.993722 -245.091364) (xy 367.023287 -245.130708)
			(xy 367.046158 -245.174285) (xy 367.061742 -245.220966) (xy 367.069637 -245.269543) (xy 367.070132 -245.29415)
			(xy 369.278928 -245.29415) (xy 369.282888 -245.245096) (xy 369.294665 -245.197312) (xy 369.313956 -245.152036)
			(xy 369.340259 -245.11044) (xy 369.372894 -245.073603) (xy 369.411015 -245.042478) (xy 369.453636 -245.017871)
			(xy 369.499652 -245.000419) (xy 369.547871 -244.990575) (xy 369.597046 -244.988594) (xy 369.645901 -244.994526)
			(xy 369.693172 -245.008218) (xy 369.737634 -245.029316) (xy 369.778137 -245.057272) (xy 369.81363 -245.091364)
			(xy 369.843195 -245.130708) (xy 369.866066 -245.174285) (xy 369.88165 -245.220966) (xy 369.889545 -245.269543)
			(xy 369.89004 -245.29415) (xy 372.09909 -245.29415) (xy 372.10305 -245.245096) (xy 372.114827 -245.197312)
			(xy 372.134118 -245.152036) (xy 372.160421 -245.11044) (xy 372.193056 -245.073603) (xy 372.231177 -245.042478)
			(xy 372.273798 -245.017871) (xy 372.319814 -245.000419) (xy 372.368033 -244.990575) (xy 372.417208 -244.988594)
			(xy 372.466063 -244.994526) (xy 372.513334 -245.008218) (xy 372.557796 -245.029316) (xy 372.598299 -245.057272)
			(xy 372.633792 -245.091364) (xy 372.663357 -245.130708) (xy 372.686228 -245.174285) (xy 372.701812 -245.220966)
			(xy 372.709707 -245.269543) (xy 372.710202 -245.29415) (xy 372.709707 -245.318757) (xy 372.701812 -245.367334)
			(xy 372.686228 -245.414015) (xy 372.663357 -245.457592) (xy 372.633792 -245.496936) (xy 372.598299 -245.531028)
			(xy 372.557796 -245.558984) (xy 372.513334 -245.580082) (xy 372.466063 -245.593774) (xy 372.417208 -245.599706)
			(xy 372.368033 -245.597725) (xy 372.319814 -245.587881) (xy 372.273798 -245.570429) (xy 372.231177 -245.545822)
			(xy 372.193056 -245.514697) (xy 372.160421 -245.47786) (xy 372.134118 -245.436264) (xy 372.114827 -245.390988)
			(xy 372.10305 -245.343204) (xy 372.09909 -245.29415) (xy 369.89004 -245.29415) (xy 369.889545 -245.318757)
			(xy 369.88165 -245.367334) (xy 369.866066 -245.414015) (xy 369.843195 -245.457592) (xy 369.81363 -245.496936)
			(xy 369.778137 -245.531028) (xy 369.737634 -245.558984) (xy 369.693172 -245.580082) (xy 369.645901 -245.593774)
			(xy 369.597046 -245.599706) (xy 369.547871 -245.597725) (xy 369.499652 -245.587881) (xy 369.453636 -245.570429)
			(xy 369.411015 -245.545822) (xy 369.372894 -245.514697) (xy 369.340259 -245.47786) (xy 369.313956 -245.436264)
			(xy 369.294665 -245.390988) (xy 369.282888 -245.343204) (xy 369.278928 -245.29415) (xy 367.070132 -245.29415)
			(xy 367.069637 -245.318757) (xy 367.061742 -245.367334) (xy 367.046158 -245.414015) (xy 367.023287 -245.457592)
			(xy 366.993722 -245.496936) (xy 366.958229 -245.531028) (xy 366.917726 -245.558984) (xy 366.873264 -245.580082)
			(xy 366.825993 -245.593774) (xy 366.777138 -245.599706) (xy 366.727963 -245.597725) (xy 366.679744 -245.587881)
			(xy 366.633728 -245.570429) (xy 366.591107 -245.545822) (xy 366.552986 -245.514697) (xy 366.520351 -245.47786)
			(xy 366.494048 -245.436264) (xy 366.474757 -245.390988) (xy 366.46298 -245.343204) (xy 366.45902 -245.29415)
			(xy 364.250224 -245.29415) (xy 364.249729 -245.318757) (xy 364.241834 -245.367334) (xy 364.22625 -245.414015)
			(xy 364.203379 -245.457592) (xy 364.173814 -245.496936) (xy 364.138321 -245.531028) (xy 364.097818 -245.558984)
			(xy 364.053356 -245.580082) (xy 364.006085 -245.593774) (xy 363.95723 -245.599706) (xy 363.908055 -245.597725)
			(xy 363.859836 -245.587881) (xy 363.81382 -245.570429) (xy 363.771199 -245.545822) (xy 363.733078 -245.514697)
			(xy 363.700443 -245.47786) (xy 363.67414 -245.436264) (xy 363.654849 -245.390988) (xy 363.643072 -245.343204)
			(xy 363.639112 -245.29415) (xy 363.320584 -245.29415) (xy 363.320072 -245.319596) (xy 363.311908 -245.36983)
			(xy 363.295792 -245.418104) (xy 363.272141 -245.463167) (xy 363.241568 -245.503853) (xy 363.204864 -245.539108)
			(xy 363.16298 -245.568018) (xy 363.117001 -245.589835) (xy 363.068117 -245.603995) (xy 363.017596 -245.610129)
			(xy 362.966744 -245.60808) (xy 362.91688 -245.5979) (xy 362.869294 -245.579853) (xy 362.82522 -245.554407)
			(xy 362.785798 -245.52222) (xy 362.75205 -245.484126) (xy 362.724849 -245.441112) (xy 362.704901 -245.394292)
			(xy 362.692722 -245.344878) (xy 362.688627 -245.29415) (xy 362.38053 -245.29415) (xy 362.380018 -245.319596)
			(xy 362.371854 -245.36983) (xy 362.355738 -245.418104) (xy 362.332087 -245.463167) (xy 362.301514 -245.503853)
			(xy 362.26481 -245.539108) (xy 362.222926 -245.568018) (xy 362.176947 -245.589835) (xy 362.128063 -245.603995)
			(xy 362.077542 -245.610129) (xy 362.02669 -245.60808) (xy 361.976826 -245.5979) (xy 361.92924 -245.579853)
			(xy 361.885166 -245.554407) (xy 361.845744 -245.52222) (xy 361.811996 -245.484126) (xy 361.784795 -245.441112)
			(xy 361.764847 -245.394292) (xy 361.752668 -245.344878) (xy 361.748573 -245.29415) (xy 361.430062 -245.29415)
			(xy 361.429567 -245.318757) (xy 361.421672 -245.367334) (xy 361.406088 -245.414015) (xy 361.383217 -245.457592)
			(xy 361.353652 -245.496936) (xy 361.318159 -245.531028) (xy 361.277656 -245.558984) (xy 361.233194 -245.580082)
			(xy 361.185923 -245.593774) (xy 361.137068 -245.599706) (xy 361.087893 -245.597725) (xy 361.039674 -245.587881)
			(xy 360.993658 -245.570429) (xy 360.951037 -245.545822) (xy 360.912916 -245.514697) (xy 360.880281 -245.47786)
			(xy 360.853978 -245.436264) (xy 360.834687 -245.390988) (xy 360.82291 -245.343204) (xy 360.81895 -245.29415)
			(xy 360.27868 -245.29415) (xy 360.27868 -245.469918) (xy 360.278253 -245.479986) (xy 360.270532 -245.498584)
			(xy 360.263694 -245.505986) (xy 360.024172 -245.745508) (xy 360.021632 -245.749064) (xy 360.003944 -245.773173)
			(xy 359.961666 -245.815449) (xy 359.937558 -245.833138) (xy 359.934002 -245.835678) (xy 359.665524 -246.104156)
			(xy 363.168958 -246.104156) (xy 363.172918 -246.055102) (xy 363.184695 -246.007318) (xy 363.203986 -245.962042)
			(xy 363.230289 -245.920446) (xy 363.262924 -245.883609) (xy 363.301045 -245.852484) (xy 363.343666 -245.827877)
			(xy 363.389682 -245.810425) (xy 363.437901 -245.800581) (xy 363.487076 -245.7986) (xy 363.535931 -245.804532)
			(xy 363.583202 -245.818224) (xy 363.627664 -245.839322) (xy 363.668167 -245.867278) (xy 363.70366 -245.90137)
			(xy 363.733225 -245.940714) (xy 363.756096 -245.984291) (xy 363.77168 -246.030972) (xy 363.779575 -246.079549)
			(xy 363.78007 -246.104156) (xy 364.098581 -246.104156) (xy 364.102676 -246.053428) (xy 364.114855 -246.004014)
			(xy 364.134803 -245.957194) (xy 364.162004 -245.91418) (xy 364.195752 -245.876086) (xy 364.235174 -245.843899)
			(xy 364.279248 -245.818453) (xy 364.326834 -245.800406) (xy 364.376698 -245.790226) (xy 364.42755 -245.788177)
			(xy 364.478071 -245.794311) (xy 364.526955 -245.808471) (xy 364.572934 -245.830288) (xy 364.614818 -245.859198)
			(xy 364.651522 -245.894453) (xy 364.682095 -245.935139) (xy 364.705746 -245.980202) (xy 364.721862 -246.028476)
			(xy 364.730026 -246.07871) (xy 364.730538 -246.104156) (xy 365.038635 -246.104156) (xy 365.04273 -246.053428)
			(xy 365.054909 -246.004014) (xy 365.074857 -245.957194) (xy 365.102058 -245.91418) (xy 365.135806 -245.876086)
			(xy 365.175228 -245.843899) (xy 365.219302 -245.818453) (xy 365.266888 -245.800406) (xy 365.316752 -245.790226)
			(xy 365.367604 -245.788177) (xy 365.418125 -245.794311) (xy 365.467009 -245.808471) (xy 365.512988 -245.830288)
			(xy 365.554872 -245.859198) (xy 365.591576 -245.894453) (xy 365.622149 -245.935139) (xy 365.6458 -245.980202)
			(xy 365.661916 -246.028476) (xy 365.67008 -246.07871) (xy 365.670592 -246.104156) (xy 365.98912 -246.104156)
			(xy 365.99308 -246.055102) (xy 366.004857 -246.007318) (xy 366.024148 -245.962042) (xy 366.050451 -245.920446)
			(xy 366.083086 -245.883609) (xy 366.121207 -245.852484) (xy 366.163828 -245.827877) (xy 366.209844 -245.810425)
			(xy 366.258063 -245.800581) (xy 366.307238 -245.7986) (xy 366.356093 -245.804532) (xy 366.403364 -245.818224)
			(xy 366.447826 -245.839322) (xy 366.488329 -245.867278) (xy 366.523822 -245.90137) (xy 366.553387 -245.940714)
			(xy 366.576258 -245.984291) (xy 366.591842 -246.030972) (xy 366.599737 -246.079549) (xy 366.600232 -246.104156)
			(xy 366.918489 -246.104156) (xy 366.922584 -246.053428) (xy 366.934763 -246.004014) (xy 366.954711 -245.957194)
			(xy 366.981912 -245.91418) (xy 367.01566 -245.876086) (xy 367.055082 -245.843899) (xy 367.099156 -245.818453)
			(xy 367.146742 -245.800406) (xy 367.196606 -245.790226) (xy 367.247458 -245.788177) (xy 367.297979 -245.794311)
			(xy 367.346863 -245.808471) (xy 367.392842 -245.830288) (xy 367.434726 -245.859198) (xy 367.47143 -245.894453)
			(xy 367.502003 -245.935139) (xy 367.525654 -245.980202) (xy 367.54177 -246.028476) (xy 367.549934 -246.07871)
			(xy 367.550446 -246.104156) (xy 367.858543 -246.104156) (xy 367.862638 -246.053428) (xy 367.874817 -246.004014)
			(xy 367.894765 -245.957194) (xy 367.921966 -245.91418) (xy 367.955714 -245.876086) (xy 367.995136 -245.843899)
			(xy 368.03921 -245.818453) (xy 368.086796 -245.800406) (xy 368.13666 -245.790226) (xy 368.187512 -245.788177)
			(xy 368.238033 -245.794311) (xy 368.286917 -245.808471) (xy 368.332896 -245.830288) (xy 368.37478 -245.859198)
			(xy 368.411484 -245.894453) (xy 368.442057 -245.935139) (xy 368.465708 -245.980202) (xy 368.481824 -246.028476)
			(xy 368.489988 -246.07871) (xy 368.4905 -246.104156) (xy 368.809028 -246.104156) (xy 368.812988 -246.055102)
			(xy 368.824765 -246.007318) (xy 368.844056 -245.962042) (xy 368.870359 -245.920446) (xy 368.902994 -245.883609)
			(xy 368.941115 -245.852484) (xy 368.983736 -245.827877) (xy 369.029752 -245.810425) (xy 369.077971 -245.800581)
			(xy 369.127146 -245.7986) (xy 369.176001 -245.804532) (xy 369.223272 -245.818224) (xy 369.267734 -245.839322)
			(xy 369.308237 -245.867278) (xy 369.34373 -245.90137) (xy 369.373295 -245.940714) (xy 369.396166 -245.984291)
			(xy 369.41175 -246.030972) (xy 369.419645 -246.079549) (xy 369.42014 -246.104156) (xy 369.738651 -246.104156)
			(xy 369.742746 -246.053428) (xy 369.754925 -246.004014) (xy 369.774873 -245.957194) (xy 369.802074 -245.91418)
			(xy 369.835822 -245.876086) (xy 369.875244 -245.843899) (xy 369.919318 -245.818453) (xy 369.966904 -245.800406)
			(xy 370.016768 -245.790226) (xy 370.06762 -245.788177) (xy 370.118141 -245.794311) (xy 370.167025 -245.808471)
			(xy 370.213004 -245.830288) (xy 370.254888 -245.859198) (xy 370.291592 -245.894453) (xy 370.322165 -245.935139)
			(xy 370.345816 -245.980202) (xy 370.361932 -246.028476) (xy 370.370096 -246.07871) (xy 370.370608 -246.104156)
			(xy 370.678451 -246.104156) (xy 370.682546 -246.053428) (xy 370.694725 -246.004014) (xy 370.714673 -245.957194)
			(xy 370.741874 -245.91418) (xy 370.775622 -245.876086) (xy 370.815044 -245.843899) (xy 370.859118 -245.818453)
			(xy 370.906704 -245.800406) (xy 370.956568 -245.790226) (xy 371.00742 -245.788177) (xy 371.057941 -245.794311)
			(xy 371.106825 -245.808471) (xy 371.152804 -245.830288) (xy 371.194688 -245.859198) (xy 371.231392 -245.894453)
			(xy 371.261965 -245.935139) (xy 371.285616 -245.980202) (xy 371.301732 -246.028476) (xy 371.309896 -246.07871)
			(xy 371.310408 -246.104156) (xy 371.628936 -246.104156) (xy 371.632896 -246.055102) (xy 371.644673 -246.007318)
			(xy 371.663964 -245.962042) (xy 371.690267 -245.920446) (xy 371.722902 -245.883609) (xy 371.761023 -245.852484)
			(xy 371.803644 -245.827877) (xy 371.84966 -245.810425) (xy 371.897879 -245.800581) (xy 371.947054 -245.7986)
			(xy 371.995909 -245.804532) (xy 372.04318 -245.818224) (xy 372.087642 -245.839322) (xy 372.128145 -245.867278)
			(xy 372.163638 -245.90137) (xy 372.193203 -245.940714) (xy 372.216074 -245.984291) (xy 372.231658 -246.030972)
			(xy 372.239553 -246.079549) (xy 372.240048 -246.104156) (xy 372.558559 -246.104156) (xy 372.562654 -246.053428)
			(xy 372.574833 -246.004014) (xy 372.594781 -245.957194) (xy 372.621982 -245.91418) (xy 372.65573 -245.876086)
			(xy 372.695152 -245.843899) (xy 372.739226 -245.818453) (xy 372.786812 -245.800406) (xy 372.836676 -245.790226)
			(xy 372.887528 -245.788177) (xy 372.938049 -245.794311) (xy 372.986933 -245.808471) (xy 373.032912 -245.830288)
			(xy 373.074796 -245.859198) (xy 373.1115 -245.894453) (xy 373.142073 -245.935139) (xy 373.165724 -245.980202)
			(xy 373.18184 -246.028476) (xy 373.190004 -246.07871) (xy 373.190516 -246.104156) (xy 373.498613 -246.104156)
			(xy 373.502708 -246.053428) (xy 373.514887 -246.004014) (xy 373.534835 -245.957194) (xy 373.562036 -245.91418)
			(xy 373.595784 -245.876086) (xy 373.635206 -245.843899) (xy 373.67928 -245.818453) (xy 373.726866 -245.800406)
			(xy 373.77673 -245.790226) (xy 373.827582 -245.788177) (xy 373.878103 -245.794311) (xy 373.926987 -245.808471)
			(xy 373.972966 -245.830288) (xy 374.01485 -245.859198) (xy 374.051554 -245.894453) (xy 374.082127 -245.935139)
			(xy 374.105778 -245.980202) (xy 374.121894 -246.028476) (xy 374.130058 -246.07871) (xy 374.13057 -246.104156)
			(xy 374.130058 -246.129602) (xy 374.121894 -246.179836) (xy 374.105778 -246.22811) (xy 374.082127 -246.273173)
			(xy 374.051554 -246.313859) (xy 374.01485 -246.349114) (xy 373.972966 -246.378024) (xy 373.926987 -246.399841)
			(xy 373.878103 -246.414001) (xy 373.827582 -246.420135) (xy 373.77673 -246.418086) (xy 373.726866 -246.407906)
			(xy 373.67928 -246.389859) (xy 373.635206 -246.364413) (xy 373.595784 -246.332226) (xy 373.562036 -246.294132)
			(xy 373.534835 -246.251118) (xy 373.514887 -246.204298) (xy 373.502708 -246.154884) (xy 373.498613 -246.104156)
			(xy 373.190516 -246.104156) (xy 373.190004 -246.129602) (xy 373.18184 -246.179836) (xy 373.165724 -246.22811)
			(xy 373.142073 -246.273173) (xy 373.1115 -246.313859) (xy 373.074796 -246.349114) (xy 373.032912 -246.378024)
			(xy 372.986933 -246.399841) (xy 372.938049 -246.414001) (xy 372.887528 -246.420135) (xy 372.836676 -246.418086)
			(xy 372.786812 -246.407906) (xy 372.739226 -246.389859) (xy 372.695152 -246.364413) (xy 372.65573 -246.332226)
			(xy 372.621982 -246.294132) (xy 372.594781 -246.251118) (xy 372.574833 -246.204298) (xy 372.562654 -246.154884)
			(xy 372.558559 -246.104156) (xy 372.240048 -246.104156) (xy 372.239553 -246.128763) (xy 372.231658 -246.17734)
			(xy 372.216074 -246.224021) (xy 372.193203 -246.267598) (xy 372.163638 -246.306942) (xy 372.128145 -246.341034)
			(xy 372.087642 -246.36899) (xy 372.04318 -246.390088) (xy 371.995909 -246.40378) (xy 371.947054 -246.409712)
			(xy 371.897879 -246.407731) (xy 371.84966 -246.397887) (xy 371.803644 -246.380435) (xy 371.761023 -246.355828)
			(xy 371.722902 -246.324703) (xy 371.690267 -246.287866) (xy 371.663964 -246.24627) (xy 371.644673 -246.200994)
			(xy 371.632896 -246.15321) (xy 371.628936 -246.104156) (xy 371.310408 -246.104156) (xy 371.309896 -246.129602)
			(xy 371.301732 -246.179836) (xy 371.285616 -246.22811) (xy 371.261965 -246.273173) (xy 371.231392 -246.313859)
			(xy 371.194688 -246.349114) (xy 371.152804 -246.378024) (xy 371.106825 -246.399841) (xy 371.057941 -246.414001)
			(xy 371.00742 -246.420135) (xy 370.956568 -246.418086) (xy 370.906704 -246.407906) (xy 370.859118 -246.389859)
			(xy 370.815044 -246.364413) (xy 370.775622 -246.332226) (xy 370.741874 -246.294132) (xy 370.714673 -246.251118)
			(xy 370.694725 -246.204298) (xy 370.682546 -246.154884) (xy 370.678451 -246.104156) (xy 370.370608 -246.104156)
			(xy 370.370096 -246.129602) (xy 370.361932 -246.179836) (xy 370.345816 -246.22811) (xy 370.322165 -246.273173)
			(xy 370.291592 -246.313859) (xy 370.254888 -246.349114) (xy 370.213004 -246.378024) (xy 370.167025 -246.399841)
			(xy 370.118141 -246.414001) (xy 370.06762 -246.420135) (xy 370.016768 -246.418086) (xy 369.966904 -246.407906)
			(xy 369.919318 -246.389859) (xy 369.875244 -246.364413) (xy 369.835822 -246.332226) (xy 369.802074 -246.294132)
			(xy 369.774873 -246.251118) (xy 369.754925 -246.204298) (xy 369.742746 -246.154884) (xy 369.738651 -246.104156)
			(xy 369.42014 -246.104156) (xy 369.419645 -246.128763) (xy 369.41175 -246.17734) (xy 369.396166 -246.224021)
			(xy 369.373295 -246.267598) (xy 369.34373 -246.306942) (xy 369.308237 -246.341034) (xy 369.267734 -246.36899)
			(xy 369.223272 -246.390088) (xy 369.176001 -246.40378) (xy 369.127146 -246.409712) (xy 369.077971 -246.407731)
			(xy 369.029752 -246.397887) (xy 368.983736 -246.380435) (xy 368.941115 -246.355828) (xy 368.902994 -246.324703)
			(xy 368.870359 -246.287866) (xy 368.844056 -246.24627) (xy 368.824765 -246.200994) (xy 368.812988 -246.15321)
			(xy 368.809028 -246.104156) (xy 368.4905 -246.104156) (xy 368.489988 -246.129602) (xy 368.481824 -246.179836)
			(xy 368.465708 -246.22811) (xy 368.442057 -246.273173) (xy 368.411484 -246.313859) (xy 368.37478 -246.349114)
			(xy 368.332896 -246.378024) (xy 368.286917 -246.399841) (xy 368.238033 -246.414001) (xy 368.187512 -246.420135)
			(xy 368.13666 -246.418086) (xy 368.086796 -246.407906) (xy 368.03921 -246.389859) (xy 367.995136 -246.364413)
			(xy 367.955714 -246.332226) (xy 367.921966 -246.294132) (xy 367.894765 -246.251118) (xy 367.874817 -246.204298)
			(xy 367.862638 -246.154884) (xy 367.858543 -246.104156) (xy 367.550446 -246.104156) (xy 367.549934 -246.129602)
			(xy 367.54177 -246.179836) (xy 367.525654 -246.22811) (xy 367.502003 -246.273173) (xy 367.47143 -246.313859)
			(xy 367.434726 -246.349114) (xy 367.392842 -246.378024) (xy 367.346863 -246.399841) (xy 367.297979 -246.414001)
			(xy 367.247458 -246.420135) (xy 367.196606 -246.418086) (xy 367.146742 -246.407906) (xy 367.099156 -246.389859)
			(xy 367.055082 -246.364413) (xy 367.01566 -246.332226) (xy 366.981912 -246.294132) (xy 366.954711 -246.251118)
			(xy 366.934763 -246.204298) (xy 366.922584 -246.154884) (xy 366.918489 -246.104156) (xy 366.600232 -246.104156)
			(xy 366.599737 -246.128763) (xy 366.591842 -246.17734) (xy 366.576258 -246.224021) (xy 366.553387 -246.267598)
			(xy 366.523822 -246.306942) (xy 366.488329 -246.341034) (xy 366.447826 -246.36899) (xy 366.403364 -246.390088)
			(xy 366.356093 -246.40378) (xy 366.307238 -246.409712) (xy 366.258063 -246.407731) (xy 366.209844 -246.397887)
			(xy 366.163828 -246.380435) (xy 366.121207 -246.355828) (xy 366.083086 -246.324703) (xy 366.050451 -246.287866)
			(xy 366.024148 -246.24627) (xy 366.004857 -246.200994) (xy 365.99308 -246.15321) (xy 365.98912 -246.104156)
			(xy 365.670592 -246.104156) (xy 365.67008 -246.129602) (xy 365.661916 -246.179836) (xy 365.6458 -246.22811)
			(xy 365.622149 -246.273173) (xy 365.591576 -246.313859) (xy 365.554872 -246.349114) (xy 365.512988 -246.378024)
			(xy 365.467009 -246.399841) (xy 365.418125 -246.414001) (xy 365.367604 -246.420135) (xy 365.316752 -246.418086)
			(xy 365.266888 -246.407906) (xy 365.219302 -246.389859) (xy 365.175228 -246.364413) (xy 365.135806 -246.332226)
			(xy 365.102058 -246.294132) (xy 365.074857 -246.251118) (xy 365.054909 -246.204298) (xy 365.04273 -246.154884)
			(xy 365.038635 -246.104156) (xy 364.730538 -246.104156) (xy 364.730026 -246.129602) (xy 364.721862 -246.179836)
			(xy 364.705746 -246.22811) (xy 364.682095 -246.273173) (xy 364.651522 -246.313859) (xy 364.614818 -246.349114)
			(xy 364.572934 -246.378024) (xy 364.526955 -246.399841) (xy 364.478071 -246.414001) (xy 364.42755 -246.420135)
			(xy 364.376698 -246.418086) (xy 364.326834 -246.407906) (xy 364.279248 -246.389859) (xy 364.235174 -246.364413)
			(xy 364.195752 -246.332226) (xy 364.162004 -246.294132) (xy 364.134803 -246.251118) (xy 364.114855 -246.204298)
			(xy 364.102676 -246.154884) (xy 364.098581 -246.104156) (xy 363.78007 -246.104156) (xy 363.779575 -246.128763)
			(xy 363.77168 -246.17734) (xy 363.756096 -246.224021) (xy 363.733225 -246.267598) (xy 363.70366 -246.306942)
			(xy 363.668167 -246.341034) (xy 363.627664 -246.36899) (xy 363.583202 -246.390088) (xy 363.535931 -246.40378)
			(xy 363.487076 -246.409712) (xy 363.437901 -246.407731) (xy 363.389682 -246.397887) (xy 363.343666 -246.380435)
			(xy 363.301045 -246.355828) (xy 363.262924 -246.324703) (xy 363.230289 -246.287866) (xy 363.203986 -246.24627)
			(xy 363.184695 -246.200994) (xy 363.172918 -246.15321) (xy 363.168958 -246.104156) (xy 359.665524 -246.104156)
			(xy 359.285286 -246.484394) (xy 359.27792 -246.491506) (xy 359.2703 -246.510302) (xy 359.2703 -246.914162)
			(xy 360.81895 -246.914162) (xy 360.82291 -246.865108) (xy 360.834687 -246.817324) (xy 360.853978 -246.772048)
			(xy 360.880281 -246.730452) (xy 360.912916 -246.693615) (xy 360.951037 -246.66249) (xy 360.993658 -246.637883)
			(xy 361.039674 -246.620431) (xy 361.087893 -246.610587) (xy 361.137068 -246.608606) (xy 361.185923 -246.614538)
			(xy 361.233194 -246.62823) (xy 361.277656 -246.649328) (xy 361.318159 -246.677284) (xy 361.353652 -246.711376)
			(xy 361.383217 -246.75072) (xy 361.406088 -246.794297) (xy 361.421672 -246.840978) (xy 361.429567 -246.889555)
			(xy 361.430062 -246.914162) (xy 361.748573 -246.914162) (xy 361.752668 -246.863434) (xy 361.764847 -246.81402)
			(xy 361.784795 -246.7672) (xy 361.811996 -246.724186) (xy 361.845744 -246.686092) (xy 361.885166 -246.653905)
			(xy 361.92924 -246.628459) (xy 361.976826 -246.610412) (xy 362.02669 -246.600232) (xy 362.077542 -246.598183)
			(xy 362.128063 -246.604317) (xy 362.176947 -246.618477) (xy 362.222926 -246.640294) (xy 362.26481 -246.669204)
			(xy 362.301514 -246.704459) (xy 362.332087 -246.745145) (xy 362.355738 -246.790208) (xy 362.371854 -246.838482)
			(xy 362.380018 -246.888716) (xy 362.38053 -246.914162) (xy 362.688627 -246.914162) (xy 362.692722 -246.863434)
			(xy 362.704901 -246.81402) (xy 362.724849 -246.7672) (xy 362.75205 -246.724186) (xy 362.785798 -246.686092)
			(xy 362.82522 -246.653905) (xy 362.869294 -246.628459) (xy 362.91688 -246.610412) (xy 362.966744 -246.600232)
			(xy 363.017596 -246.598183) (xy 363.068117 -246.604317) (xy 363.117001 -246.618477) (xy 363.16298 -246.640294)
			(xy 363.204864 -246.669204) (xy 363.241568 -246.704459) (xy 363.272141 -246.745145) (xy 363.295792 -246.790208)
			(xy 363.311908 -246.838482) (xy 363.320072 -246.888716) (xy 363.320584 -246.914162) (xy 363.639112 -246.914162)
			(xy 363.643072 -246.865108) (xy 363.654849 -246.817324) (xy 363.67414 -246.772048) (xy 363.700443 -246.730452)
			(xy 363.733078 -246.693615) (xy 363.771199 -246.66249) (xy 363.81382 -246.637883) (xy 363.859836 -246.620431)
			(xy 363.908055 -246.610587) (xy 363.95723 -246.608606) (xy 364.006085 -246.614538) (xy 364.053356 -246.62823)
			(xy 364.097818 -246.649328) (xy 364.138321 -246.677284) (xy 364.173814 -246.711376) (xy 364.203379 -246.75072)
			(xy 364.22625 -246.794297) (xy 364.241834 -246.840978) (xy 364.249729 -246.889555) (xy 364.250224 -246.914162)
			(xy 364.578912 -246.914162) (xy 364.582872 -246.865108) (xy 364.594649 -246.817324) (xy 364.61394 -246.772048)
			(xy 364.640243 -246.730452) (xy 364.672878 -246.693615) (xy 364.710999 -246.66249) (xy 364.75362 -246.637883)
			(xy 364.799636 -246.620431) (xy 364.847855 -246.610587) (xy 364.89703 -246.608606) (xy 364.945885 -246.614538)
			(xy 364.993156 -246.62823) (xy 365.037618 -246.649328) (xy 365.078121 -246.677284) (xy 365.113614 -246.711376)
			(xy 365.143179 -246.75072) (xy 365.16605 -246.794297) (xy 365.181634 -246.840978) (xy 365.189529 -246.889555)
			(xy 365.190024 -246.914162) (xy 365.518966 -246.914162) (xy 365.522926 -246.865108) (xy 365.534703 -246.817324)
			(xy 365.553994 -246.772048) (xy 365.580297 -246.730452) (xy 365.612932 -246.693615) (xy 365.651053 -246.66249)
			(xy 365.693674 -246.637883) (xy 365.73969 -246.620431) (xy 365.787909 -246.610587) (xy 365.837084 -246.608606)
			(xy 365.885939 -246.614538) (xy 365.93321 -246.62823) (xy 365.977672 -246.649328) (xy 366.018175 -246.677284)
			(xy 366.053668 -246.711376) (xy 366.083233 -246.75072) (xy 366.106104 -246.794297) (xy 366.121688 -246.840978)
			(xy 366.129583 -246.889555) (xy 366.130078 -246.914162) (xy 366.45902 -246.914162) (xy 366.46298 -246.865108)
			(xy 366.474757 -246.817324) (xy 366.494048 -246.772048) (xy 366.520351 -246.730452) (xy 366.552986 -246.693615)
			(xy 366.591107 -246.66249) (xy 366.633728 -246.637883) (xy 366.679744 -246.620431) (xy 366.727963 -246.610587)
			(xy 366.777138 -246.608606) (xy 366.825993 -246.614538) (xy 366.873264 -246.62823) (xy 366.917726 -246.649328)
			(xy 366.958229 -246.677284) (xy 366.993722 -246.711376) (xy 367.023287 -246.75072) (xy 367.046158 -246.794297)
			(xy 367.061742 -246.840978) (xy 367.069637 -246.889555) (xy 367.070132 -246.914162) (xy 367.399074 -246.914162)
			(xy 367.403034 -246.865108) (xy 367.414811 -246.817324) (xy 367.434102 -246.772048) (xy 367.460405 -246.730452)
			(xy 367.49304 -246.693615) (xy 367.531161 -246.66249) (xy 367.573782 -246.637883) (xy 367.619798 -246.620431)
			(xy 367.668017 -246.610587) (xy 367.717192 -246.608606) (xy 367.766047 -246.614538) (xy 367.813318 -246.62823)
			(xy 367.85778 -246.649328) (xy 367.898283 -246.677284) (xy 367.933776 -246.711376) (xy 367.963341 -246.75072)
			(xy 367.986212 -246.794297) (xy 368.001796 -246.840978) (xy 368.009691 -246.889555) (xy 368.010186 -246.914162)
			(xy 368.338874 -246.914162) (xy 368.342834 -246.865108) (xy 368.354611 -246.817324) (xy 368.373902 -246.772048)
			(xy 368.400205 -246.730452) (xy 368.43284 -246.693615) (xy 368.470961 -246.66249) (xy 368.513582 -246.637883)
			(xy 368.559598 -246.620431) (xy 368.607817 -246.610587) (xy 368.656992 -246.608606) (xy 368.705847 -246.614538)
			(xy 368.753118 -246.62823) (xy 368.79758 -246.649328) (xy 368.838083 -246.677284) (xy 368.873576 -246.711376)
			(xy 368.903141 -246.75072) (xy 368.926012 -246.794297) (xy 368.941596 -246.840978) (xy 368.949491 -246.889555)
			(xy 368.949986 -246.914162) (xy 369.278928 -246.914162) (xy 369.282888 -246.865108) (xy 369.294665 -246.817324)
			(xy 369.313956 -246.772048) (xy 369.340259 -246.730452) (xy 369.372894 -246.693615) (xy 369.411015 -246.66249)
			(xy 369.453636 -246.637883) (xy 369.499652 -246.620431) (xy 369.547871 -246.610587) (xy 369.597046 -246.608606)
			(xy 369.645901 -246.614538) (xy 369.693172 -246.62823) (xy 369.737634 -246.649328) (xy 369.778137 -246.677284)
			(xy 369.81363 -246.711376) (xy 369.843195 -246.75072) (xy 369.866066 -246.794297) (xy 369.88165 -246.840978)
			(xy 369.889545 -246.889555) (xy 369.89004 -246.914162) (xy 370.218982 -246.914162) (xy 370.222942 -246.865108)
			(xy 370.234719 -246.817324) (xy 370.25401 -246.772048) (xy 370.280313 -246.730452) (xy 370.312948 -246.693615)
			(xy 370.351069 -246.66249) (xy 370.39369 -246.637883) (xy 370.439706 -246.620431) (xy 370.487925 -246.610587)
			(xy 370.5371 -246.608606) (xy 370.585955 -246.614538) (xy 370.633226 -246.62823) (xy 370.677688 -246.649328)
			(xy 370.718191 -246.677284) (xy 370.753684 -246.711376) (xy 370.783249 -246.75072) (xy 370.80612 -246.794297)
			(xy 370.821704 -246.840978) (xy 370.829599 -246.889555) (xy 370.830094 -246.914162) (xy 371.159036 -246.914162)
			(xy 371.162996 -246.865108) (xy 371.174773 -246.817324) (xy 371.194064 -246.772048) (xy 371.220367 -246.730452)
			(xy 371.253002 -246.693615) (xy 371.291123 -246.66249) (xy 371.333744 -246.637883) (xy 371.37976 -246.620431)
			(xy 371.427979 -246.610587) (xy 371.477154 -246.608606) (xy 371.526009 -246.614538) (xy 371.57328 -246.62823)
			(xy 371.617742 -246.649328) (xy 371.658245 -246.677284) (xy 371.693738 -246.711376) (xy 371.723303 -246.75072)
			(xy 371.746174 -246.794297) (xy 371.761758 -246.840978) (xy 371.769653 -246.889555) (xy 371.770148 -246.914162)
			(xy 372.09909 -246.914162) (xy 372.10305 -246.865108) (xy 372.114827 -246.817324) (xy 372.134118 -246.772048)
			(xy 372.160421 -246.730452) (xy 372.193056 -246.693615) (xy 372.231177 -246.66249) (xy 372.273798 -246.637883)
			(xy 372.319814 -246.620431) (xy 372.368033 -246.610587) (xy 372.417208 -246.608606) (xy 372.466063 -246.614538)
			(xy 372.513334 -246.62823) (xy 372.557796 -246.649328) (xy 372.598299 -246.677284) (xy 372.633792 -246.711376)
			(xy 372.663357 -246.75072) (xy 372.686228 -246.794297) (xy 372.701812 -246.840978) (xy 372.709707 -246.889555)
			(xy 372.710202 -246.914162) (xy 373.03889 -246.914162) (xy 373.04285 -246.865108) (xy 373.054627 -246.817324)
			(xy 373.073918 -246.772048) (xy 373.100221 -246.730452) (xy 373.132856 -246.693615) (xy 373.170977 -246.66249)
			(xy 373.213598 -246.637883) (xy 373.259614 -246.620431) (xy 373.307833 -246.610587) (xy 373.357008 -246.608606)
			(xy 373.405863 -246.614538) (xy 373.453134 -246.62823) (xy 373.497596 -246.649328) (xy 373.538099 -246.677284)
			(xy 373.573592 -246.711376) (xy 373.603157 -246.75072) (xy 373.626028 -246.794297) (xy 373.641612 -246.840978)
			(xy 373.649507 -246.889555) (xy 373.650002 -246.914162) (xy 373.649507 -246.938769) (xy 373.641612 -246.987346)
			(xy 373.626028 -247.034027) (xy 373.603157 -247.077604) (xy 373.573592 -247.116948) (xy 373.538099 -247.15104)
			(xy 373.497596 -247.178996) (xy 373.453134 -247.200094) (xy 373.405863 -247.213786) (xy 373.357008 -247.219718)
			(xy 373.307833 -247.217737) (xy 373.259614 -247.207893) (xy 373.213598 -247.190441) (xy 373.170977 -247.165834)
			(xy 373.132856 -247.134709) (xy 373.100221 -247.097872) (xy 373.073918 -247.056276) (xy 373.054627 -247.011)
			(xy 373.04285 -246.963216) (xy 373.03889 -246.914162) (xy 372.710202 -246.914162) (xy 372.709707 -246.938769)
			(xy 372.701812 -246.987346) (xy 372.686228 -247.034027) (xy 372.663357 -247.077604) (xy 372.633792 -247.116948)
			(xy 372.598299 -247.15104) (xy 372.557796 -247.178996) (xy 372.513334 -247.200094) (xy 372.466063 -247.213786)
			(xy 372.417208 -247.219718) (xy 372.368033 -247.217737) (xy 372.319814 -247.207893) (xy 372.273798 -247.190441)
			(xy 372.231177 -247.165834) (xy 372.193056 -247.134709) (xy 372.160421 -247.097872) (xy 372.134118 -247.056276)
			(xy 372.114827 -247.011) (xy 372.10305 -246.963216) (xy 372.09909 -246.914162) (xy 371.770148 -246.914162)
			(xy 371.769653 -246.938769) (xy 371.761758 -246.987346) (xy 371.746174 -247.034027) (xy 371.723303 -247.077604)
			(xy 371.693738 -247.116948) (xy 371.658245 -247.15104) (xy 371.617742 -247.178996) (xy 371.57328 -247.200094)
			(xy 371.526009 -247.213786) (xy 371.477154 -247.219718) (xy 371.427979 -247.217737) (xy 371.37976 -247.207893)
			(xy 371.333744 -247.190441) (xy 371.291123 -247.165834) (xy 371.253002 -247.134709) (xy 371.220367 -247.097872)
			(xy 371.194064 -247.056276) (xy 371.174773 -247.011) (xy 371.162996 -246.963216) (xy 371.159036 -246.914162)
			(xy 370.830094 -246.914162) (xy 370.829599 -246.938769) (xy 370.821704 -246.987346) (xy 370.80612 -247.034027)
			(xy 370.783249 -247.077604) (xy 370.753684 -247.116948) (xy 370.718191 -247.15104) (xy 370.677688 -247.178996)
			(xy 370.633226 -247.200094) (xy 370.585955 -247.213786) (xy 370.5371 -247.219718) (xy 370.487925 -247.217737)
			(xy 370.439706 -247.207893) (xy 370.39369 -247.190441) (xy 370.351069 -247.165834) (xy 370.312948 -247.134709)
			(xy 370.280313 -247.097872) (xy 370.25401 -247.056276) (xy 370.234719 -247.011) (xy 370.222942 -246.963216)
			(xy 370.218982 -246.914162) (xy 369.89004 -246.914162) (xy 369.889545 -246.938769) (xy 369.88165 -246.987346)
			(xy 369.866066 -247.034027) (xy 369.843195 -247.077604) (xy 369.81363 -247.116948) (xy 369.778137 -247.15104)
			(xy 369.737634 -247.178996) (xy 369.693172 -247.200094) (xy 369.645901 -247.213786) (xy 369.597046 -247.219718)
			(xy 369.547871 -247.217737) (xy 369.499652 -247.207893) (xy 369.453636 -247.190441) (xy 369.411015 -247.165834)
			(xy 369.372894 -247.134709) (xy 369.340259 -247.097872) (xy 369.313956 -247.056276) (xy 369.294665 -247.011)
			(xy 369.282888 -246.963216) (xy 369.278928 -246.914162) (xy 368.949986 -246.914162) (xy 368.949491 -246.938769)
			(xy 368.941596 -246.987346) (xy 368.926012 -247.034027) (xy 368.903141 -247.077604) (xy 368.873576 -247.116948)
			(xy 368.838083 -247.15104) (xy 368.79758 -247.178996) (xy 368.753118 -247.200094) (xy 368.705847 -247.213786)
			(xy 368.656992 -247.219718) (xy 368.607817 -247.217737) (xy 368.559598 -247.207893) (xy 368.513582 -247.190441)
			(xy 368.470961 -247.165834) (xy 368.43284 -247.134709) (xy 368.400205 -247.097872) (xy 368.373902 -247.056276)
			(xy 368.354611 -247.011) (xy 368.342834 -246.963216) (xy 368.338874 -246.914162) (xy 368.010186 -246.914162)
			(xy 368.009691 -246.938769) (xy 368.001796 -246.987346) (xy 367.986212 -247.034027) (xy 367.963341 -247.077604)
			(xy 367.933776 -247.116948) (xy 367.898283 -247.15104) (xy 367.85778 -247.178996) (xy 367.813318 -247.200094)
			(xy 367.766047 -247.213786) (xy 367.717192 -247.219718) (xy 367.668017 -247.217737) (xy 367.619798 -247.207893)
			(xy 367.573782 -247.190441) (xy 367.531161 -247.165834) (xy 367.49304 -247.134709) (xy 367.460405 -247.097872)
			(xy 367.434102 -247.056276) (xy 367.414811 -247.011) (xy 367.403034 -246.963216) (xy 367.399074 -246.914162)
			(xy 367.070132 -246.914162) (xy 367.069637 -246.938769) (xy 367.061742 -246.987346) (xy 367.046158 -247.034027)
			(xy 367.023287 -247.077604) (xy 366.993722 -247.116948) (xy 366.958229 -247.15104) (xy 366.917726 -247.178996)
			(xy 366.873264 -247.200094) (xy 366.825993 -247.213786) (xy 366.777138 -247.219718) (xy 366.727963 -247.217737)
			(xy 366.679744 -247.207893) (xy 366.633728 -247.190441) (xy 366.591107 -247.165834) (xy 366.552986 -247.134709)
			(xy 366.520351 -247.097872) (xy 366.494048 -247.056276) (xy 366.474757 -247.011) (xy 366.46298 -246.963216)
			(xy 366.45902 -246.914162) (xy 366.130078 -246.914162) (xy 366.129583 -246.938769) (xy 366.121688 -246.987346)
			(xy 366.106104 -247.034027) (xy 366.083233 -247.077604) (xy 366.053668 -247.116948) (xy 366.018175 -247.15104)
			(xy 365.977672 -247.178996) (xy 365.93321 -247.200094) (xy 365.885939 -247.213786) (xy 365.837084 -247.219718)
			(xy 365.787909 -247.217737) (xy 365.73969 -247.207893) (xy 365.693674 -247.190441) (xy 365.651053 -247.165834)
			(xy 365.612932 -247.134709) (xy 365.580297 -247.097872) (xy 365.553994 -247.056276) (xy 365.534703 -247.011)
			(xy 365.522926 -246.963216) (xy 365.518966 -246.914162) (xy 365.190024 -246.914162) (xy 365.189529 -246.938769)
			(xy 365.181634 -246.987346) (xy 365.16605 -247.034027) (xy 365.143179 -247.077604) (xy 365.113614 -247.116948)
			(xy 365.078121 -247.15104) (xy 365.037618 -247.178996) (xy 364.993156 -247.200094) (xy 364.945885 -247.213786)
			(xy 364.89703 -247.219718) (xy 364.847855 -247.217737) (xy 364.799636 -247.207893) (xy 364.75362 -247.190441)
			(xy 364.710999 -247.165834) (xy 364.672878 -247.134709) (xy 364.640243 -247.097872) (xy 364.61394 -247.056276)
			(xy 364.594649 -247.011) (xy 364.582872 -246.963216) (xy 364.578912 -246.914162) (xy 364.250224 -246.914162)
			(xy 364.249729 -246.938769) (xy 364.241834 -246.987346) (xy 364.22625 -247.034027) (xy 364.203379 -247.077604)
			(xy 364.173814 -247.116948) (xy 364.138321 -247.15104) (xy 364.097818 -247.178996) (xy 364.053356 -247.200094)
			(xy 364.006085 -247.213786) (xy 363.95723 -247.219718) (xy 363.908055 -247.217737) (xy 363.859836 -247.207893)
			(xy 363.81382 -247.190441) (xy 363.771199 -247.165834) (xy 363.733078 -247.134709) (xy 363.700443 -247.097872)
			(xy 363.67414 -247.056276) (xy 363.654849 -247.011) (xy 363.643072 -246.963216) (xy 363.639112 -246.914162)
			(xy 363.320584 -246.914162) (xy 363.320072 -246.939608) (xy 363.311908 -246.989842) (xy 363.295792 -247.038116)
			(xy 363.272141 -247.083179) (xy 363.241568 -247.123865) (xy 363.204864 -247.15912) (xy 363.16298 -247.18803)
			(xy 363.117001 -247.209847) (xy 363.068117 -247.224007) (xy 363.017596 -247.230141) (xy 362.966744 -247.228092)
			(xy 362.91688 -247.217912) (xy 362.869294 -247.199865) (xy 362.82522 -247.174419) (xy 362.785798 -247.142232)
			(xy 362.75205 -247.104138) (xy 362.724849 -247.061124) (xy 362.704901 -247.014304) (xy 362.692722 -246.96489)
			(xy 362.688627 -246.914162) (xy 362.38053 -246.914162) (xy 362.380018 -246.939608) (xy 362.371854 -246.989842)
			(xy 362.355738 -247.038116) (xy 362.332087 -247.083179) (xy 362.301514 -247.123865) (xy 362.26481 -247.15912)
			(xy 362.222926 -247.18803) (xy 362.176947 -247.209847) (xy 362.128063 -247.224007) (xy 362.077542 -247.230141)
			(xy 362.02669 -247.228092) (xy 361.976826 -247.217912) (xy 361.92924 -247.199865) (xy 361.885166 -247.174419)
			(xy 361.845744 -247.142232) (xy 361.811996 -247.104138) (xy 361.784795 -247.061124) (xy 361.764847 -247.014304)
			(xy 361.752668 -246.96489) (xy 361.748573 -246.914162) (xy 361.430062 -246.914162) (xy 361.429567 -246.938769)
			(xy 361.421672 -246.987346) (xy 361.406088 -247.034027) (xy 361.383217 -247.077604) (xy 361.353652 -247.116948)
			(xy 361.318159 -247.15104) (xy 361.277656 -247.178996) (xy 361.233194 -247.200094) (xy 361.185923 -247.213786)
			(xy 361.137068 -247.219718) (xy 361.087893 -247.217737) (xy 361.039674 -247.207893) (xy 360.993658 -247.190441)
			(xy 360.951037 -247.165834) (xy 360.912916 -247.134709) (xy 360.880281 -247.097872) (xy 360.853978 -247.056276)
			(xy 360.834687 -247.011) (xy 360.82291 -246.963216) (xy 360.81895 -246.914162) (xy 359.2703 -246.914162)
			(xy 359.2703 -247.45696) (xy 359.396541 -247.45696) (xy 359.400571 -247.404462) (xy 359.412568 -247.353194)
			(xy 359.432251 -247.304359) (xy 359.459157 -247.2591) (xy 359.492657 -247.218479) (xy 359.531965 -247.183448)
			(xy 359.57616 -247.154828) (xy 359.624205 -247.133289) (xy 359.674976 -247.119337) (xy 359.727281 -247.113299)
			(xy 359.779895 -247.115316) (xy 359.831585 -247.12534) (xy 359.881138 -247.143138) (xy 359.927394 -247.168291)
			(xy 359.969268 -247.20021) (xy 360.00578 -247.238148) (xy 360.036072 -247.281214) (xy 360.059435 -247.328399)
			(xy 360.075321 -247.378598) (xy 360.083358 -247.430634) (xy 360.083862 -247.45696) (xy 360.083358 -247.483286)
			(xy 360.075321 -247.535322) (xy 360.059435 -247.585521) (xy 360.036072 -247.632706) (xy 360.00578 -247.675772)
			(xy 359.969268 -247.71371) (xy 359.955548 -247.724168) (xy 361.289104 -247.724168) (xy 361.293064 -247.675114)
			(xy 361.304841 -247.62733) (xy 361.324132 -247.582054) (xy 361.350435 -247.540458) (xy 361.38307 -247.503621)
			(xy 361.421191 -247.472496) (xy 361.463812 -247.447889) (xy 361.509828 -247.430437) (xy 361.558047 -247.420593)
			(xy 361.607222 -247.418612) (xy 361.656077 -247.424544) (xy 361.703348 -247.438236) (xy 361.74781 -247.459334)
			(xy 361.788313 -247.48729) (xy 361.823806 -247.521382) (xy 361.853371 -247.560726) (xy 361.876242 -247.604303)
			(xy 361.891826 -247.650984) (xy 361.899721 -247.699561) (xy 361.900216 -247.724168) (xy 362.228904 -247.724168)
			(xy 362.232864 -247.675114) (xy 362.244641 -247.62733) (xy 362.263932 -247.582054) (xy 362.290235 -247.540458)
			(xy 362.32287 -247.503621) (xy 362.360991 -247.472496) (xy 362.403612 -247.447889) (xy 362.449628 -247.430437)
			(xy 362.497847 -247.420593) (xy 362.547022 -247.418612) (xy 362.595877 -247.424544) (xy 362.643148 -247.438236)
			(xy 362.68761 -247.459334) (xy 362.728113 -247.48729) (xy 362.763606 -247.521382) (xy 362.793171 -247.560726)
			(xy 362.816042 -247.604303) (xy 362.831626 -247.650984) (xy 362.839521 -247.699561) (xy 362.840016 -247.724168)
			(xy 363.168958 -247.724168) (xy 363.172918 -247.675114) (xy 363.184695 -247.62733) (xy 363.203986 -247.582054)
			(xy 363.230289 -247.540458) (xy 363.262924 -247.503621) (xy 363.301045 -247.472496) (xy 363.343666 -247.447889)
			(xy 363.389682 -247.430437) (xy 363.437901 -247.420593) (xy 363.487076 -247.418612) (xy 363.535931 -247.424544)
			(xy 363.583202 -247.438236) (xy 363.627664 -247.459334) (xy 363.668167 -247.48729) (xy 363.70366 -247.521382)
			(xy 363.733225 -247.560726) (xy 363.756096 -247.604303) (xy 363.77168 -247.650984) (xy 363.779575 -247.699561)
			(xy 363.78007 -247.724168) (xy 364.098581 -247.724168) (xy 364.102676 -247.67344) (xy 364.114855 -247.624026)
			(xy 364.134803 -247.577206) (xy 364.162004 -247.534192) (xy 364.195752 -247.496098) (xy 364.235174 -247.463911)
			(xy 364.279248 -247.438465) (xy 364.326834 -247.420418) (xy 364.376698 -247.410238) (xy 364.42755 -247.408189)
			(xy 364.478071 -247.414323) (xy 364.526955 -247.428483) (xy 364.572934 -247.4503) (xy 364.614818 -247.47921)
			(xy 364.651522 -247.514465) (xy 364.682095 -247.555151) (xy 364.705746 -247.600214) (xy 364.721862 -247.648488)
			(xy 364.730026 -247.698722) (xy 364.730538 -247.724168) (xy 365.038635 -247.724168) (xy 365.04273 -247.67344)
			(xy 365.054909 -247.624026) (xy 365.074857 -247.577206) (xy 365.102058 -247.534192) (xy 365.135806 -247.496098)
			(xy 365.175228 -247.463911) (xy 365.219302 -247.438465) (xy 365.266888 -247.420418) (xy 365.316752 -247.410238)
			(xy 365.367604 -247.408189) (xy 365.418125 -247.414323) (xy 365.467009 -247.428483) (xy 365.512988 -247.4503)
			(xy 365.554872 -247.47921) (xy 365.591576 -247.514465) (xy 365.622149 -247.555151) (xy 365.6458 -247.600214)
			(xy 365.661916 -247.648488) (xy 365.67008 -247.698722) (xy 365.670592 -247.724168) (xy 365.98912 -247.724168)
			(xy 365.99308 -247.675114) (xy 366.004857 -247.62733) (xy 366.024148 -247.582054) (xy 366.050451 -247.540458)
			(xy 366.083086 -247.503621) (xy 366.121207 -247.472496) (xy 366.163828 -247.447889) (xy 366.209844 -247.430437)
			(xy 366.258063 -247.420593) (xy 366.307238 -247.418612) (xy 366.356093 -247.424544) (xy 366.403364 -247.438236)
			(xy 366.447826 -247.459334) (xy 366.488329 -247.48729) (xy 366.523822 -247.521382) (xy 366.553387 -247.560726)
			(xy 366.576258 -247.604303) (xy 366.591842 -247.650984) (xy 366.599737 -247.699561) (xy 366.600232 -247.724168)
			(xy 366.918489 -247.724168) (xy 366.922584 -247.67344) (xy 366.934763 -247.624026) (xy 366.954711 -247.577206)
			(xy 366.981912 -247.534192) (xy 367.01566 -247.496098) (xy 367.055082 -247.463911) (xy 367.099156 -247.438465)
			(xy 367.146742 -247.420418) (xy 367.196606 -247.410238) (xy 367.247458 -247.408189) (xy 367.297979 -247.414323)
			(xy 367.346863 -247.428483) (xy 367.392842 -247.4503) (xy 367.434726 -247.47921) (xy 367.47143 -247.514465)
			(xy 367.502003 -247.555151) (xy 367.525654 -247.600214) (xy 367.54177 -247.648488) (xy 367.549934 -247.698722)
			(xy 367.550446 -247.724168) (xy 367.858543 -247.724168) (xy 367.862638 -247.67344) (xy 367.874817 -247.624026)
			(xy 367.894765 -247.577206) (xy 367.921966 -247.534192) (xy 367.955714 -247.496098) (xy 367.995136 -247.463911)
			(xy 368.03921 -247.438465) (xy 368.086796 -247.420418) (xy 368.13666 -247.410238) (xy 368.187512 -247.408189)
			(xy 368.238033 -247.414323) (xy 368.286917 -247.428483) (xy 368.332896 -247.4503) (xy 368.37478 -247.47921)
			(xy 368.411484 -247.514465) (xy 368.442057 -247.555151) (xy 368.465708 -247.600214) (xy 368.481824 -247.648488)
			(xy 368.489988 -247.698722) (xy 368.4905 -247.724168) (xy 368.809028 -247.724168) (xy 368.812988 -247.675114)
			(xy 368.824765 -247.62733) (xy 368.844056 -247.582054) (xy 368.870359 -247.540458) (xy 368.902994 -247.503621)
			(xy 368.941115 -247.472496) (xy 368.983736 -247.447889) (xy 369.029752 -247.430437) (xy 369.077971 -247.420593)
			(xy 369.127146 -247.418612) (xy 369.176001 -247.424544) (xy 369.223272 -247.438236) (xy 369.267734 -247.459334)
			(xy 369.308237 -247.48729) (xy 369.34373 -247.521382) (xy 369.373295 -247.560726) (xy 369.396166 -247.604303)
			(xy 369.41175 -247.650984) (xy 369.419645 -247.699561) (xy 369.42014 -247.724168) (xy 369.738651 -247.724168)
			(xy 369.742746 -247.67344) (xy 369.754925 -247.624026) (xy 369.774873 -247.577206) (xy 369.802074 -247.534192)
			(xy 369.835822 -247.496098) (xy 369.875244 -247.463911) (xy 369.919318 -247.438465) (xy 369.966904 -247.420418)
			(xy 370.016768 -247.410238) (xy 370.06762 -247.408189) (xy 370.118141 -247.414323) (xy 370.167025 -247.428483)
			(xy 370.213004 -247.4503) (xy 370.254888 -247.47921) (xy 370.291592 -247.514465) (xy 370.322165 -247.555151)
			(xy 370.345816 -247.600214) (xy 370.361932 -247.648488) (xy 370.370096 -247.698722) (xy 370.370608 -247.724168)
			(xy 370.678451 -247.724168) (xy 370.682546 -247.67344) (xy 370.694725 -247.624026) (xy 370.714673 -247.577206)
			(xy 370.741874 -247.534192) (xy 370.775622 -247.496098) (xy 370.815044 -247.463911) (xy 370.859118 -247.438465)
			(xy 370.906704 -247.420418) (xy 370.956568 -247.410238) (xy 371.00742 -247.408189) (xy 371.057941 -247.414323)
			(xy 371.106825 -247.428483) (xy 371.152804 -247.4503) (xy 371.194688 -247.47921) (xy 371.231392 -247.514465)
			(xy 371.261965 -247.555151) (xy 371.285616 -247.600214) (xy 371.301732 -247.648488) (xy 371.309896 -247.698722)
			(xy 371.310408 -247.724168) (xy 371.628936 -247.724168) (xy 371.632896 -247.675114) (xy 371.644673 -247.62733)
			(xy 371.663964 -247.582054) (xy 371.690267 -247.540458) (xy 371.722902 -247.503621) (xy 371.761023 -247.472496)
			(xy 371.803644 -247.447889) (xy 371.84966 -247.430437) (xy 371.897879 -247.420593) (xy 371.947054 -247.418612)
			(xy 371.995909 -247.424544) (xy 372.04318 -247.438236) (xy 372.087642 -247.459334) (xy 372.128145 -247.48729)
			(xy 372.163638 -247.521382) (xy 372.193203 -247.560726) (xy 372.216074 -247.604303) (xy 372.231658 -247.650984)
			(xy 372.239553 -247.699561) (xy 372.240048 -247.724168) (xy 372.558559 -247.724168) (xy 372.562654 -247.67344)
			(xy 372.574833 -247.624026) (xy 372.594781 -247.577206) (xy 372.621982 -247.534192) (xy 372.65573 -247.496098)
			(xy 372.695152 -247.463911) (xy 372.739226 -247.438465) (xy 372.786812 -247.420418) (xy 372.836676 -247.410238)
			(xy 372.887528 -247.408189) (xy 372.938049 -247.414323) (xy 372.986933 -247.428483) (xy 373.032912 -247.4503)
			(xy 373.074796 -247.47921) (xy 373.1115 -247.514465) (xy 373.142073 -247.555151) (xy 373.165724 -247.600214)
			(xy 373.18184 -247.648488) (xy 373.190004 -247.698722) (xy 373.190516 -247.724168) (xy 373.498613 -247.724168)
			(xy 373.502708 -247.67344) (xy 373.514887 -247.624026) (xy 373.534835 -247.577206) (xy 373.562036 -247.534192)
			(xy 373.595784 -247.496098) (xy 373.635206 -247.463911) (xy 373.67928 -247.438465) (xy 373.726866 -247.420418)
			(xy 373.77673 -247.410238) (xy 373.827582 -247.408189) (xy 373.878103 -247.414323) (xy 373.926987 -247.428483)
			(xy 373.972966 -247.4503) (xy 374.01485 -247.47921) (xy 374.051554 -247.514465) (xy 374.082127 -247.555151)
			(xy 374.105778 -247.600214) (xy 374.121894 -247.648488) (xy 374.130058 -247.698722) (xy 374.13057 -247.724168)
			(xy 374.130058 -247.749614) (xy 374.121894 -247.799848) (xy 374.105778 -247.848122) (xy 374.082127 -247.893185)
			(xy 374.051554 -247.933871) (xy 374.01485 -247.969126) (xy 373.972966 -247.998036) (xy 373.926987 -248.019853)
			(xy 373.878103 -248.034013) (xy 373.827582 -248.040147) (xy 373.77673 -248.038098) (xy 373.726866 -248.027918)
			(xy 373.67928 -248.009871) (xy 373.635206 -247.984425) (xy 373.595784 -247.952238) (xy 373.562036 -247.914144)
			(xy 373.534835 -247.87113) (xy 373.514887 -247.82431) (xy 373.502708 -247.774896) (xy 373.498613 -247.724168)
			(xy 373.190516 -247.724168) (xy 373.190004 -247.749614) (xy 373.18184 -247.799848) (xy 373.165724 -247.848122)
			(xy 373.142073 -247.893185) (xy 373.1115 -247.933871) (xy 373.074796 -247.969126) (xy 373.032912 -247.998036)
			(xy 372.986933 -248.019853) (xy 372.938049 -248.034013) (xy 372.887528 -248.040147) (xy 372.836676 -248.038098)
			(xy 372.786812 -248.027918) (xy 372.739226 -248.009871) (xy 372.695152 -247.984425) (xy 372.65573 -247.952238)
			(xy 372.621982 -247.914144) (xy 372.594781 -247.87113) (xy 372.574833 -247.82431) (xy 372.562654 -247.774896)
			(xy 372.558559 -247.724168) (xy 372.240048 -247.724168) (xy 372.239553 -247.748775) (xy 372.231658 -247.797352)
			(xy 372.216074 -247.844033) (xy 372.193203 -247.88761) (xy 372.163638 -247.926954) (xy 372.128145 -247.961046)
			(xy 372.087642 -247.989002) (xy 372.04318 -248.0101) (xy 371.995909 -248.023792) (xy 371.947054 -248.029724)
			(xy 371.897879 -248.027743) (xy 371.84966 -248.017899) (xy 371.803644 -248.000447) (xy 371.761023 -247.97584)
			(xy 371.722902 -247.944715) (xy 371.690267 -247.907878) (xy 371.663964 -247.866282) (xy 371.644673 -247.821006)
			(xy 371.632896 -247.773222) (xy 371.628936 -247.724168) (xy 371.310408 -247.724168) (xy 371.309896 -247.749614)
			(xy 371.301732 -247.799848) (xy 371.285616 -247.848122) (xy 371.261965 -247.893185) (xy 371.231392 -247.933871)
			(xy 371.194688 -247.969126) (xy 371.152804 -247.998036) (xy 371.106825 -248.019853) (xy 371.057941 -248.034013)
			(xy 371.00742 -248.040147) (xy 370.956568 -248.038098) (xy 370.906704 -248.027918) (xy 370.859118 -248.009871)
			(xy 370.815044 -247.984425) (xy 370.775622 -247.952238) (xy 370.741874 -247.914144) (xy 370.714673 -247.87113)
			(xy 370.694725 -247.82431) (xy 370.682546 -247.774896) (xy 370.678451 -247.724168) (xy 370.370608 -247.724168)
			(xy 370.370096 -247.749614) (xy 370.361932 -247.799848) (xy 370.345816 -247.848122) (xy 370.322165 -247.893185)
			(xy 370.291592 -247.933871) (xy 370.254888 -247.969126) (xy 370.213004 -247.998036) (xy 370.167025 -248.019853)
			(xy 370.118141 -248.034013) (xy 370.06762 -248.040147) (xy 370.016768 -248.038098) (xy 369.966904 -248.027918)
			(xy 369.919318 -248.009871) (xy 369.875244 -247.984425) (xy 369.835822 -247.952238) (xy 369.802074 -247.914144)
			(xy 369.774873 -247.87113) (xy 369.754925 -247.82431) (xy 369.742746 -247.774896) (xy 369.738651 -247.724168)
			(xy 369.42014 -247.724168) (xy 369.419645 -247.748775) (xy 369.41175 -247.797352) (xy 369.396166 -247.844033)
			(xy 369.373295 -247.88761) (xy 369.34373 -247.926954) (xy 369.308237 -247.961046) (xy 369.267734 -247.989002)
			(xy 369.223272 -248.0101) (xy 369.176001 -248.023792) (xy 369.127146 -248.029724) (xy 369.077971 -248.027743)
			(xy 369.029752 -248.017899) (xy 368.983736 -248.000447) (xy 368.941115 -247.97584) (xy 368.902994 -247.944715)
			(xy 368.870359 -247.907878) (xy 368.844056 -247.866282) (xy 368.824765 -247.821006) (xy 368.812988 -247.773222)
			(xy 368.809028 -247.724168) (xy 368.4905 -247.724168) (xy 368.489988 -247.749614) (xy 368.481824 -247.799848)
			(xy 368.465708 -247.848122) (xy 368.442057 -247.893185) (xy 368.411484 -247.933871) (xy 368.37478 -247.969126)
			(xy 368.332896 -247.998036) (xy 368.286917 -248.019853) (xy 368.238033 -248.034013) (xy 368.187512 -248.040147)
			(xy 368.13666 -248.038098) (xy 368.086796 -248.027918) (xy 368.03921 -248.009871) (xy 367.995136 -247.984425)
			(xy 367.955714 -247.952238) (xy 367.921966 -247.914144) (xy 367.894765 -247.87113) (xy 367.874817 -247.82431)
			(xy 367.862638 -247.774896) (xy 367.858543 -247.724168) (xy 367.550446 -247.724168) (xy 367.549934 -247.749614)
			(xy 367.54177 -247.799848) (xy 367.525654 -247.848122) (xy 367.502003 -247.893185) (xy 367.47143 -247.933871)
			(xy 367.434726 -247.969126) (xy 367.392842 -247.998036) (xy 367.346863 -248.019853) (xy 367.297979 -248.034013)
			(xy 367.247458 -248.040147) (xy 367.196606 -248.038098) (xy 367.146742 -248.027918) (xy 367.099156 -248.009871)
			(xy 367.055082 -247.984425) (xy 367.01566 -247.952238) (xy 366.981912 -247.914144) (xy 366.954711 -247.87113)
			(xy 366.934763 -247.82431) (xy 366.922584 -247.774896) (xy 366.918489 -247.724168) (xy 366.600232 -247.724168)
			(xy 366.599737 -247.748775) (xy 366.591842 -247.797352) (xy 366.576258 -247.844033) (xy 366.553387 -247.88761)
			(xy 366.523822 -247.926954) (xy 366.488329 -247.961046) (xy 366.447826 -247.989002) (xy 366.403364 -248.0101)
			(xy 366.356093 -248.023792) (xy 366.307238 -248.029724) (xy 366.258063 -248.027743) (xy 366.209844 -248.017899)
			(xy 366.163828 -248.000447) (xy 366.121207 -247.97584) (xy 366.083086 -247.944715) (xy 366.050451 -247.907878)
			(xy 366.024148 -247.866282) (xy 366.004857 -247.821006) (xy 365.99308 -247.773222) (xy 365.98912 -247.724168)
			(xy 365.670592 -247.724168) (xy 365.67008 -247.749614) (xy 365.661916 -247.799848) (xy 365.6458 -247.848122)
			(xy 365.622149 -247.893185) (xy 365.591576 -247.933871) (xy 365.554872 -247.969126) (xy 365.512988 -247.998036)
			(xy 365.467009 -248.019853) (xy 365.418125 -248.034013) (xy 365.367604 -248.040147) (xy 365.316752 -248.038098)
			(xy 365.266888 -248.027918) (xy 365.219302 -248.009871) (xy 365.175228 -247.984425) (xy 365.135806 -247.952238)
			(xy 365.102058 -247.914144) (xy 365.074857 -247.87113) (xy 365.054909 -247.82431) (xy 365.04273 -247.774896)
			(xy 365.038635 -247.724168) (xy 364.730538 -247.724168) (xy 364.730026 -247.749614) (xy 364.721862 -247.799848)
			(xy 364.705746 -247.848122) (xy 364.682095 -247.893185) (xy 364.651522 -247.933871) (xy 364.614818 -247.969126)
			(xy 364.572934 -247.998036) (xy 364.526955 -248.019853) (xy 364.478071 -248.034013) (xy 364.42755 -248.040147)
			(xy 364.376698 -248.038098) (xy 364.326834 -248.027918) (xy 364.279248 -248.009871) (xy 364.235174 -247.984425)
			(xy 364.195752 -247.952238) (xy 364.162004 -247.914144) (xy 364.134803 -247.87113) (xy 364.114855 -247.82431)
			(xy 364.102676 -247.774896) (xy 364.098581 -247.724168) (xy 363.78007 -247.724168) (xy 363.779575 -247.748775)
			(xy 363.77168 -247.797352) (xy 363.756096 -247.844033) (xy 363.733225 -247.88761) (xy 363.70366 -247.926954)
			(xy 363.668167 -247.961046) (xy 363.627664 -247.989002) (xy 363.583202 -248.0101) (xy 363.535931 -248.023792)
			(xy 363.487076 -248.029724) (xy 363.437901 -248.027743) (xy 363.389682 -248.017899) (xy 363.343666 -248.000447)
			(xy 363.301045 -247.97584) (xy 363.262924 -247.944715) (xy 363.230289 -247.907878) (xy 363.203986 -247.866282)
			(xy 363.184695 -247.821006) (xy 363.172918 -247.773222) (xy 363.168958 -247.724168) (xy 362.840016 -247.724168)
			(xy 362.839521 -247.748775) (xy 362.831626 -247.797352) (xy 362.816042 -247.844033) (xy 362.793171 -247.88761)
			(xy 362.763606 -247.926954) (xy 362.728113 -247.961046) (xy 362.68761 -247.989002) (xy 362.643148 -248.0101)
			(xy 362.595877 -248.023792) (xy 362.547022 -248.029724) (xy 362.497847 -248.027743) (xy 362.449628 -248.017899)
			(xy 362.403612 -248.000447) (xy 362.360991 -247.97584) (xy 362.32287 -247.944715) (xy 362.290235 -247.907878)
			(xy 362.263932 -247.866282) (xy 362.244641 -247.821006) (xy 362.232864 -247.773222) (xy 362.228904 -247.724168)
			(xy 361.900216 -247.724168) (xy 361.899721 -247.748775) (xy 361.891826 -247.797352) (xy 361.876242 -247.844033)
			(xy 361.853371 -247.88761) (xy 361.823806 -247.926954) (xy 361.788313 -247.961046) (xy 361.74781 -247.989002)
			(xy 361.703348 -248.0101) (xy 361.656077 -248.023792) (xy 361.607222 -248.029724) (xy 361.558047 -248.027743)
			(xy 361.509828 -248.017899) (xy 361.463812 -248.000447) (xy 361.421191 -247.97584) (xy 361.38307 -247.944715)
			(xy 361.350435 -247.907878) (xy 361.324132 -247.866282) (xy 361.304841 -247.821006) (xy 361.293064 -247.773222)
			(xy 361.289104 -247.724168) (xy 359.955548 -247.724168) (xy 359.927394 -247.745629) (xy 359.881138 -247.770782)
			(xy 359.831585 -247.78858) (xy 359.779895 -247.798604) (xy 359.727281 -247.800621) (xy 359.674976 -247.794583)
			(xy 359.624205 -247.780631) (xy 359.57616 -247.759092) (xy 359.531965 -247.730472) (xy 359.492657 -247.695441)
			(xy 359.459157 -247.65482) (xy 359.432251 -247.609561) (xy 359.412568 -247.560726) (xy 359.400571 -247.509458)
			(xy 359.396541 -247.45696) (xy 359.2703 -247.45696) (xy 359.2703 -248.365518) (xy 359.269873 -248.375587)
			(xy 359.262154 -248.394186) (xy 359.255314 -248.401586) (xy 359.122726 -248.534174) (xy 360.81895 -248.534174)
			(xy 360.82291 -248.48512) (xy 360.834687 -248.437336) (xy 360.853978 -248.39206) (xy 360.880281 -248.350464)
			(xy 360.912916 -248.313627) (xy 360.951037 -248.282502) (xy 360.993658 -248.257895) (xy 361.039674 -248.240443)
			(xy 361.087893 -248.230599) (xy 361.137068 -248.228618) (xy 361.185923 -248.23455) (xy 361.233194 -248.248242)
			(xy 361.277656 -248.26934) (xy 361.318159 -248.297296) (xy 361.353652 -248.331388) (xy 361.383217 -248.370732)
			(xy 361.406088 -248.414309) (xy 361.421672 -248.46099) (xy 361.429567 -248.509567) (xy 361.430062 -248.534174)
			(xy 361.748573 -248.534174) (xy 361.752668 -248.483446) (xy 361.764847 -248.434032) (xy 361.784795 -248.387212)
			(xy 361.811996 -248.344198) (xy 361.845744 -248.306104) (xy 361.885166 -248.273917) (xy 361.92924 -248.248471)
			(xy 361.976826 -248.230424) (xy 362.02669 -248.220244) (xy 362.077542 -248.218195) (xy 362.128063 -248.224329)
			(xy 362.176947 -248.238489) (xy 362.222926 -248.260306) (xy 362.26481 -248.289216) (xy 362.301514 -248.324471)
			(xy 362.332087 -248.365157) (xy 362.355738 -248.41022) (xy 362.371854 -248.458494) (xy 362.380018 -248.508728)
			(xy 362.38053 -248.534174) (xy 362.688627 -248.534174) (xy 362.692722 -248.483446) (xy 362.704901 -248.434032)
			(xy 362.724849 -248.387212) (xy 362.75205 -248.344198) (xy 362.785798 -248.306104) (xy 362.82522 -248.273917)
			(xy 362.869294 -248.248471) (xy 362.91688 -248.230424) (xy 362.966744 -248.220244) (xy 363.017596 -248.218195)
			(xy 363.068117 -248.224329) (xy 363.117001 -248.238489) (xy 363.16298 -248.260306) (xy 363.204864 -248.289216)
			(xy 363.241568 -248.324471) (xy 363.272141 -248.365157) (xy 363.295792 -248.41022) (xy 363.311908 -248.458494)
			(xy 363.320072 -248.508728) (xy 363.320584 -248.534174) (xy 363.639112 -248.534174) (xy 363.643072 -248.48512)
			(xy 363.654849 -248.437336) (xy 363.67414 -248.39206) (xy 363.700443 -248.350464) (xy 363.733078 -248.313627)
			(xy 363.771199 -248.282502) (xy 363.81382 -248.257895) (xy 363.859836 -248.240443) (xy 363.908055 -248.230599)
			(xy 363.95723 -248.228618) (xy 364.006085 -248.23455) (xy 364.053356 -248.248242) (xy 364.097818 -248.26934)
			(xy 364.138321 -248.297296) (xy 364.173814 -248.331388) (xy 364.203379 -248.370732) (xy 364.22625 -248.414309)
			(xy 364.241834 -248.46099) (xy 364.249729 -248.509567) (xy 364.250224 -248.534174) (xy 366.45902 -248.534174)
			(xy 366.46298 -248.48512) (xy 366.474757 -248.437336) (xy 366.494048 -248.39206) (xy 366.520351 -248.350464)
			(xy 366.552986 -248.313627) (xy 366.591107 -248.282502) (xy 366.633728 -248.257895) (xy 366.679744 -248.240443)
			(xy 366.727963 -248.230599) (xy 366.777138 -248.228618) (xy 366.825993 -248.23455) (xy 366.873264 -248.248242)
			(xy 366.917726 -248.26934) (xy 366.958229 -248.297296) (xy 366.993722 -248.331388) (xy 367.023287 -248.370732)
			(xy 367.046158 -248.414309) (xy 367.061742 -248.46099) (xy 367.069637 -248.509567) (xy 367.070132 -248.534174)
			(xy 369.278928 -248.534174) (xy 369.282888 -248.48512) (xy 369.294665 -248.437336) (xy 369.313956 -248.39206)
			(xy 369.340259 -248.350464) (xy 369.372894 -248.313627) (xy 369.411015 -248.282502) (xy 369.453636 -248.257895)
			(xy 369.499652 -248.240443) (xy 369.547871 -248.230599) (xy 369.597046 -248.228618) (xy 369.645901 -248.23455)
			(xy 369.693172 -248.248242) (xy 369.737634 -248.26934) (xy 369.778137 -248.297296) (xy 369.81363 -248.331388)
			(xy 369.843195 -248.370732) (xy 369.866066 -248.414309) (xy 369.88165 -248.46099) (xy 369.889545 -248.509567)
			(xy 369.89004 -248.534174) (xy 372.09909 -248.534174) (xy 372.10305 -248.48512) (xy 372.114827 -248.437336)
			(xy 372.134118 -248.39206) (xy 372.160421 -248.350464) (xy 372.193056 -248.313627) (xy 372.231177 -248.282502)
			(xy 372.273798 -248.257895) (xy 372.319814 -248.240443) (xy 372.368033 -248.230599) (xy 372.417208 -248.228618)
			(xy 372.466063 -248.23455) (xy 372.513334 -248.248242) (xy 372.557796 -248.26934) (xy 372.598299 -248.297296)
			(xy 372.633792 -248.331388) (xy 372.663357 -248.370732) (xy 372.686228 -248.414309) (xy 372.701812 -248.46099)
			(xy 372.709707 -248.509567) (xy 372.710202 -248.534174) (xy 372.709707 -248.558781) (xy 372.701812 -248.607358)
			(xy 372.686228 -248.654039) (xy 372.663357 -248.697616) (xy 372.633792 -248.73696) (xy 372.598299 -248.771052)
			(xy 372.557796 -248.799008) (xy 372.513334 -248.820106) (xy 372.466063 -248.833798) (xy 372.417208 -248.83973)
			(xy 372.368033 -248.837749) (xy 372.319814 -248.827905) (xy 372.273798 -248.810453) (xy 372.231177 -248.785846)
			(xy 372.193056 -248.754721) (xy 372.160421 -248.717884) (xy 372.134118 -248.676288) (xy 372.114827 -248.631012)
			(xy 372.10305 -248.583228) (xy 372.09909 -248.534174) (xy 369.89004 -248.534174) (xy 369.889545 -248.558781)
			(xy 369.88165 -248.607358) (xy 369.866066 -248.654039) (xy 369.843195 -248.697616) (xy 369.81363 -248.73696)
			(xy 369.778137 -248.771052) (xy 369.737634 -248.799008) (xy 369.693172 -248.820106) (xy 369.645901 -248.833798)
			(xy 369.597046 -248.83973) (xy 369.547871 -248.837749) (xy 369.499652 -248.827905) (xy 369.453636 -248.810453)
			(xy 369.411015 -248.785846) (xy 369.372894 -248.754721) (xy 369.340259 -248.717884) (xy 369.313956 -248.676288)
			(xy 369.294665 -248.631012) (xy 369.282888 -248.583228) (xy 369.278928 -248.534174) (xy 367.070132 -248.534174)
			(xy 367.069637 -248.558781) (xy 367.061742 -248.607358) (xy 367.046158 -248.654039) (xy 367.023287 -248.697616)
			(xy 366.993722 -248.73696) (xy 366.958229 -248.771052) (xy 366.917726 -248.799008) (xy 366.873264 -248.820106)
			(xy 366.825993 -248.833798) (xy 366.777138 -248.83973) (xy 366.727963 -248.837749) (xy 366.679744 -248.827905)
			(xy 366.633728 -248.810453) (xy 366.591107 -248.785846) (xy 366.552986 -248.754721) (xy 366.520351 -248.717884)
			(xy 366.494048 -248.676288) (xy 366.474757 -248.631012) (xy 366.46298 -248.583228) (xy 366.45902 -248.534174)
			(xy 364.250224 -248.534174) (xy 364.249729 -248.558781) (xy 364.241834 -248.607358) (xy 364.22625 -248.654039)
			(xy 364.203379 -248.697616) (xy 364.173814 -248.73696) (xy 364.138321 -248.771052) (xy 364.097818 -248.799008)
			(xy 364.053356 -248.820106) (xy 364.006085 -248.833798) (xy 363.95723 -248.83973) (xy 363.908055 -248.837749)
			(xy 363.859836 -248.827905) (xy 363.81382 -248.810453) (xy 363.771199 -248.785846) (xy 363.733078 -248.754721)
			(xy 363.700443 -248.717884) (xy 363.67414 -248.676288) (xy 363.654849 -248.631012) (xy 363.643072 -248.583228)
			(xy 363.639112 -248.534174) (xy 363.320584 -248.534174) (xy 363.320072 -248.55962) (xy 363.311908 -248.609854)
			(xy 363.295792 -248.658128) (xy 363.272141 -248.703191) (xy 363.241568 -248.743877) (xy 363.204864 -248.779132)
			(xy 363.16298 -248.808042) (xy 363.117001 -248.829859) (xy 363.068117 -248.844019) (xy 363.017596 -248.850153)
			(xy 362.966744 -248.848104) (xy 362.91688 -248.837924) (xy 362.869294 -248.819877) (xy 362.82522 -248.794431)
			(xy 362.785798 -248.762244) (xy 362.75205 -248.72415) (xy 362.724849 -248.681136) (xy 362.704901 -248.634316)
			(xy 362.692722 -248.584902) (xy 362.688627 -248.534174) (xy 362.38053 -248.534174) (xy 362.380018 -248.55962)
			(xy 362.371854 -248.609854) (xy 362.355738 -248.658128) (xy 362.332087 -248.703191) (xy 362.301514 -248.743877)
			(xy 362.26481 -248.779132) (xy 362.222926 -248.808042) (xy 362.176947 -248.829859) (xy 362.128063 -248.844019)
			(xy 362.077542 -248.850153) (xy 362.02669 -248.848104) (xy 361.976826 -248.837924) (xy 361.92924 -248.819877)
			(xy 361.885166 -248.794431) (xy 361.845744 -248.762244) (xy 361.811996 -248.72415) (xy 361.784795 -248.681136)
			(xy 361.764847 -248.634316) (xy 361.752668 -248.584902) (xy 361.748573 -248.534174) (xy 361.430062 -248.534174)
			(xy 361.429567 -248.558781) (xy 361.421672 -248.607358) (xy 361.406088 -248.654039) (xy 361.383217 -248.697616)
			(xy 361.353652 -248.73696) (xy 361.318159 -248.771052) (xy 361.277656 -248.799008) (xy 361.233194 -248.820106)
			(xy 361.185923 -248.833798) (xy 361.137068 -248.83973) (xy 361.087893 -248.837749) (xy 361.039674 -248.827905)
			(xy 360.993658 -248.810453) (xy 360.951037 -248.785846) (xy 360.912916 -248.754721) (xy 360.880281 -248.717884)
			(xy 360.853978 -248.676288) (xy 360.834687 -248.631012) (xy 360.82291 -248.583228) (xy 360.81895 -248.534174)
			(xy 359.122726 -248.534174) (xy 358.673146 -248.983754) (xy 358.665747 -248.990597) (xy 358.647148 -248.998319)
			(xy 358.637078 -248.99874) (xy 358.008428 -248.99874) (xy 357.99701 -248.999199) (xy 357.976385 -249.008985)
			(xy 357.968804 -249.017536) (xy 357.944532 -249.046825) (xy 357.8911 -249.100973) (xy 357.83258 -249.149578)
			(xy 357.769546 -249.192167) (xy 357.702614 -249.228321) (xy 357.632439 -249.257689) (xy 357.559706 -249.279982)
			(xy 357.485128 -249.294983) (xy 357.409432 -249.302545) (xy 357.371396 -249.303032) (xy 357.236522 -249.303032)
			(xy 357.207058 -249.331734) (xy 357.20655 -249.352308) (xy 357.206104 -249.36196) (xy 359.396541 -249.36196)
			(xy 359.400571 -249.309462) (xy 359.412568 -249.258194) (xy 359.432251 -249.209359) (xy 359.459157 -249.1641)
			(xy 359.492657 -249.123479) (xy 359.531965 -249.088448) (xy 359.57616 -249.059828) (xy 359.624205 -249.038289)
			(xy 359.674976 -249.024337) (xy 359.727281 -249.018299) (xy 359.779895 -249.020316) (xy 359.831585 -249.03034)
			(xy 359.881138 -249.048138) (xy 359.927394 -249.073291) (xy 359.969268 -249.10521) (xy 360.00578 -249.143148)
			(xy 360.036072 -249.186214) (xy 360.059435 -249.233399) (xy 360.075321 -249.283598) (xy 360.083358 -249.335634)
			(xy 360.083522 -249.34418) (xy 361.289104 -249.34418) (xy 361.293064 -249.295126) (xy 361.304841 -249.247342)
			(xy 361.324132 -249.202066) (xy 361.350435 -249.16047) (xy 361.38307 -249.123633) (xy 361.421191 -249.092508)
			(xy 361.463812 -249.067901) (xy 361.509828 -249.050449) (xy 361.558047 -249.040605) (xy 361.607222 -249.038624)
			(xy 361.656077 -249.044556) (xy 361.703348 -249.058248) (xy 361.74781 -249.079346) (xy 361.788313 -249.107302)
			(xy 361.823806 -249.141394) (xy 361.853371 -249.180738) (xy 361.876242 -249.224315) (xy 361.891826 -249.270996)
			(xy 361.899721 -249.319573) (xy 361.900216 -249.34418) (xy 363.168958 -249.34418) (xy 363.172918 -249.295126)
			(xy 363.184695 -249.247342) (xy 363.203986 -249.202066) (xy 363.230289 -249.16047) (xy 363.262924 -249.123633)
			(xy 363.301045 -249.092508) (xy 363.343666 -249.067901) (xy 363.389682 -249.050449) (xy 363.437901 -249.040605)
			(xy 363.487076 -249.038624) (xy 363.535931 -249.044556) (xy 363.583202 -249.058248) (xy 363.627664 -249.079346)
			(xy 363.668167 -249.107302) (xy 363.70366 -249.141394) (xy 363.733225 -249.180738) (xy 363.756096 -249.224315)
			(xy 363.77168 -249.270996) (xy 363.779575 -249.319573) (xy 363.78007 -249.34418) (xy 365.049066 -249.34418)
			(xy 365.053026 -249.295126) (xy 365.064803 -249.247342) (xy 365.084094 -249.202066) (xy 365.110397 -249.16047)
			(xy 365.143032 -249.123633) (xy 365.181153 -249.092508) (xy 365.223774 -249.067901) (xy 365.26979 -249.050449)
			(xy 365.318009 -249.040605) (xy 365.367184 -249.038624) (xy 365.416039 -249.044556) (xy 365.46331 -249.058248)
			(xy 365.507772 -249.079346) (xy 365.548275 -249.107302) (xy 365.583768 -249.141394) (xy 365.613333 -249.180738)
			(xy 365.636204 -249.224315) (xy 365.651788 -249.270996) (xy 365.659683 -249.319573) (xy 365.660178 -249.34418)
			(xy 366.92892 -249.34418) (xy 366.93288 -249.295126) (xy 366.944657 -249.247342) (xy 366.963948 -249.202066)
			(xy 366.990251 -249.16047) (xy 367.022886 -249.123633) (xy 367.061007 -249.092508) (xy 367.103628 -249.067901)
			(xy 367.149644 -249.050449) (xy 367.197863 -249.040605) (xy 367.247038 -249.038624) (xy 367.295893 -249.044556)
			(xy 367.343164 -249.058248) (xy 367.387626 -249.079346) (xy 367.428129 -249.107302) (xy 367.463622 -249.141394)
			(xy 367.493187 -249.180738) (xy 367.516058 -249.224315) (xy 367.531642 -249.270996) (xy 367.539537 -249.319573)
			(xy 367.540032 -249.34418) (xy 368.809028 -249.34418) (xy 368.812988 -249.295126) (xy 368.824765 -249.247342)
			(xy 368.844056 -249.202066) (xy 368.870359 -249.16047) (xy 368.902994 -249.123633) (xy 368.941115 -249.092508)
			(xy 368.983736 -249.067901) (xy 369.029752 -249.050449) (xy 369.077971 -249.040605) (xy 369.127146 -249.038624)
			(xy 369.176001 -249.044556) (xy 369.223272 -249.058248) (xy 369.267734 -249.079346) (xy 369.308237 -249.107302)
			(xy 369.34373 -249.141394) (xy 369.373295 -249.180738) (xy 369.396166 -249.224315) (xy 369.41175 -249.270996)
			(xy 369.419645 -249.319573) (xy 369.42014 -249.34418) (xy 370.688882 -249.34418) (xy 370.692842 -249.295126)
			(xy 370.704619 -249.247342) (xy 370.72391 -249.202066) (xy 370.750213 -249.16047) (xy 370.782848 -249.123633)
			(xy 370.820969 -249.092508) (xy 370.86359 -249.067901) (xy 370.909606 -249.050449) (xy 370.957825 -249.040605)
			(xy 371.007 -249.038624) (xy 371.055855 -249.044556) (xy 371.103126 -249.058248) (xy 371.147588 -249.079346)
			(xy 371.188091 -249.107302) (xy 371.223584 -249.141394) (xy 371.253149 -249.180738) (xy 371.27602 -249.224315)
			(xy 371.291604 -249.270996) (xy 371.299499 -249.319573) (xy 371.299994 -249.34418) (xy 372.56899 -249.34418)
			(xy 372.57295 -249.295126) (xy 372.584727 -249.247342) (xy 372.604018 -249.202066) (xy 372.630321 -249.16047)
			(xy 372.662956 -249.123633) (xy 372.701077 -249.092508) (xy 372.743698 -249.067901) (xy 372.789714 -249.050449)
			(xy 372.837933 -249.040605) (xy 372.887108 -249.038624) (xy 372.935963 -249.044556) (xy 372.983234 -249.058248)
			(xy 373.027696 -249.079346) (xy 373.068199 -249.107302) (xy 373.103692 -249.141394) (xy 373.133257 -249.180738)
			(xy 373.156128 -249.224315) (xy 373.171712 -249.270996) (xy 373.179607 -249.319573) (xy 373.180102 -249.34418)
			(xy 373.179607 -249.368787) (xy 373.171712 -249.417364) (xy 373.156128 -249.464045) (xy 373.133257 -249.507622)
			(xy 373.103692 -249.546966) (xy 373.068199 -249.581058) (xy 373.027696 -249.609014) (xy 372.983234 -249.630112)
			(xy 372.935963 -249.643804) (xy 372.887108 -249.649736) (xy 372.837933 -249.647755) (xy 372.789714 -249.637911)
			(xy 372.743698 -249.620459) (xy 372.701077 -249.595852) (xy 372.662956 -249.564727) (xy 372.630321 -249.52789)
			(xy 372.604018 -249.486294) (xy 372.584727 -249.441018) (xy 372.57295 -249.393234) (xy 372.56899 -249.34418)
			(xy 371.299994 -249.34418) (xy 371.299499 -249.368787) (xy 371.291604 -249.417364) (xy 371.27602 -249.464045)
			(xy 371.253149 -249.507622) (xy 371.223584 -249.546966) (xy 371.188091 -249.581058) (xy 371.147588 -249.609014)
			(xy 371.103126 -249.630112) (xy 371.055855 -249.643804) (xy 371.007 -249.649736) (xy 370.957825 -249.647755)
			(xy 370.909606 -249.637911) (xy 370.86359 -249.620459) (xy 370.820969 -249.595852) (xy 370.782848 -249.564727)
			(xy 370.750213 -249.52789) (xy 370.72391 -249.486294) (xy 370.704619 -249.441018) (xy 370.692842 -249.393234)
			(xy 370.688882 -249.34418) (xy 369.42014 -249.34418) (xy 369.419645 -249.368787) (xy 369.41175 -249.417364)
			(xy 369.396166 -249.464045) (xy 369.373295 -249.507622) (xy 369.34373 -249.546966) (xy 369.308237 -249.581058)
			(xy 369.267734 -249.609014) (xy 369.223272 -249.630112) (xy 369.176001 -249.643804) (xy 369.127146 -249.649736)
			(xy 369.077971 -249.647755) (xy 369.029752 -249.637911) (xy 368.983736 -249.620459) (xy 368.941115 -249.595852)
			(xy 368.902994 -249.564727) (xy 368.870359 -249.52789) (xy 368.844056 -249.486294) (xy 368.824765 -249.441018)
			(xy 368.812988 -249.393234) (xy 368.809028 -249.34418) (xy 367.540032 -249.34418) (xy 367.539537 -249.368787)
			(xy 367.531642 -249.417364) (xy 367.516058 -249.464045) (xy 367.493187 -249.507622) (xy 367.463622 -249.546966)
			(xy 367.428129 -249.581058) (xy 367.387626 -249.609014) (xy 367.343164 -249.630112) (xy 367.295893 -249.643804)
			(xy 367.247038 -249.649736) (xy 367.197863 -249.647755) (xy 367.149644 -249.637911) (xy 367.103628 -249.620459)
			(xy 367.061007 -249.595852) (xy 367.022886 -249.564727) (xy 366.990251 -249.52789) (xy 366.963948 -249.486294)
			(xy 366.944657 -249.441018) (xy 366.93288 -249.393234) (xy 366.92892 -249.34418) (xy 365.660178 -249.34418)
			(xy 365.659683 -249.368787) (xy 365.651788 -249.417364) (xy 365.636204 -249.464045) (xy 365.613333 -249.507622)
			(xy 365.583768 -249.546966) (xy 365.548275 -249.581058) (xy 365.507772 -249.609014) (xy 365.46331 -249.630112)
			(xy 365.416039 -249.643804) (xy 365.367184 -249.649736) (xy 365.318009 -249.647755) (xy 365.26979 -249.637911)
			(xy 365.223774 -249.620459) (xy 365.181153 -249.595852) (xy 365.143032 -249.564727) (xy 365.110397 -249.52789)
			(xy 365.084094 -249.486294) (xy 365.064803 -249.441018) (xy 365.053026 -249.393234) (xy 365.049066 -249.34418)
			(xy 363.78007 -249.34418) (xy 363.779575 -249.368787) (xy 363.77168 -249.417364) (xy 363.756096 -249.464045)
			(xy 363.733225 -249.507622) (xy 363.70366 -249.546966) (xy 363.668167 -249.581058) (xy 363.627664 -249.609014)
			(xy 363.583202 -249.630112) (xy 363.535931 -249.643804) (xy 363.487076 -249.649736) (xy 363.437901 -249.647755)
			(xy 363.389682 -249.637911) (xy 363.343666 -249.620459) (xy 363.301045 -249.595852) (xy 363.262924 -249.564727)
			(xy 363.230289 -249.52789) (xy 363.203986 -249.486294) (xy 363.184695 -249.441018) (xy 363.172918 -249.393234)
			(xy 363.168958 -249.34418) (xy 361.900216 -249.34418) (xy 361.899721 -249.368787) (xy 361.891826 -249.417364)
			(xy 361.876242 -249.464045) (xy 361.853371 -249.507622) (xy 361.823806 -249.546966) (xy 361.788313 -249.581058)
			(xy 361.74781 -249.609014) (xy 361.703348 -249.630112) (xy 361.656077 -249.643804) (xy 361.607222 -249.649736)
			(xy 361.558047 -249.647755) (xy 361.509828 -249.637911) (xy 361.463812 -249.620459) (xy 361.421191 -249.595852)
			(xy 361.38307 -249.564727) (xy 361.350435 -249.52789) (xy 361.324132 -249.486294) (xy 361.304841 -249.441018)
			(xy 361.293064 -249.393234) (xy 361.289104 -249.34418) (xy 360.083522 -249.34418) (xy 360.083862 -249.36196)
			(xy 360.083358 -249.388286) (xy 360.075321 -249.440322) (xy 360.059435 -249.490521) (xy 360.036072 -249.537706)
			(xy 360.00578 -249.580772) (xy 359.969268 -249.61871) (xy 359.927394 -249.650629) (xy 359.881138 -249.675782)
			(xy 359.831585 -249.69358) (xy 359.779895 -249.703604) (xy 359.727281 -249.705621) (xy 359.674976 -249.699583)
			(xy 359.624205 -249.685631) (xy 359.57616 -249.664092) (xy 359.531965 -249.635472) (xy 359.492657 -249.600441)
			(xy 359.459157 -249.55982) (xy 359.432251 -249.514561) (xy 359.412568 -249.465726) (xy 359.400571 -249.414458)
			(xy 359.396541 -249.36196) (xy 357.206104 -249.36196) (xy 357.205403 -249.377123) (xy 357.196062 -249.425912)
			(xy 357.178949 -249.472545) (xy 357.154515 -249.515795) (xy 357.123404 -249.55452) (xy 357.086437 -249.5877)
			(xy 357.044587 -249.61446) (xy 356.998957 -249.634095) (xy 356.950752 -249.646087) (xy 356.901242 -249.65012)
			(xy 356.851732 -249.646087) (xy 356.803527 -249.634095) (xy 356.757897 -249.61446) (xy 356.716047 -249.5877)
			(xy 356.67908 -249.55452) (xy 356.647969 -249.515795) (xy 356.623535 -249.472545) (xy 356.606422 -249.425912)
			(xy 356.597081 -249.377123) (xy 356.595934 -249.352308) (xy 356.595426 -249.331734) (xy 356.565962 -249.303032)
			(xy 356.430834 -249.303032) (xy 356.391843 -249.302525) (xy 356.314267 -249.294576) (xy 356.237894 -249.278816)
			(xy 356.163507 -249.255408) (xy 356.091872 -249.224592) (xy 356.023723 -249.186684) (xy 355.959761 -249.142073)
			(xy 355.900642 -249.091218) (xy 355.846974 -249.034641) (xy 355.799307 -248.972923) (xy 355.778308 -248.940066)
			(xy 355.775006 -248.934986) (xy 355.654864 -248.814844) (xy 355.624892 -248.809002) (xy 355.610414 -248.815098)
			(xy 355.581878 -248.826432) (xy 355.521729 -248.838718) (xy 355.491034 -248.839482) (xy 355.466785 -248.839011)
			(xy 355.418899 -248.831335) (xy 355.372827 -248.816187) (xy 355.329729 -248.793948) (xy 355.290687 -248.765176)
			(xy 355.256684 -248.730596) (xy 355.228573 -248.691076) (xy 355.207062 -248.647609) (xy 355.192692 -248.601289)
			(xy 355.188774 -248.577354) (xy 355.18725 -248.567702) (xy 355.177852 -248.550938) (xy 355.115876 -248.501408)
			(xy 355.112083 -248.498504) (xy 355.103646 -248.494022) (xy 355.099112 -248.492518) (xy 355.090476 -248.489724)
			(xy 355.073177 -248.491168) (xy 355.038493 -248.49269) (xy 355.021134 -248.492772) (xy 354.723192 -248.492772)
			(xy 354.688004 -248.49241) (xy 354.617917 -248.486049) (xy 354.583238 -248.480072) (xy 354.564188 -248.476262)
			(xy 354.561648 -248.475754) (xy 354.551234 -248.474738) (xy 354.540566 -248.475754) (xy 354.538026 -248.476262)
			(xy 354.518976 -248.480072) (xy 354.484298 -248.486056) (xy 354.41421 -248.492417) (xy 354.379022 -248.492772)
			(xy 354.08108 -248.492772) (xy 354.041056 -248.492272) (xy 353.96144 -248.48398) (xy 353.883117 -248.467457)
			(xy 353.806936 -248.442881) (xy 353.733722 -248.41052) (xy 353.664269 -248.370723) (xy 353.6315 -248.347738)
			(xy 353.62515 -248.343166) (xy 353.603052 -248.3358) (xy 353.599156 -248.334624) (xy 353.591119 -248.333354)
			(xy 353.58705 -248.33326) (xy 353.065842 -248.33326) (xy 353.054216 -248.333827) (xy 353.033308 -248.344002)
			(xy 353.02571 -248.352818) (xy 352.976434 -248.416064) (xy 352.969705 -248.425645) (xy 352.964927 -248.44854)
			(xy 352.96729 -248.460006) (xy 352.971483 -248.477877) (xy 352.976066 -248.514298) (xy 352.976434 -248.53265)
			(xy 352.976434 -248.536968) (xy 352.975758 -248.560818) (xy 352.967911 -248.607877) (xy 352.95284 -248.653144)
			(xy 352.930912 -248.695516) (xy 352.902661 -248.733961) (xy 352.868774 -248.767545) (xy 352.830076 -248.79545)
			(xy 352.787509 -248.816997) (xy 352.742109 -248.83166) (xy 352.694981 -248.839085) (xy 352.671126 -248.839482)
			(xy 352.646873 -248.839018) (xy 352.598975 -248.831354) (xy 352.552892 -248.816214) (xy 352.509781 -248.79398)
			(xy 352.470727 -248.765211) (xy 352.436712 -248.730629) (xy 352.408591 -248.691106) (xy 352.387072 -248.647634)
			(xy 352.372696 -248.601306) (xy 352.368866 -248.577354) (xy 352.367342 -248.567702) (xy 352.357944 -248.550938)
			(xy 352.295968 -248.501408) (xy 352.292174 -248.498504) (xy 352.283738 -248.494024) (xy 352.279204 -248.492518)
			(xy 352.270568 -248.489724) (xy 352.253269 -248.49117) (xy 352.218585 -248.492697) (xy 352.201226 -248.492772)
			(xy 351.903284 -248.492772) (xy 351.868096 -248.49241) (xy 351.798009 -248.486048) (xy 351.76333 -248.480072)
			(xy 351.74428 -248.476262) (xy 351.74174 -248.475754) (xy 351.731326 -248.474738) (xy 351.720658 -248.475754)
			(xy 351.718118 -248.476262) (xy 351.699068 -248.480072) (xy 351.66439 -248.486056) (xy 351.594302 -248.492416)
			(xy 351.559114 -248.492772) (xy 351.261172 -248.492772) (xy 351.221148 -248.492271) (xy 351.141533 -248.483979)
			(xy 351.06321 -248.467455) (xy 350.987029 -248.442879) (xy 350.913816 -248.410517) (xy 350.844364 -248.370719)
			(xy 350.811592 -248.347738) (xy 350.805242 -248.343166) (xy 350.783144 -248.3358) (xy 350.779248 -248.334624)
			(xy 350.771211 -248.333356) (xy 350.767142 -248.33326) (xy 350.245934 -248.33326) (xy 350.234309 -248.333828)
			(xy 350.213404 -248.344006) (xy 350.205802 -248.352818) (xy 350.156526 -248.416064) (xy 350.149798 -248.425646)
			(xy 350.14502 -248.44854) (xy 350.147382 -248.460006) (xy 350.151575 -248.477877) (xy 350.156158 -248.514298)
			(xy 350.156526 -248.53265) (xy 350.156526 -248.536968) (xy 350.15585 -248.560817) (xy 350.148003 -248.607877)
			(xy 350.132932 -248.653143) (xy 350.111004 -248.695514) (xy 350.082752 -248.733959) (xy 350.048865 -248.767542)
			(xy 350.010167 -248.795446) (xy 349.967601 -248.816991) (xy 349.922201 -248.831654) (xy 349.875073 -248.839077)
			(xy 349.851218 -248.839482) (xy 349.826965 -248.839017) (xy 349.779069 -248.831352) (xy 349.732986 -248.816212)
			(xy 349.689876 -248.793978) (xy 349.650823 -248.765208) (xy 349.616809 -248.730627) (xy 349.58869 -248.691103)
			(xy 349.567171 -248.647631) (xy 349.552796 -248.601305) (xy 349.548958 -248.577354) (xy 349.547688 -248.567702)
			(xy 349.538036 -248.550938) (xy 349.47606 -248.501408) (xy 349.472266 -248.498505) (xy 349.463829 -248.494026)
			(xy 349.459296 -248.492518) (xy 349.450406 -248.489724) (xy 349.433107 -248.491169) (xy 349.398423 -248.492692)
			(xy 349.381064 -248.492772) (xy 349.083122 -248.492772) (xy 349.047934 -248.492412) (xy 348.977846 -248.486053)
			(xy 348.943168 -248.480072) (xy 348.924118 -248.476262) (xy 348.921578 -248.475754) (xy 348.911164 -248.474738)
			(xy 348.900496 -248.475754) (xy 348.897956 -248.476262) (xy 348.878906 -248.480072) (xy 348.844228 -248.486058)
			(xy 348.774141 -248.492421) (xy 348.738952 -248.492772) (xy 348.44101 -248.492772) (xy 348.400986 -248.492273)
			(xy 348.321368 -248.483984) (xy 348.243044 -248.467464) (xy 348.166861 -248.442891) (xy 348.093645 -248.410531)
			(xy 348.02419 -248.370736) (xy 347.99143 -248.347738) (xy 347.98508 -248.343166) (xy 347.962982 -248.3358)
			(xy 347.959087 -248.334621) (xy 347.951049 -248.333347) (xy 347.94698 -248.33326) (xy 347.425772 -248.33326)
			(xy 347.414143 -248.33382) (xy 347.393225 -248.343989) (xy 347.38564 -248.352818) (xy 347.336364 -248.416064)
			(xy 347.329632 -248.425645) (xy 347.324851 -248.448541) (xy 347.32722 -248.460006) (xy 347.331414 -248.477877)
			(xy 347.335998 -248.514298) (xy 347.336364 -248.53265) (xy 347.336364 -248.536968) (xy 347.335688 -248.560816)
			(xy 347.32784 -248.607871) (xy 347.312768 -248.653133) (xy 347.290839 -248.6955) (xy 347.262587 -248.73394)
			(xy 347.228699 -248.767517) (xy 347.190001 -248.795414) (xy 347.147434 -248.816952) (xy 347.102035 -248.831606)
			(xy 347.054909 -248.83902) (xy 347.031056 -248.839482) (xy 347.006806 -248.839012) (xy 346.958917 -248.831339)
			(xy 346.912842 -248.816194) (xy 346.869741 -248.793956) (xy 346.830697 -248.765185) (xy 346.79669 -248.730604)
			(xy 346.768578 -248.691083) (xy 346.747065 -248.647615) (xy 346.732693 -248.601293) (xy 346.728796 -248.577354)
			(xy 346.727272 -248.567702) (xy 346.717874 -248.550938) (xy 346.655898 -248.501408) (xy 346.652105 -248.498502)
			(xy 346.64367 -248.494017) (xy 346.639134 -248.492518) (xy 346.630498 -248.489724) (xy 346.613199 -248.491169)
			(xy 346.578515 -248.492692) (xy 346.561156 -248.492772) (xy 346.263214 -248.492772) (xy 346.228026 -248.492411)
			(xy 346.157938 -248.486052) (xy 346.12326 -248.480072) (xy 346.10421 -248.476262) (xy 346.10167 -248.475754)
			(xy 346.091256 -248.474738) (xy 346.080588 -248.475754) (xy 346.078048 -248.476262) (xy 346.058998 -248.480072)
			(xy 346.02432 -248.486057) (xy 345.954232 -248.49242) (xy 345.919044 -248.492772) (xy 345.621102 -248.492772)
			(xy 345.580426 -248.492252) (xy 345.499526 -248.483684) (xy 345.419983 -248.466622) (xy 345.342686 -248.441257)
			(xy 345.2685 -248.407872) (xy 345.198253 -248.366841) (xy 345.165172 -248.343166) (xy 345.161956 -248.340842)
			(xy 345.154937 -248.337141) (xy 345.151202 -248.3358) (xy 345.143328 -248.33326) (xy 345.125802 -248.33326)
			(xy 345.115733 -248.333684) (xy 345.097134 -248.341405) (xy 345.089734 -248.348246) (xy 344.886026 -248.551954)
			(xy 344.87866 -248.559066) (xy 344.87104 -248.577862) (xy 344.87104 -249.07113) (xy 344.871183 -249.076427)
			(xy 344.873369 -249.086793) (xy 344.875358 -249.091704) (xy 344.887296 -249.118882) (xy 344.894408 -249.12574)
			(xy 344.911593 -249.143241) (xy 344.940715 -249.182705) (xy 344.963158 -249.226315) (xy 344.978347 -249.27295)
			(xy 344.985891 -249.321412) (xy 344.985754 -249.34418) (xy 345.315298 -249.34418) (xy 345.319258 -249.295126)
			(xy 345.331035 -249.247342) (xy 345.350326 -249.202066) (xy 345.376629 -249.16047) (xy 345.409264 -249.123633)
			(xy 345.447385 -249.092508) (xy 345.490006 -249.067901) (xy 345.536022 -249.050449) (xy 345.584241 -249.040605)
			(xy 345.633416 -249.038624) (xy 345.682271 -249.044556) (xy 345.729542 -249.058248) (xy 345.774004 -249.079346)
			(xy 345.814507 -249.107302) (xy 345.85 -249.141394) (xy 345.879565 -249.180738) (xy 345.902436 -249.224315)
			(xy 345.91802 -249.270996) (xy 345.925915 -249.319573) (xy 345.92641 -249.34418) (xy 346.255352 -249.34418)
			(xy 346.259312 -249.295126) (xy 346.271089 -249.247342) (xy 346.29038 -249.202066) (xy 346.316683 -249.16047)
			(xy 346.349318 -249.123633) (xy 346.387439 -249.092508) (xy 346.43006 -249.067901) (xy 346.476076 -249.050449)
			(xy 346.524295 -249.040605) (xy 346.57347 -249.038624) (xy 346.622325 -249.044556) (xy 346.669596 -249.058248)
			(xy 346.714058 -249.079346) (xy 346.754561 -249.107302) (xy 346.790054 -249.141394) (xy 346.819619 -249.180738)
			(xy 346.84249 -249.224315) (xy 346.858074 -249.270996) (xy 346.865969 -249.319573) (xy 346.866464 -249.34418)
			(xy 347.195406 -249.34418) (xy 347.199366 -249.295126) (xy 347.211143 -249.247342) (xy 347.230434 -249.202066)
			(xy 347.256737 -249.16047) (xy 347.289372 -249.123633) (xy 347.327493 -249.092508) (xy 347.370114 -249.067901)
			(xy 347.41613 -249.050449) (xy 347.464349 -249.040605) (xy 347.513524 -249.038624) (xy 347.562379 -249.044556)
			(xy 347.60965 -249.058248) (xy 347.654112 -249.079346) (xy 347.694615 -249.107302) (xy 347.730108 -249.141394)
			(xy 347.759673 -249.180738) (xy 347.782544 -249.224315) (xy 347.798128 -249.270996) (xy 347.806023 -249.319573)
			(xy 347.806518 -249.34418) (xy 349.07526 -249.34418) (xy 349.07922 -249.295126) (xy 349.090997 -249.247342)
			(xy 349.110288 -249.202066) (xy 349.136591 -249.16047) (xy 349.169226 -249.123633) (xy 349.207347 -249.092508)
			(xy 349.249968 -249.067901) (xy 349.295984 -249.050449) (xy 349.344203 -249.040605) (xy 349.393378 -249.038624)
			(xy 349.442233 -249.044556) (xy 349.489504 -249.058248) (xy 349.533966 -249.079346) (xy 349.574469 -249.107302)
			(xy 349.609962 -249.141394) (xy 349.639527 -249.180738) (xy 349.662398 -249.224315) (xy 349.677982 -249.270996)
			(xy 349.685877 -249.319573) (xy 349.686372 -249.34418) (xy 350.955368 -249.34418) (xy 350.959328 -249.295126)
			(xy 350.971105 -249.247342) (xy 350.990396 -249.202066) (xy 351.016699 -249.16047) (xy 351.049334 -249.123633)
			(xy 351.087455 -249.092508) (xy 351.130076 -249.067901) (xy 351.176092 -249.050449) (xy 351.224311 -249.040605)
			(xy 351.273486 -249.038624) (xy 351.322341 -249.044556) (xy 351.369612 -249.058248) (xy 351.414074 -249.079346)
			(xy 351.454577 -249.107302) (xy 351.49007 -249.141394) (xy 351.519635 -249.180738) (xy 351.542506 -249.224315)
			(xy 351.55809 -249.270996) (xy 351.565985 -249.319573) (xy 351.56648 -249.34418) (xy 352.835222 -249.34418)
			(xy 352.839182 -249.295126) (xy 352.850959 -249.247342) (xy 352.87025 -249.202066) (xy 352.896553 -249.16047)
			(xy 352.929188 -249.123633) (xy 352.967309 -249.092508) (xy 353.00993 -249.067901) (xy 353.055946 -249.050449)
			(xy 353.104165 -249.040605) (xy 353.15334 -249.038624) (xy 353.202195 -249.044556) (xy 353.249466 -249.058248)
			(xy 353.293928 -249.079346) (xy 353.334431 -249.107302) (xy 353.369924 -249.141394) (xy 353.399489 -249.180738)
			(xy 353.42236 -249.224315) (xy 353.437944 -249.270996) (xy 353.445839 -249.319573) (xy 353.446334 -249.34418)
			(xy 354.71533 -249.34418) (xy 354.71929 -249.295126) (xy 354.731067 -249.247342) (xy 354.750358 -249.202066)
			(xy 354.776661 -249.16047) (xy 354.809296 -249.123633) (xy 354.847417 -249.092508) (xy 354.890038 -249.067901)
			(xy 354.936054 -249.050449) (xy 354.984273 -249.040605) (xy 355.033448 -249.038624) (xy 355.082303 -249.044556)
			(xy 355.129574 -249.058248) (xy 355.174036 -249.079346) (xy 355.214539 -249.107302) (xy 355.250032 -249.141394)
			(xy 355.279597 -249.180738) (xy 355.302468 -249.224315) (xy 355.318052 -249.270996) (xy 355.325947 -249.319573)
			(xy 355.326442 -249.34418) (xy 355.325947 -249.368787) (xy 355.318052 -249.417364) (xy 355.302468 -249.464045)
			(xy 355.279597 -249.507622) (xy 355.250032 -249.546966) (xy 355.214539 -249.581058) (xy 355.174036 -249.609014)
			(xy 355.129574 -249.630112) (xy 355.082303 -249.643804) (xy 355.033448 -249.649736) (xy 354.984273 -249.647755)
			(xy 354.936054 -249.637911) (xy 354.890038 -249.620459) (xy 354.847417 -249.595852) (xy 354.809296 -249.564727)
			(xy 354.776661 -249.52789) (xy 354.750358 -249.486294) (xy 354.731067 -249.441018) (xy 354.71929 -249.393234)
			(xy 354.71533 -249.34418) (xy 353.446334 -249.34418) (xy 353.445839 -249.368787) (xy 353.437944 -249.417364)
			(xy 353.42236 -249.464045) (xy 353.399489 -249.507622) (xy 353.369924 -249.546966) (xy 353.334431 -249.581058)
			(xy 353.293928 -249.609014) (xy 353.249466 -249.630112) (xy 353.202195 -249.643804) (xy 353.15334 -249.649736)
			(xy 353.104165 -249.647755) (xy 353.055946 -249.637911) (xy 353.00993 -249.620459) (xy 352.967309 -249.595852)
			(xy 352.929188 -249.564727) (xy 352.896553 -249.52789) (xy 352.87025 -249.486294) (xy 352.850959 -249.441018)
			(xy 352.839182 -249.393234) (xy 352.835222 -249.34418) (xy 351.56648 -249.34418) (xy 351.565985 -249.368787)
			(xy 351.55809 -249.417364) (xy 351.542506 -249.464045) (xy 351.519635 -249.507622) (xy 351.49007 -249.546966)
			(xy 351.454577 -249.581058) (xy 351.414074 -249.609014) (xy 351.369612 -249.630112) (xy 351.322341 -249.643804)
			(xy 351.273486 -249.649736) (xy 351.224311 -249.647755) (xy 351.176092 -249.637911) (xy 351.130076 -249.620459)
			(xy 351.087455 -249.595852) (xy 351.049334 -249.564727) (xy 351.016699 -249.52789) (xy 350.990396 -249.486294)
			(xy 350.971105 -249.441018) (xy 350.959328 -249.393234) (xy 350.955368 -249.34418) (xy 349.686372 -249.34418)
			(xy 349.685877 -249.368787) (xy 349.677982 -249.417364) (xy 349.662398 -249.464045) (xy 349.639527 -249.507622)
			(xy 349.609962 -249.546966) (xy 349.574469 -249.581058) (xy 349.533966 -249.609014) (xy 349.489504 -249.630112)
			(xy 349.442233 -249.643804) (xy 349.393378 -249.649736) (xy 349.344203 -249.647755) (xy 349.295984 -249.637911)
			(xy 349.249968 -249.620459) (xy 349.207347 -249.595852) (xy 349.169226 -249.564727) (xy 349.136591 -249.52789)
			(xy 349.110288 -249.486294) (xy 349.090997 -249.441018) (xy 349.07922 -249.393234) (xy 349.07526 -249.34418)
			(xy 347.806518 -249.34418) (xy 347.806023 -249.368787) (xy 347.798128 -249.417364) (xy 347.782544 -249.464045)
			(xy 347.759673 -249.507622) (xy 347.730108 -249.546966) (xy 347.694615 -249.581058) (xy 347.654112 -249.609014)
			(xy 347.60965 -249.630112) (xy 347.562379 -249.643804) (xy 347.513524 -249.649736) (xy 347.464349 -249.647755)
			(xy 347.41613 -249.637911) (xy 347.370114 -249.620459) (xy 347.327493 -249.595852) (xy 347.289372 -249.564727)
			(xy 347.256737 -249.52789) (xy 347.230434 -249.486294) (xy 347.211143 -249.441018) (xy 347.199366 -249.393234)
			(xy 347.195406 -249.34418) (xy 346.866464 -249.34418) (xy 346.865969 -249.368787) (xy 346.858074 -249.417364)
			(xy 346.84249 -249.464045) (xy 346.819619 -249.507622) (xy 346.790054 -249.546966) (xy 346.754561 -249.581058)
			(xy 346.714058 -249.609014) (xy 346.669596 -249.630112) (xy 346.622325 -249.643804) (xy 346.57347 -249.649736)
			(xy 346.524295 -249.647755) (xy 346.476076 -249.637911) (xy 346.43006 -249.620459) (xy 346.387439 -249.595852)
			(xy 346.349318 -249.564727) (xy 346.316683 -249.52789) (xy 346.29038 -249.486294) (xy 346.271089 -249.441018)
			(xy 346.259312 -249.393234) (xy 346.255352 -249.34418) (xy 345.92641 -249.34418) (xy 345.925915 -249.368787)
			(xy 345.91802 -249.417364) (xy 345.902436 -249.464045) (xy 345.879565 -249.507622) (xy 345.85 -249.546966)
			(xy 345.814507 -249.581058) (xy 345.774004 -249.609014) (xy 345.729542 -249.630112) (xy 345.682271 -249.643804)
			(xy 345.633416 -249.649736) (xy 345.584241 -249.647755) (xy 345.536022 -249.637911) (xy 345.490006 -249.620459)
			(xy 345.447385 -249.595852) (xy 345.409264 -249.564727) (xy 345.376629 -249.52789) (xy 345.350326 -249.486294)
			(xy 345.331035 -249.441018) (xy 345.319258 -249.393234) (xy 345.315298 -249.34418) (xy 344.985754 -249.34418)
			(xy 344.985596 -249.370457) (xy 344.982038 -249.394726) (xy 344.982292 -249.394726) (xy 344.977834 -249.418413)
			(xy 344.962455 -249.46409) (xy 344.940103 -249.506791) (xy 344.91133 -249.545457) (xy 344.894408 -249.56262)
			(xy 344.88755 -249.569478) (xy 344.875358 -249.596656) (xy 344.873329 -249.601554) (xy 344.871155 -249.611929)
			(xy 344.87104 -249.61723) (xy 344.87104 -249.788426) (xy 344.87139 -249.79703) (xy 344.877094 -249.813266)
			(xy 344.887824 -249.826721) (xy 344.894916 -249.831606) (xy 344.979244 -249.884184) (xy 345.005406 -249.885454)
			(xy 345.017344 -249.879866) (xy 345.038292 -249.870096) (xy 345.082402 -249.856291) (xy 345.128092 -249.849309)
			(xy 345.151202 -249.848878) (xy 345.156282 -249.848878) (xy 345.18001 -249.849724) (xy 345.226785 -249.857854)
			(xy 345.271738 -249.873128) (xy 345.313784 -249.895177) (xy 345.35191 -249.92347) (xy 345.385195 -249.957324)
			(xy 345.412838 -249.995923) (xy 345.434173 -250.038336) (xy 345.448683 -250.083541) (xy 345.45602 -250.130448)
			(xy 345.45651 -250.154186) (xy 345.785198 -250.154186) (xy 345.789158 -250.105132) (xy 345.800935 -250.057348)
			(xy 345.820226 -250.012072) (xy 345.846529 -249.970476) (xy 345.879164 -249.933639) (xy 345.917285 -249.902514)
			(xy 345.959906 -249.877907) (xy 346.005922 -249.860455) (xy 346.054141 -249.850611) (xy 346.103316 -249.84863)
			(xy 346.152171 -249.854562) (xy 346.199442 -249.868254) (xy 346.243904 -249.889352) (xy 346.284407 -249.917308)
			(xy 346.3199 -249.9514) (xy 346.349465 -249.990744) (xy 346.372336 -250.034321) (xy 346.38792 -250.081002)
			(xy 346.395815 -250.129579) (xy 346.39631 -250.154186) (xy 346.725252 -250.154186) (xy 346.729212 -250.105132)
			(xy 346.740989 -250.057348) (xy 346.76028 -250.012072) (xy 346.786583 -249.970476) (xy 346.819218 -249.933639)
			(xy 346.857339 -249.902514) (xy 346.89996 -249.877907) (xy 346.945976 -249.860455) (xy 346.994195 -249.850611)
			(xy 347.04337 -249.84863) (xy 347.092225 -249.854562) (xy 347.139496 -249.868254) (xy 347.183958 -249.889352)
			(xy 347.224461 -249.917308) (xy 347.259954 -249.9514) (xy 347.289519 -249.990744) (xy 347.31239 -250.034321)
			(xy 347.327974 -250.081002) (xy 347.335869 -250.129579) (xy 347.336364 -250.154186) (xy 347.665306 -250.154186)
			(xy 347.669266 -250.105132) (xy 347.681043 -250.057348) (xy 347.700334 -250.012072) (xy 347.726637 -249.970476)
			(xy 347.759272 -249.933639) (xy 347.797393 -249.902514) (xy 347.840014 -249.877907) (xy 347.88603 -249.860455)
			(xy 347.934249 -249.850611) (xy 347.983424 -249.84863) (xy 348.032279 -249.854562) (xy 348.07955 -249.868254)
			(xy 348.124012 -249.889352) (xy 348.164515 -249.917308) (xy 348.200008 -249.9514) (xy 348.229573 -249.990744)
			(xy 348.252444 -250.034321) (xy 348.268028 -250.081002) (xy 348.275923 -250.129579) (xy 348.276418 -250.154186)
			(xy 349.545414 -250.154186) (xy 349.549374 -250.105132) (xy 349.561151 -250.057348) (xy 349.580442 -250.012072)
			(xy 349.606745 -249.970476) (xy 349.63938 -249.933639) (xy 349.677501 -249.902514) (xy 349.720122 -249.877907)
			(xy 349.766138 -249.860455) (xy 349.814357 -249.850611) (xy 349.863532 -249.84863) (xy 349.912387 -249.854562)
			(xy 349.959658 -249.868254) (xy 350.00412 -249.889352) (xy 350.044623 -249.917308) (xy 350.080116 -249.9514)
			(xy 350.109681 -249.990744) (xy 350.132552 -250.034321) (xy 350.148136 -250.081002) (xy 350.156031 -250.129579)
			(xy 350.156526 -250.154186) (xy 351.425268 -250.154186) (xy 351.429228 -250.105132) (xy 351.441005 -250.057348)
			(xy 351.460296 -250.012072) (xy 351.486599 -249.970476) (xy 351.519234 -249.933639) (xy 351.557355 -249.902514)
			(xy 351.599976 -249.877907) (xy 351.645992 -249.860455) (xy 351.694211 -249.850611) (xy 351.743386 -249.84863)
			(xy 351.792241 -249.854562) (xy 351.839512 -249.868254) (xy 351.883974 -249.889352) (xy 351.924477 -249.917308)
			(xy 351.95997 -249.9514) (xy 351.989535 -249.990744) (xy 352.012406 -250.034321) (xy 352.02799 -250.081002)
			(xy 352.035885 -250.129579) (xy 352.03638 -250.154186) (xy 353.305376 -250.154186) (xy 353.309336 -250.105132)
			(xy 353.321113 -250.057348) (xy 353.340404 -250.012072) (xy 353.366707 -249.970476) (xy 353.399342 -249.933639)
			(xy 353.437463 -249.902514) (xy 353.480084 -249.877907) (xy 353.5261 -249.860455) (xy 353.574319 -249.850611)
			(xy 353.623494 -249.84863) (xy 353.672349 -249.854562) (xy 353.71962 -249.868254) (xy 353.764082 -249.889352)
			(xy 353.804585 -249.917308) (xy 353.840078 -249.9514) (xy 353.869643 -249.990744) (xy 353.892514 -250.034321)
			(xy 353.908098 -250.081002) (xy 353.915993 -250.129579) (xy 353.916488 -250.154186) (xy 355.18523 -250.154186)
			(xy 355.18919 -250.105132) (xy 355.200967 -250.057348) (xy 355.220258 -250.012072) (xy 355.246561 -249.970476)
			(xy 355.279196 -249.933639) (xy 355.317317 -249.902514) (xy 355.359938 -249.877907) (xy 355.405954 -249.860455)
			(xy 355.454173 -249.850611) (xy 355.503348 -249.84863) (xy 355.552203 -249.854562) (xy 355.599474 -249.868254)
			(xy 355.643936 -249.889352) (xy 355.684439 -249.917308) (xy 355.719932 -249.9514) (xy 355.749497 -249.990744)
			(xy 355.772368 -250.034321) (xy 355.787952 -250.081002) (xy 355.795847 -250.129579) (xy 355.796342 -250.154186)
			(xy 357.065338 -250.154186) (xy 357.069298 -250.105132) (xy 357.081075 -250.057348) (xy 357.100366 -250.012072)
			(xy 357.126669 -249.970476) (xy 357.159304 -249.933639) (xy 357.197425 -249.902514) (xy 357.240046 -249.877907)
			(xy 357.286062 -249.860455) (xy 357.334281 -249.850611) (xy 357.383456 -249.84863) (xy 357.432311 -249.854562)
			(xy 357.479582 -249.868254) (xy 357.524044 -249.889352) (xy 357.564547 -249.917308) (xy 357.60004 -249.9514)
			(xy 357.629605 -249.990744) (xy 357.652476 -250.034321) (xy 357.66806 -250.081002) (xy 357.675955 -250.129579)
			(xy 357.67645 -250.154186) (xy 360.81895 -250.154186) (xy 360.82291 -250.105132) (xy 360.834687 -250.057348)
			(xy 360.853978 -250.012072) (xy 360.880281 -249.970476) (xy 360.912916 -249.933639) (xy 360.951037 -249.902514)
			(xy 360.993658 -249.877907) (xy 361.039674 -249.860455) (xy 361.087893 -249.850611) (xy 361.137068 -249.84863)
			(xy 361.185923 -249.854562) (xy 361.233194 -249.868254) (xy 361.277656 -249.889352) (xy 361.318159 -249.917308)
			(xy 361.353652 -249.9514) (xy 361.383217 -249.990744) (xy 361.406088 -250.034321) (xy 361.421672 -250.081002)
			(xy 361.429567 -250.129579) (xy 361.430062 -250.154186) (xy 362.699058 -250.154186) (xy 362.703018 -250.105132)
			(xy 362.714795 -250.057348) (xy 362.734086 -250.012072) (xy 362.760389 -249.970476) (xy 362.793024 -249.933639)
			(xy 362.831145 -249.902514) (xy 362.873766 -249.877907) (xy 362.919782 -249.860455) (xy 362.968001 -249.850611)
			(xy 363.017176 -249.84863) (xy 363.066031 -249.854562) (xy 363.113302 -249.868254) (xy 363.157764 -249.889352)
			(xy 363.198267 -249.917308) (xy 363.23376 -249.9514) (xy 363.263325 -249.990744) (xy 363.286196 -250.034321)
			(xy 363.30178 -250.081002) (xy 363.309675 -250.129579) (xy 363.31017 -250.154186) (xy 364.578912 -250.154186)
			(xy 364.582872 -250.105132) (xy 364.594649 -250.057348) (xy 364.61394 -250.012072) (xy 364.640243 -249.970476)
			(xy 364.672878 -249.933639) (xy 364.710999 -249.902514) (xy 364.75362 -249.877907) (xy 364.799636 -249.860455)
			(xy 364.847855 -249.850611) (xy 364.89703 -249.84863) (xy 364.945885 -249.854562) (xy 364.993156 -249.868254)
			(xy 365.037618 -249.889352) (xy 365.078121 -249.917308) (xy 365.113614 -249.9514) (xy 365.143179 -249.990744)
			(xy 365.16605 -250.034321) (xy 365.181634 -250.081002) (xy 365.189529 -250.129579) (xy 365.190024 -250.154186)
			(xy 366.45902 -250.154186) (xy 366.46298 -250.105132) (xy 366.474757 -250.057348) (xy 366.494048 -250.012072)
			(xy 366.520351 -249.970476) (xy 366.552986 -249.933639) (xy 366.591107 -249.902514) (xy 366.633728 -249.877907)
			(xy 366.679744 -249.860455) (xy 366.727963 -249.850611) (xy 366.777138 -249.84863) (xy 366.825993 -249.854562)
			(xy 366.873264 -249.868254) (xy 366.917726 -249.889352) (xy 366.958229 -249.917308) (xy 366.993722 -249.9514)
			(xy 367.023287 -249.990744) (xy 367.046158 -250.034321) (xy 367.061742 -250.081002) (xy 367.069637 -250.129579)
			(xy 367.070132 -250.154186) (xy 368.338874 -250.154186) (xy 368.342834 -250.105132) (xy 368.354611 -250.057348)
			(xy 368.373902 -250.012072) (xy 368.400205 -249.970476) (xy 368.43284 -249.933639) (xy 368.470961 -249.902514)
			(xy 368.513582 -249.877907) (xy 368.559598 -249.860455) (xy 368.607817 -249.850611) (xy 368.656992 -249.84863)
			(xy 368.705847 -249.854562) (xy 368.753118 -249.868254) (xy 368.79758 -249.889352) (xy 368.838083 -249.917308)
			(xy 368.873576 -249.9514) (xy 368.903141 -249.990744) (xy 368.926012 -250.034321) (xy 368.941596 -250.081002)
			(xy 368.949491 -250.129579) (xy 368.949986 -250.154186) (xy 370.218982 -250.154186) (xy 370.222942 -250.105132)
			(xy 370.234719 -250.057348) (xy 370.25401 -250.012072) (xy 370.280313 -249.970476) (xy 370.312948 -249.933639)
			(xy 370.351069 -249.902514) (xy 370.39369 -249.877907) (xy 370.439706 -249.860455) (xy 370.487925 -249.850611)
			(xy 370.5371 -249.84863) (xy 370.585955 -249.854562) (xy 370.633226 -249.868254) (xy 370.677688 -249.889352)
			(xy 370.718191 -249.917308) (xy 370.753684 -249.9514) (xy 370.783249 -249.990744) (xy 370.80612 -250.034321)
			(xy 370.821704 -250.081002) (xy 370.829599 -250.129579) (xy 370.830094 -250.154186) (xy 372.09909 -250.154186)
			(xy 372.10305 -250.105132) (xy 372.114827 -250.057348) (xy 372.134118 -250.012072) (xy 372.160421 -249.970476)
			(xy 372.193056 -249.933639) (xy 372.231177 -249.902514) (xy 372.273798 -249.877907) (xy 372.319814 -249.860455)
			(xy 372.368033 -249.850611) (xy 372.417208 -249.84863) (xy 372.466063 -249.854562) (xy 372.513334 -249.868254)
			(xy 372.557796 -249.889352) (xy 372.598299 -249.917308) (xy 372.633792 -249.9514) (xy 372.663357 -249.990744)
			(xy 372.686228 -250.034321) (xy 372.701812 -250.081002) (xy 372.709707 -250.129579) (xy 372.710202 -250.154186)
			(xy 372.709707 -250.178793) (xy 372.701812 -250.22737) (xy 372.686228 -250.274051) (xy 372.663357 -250.317628)
			(xy 372.633792 -250.356972) (xy 372.598299 -250.391064) (xy 372.557796 -250.41902) (xy 372.513334 -250.440118)
			(xy 372.466063 -250.45381) (xy 372.417208 -250.459742) (xy 372.368033 -250.457761) (xy 372.319814 -250.447917)
			(xy 372.273798 -250.430465) (xy 372.231177 -250.405858) (xy 372.193056 -250.374733) (xy 372.160421 -250.337896)
			(xy 372.134118 -250.2963) (xy 372.114827 -250.251024) (xy 372.10305 -250.20324) (xy 372.09909 -250.154186)
			(xy 370.830094 -250.154186) (xy 370.829599 -250.178793) (xy 370.821704 -250.22737) (xy 370.80612 -250.274051)
			(xy 370.783249 -250.317628) (xy 370.753684 -250.356972) (xy 370.718191 -250.391064) (xy 370.677688 -250.41902)
			(xy 370.633226 -250.440118) (xy 370.585955 -250.45381) (xy 370.5371 -250.459742) (xy 370.487925 -250.457761)
			(xy 370.439706 -250.447917) (xy 370.39369 -250.430465) (xy 370.351069 -250.405858) (xy 370.312948 -250.374733)
			(xy 370.280313 -250.337896) (xy 370.25401 -250.2963) (xy 370.234719 -250.251024) (xy 370.222942 -250.20324)
			(xy 370.218982 -250.154186) (xy 368.949986 -250.154186) (xy 368.949491 -250.178793) (xy 368.941596 -250.22737)
			(xy 368.926012 -250.274051) (xy 368.903141 -250.317628) (xy 368.873576 -250.356972) (xy 368.838083 -250.391064)
			(xy 368.79758 -250.41902) (xy 368.753118 -250.440118) (xy 368.705847 -250.45381) (xy 368.656992 -250.459742)
			(xy 368.607817 -250.457761) (xy 368.559598 -250.447917) (xy 368.513582 -250.430465) (xy 368.470961 -250.405858)
			(xy 368.43284 -250.374733) (xy 368.400205 -250.337896) (xy 368.373902 -250.2963) (xy 368.354611 -250.251024)
			(xy 368.342834 -250.20324) (xy 368.338874 -250.154186) (xy 367.070132 -250.154186) (xy 367.069637 -250.178793)
			(xy 367.061742 -250.22737) (xy 367.046158 -250.274051) (xy 367.023287 -250.317628) (xy 366.993722 -250.356972)
			(xy 366.958229 -250.391064) (xy 366.917726 -250.41902) (xy 366.873264 -250.440118) (xy 366.825993 -250.45381)
			(xy 366.777138 -250.459742) (xy 366.727963 -250.457761) (xy 366.679744 -250.447917) (xy 366.633728 -250.430465)
			(xy 366.591107 -250.405858) (xy 366.552986 -250.374733) (xy 366.520351 -250.337896) (xy 366.494048 -250.2963)
			(xy 366.474757 -250.251024) (xy 366.46298 -250.20324) (xy 366.45902 -250.154186) (xy 365.190024 -250.154186)
			(xy 365.189529 -250.178793) (xy 365.181634 -250.22737) (xy 365.16605 -250.274051) (xy 365.143179 -250.317628)
			(xy 365.113614 -250.356972) (xy 365.078121 -250.391064) (xy 365.037618 -250.41902) (xy 364.993156 -250.440118)
			(xy 364.945885 -250.45381) (xy 364.89703 -250.459742) (xy 364.847855 -250.457761) (xy 364.799636 -250.447917)
			(xy 364.75362 -250.430465) (xy 364.710999 -250.405858) (xy 364.672878 -250.374733) (xy 364.640243 -250.337896)
			(xy 364.61394 -250.2963) (xy 364.594649 -250.251024) (xy 364.582872 -250.20324) (xy 364.578912 -250.154186)
			(xy 363.31017 -250.154186) (xy 363.309675 -250.178793) (xy 363.30178 -250.22737) (xy 363.286196 -250.274051)
			(xy 363.263325 -250.317628) (xy 363.23376 -250.356972) (xy 363.198267 -250.391064) (xy 363.157764 -250.41902)
			(xy 363.113302 -250.440118) (xy 363.066031 -250.45381) (xy 363.017176 -250.459742) (xy 362.968001 -250.457761)
			(xy 362.919782 -250.447917) (xy 362.873766 -250.430465) (xy 362.831145 -250.405858) (xy 362.793024 -250.374733)
			(xy 362.760389 -250.337896) (xy 362.734086 -250.2963) (xy 362.714795 -250.251024) (xy 362.703018 -250.20324)
			(xy 362.699058 -250.154186) (xy 361.430062 -250.154186) (xy 361.429567 -250.178793) (xy 361.421672 -250.22737)
			(xy 361.406088 -250.274051) (xy 361.383217 -250.317628) (xy 361.353652 -250.356972) (xy 361.318159 -250.391064)
			(xy 361.277656 -250.41902) (xy 361.233194 -250.440118) (xy 361.185923 -250.45381) (xy 361.137068 -250.459742)
			(xy 361.087893 -250.457761) (xy 361.039674 -250.447917) (xy 360.993658 -250.430465) (xy 360.951037 -250.405858)
			(xy 360.912916 -250.374733) (xy 360.880281 -250.337896) (xy 360.853978 -250.2963) (xy 360.834687 -250.251024)
			(xy 360.82291 -250.20324) (xy 360.81895 -250.154186) (xy 357.67645 -250.154186) (xy 357.675955 -250.178793)
			(xy 357.66806 -250.22737) (xy 357.652476 -250.274051) (xy 357.629605 -250.317628) (xy 357.60004 -250.356972)
			(xy 357.564547 -250.391064) (xy 357.524044 -250.41902) (xy 357.479582 -250.440118) (xy 357.432311 -250.45381)
			(xy 357.383456 -250.459742) (xy 357.334281 -250.457761) (xy 357.286062 -250.447917) (xy 357.240046 -250.430465)
			(xy 357.197425 -250.405858) (xy 357.159304 -250.374733) (xy 357.126669 -250.337896) (xy 357.100366 -250.2963)
			(xy 357.081075 -250.251024) (xy 357.069298 -250.20324) (xy 357.065338 -250.154186) (xy 355.796342 -250.154186)
			(xy 355.795847 -250.178793) (xy 355.787952 -250.22737) (xy 355.772368 -250.274051) (xy 355.749497 -250.317628)
			(xy 355.719932 -250.356972) (xy 355.684439 -250.391064) (xy 355.643936 -250.41902) (xy 355.599474 -250.440118)
			(xy 355.552203 -250.45381) (xy 355.503348 -250.459742) (xy 355.454173 -250.457761) (xy 355.405954 -250.447917)
			(xy 355.359938 -250.430465) (xy 355.317317 -250.405858) (xy 355.279196 -250.374733) (xy 355.246561 -250.337896)
			(xy 355.220258 -250.2963) (xy 355.200967 -250.251024) (xy 355.18919 -250.20324) (xy 355.18523 -250.154186)
			(xy 353.916488 -250.154186) (xy 353.915993 -250.178793) (xy 353.908098 -250.22737) (xy 353.892514 -250.274051)
			(xy 353.869643 -250.317628) (xy 353.840078 -250.356972) (xy 353.804585 -250.391064) (xy 353.764082 -250.41902)
			(xy 353.71962 -250.440118) (xy 353.672349 -250.45381) (xy 353.623494 -250.459742) (xy 353.574319 -250.457761)
			(xy 353.5261 -250.447917) (xy 353.480084 -250.430465) (xy 353.437463 -250.405858) (xy 353.399342 -250.374733)
			(xy 353.366707 -250.337896) (xy 353.340404 -250.2963) (xy 353.321113 -250.251024) (xy 353.309336 -250.20324)
			(xy 353.305376 -250.154186) (xy 352.03638 -250.154186) (xy 352.035885 -250.178793) (xy 352.02799 -250.22737)
			(xy 352.012406 -250.274051) (xy 351.989535 -250.317628) (xy 351.95997 -250.356972) (xy 351.924477 -250.391064)
			(xy 351.883974 -250.41902) (xy 351.839512 -250.440118) (xy 351.792241 -250.45381) (xy 351.743386 -250.459742)
			(xy 351.694211 -250.457761) (xy 351.645992 -250.447917) (xy 351.599976 -250.430465) (xy 351.557355 -250.405858)
			(xy 351.519234 -250.374733) (xy 351.486599 -250.337896) (xy 351.460296 -250.2963) (xy 351.441005 -250.251024)
			(xy 351.429228 -250.20324) (xy 351.425268 -250.154186) (xy 350.156526 -250.154186) (xy 350.156031 -250.178793)
			(xy 350.148136 -250.22737) (xy 350.132552 -250.274051) (xy 350.109681 -250.317628) (xy 350.080116 -250.356972)
			(xy 350.044623 -250.391064) (xy 350.00412 -250.41902) (xy 349.959658 -250.440118) (xy 349.912387 -250.45381)
			(xy 349.863532 -250.459742) (xy 349.814357 -250.457761) (xy 349.766138 -250.447917) (xy 349.720122 -250.430465)
			(xy 349.677501 -250.405858) (xy 349.63938 -250.374733) (xy 349.606745 -250.337896) (xy 349.580442 -250.2963)
			(xy 349.561151 -250.251024) (xy 349.549374 -250.20324) (xy 349.545414 -250.154186) (xy 348.276418 -250.154186)
			(xy 348.275923 -250.178793) (xy 348.268028 -250.22737) (xy 348.252444 -250.274051) (xy 348.229573 -250.317628)
			(xy 348.200008 -250.356972) (xy 348.164515 -250.391064) (xy 348.124012 -250.41902) (xy 348.07955 -250.440118)
			(xy 348.032279 -250.45381) (xy 347.983424 -250.459742) (xy 347.934249 -250.457761) (xy 347.88603 -250.447917)
			(xy 347.840014 -250.430465) (xy 347.797393 -250.405858) (xy 347.759272 -250.374733) (xy 347.726637 -250.337896)
			(xy 347.700334 -250.2963) (xy 347.681043 -250.251024) (xy 347.669266 -250.20324) (xy 347.665306 -250.154186)
			(xy 347.336364 -250.154186) (xy 347.335869 -250.178793) (xy 347.327974 -250.22737) (xy 347.31239 -250.274051)
			(xy 347.289519 -250.317628) (xy 347.259954 -250.356972) (xy 347.224461 -250.391064) (xy 347.183958 -250.41902)
			(xy 347.139496 -250.440118) (xy 347.092225 -250.45381) (xy 347.04337 -250.459742) (xy 346.994195 -250.457761)
			(xy 346.945976 -250.447917) (xy 346.89996 -250.430465) (xy 346.857339 -250.405858) (xy 346.819218 -250.374733)
			(xy 346.786583 -250.337896) (xy 346.76028 -250.2963) (xy 346.740989 -250.251024) (xy 346.729212 -250.20324)
			(xy 346.725252 -250.154186) (xy 346.39631 -250.154186) (xy 346.395815 -250.178793) (xy 346.38792 -250.22737)
			(xy 346.372336 -250.274051) (xy 346.349465 -250.317628) (xy 346.3199 -250.356972) (xy 346.284407 -250.391064)
			(xy 346.243904 -250.41902) (xy 346.199442 -250.440118) (xy 346.152171 -250.45381) (xy 346.103316 -250.459742)
			(xy 346.054141 -250.457761) (xy 346.005922 -250.447917) (xy 345.959906 -250.430465) (xy 345.917285 -250.405858)
			(xy 345.879164 -250.374733) (xy 345.846529 -250.337896) (xy 345.820226 -250.2963) (xy 345.800935 -250.251024)
			(xy 345.789158 -250.20324) (xy 345.785198 -250.154186) (xy 345.45651 -250.154186) (xy 345.456065 -250.17818)
			(xy 345.44856 -250.225577) (xy 345.433733 -250.271217) (xy 345.411948 -250.313975) (xy 345.383743 -250.352799)
			(xy 345.349811 -250.386732) (xy 345.310989 -250.41494) (xy 345.268232 -250.436726) (xy 345.222593 -250.451556)
			(xy 345.175196 -250.459064) (xy 345.151202 -250.459494) (xy 345.128093 -250.45905) (xy 345.082407 -250.452057)
			(xy 345.038291 -250.438274) (xy 345.017344 -250.428506) (xy 345.005406 -250.422918) (xy 344.979244 -250.424188)
			(xy 344.894916 -250.476766) (xy 344.887781 -250.481605) (xy 344.877016 -250.495058) (xy 344.871352 -250.51133)
			(xy 344.87104 -250.519946) (xy 344.87104 -250.691142) (xy 344.871175 -250.696441) (xy 344.873344 -250.706814)
			(xy 344.875358 -250.711716) (xy 344.887296 -250.738894) (xy 344.894408 -250.745752) (xy 344.911483 -250.763088)
			(xy 344.940459 -250.802177) (xy 344.962861 -250.84537) (xy 344.978123 -250.891571) (xy 344.985857 -250.93961)
			(xy 344.986356 -250.963938) (xy 344.986356 -250.964192) (xy 344.98628 -250.974575) (xy 344.984882 -250.995295)
			(xy 344.983562 -251.005594) (xy 344.982038 -251.017532) (xy 344.989404 -251.039884) (xy 345.160854 -251.211334)
			(xy 345.161362 -251.211842) (xy 345.168743 -251.218424) (xy 345.187042 -251.225873) (xy 345.196922 -251.22632)
		)
		(stroke
			(width 0)
			(type solid)
		)
		(fill yes)
		(layer "In15.Cu")
		(net "PVDDCR_CPU0_P0")
	)
	(gr_poly
		(pts
			(xy 364.308136 -295.76522) (xy 364.318204 -295.764791) (xy 364.336801 -295.75707) (xy 364.344204 -295.750234)
			(xy 364.682278 -295.41216) (xy 364.689121 -295.40476) (xy 364.696844 -295.386162) (xy 364.697264 -295.376092)
			(xy 364.697264 -294.666924) (xy 364.674404 -294.639238) (xy 364.656116 -294.635682) (xy 364.631911 -294.630453)
			(xy 364.585489 -294.613221) (xy 364.542455 -294.588726) (xy 364.503937 -294.557608) (xy 364.470945 -294.520683)
			(xy 364.444342 -294.478919) (xy 364.424827 -294.433409) (xy 364.412909 -294.385348) (xy 364.408903 -294.335993)
			(xy 364.412912 -294.286638) (xy 364.424831 -294.238577) (xy 364.444349 -294.193069) (xy 364.470954 -294.151306)
			(xy 364.503948 -294.114382) (xy 364.542467 -294.083266) (xy 364.585502 -294.058772) (xy 364.631925 -294.041543)
			(xy 364.656116 -294.036242) (xy 364.674404 -294.032686) (xy 364.697264 -294.005) (xy 364.697264 -293.046912)
			(xy 364.674404 -293.019226) (xy 364.656116 -293.01567) (xy 364.633257 -293.010743) (xy 364.589275 -292.99487)
			(xy 364.548229 -292.972473) (xy 364.51108 -292.944076) (xy 364.478699 -292.910345) (xy 364.451843 -292.872067)
			(xy 364.43114 -292.830141) (xy 364.417077 -292.785547) (xy 364.409981 -292.73933) (xy 364.409482 -292.71595)
			(xy 364.409956 -292.691961) (xy 364.417469 -292.644575) (xy 364.4323 -292.598947) (xy 364.454086 -292.5562)
			(xy 364.48229 -292.517388) (xy 364.516218 -292.483464) (xy 364.555035 -292.455265) (xy 364.597784 -292.433485)
			(xy 364.643414 -292.418659) (xy 364.690801 -292.411153) (xy 364.71479 -292.410642) (xy 364.738423 -292.411084)
			(xy 364.785125 -292.418365) (xy 364.830148 -292.432757) (xy 364.872415 -292.453913) (xy 364.910917 -292.48133)
			(xy 364.92815 -292.49751) (xy 364.935516 -292.504622) (xy 364.953804 -292.511988) (xy 365.035338 -292.51148)
			(xy 365.045233 -292.510953) (xy 365.063516 -292.503361) (xy 365.070898 -292.496748) (xy 365.081566 -292.48608)
			(xy 365.088964 -292.479235) (xy 365.107563 -292.471512) (xy 365.117634 -292.471094) (xy 365.443008 -292.471094)
			(xy 365.450944 -292.470825) (xy 365.466073 -292.466032) (xy 365.472726 -292.461696) (xy 365.492927 -292.447815)
			(xy 365.536738 -292.425842) (xy 365.583439 -292.410969) (xy 365.631887 -292.403558) (xy 365.680898 -292.403793)
			(xy 365.729274 -292.411665) (xy 365.77583 -292.426985) (xy 365.819429 -292.449375) (xy 365.859003 -292.47829)
			(xy 365.893585 -292.513021) (xy 365.92233 -292.552719) (xy 365.944533 -292.596413) (xy 365.959651 -292.643035)
			(xy 365.967316 -292.691444) (xy 365.967772 -292.71595) (xy 367.228894 -292.71595) (xy 367.232854 -292.666896)
			(xy 367.244631 -292.619112) (xy 367.263922 -292.573836) (xy 367.290225 -292.53224) (xy 367.32286 -292.495403)
			(xy 367.360981 -292.464278) (xy 367.403602 -292.439671) (xy 367.449618 -292.422219) (xy 367.497837 -292.412375)
			(xy 367.547012 -292.410394) (xy 367.595867 -292.416326) (xy 367.643138 -292.430018) (xy 367.6876 -292.451116)
			(xy 367.728103 -292.479072) (xy 367.763596 -292.513164) (xy 367.793161 -292.552508) (xy 367.816032 -292.596085)
			(xy 367.831616 -292.642766) (xy 367.839511 -292.691343) (xy 367.840006 -292.71595) (xy 368.168948 -292.71595)
			(xy 368.172908 -292.666896) (xy 368.184685 -292.619112) (xy 368.203976 -292.573836) (xy 368.230279 -292.53224)
			(xy 368.262914 -292.495403) (xy 368.301035 -292.464278) (xy 368.343656 -292.439671) (xy 368.389672 -292.422219)
			(xy 368.437891 -292.412375) (xy 368.487066 -292.410394) (xy 368.535921 -292.416326) (xy 368.583192 -292.430018)
			(xy 368.627654 -292.451116) (xy 368.668157 -292.479072) (xy 368.70365 -292.513164) (xy 368.733215 -292.552508)
			(xy 368.756086 -292.596085) (xy 368.77167 -292.642766) (xy 368.779565 -292.691343) (xy 368.78006 -292.71595)
			(xy 370.049056 -292.71595) (xy 370.053016 -292.666896) (xy 370.064793 -292.619112) (xy 370.084084 -292.573836)
			(xy 370.110387 -292.53224) (xy 370.143022 -292.495403) (xy 370.181143 -292.464278) (xy 370.223764 -292.439671)
			(xy 370.26978 -292.422219) (xy 370.317999 -292.412375) (xy 370.367174 -292.410394) (xy 370.416029 -292.416326)
			(xy 370.4633 -292.430018) (xy 370.507762 -292.451116) (xy 370.548265 -292.479072) (xy 370.583758 -292.513164)
			(xy 370.613323 -292.552508) (xy 370.636194 -292.596085) (xy 370.651778 -292.642766) (xy 370.659673 -292.691343)
			(xy 370.660168 -292.71595) (xy 370.98911 -292.71595) (xy 370.99307 -292.666896) (xy 371.004847 -292.619112)
			(xy 371.024138 -292.573836) (xy 371.050441 -292.53224) (xy 371.083076 -292.495403) (xy 371.121197 -292.464278)
			(xy 371.163818 -292.439671) (xy 371.209834 -292.422219) (xy 371.258053 -292.412375) (xy 371.307228 -292.410394)
			(xy 371.356083 -292.416326) (xy 371.403354 -292.430018) (xy 371.447816 -292.451116) (xy 371.488319 -292.479072)
			(xy 371.523812 -292.513164) (xy 371.553377 -292.552508) (xy 371.576248 -292.596085) (xy 371.591832 -292.642766)
			(xy 371.599727 -292.691343) (xy 371.600222 -292.71595) (xy 372.868964 -292.71595) (xy 372.872924 -292.666896)
			(xy 372.884701 -292.619112) (xy 372.903992 -292.573836) (xy 372.930295 -292.53224) (xy 372.96293 -292.495403)
			(xy 373.001051 -292.464278) (xy 373.043672 -292.439671) (xy 373.089688 -292.422219) (xy 373.137907 -292.412375)
			(xy 373.187082 -292.410394) (xy 373.235937 -292.416326) (xy 373.283208 -292.430018) (xy 373.32767 -292.451116)
			(xy 373.368173 -292.479072) (xy 373.403666 -292.513164) (xy 373.433231 -292.552508) (xy 373.456102 -292.596085)
			(xy 373.471686 -292.642766) (xy 373.479581 -292.691343) (xy 373.480076 -292.71595) (xy 373.809018 -292.71595)
			(xy 373.812978 -292.666896) (xy 373.824755 -292.619112) (xy 373.844046 -292.573836) (xy 373.870349 -292.53224)
			(xy 373.902984 -292.495403) (xy 373.941105 -292.464278) (xy 373.983726 -292.439671) (xy 374.029742 -292.422219)
			(xy 374.077961 -292.412375) (xy 374.127136 -292.410394) (xy 374.175991 -292.416326) (xy 374.223262 -292.430018)
			(xy 374.267724 -292.451116) (xy 374.308227 -292.479072) (xy 374.34372 -292.513164) (xy 374.373285 -292.552508)
			(xy 374.396156 -292.596085) (xy 374.41174 -292.642766) (xy 374.419635 -292.691343) (xy 374.42013 -292.71595)
			(xy 375.678695 -292.71595) (xy 375.68279 -292.665222) (xy 375.694969 -292.615808) (xy 375.714917 -292.568988)
			(xy 375.742118 -292.525974) (xy 375.775866 -292.48788) (xy 375.815288 -292.455693) (xy 375.859362 -292.430247)
			(xy 375.906948 -292.4122) (xy 375.956812 -292.40202) (xy 376.007664 -292.399971) (xy 376.058185 -292.406105)
			(xy 376.107069 -292.420265) (xy 376.153048 -292.442082) (xy 376.194932 -292.470992) (xy 376.231636 -292.506247)
			(xy 376.262209 -292.546933) (xy 376.28586 -292.591996) (xy 376.301976 -292.64027) (xy 376.31014 -292.690504)
			(xy 376.310652 -292.71595) (xy 376.628926 -292.71595) (xy 376.632886 -292.666896) (xy 376.644663 -292.619112)
			(xy 376.663954 -292.573836) (xy 376.690257 -292.53224) (xy 376.722892 -292.495403) (xy 376.761013 -292.464278)
			(xy 376.803634 -292.439671) (xy 376.84965 -292.422219) (xy 376.897869 -292.412375) (xy 376.947044 -292.410394)
			(xy 376.995899 -292.416326) (xy 377.04317 -292.430018) (xy 377.087632 -292.451116) (xy 377.128135 -292.479072)
			(xy 377.163628 -292.513164) (xy 377.193193 -292.552508) (xy 377.216064 -292.596085) (xy 377.231648 -292.642766)
			(xy 377.239543 -292.691343) (xy 377.240038 -292.71595) (xy 377.239543 -292.740557) (xy 377.231648 -292.789134)
			(xy 377.216064 -292.835815) (xy 377.193193 -292.879392) (xy 377.163628 -292.918736) (xy 377.128135 -292.952828)
			(xy 377.087632 -292.980784) (xy 377.04317 -293.001882) (xy 376.995899 -293.015574) (xy 376.947044 -293.021506)
			(xy 376.897869 -293.019525) (xy 376.84965 -293.009681) (xy 376.803634 -292.992229) (xy 376.761013 -292.967622)
			(xy 376.722892 -292.936497) (xy 376.690257 -292.89966) (xy 376.663954 -292.858064) (xy 376.644663 -292.812788)
			(xy 376.632886 -292.765004) (xy 376.628926 -292.71595) (xy 376.310652 -292.71595) (xy 376.31014 -292.741396)
			(xy 376.301976 -292.79163) (xy 376.28586 -292.839904) (xy 376.262209 -292.884967) (xy 376.231636 -292.925653)
			(xy 376.194932 -292.960908) (xy 376.153048 -292.989818) (xy 376.107069 -293.011635) (xy 376.058185 -293.025795)
			(xy 376.007664 -293.031929) (xy 375.956812 -293.02988) (xy 375.906948 -293.0197) (xy 375.859362 -293.001653)
			(xy 375.815288 -292.976207) (xy 375.775866 -292.94402) (xy 375.742118 -292.905926) (xy 375.714917 -292.862912)
			(xy 375.694969 -292.816092) (xy 375.68279 -292.766678) (xy 375.678695 -292.71595) (xy 374.42013 -292.71595)
			(xy 374.419635 -292.740557) (xy 374.41174 -292.789134) (xy 374.396156 -292.835815) (xy 374.373285 -292.879392)
			(xy 374.34372 -292.918736) (xy 374.308227 -292.952828) (xy 374.267724 -292.980784) (xy 374.223262 -293.001882)
			(xy 374.175991 -293.015574) (xy 374.127136 -293.021506) (xy 374.077961 -293.019525) (xy 374.029742 -293.009681)
			(xy 373.983726 -292.992229) (xy 373.941105 -292.967622) (xy 373.902984 -292.936497) (xy 373.870349 -292.89966)
			(xy 373.844046 -292.858064) (xy 373.824755 -292.812788) (xy 373.812978 -292.765004) (xy 373.809018 -292.71595)
			(xy 373.480076 -292.71595) (xy 373.479581 -292.740557) (xy 373.471686 -292.789134) (xy 373.456102 -292.835815)
			(xy 373.433231 -292.879392) (xy 373.403666 -292.918736) (xy 373.368173 -292.952828) (xy 373.32767 -292.980784)
			(xy 373.283208 -293.001882) (xy 373.235937 -293.015574) (xy 373.187082 -293.021506) (xy 373.137907 -293.019525)
			(xy 373.089688 -293.009681) (xy 373.043672 -292.992229) (xy 373.001051 -292.967622) (xy 372.96293 -292.936497)
			(xy 372.930295 -292.89966) (xy 372.903992 -292.858064) (xy 372.884701 -292.812788) (xy 372.872924 -292.765004)
			(xy 372.868964 -292.71595) (xy 371.600222 -292.71595) (xy 371.599727 -292.740557) (xy 371.591832 -292.789134)
			(xy 371.576248 -292.835815) (xy 371.553377 -292.879392) (xy 371.523812 -292.918736) (xy 371.488319 -292.952828)
			(xy 371.447816 -292.980784) (xy 371.403354 -293.001882) (xy 371.356083 -293.015574) (xy 371.307228 -293.021506)
			(xy 371.258053 -293.019525) (xy 371.209834 -293.009681) (xy 371.163818 -292.992229) (xy 371.121197 -292.967622)
			(xy 371.083076 -292.936497) (xy 371.050441 -292.89966) (xy 371.024138 -292.858064) (xy 371.004847 -292.812788)
			(xy 370.99307 -292.765004) (xy 370.98911 -292.71595) (xy 370.660168 -292.71595) (xy 370.659673 -292.740557)
			(xy 370.651778 -292.789134) (xy 370.636194 -292.835815) (xy 370.613323 -292.879392) (xy 370.583758 -292.918736)
			(xy 370.548265 -292.952828) (xy 370.507762 -292.980784) (xy 370.4633 -293.001882) (xy 370.416029 -293.015574)
			(xy 370.367174 -293.021506) (xy 370.317999 -293.019525) (xy 370.26978 -293.009681) (xy 370.223764 -292.992229)
			(xy 370.181143 -292.967622) (xy 370.143022 -292.936497) (xy 370.110387 -292.89966) (xy 370.084084 -292.858064)
			(xy 370.064793 -292.812788) (xy 370.053016 -292.765004) (xy 370.049056 -292.71595) (xy 368.78006 -292.71595)
			(xy 368.779565 -292.740557) (xy 368.77167 -292.789134) (xy 368.756086 -292.835815) (xy 368.733215 -292.879392)
			(xy 368.70365 -292.918736) (xy 368.668157 -292.952828) (xy 368.627654 -292.980784) (xy 368.583192 -293.001882)
			(xy 368.535921 -293.015574) (xy 368.487066 -293.021506) (xy 368.437891 -293.019525) (xy 368.389672 -293.009681)
			(xy 368.343656 -292.992229) (xy 368.301035 -292.967622) (xy 368.262914 -292.936497) (xy 368.230279 -292.89966)
			(xy 368.203976 -292.858064) (xy 368.184685 -292.812788) (xy 368.172908 -292.765004) (xy 368.168948 -292.71595)
			(xy 367.840006 -292.71595) (xy 367.839511 -292.740557) (xy 367.831616 -292.789134) (xy 367.816032 -292.835815)
			(xy 367.793161 -292.879392) (xy 367.763596 -292.918736) (xy 367.728103 -292.952828) (xy 367.6876 -292.980784)
			(xy 367.643138 -293.001882) (xy 367.595867 -293.015574) (xy 367.547012 -293.021506) (xy 367.497837 -293.019525)
			(xy 367.449618 -293.009681) (xy 367.403602 -292.992229) (xy 367.360981 -292.967622) (xy 367.32286 -292.936497)
			(xy 367.290225 -292.89966) (xy 367.263922 -292.858064) (xy 367.244631 -292.812788) (xy 367.232854 -292.765004)
			(xy 367.228894 -292.71595) (xy 365.967772 -292.71595) (xy 365.967772 -293.123112) (xy 365.968301 -293.134036)
			(xy 365.9774 -293.153898) (xy 365.985298 -293.161466) (xy 366.004602 -293.17823) (xy 366.042448 -293.21125)
			(xy 366.046769 -293.214849) (xy 366.056642 -293.220229) (xy 366.062006 -293.221918) (xy 366.07242 -293.224966)
			(xy 366.083088 -293.223442) (xy 366.093451 -293.222125) (xy 366.114298 -293.220729) (xy 366.124744 -293.220648)
			(xy 366.148734 -293.221122) (xy 366.196123 -293.228633) (xy 366.241754 -293.243464) (xy 366.284504 -293.265249)
			(xy 366.32332 -293.293452) (xy 366.357248 -293.32738) (xy 366.385451 -293.366196) (xy 366.407236 -293.408946)
			(xy 366.422067 -293.454577) (xy 366.429578 -293.501966) (xy 366.430052 -293.525956) (xy 366.429923 -293.537496)
			(xy 366.428141 -293.560507) (xy 366.426496 -293.57193) (xy 366.425988 -293.57574) (xy 366.425988 -293.576756)
			(xy 366.421723 -293.599471) (xy 366.407259 -293.643367) (xy 366.386358 -293.684588) (xy 366.359494 -293.722196)
			(xy 366.343692 -293.739062) (xy 366.337596 -293.745158) (xy 366.326928 -293.768526) (xy 366.32508 -293.77276)
			(xy 366.322772 -293.781705) (xy 366.322356 -293.786306) (xy 366.32134 -293.8018) (xy 366.321101 -293.806827)
			(xy 366.322374 -293.81681) (xy 366.32388 -293.821612) (xy 366.331246 -293.843202) (xy 366.336072 -293.849552)
			(xy 366.353749 -293.874776) (xy 366.379842 -293.930563) (xy 366.387888 -293.960296) (xy 366.390428 -293.970202)
			(xy 366.402366 -293.986458) (xy 366.442498 -294.010334) (xy 366.443006 -294.010334) (xy 366.483138 -294.033956)
			(xy 366.503204 -294.03675) (xy 366.51311 -294.033956) (xy 366.545368 -294.027098) (xy 366.54867 -294.02659)
			(xy 366.560162 -294.025022) (xy 366.5833 -294.023371) (xy 366.594898 -294.023288) (xy 366.606433 -294.023361)
			(xy 366.629445 -294.025012) (xy 366.640872 -294.02659) (xy 366.64773 -294.027352) (xy 366.658144 -294.024304)
			(xy 366.663289 -294.022602) (xy 366.672763 -294.017344) (xy 366.67694 -294.01389) (xy 366.734598 -293.963598)
			(xy 366.7425 -293.956041) (xy 366.751565 -293.936166) (xy 366.752124 -293.925244) (xy 366.752124 -293.525956)
			(xy 366.752606 -293.501386) (xy 366.760293 -293.452851) (xy 366.775478 -293.406116) (xy 366.797787 -293.362332)
			(xy 366.826671 -293.322576) (xy 366.861418 -293.287829) (xy 366.901174 -293.258945) (xy 366.944958 -293.236636)
			(xy 366.991693 -293.221451) (xy 367.040228 -293.213764) (xy 367.089368 -293.213764) (xy 367.137903 -293.221451)
			(xy 367.184638 -293.236636) (xy 367.228422 -293.258945) (xy 367.268178 -293.287829) (xy 367.302925 -293.322576)
			(xy 367.331809 -293.362332) (xy 367.354118 -293.406116) (xy 367.369303 -293.452851) (xy 367.37699 -293.501386)
			(xy 367.377472 -293.525956) (xy 367.699048 -293.525956) (xy 367.703008 -293.476902) (xy 367.714785 -293.429118)
			(xy 367.734076 -293.383842) (xy 367.760379 -293.342246) (xy 367.793014 -293.305409) (xy 367.831135 -293.274284)
			(xy 367.873756 -293.249677) (xy 367.919772 -293.232225) (xy 367.967991 -293.222381) (xy 368.017166 -293.2204)
			(xy 368.066021 -293.226332) (xy 368.113292 -293.240024) (xy 368.157754 -293.261122) (xy 368.198257 -293.289078)
			(xy 368.23375 -293.32317) (xy 368.263315 -293.362514) (xy 368.286186 -293.406091) (xy 368.30177 -293.452772)
			(xy 368.309665 -293.501349) (xy 368.31016 -293.525956) (xy 369.578902 -293.525956) (xy 369.582862 -293.476902)
			(xy 369.594639 -293.429118) (xy 369.61393 -293.383842) (xy 369.640233 -293.342246) (xy 369.672868 -293.305409)
			(xy 369.710989 -293.274284) (xy 369.75361 -293.249677) (xy 369.799626 -293.232225) (xy 369.847845 -293.222381)
			(xy 369.89702 -293.2204) (xy 369.945875 -293.226332) (xy 369.993146 -293.240024) (xy 370.037608 -293.261122)
			(xy 370.078111 -293.289078) (xy 370.113604 -293.32317) (xy 370.143169 -293.362514) (xy 370.16604 -293.406091)
			(xy 370.181624 -293.452772) (xy 370.189519 -293.501349) (xy 370.190014 -293.525956) (xy 370.518956 -293.525956)
			(xy 370.522916 -293.476902) (xy 370.534693 -293.429118) (xy 370.553984 -293.383842) (xy 370.580287 -293.342246)
			(xy 370.612922 -293.305409) (xy 370.651043 -293.274284) (xy 370.693664 -293.249677) (xy 370.73968 -293.232225)
			(xy 370.787899 -293.222381) (xy 370.837074 -293.2204) (xy 370.885929 -293.226332) (xy 370.9332 -293.240024)
			(xy 370.977662 -293.261122) (xy 371.018165 -293.289078) (xy 371.053658 -293.32317) (xy 371.083223 -293.362514)
			(xy 371.106094 -293.406091) (xy 371.121678 -293.452772) (xy 371.129573 -293.501349) (xy 371.130068 -293.525956)
			(xy 371.45901 -293.525956) (xy 371.46297 -293.476902) (xy 371.474747 -293.429118) (xy 371.494038 -293.383842)
			(xy 371.520341 -293.342246) (xy 371.552976 -293.305409) (xy 371.591097 -293.274284) (xy 371.633718 -293.249677)
			(xy 371.679734 -293.232225) (xy 371.727953 -293.222381) (xy 371.777128 -293.2204) (xy 371.825983 -293.226332)
			(xy 371.873254 -293.240024) (xy 371.917716 -293.261122) (xy 371.958219 -293.289078) (xy 371.993712 -293.32317)
			(xy 372.023277 -293.362514) (xy 372.046148 -293.406091) (xy 372.061732 -293.452772) (xy 372.069627 -293.501349)
			(xy 372.070122 -293.525956) (xy 372.399064 -293.525956) (xy 372.403024 -293.476902) (xy 372.414801 -293.429118)
			(xy 372.434092 -293.383842) (xy 372.460395 -293.342246) (xy 372.49303 -293.305409) (xy 372.531151 -293.274284)
			(xy 372.573772 -293.249677) (xy 372.619788 -293.232225) (xy 372.668007 -293.222381) (xy 372.717182 -293.2204)
			(xy 372.766037 -293.226332) (xy 372.813308 -293.240024) (xy 372.85777 -293.261122) (xy 372.898273 -293.289078)
			(xy 372.933766 -293.32317) (xy 372.963331 -293.362514) (xy 372.986202 -293.406091) (xy 373.001786 -293.452772)
			(xy 373.009681 -293.501349) (xy 373.010176 -293.525956) (xy 373.339118 -293.525956) (xy 373.343078 -293.476902)
			(xy 373.354855 -293.429118) (xy 373.374146 -293.383842) (xy 373.400449 -293.342246) (xy 373.433084 -293.305409)
			(xy 373.471205 -293.274284) (xy 373.513826 -293.249677) (xy 373.559842 -293.232225) (xy 373.608061 -293.222381)
			(xy 373.657236 -293.2204) (xy 373.706091 -293.226332) (xy 373.753362 -293.240024) (xy 373.797824 -293.261122)
			(xy 373.838327 -293.289078) (xy 373.87382 -293.32317) (xy 373.903385 -293.362514) (xy 373.926256 -293.406091)
			(xy 373.94184 -293.452772) (xy 373.949735 -293.501349) (xy 373.95023 -293.525956) (xy 374.278918 -293.525956)
			(xy 374.282878 -293.476902) (xy 374.294655 -293.429118) (xy 374.313946 -293.383842) (xy 374.340249 -293.342246)
			(xy 374.372884 -293.305409) (xy 374.411005 -293.274284) (xy 374.453626 -293.249677) (xy 374.499642 -293.232225)
			(xy 374.547861 -293.222381) (xy 374.597036 -293.2204) (xy 374.645891 -293.226332) (xy 374.693162 -293.240024)
			(xy 374.737624 -293.261122) (xy 374.778127 -293.289078) (xy 374.81362 -293.32317) (xy 374.843185 -293.362514)
			(xy 374.866056 -293.406091) (xy 374.88164 -293.452772) (xy 374.889535 -293.501349) (xy 374.89003 -293.525956)
			(xy 375.218972 -293.525956) (xy 375.222932 -293.476902) (xy 375.234709 -293.429118) (xy 375.254 -293.383842)
			(xy 375.280303 -293.342246) (xy 375.312938 -293.305409) (xy 375.351059 -293.274284) (xy 375.39368 -293.249677)
			(xy 375.439696 -293.232225) (xy 375.487915 -293.222381) (xy 375.53709 -293.2204) (xy 375.585945 -293.226332)
			(xy 375.633216 -293.240024) (xy 375.677678 -293.261122) (xy 375.718181 -293.289078) (xy 375.753674 -293.32317)
			(xy 375.783239 -293.362514) (xy 375.80611 -293.406091) (xy 375.821694 -293.452772) (xy 375.829589 -293.501349)
			(xy 375.830084 -293.525956) (xy 376.148595 -293.525956) (xy 376.15269 -293.475228) (xy 376.164869 -293.425814)
			(xy 376.184817 -293.378994) (xy 376.212018 -293.33598) (xy 376.245766 -293.297886) (xy 376.285188 -293.265699)
			(xy 376.329262 -293.240253) (xy 376.376848 -293.222206) (xy 376.426712 -293.212026) (xy 376.477564 -293.209977)
			(xy 376.528085 -293.216111) (xy 376.576969 -293.230271) (xy 376.622948 -293.252088) (xy 376.664832 -293.280998)
			(xy 376.701536 -293.316253) (xy 376.732109 -293.356939) (xy 376.75576 -293.402002) (xy 376.771876 -293.450276)
			(xy 376.78004 -293.50051) (xy 376.780552 -293.525956) (xy 377.09908 -293.525956) (xy 377.10304 -293.476902)
			(xy 377.114817 -293.429118) (xy 377.134108 -293.383842) (xy 377.160411 -293.342246) (xy 377.193046 -293.305409)
			(xy 377.231167 -293.274284) (xy 377.273788 -293.249677) (xy 377.319804 -293.232225) (xy 377.368023 -293.222381)
			(xy 377.417198 -293.2204) (xy 377.466053 -293.226332) (xy 377.513324 -293.240024) (xy 377.557786 -293.261122)
			(xy 377.598289 -293.289078) (xy 377.633782 -293.32317) (xy 377.663347 -293.362514) (xy 377.686218 -293.406091)
			(xy 377.701802 -293.452772) (xy 377.709697 -293.501349) (xy 377.710192 -293.525956) (xy 377.709697 -293.550563)
			(xy 377.701802 -293.59914) (xy 377.686218 -293.645821) (xy 377.663347 -293.689398) (xy 377.633782 -293.728742)
			(xy 377.598289 -293.762834) (xy 377.557786 -293.79079) (xy 377.513324 -293.811888) (xy 377.466053 -293.82558)
			(xy 377.417198 -293.831512) (xy 377.368023 -293.829531) (xy 377.319804 -293.819687) (xy 377.273788 -293.802235)
			(xy 377.231167 -293.777628) (xy 377.193046 -293.746503) (xy 377.160411 -293.709666) (xy 377.134108 -293.66807)
			(xy 377.114817 -293.622794) (xy 377.10304 -293.57501) (xy 377.09908 -293.525956) (xy 376.780552 -293.525956)
			(xy 376.78004 -293.551402) (xy 376.771876 -293.601636) (xy 376.75576 -293.64991) (xy 376.732109 -293.694973)
			(xy 376.701536 -293.735659) (xy 376.664832 -293.770914) (xy 376.622948 -293.799824) (xy 376.576969 -293.821641)
			(xy 376.528085 -293.835801) (xy 376.477564 -293.841935) (xy 376.426712 -293.839886) (xy 376.376848 -293.829706)
			(xy 376.329262 -293.811659) (xy 376.285188 -293.786213) (xy 376.245766 -293.754026) (xy 376.212018 -293.715932)
			(xy 376.184817 -293.672918) (xy 376.164869 -293.626098) (xy 376.15269 -293.576684) (xy 376.148595 -293.525956)
			(xy 375.830084 -293.525956) (xy 375.829589 -293.550563) (xy 375.821694 -293.59914) (xy 375.80611 -293.645821)
			(xy 375.783239 -293.689398) (xy 375.753674 -293.728742) (xy 375.718181 -293.762834) (xy 375.677678 -293.79079)
			(xy 375.633216 -293.811888) (xy 375.585945 -293.82558) (xy 375.53709 -293.831512) (xy 375.487915 -293.829531)
			(xy 375.439696 -293.819687) (xy 375.39368 -293.802235) (xy 375.351059 -293.777628) (xy 375.312938 -293.746503)
			(xy 375.280303 -293.709666) (xy 375.254 -293.66807) (xy 375.234709 -293.622794) (xy 375.222932 -293.57501)
			(xy 375.218972 -293.525956) (xy 374.89003 -293.525956) (xy 374.889535 -293.550563) (xy 374.88164 -293.59914)
			(xy 374.866056 -293.645821) (xy 374.843185 -293.689398) (xy 374.81362 -293.728742) (xy 374.778127 -293.762834)
			(xy 374.737624 -293.79079) (xy 374.693162 -293.811888) (xy 374.645891 -293.82558) (xy 374.597036 -293.831512)
			(xy 374.547861 -293.829531) (xy 374.499642 -293.819687) (xy 374.453626 -293.802235) (xy 374.411005 -293.777628)
			(xy 374.372884 -293.746503) (xy 374.340249 -293.709666) (xy 374.313946 -293.66807) (xy 374.294655 -293.622794)
			(xy 374.282878 -293.57501) (xy 374.278918 -293.525956) (xy 373.95023 -293.525956) (xy 373.949735 -293.550563)
			(xy 373.94184 -293.59914) (xy 373.926256 -293.645821) (xy 373.903385 -293.689398) (xy 373.87382 -293.728742)
			(xy 373.838327 -293.762834) (xy 373.797824 -293.79079) (xy 373.753362 -293.811888) (xy 373.706091 -293.82558)
			(xy 373.657236 -293.831512) (xy 373.608061 -293.829531) (xy 373.559842 -293.819687) (xy 373.513826 -293.802235)
			(xy 373.471205 -293.777628) (xy 373.433084 -293.746503) (xy 373.400449 -293.709666) (xy 373.374146 -293.66807)
			(xy 373.354855 -293.622794) (xy 373.343078 -293.57501) (xy 373.339118 -293.525956) (xy 373.010176 -293.525956)
			(xy 373.009681 -293.550563) (xy 373.001786 -293.59914) (xy 372.986202 -293.645821) (xy 372.963331 -293.689398)
			(xy 372.933766 -293.728742) (xy 372.898273 -293.762834) (xy 372.85777 -293.79079) (xy 372.813308 -293.811888)
			(xy 372.766037 -293.82558) (xy 372.717182 -293.831512) (xy 372.668007 -293.829531) (xy 372.619788 -293.819687)
			(xy 372.573772 -293.802235) (xy 372.531151 -293.777628) (xy 372.49303 -293.746503) (xy 372.460395 -293.709666)
			(xy 372.434092 -293.66807) (xy 372.414801 -293.622794) (xy 372.403024 -293.57501) (xy 372.399064 -293.525956)
			(xy 372.070122 -293.525956) (xy 372.069627 -293.550563) (xy 372.061732 -293.59914) (xy 372.046148 -293.645821)
			(xy 372.023277 -293.689398) (xy 371.993712 -293.728742) (xy 371.958219 -293.762834) (xy 371.917716 -293.79079)
			(xy 371.873254 -293.811888) (xy 371.825983 -293.82558) (xy 371.777128 -293.831512) (xy 371.727953 -293.829531)
			(xy 371.679734 -293.819687) (xy 371.633718 -293.802235) (xy 371.591097 -293.777628) (xy 371.552976 -293.746503)
			(xy 371.520341 -293.709666) (xy 371.494038 -293.66807) (xy 371.474747 -293.622794) (xy 371.46297 -293.57501)
			(xy 371.45901 -293.525956) (xy 371.130068 -293.525956) (xy 371.129573 -293.550563) (xy 371.121678 -293.59914)
			(xy 371.106094 -293.645821) (xy 371.083223 -293.689398) (xy 371.053658 -293.728742) (xy 371.018165 -293.762834)
			(xy 370.977662 -293.79079) (xy 370.9332 -293.811888) (xy 370.885929 -293.82558) (xy 370.837074 -293.831512)
			(xy 370.787899 -293.829531) (xy 370.73968 -293.819687) (xy 370.693664 -293.802235) (xy 370.651043 -293.777628)
			(xy 370.612922 -293.746503) (xy 370.580287 -293.709666) (xy 370.553984 -293.66807) (xy 370.534693 -293.622794)
			(xy 370.522916 -293.57501) (xy 370.518956 -293.525956) (xy 370.190014 -293.525956) (xy 370.189519 -293.550563)
			(xy 370.181624 -293.59914) (xy 370.16604 -293.645821) (xy 370.143169 -293.689398) (xy 370.113604 -293.728742)
			(xy 370.078111 -293.762834) (xy 370.037608 -293.79079) (xy 369.993146 -293.811888) (xy 369.945875 -293.82558)
			(xy 369.89702 -293.831512) (xy 369.847845 -293.829531) (xy 369.799626 -293.819687) (xy 369.75361 -293.802235)
			(xy 369.710989 -293.777628) (xy 369.672868 -293.746503) (xy 369.640233 -293.709666) (xy 369.61393 -293.66807)
			(xy 369.594639 -293.622794) (xy 369.582862 -293.57501) (xy 369.578902 -293.525956) (xy 368.31016 -293.525956)
			(xy 368.309665 -293.550563) (xy 368.30177 -293.59914) (xy 368.286186 -293.645821) (xy 368.263315 -293.689398)
			(xy 368.23375 -293.728742) (xy 368.198257 -293.762834) (xy 368.157754 -293.79079) (xy 368.113292 -293.811888)
			(xy 368.066021 -293.82558) (xy 368.017166 -293.831512) (xy 367.967991 -293.829531) (xy 367.919772 -293.819687)
			(xy 367.873756 -293.802235) (xy 367.831135 -293.777628) (xy 367.793014 -293.746503) (xy 367.760379 -293.709666)
			(xy 367.734076 -293.66807) (xy 367.714785 -293.622794) (xy 367.703008 -293.57501) (xy 367.699048 -293.525956)
			(xy 367.377472 -293.525956) (xy 367.377472 -293.932864) (xy 367.377991 -293.943792) (xy 367.387078 -293.963669)
			(xy 367.394998 -293.971218) (xy 367.405412 -293.980362) (xy 367.452402 -294.021256) (xy 367.456721 -294.024859)
			(xy 367.466592 -294.030246) (xy 367.47196 -294.031924) (xy 367.482374 -294.034972) (xy 367.493042 -294.033448)
			(xy 367.503405 -294.03213) (xy 367.524251 -294.030731) (xy 367.534698 -294.030654) (xy 367.55869 -294.031124)
			(xy 367.606085 -294.03863) (xy 367.651721 -294.053457) (xy 367.694477 -294.07524) (xy 367.733299 -294.103442)
			(xy 367.767232 -294.13737) (xy 367.795439 -294.176189) (xy 367.817228 -294.218942) (xy 367.832061 -294.264576)
			(xy 367.839572 -294.31197) (xy 367.840006 -294.335962) (xy 369.109002 -294.335962) (xy 369.112962 -294.286908)
			(xy 369.124739 -294.239124) (xy 369.14403 -294.193848) (xy 369.170333 -294.152252) (xy 369.202968 -294.115415)
			(xy 369.241089 -294.08429) (xy 369.28371 -294.059683) (xy 369.329726 -294.042231) (xy 369.377945 -294.032387)
			(xy 369.42712 -294.030406) (xy 369.475975 -294.036338) (xy 369.523246 -294.05003) (xy 369.567708 -294.071128)
			(xy 369.608211 -294.099084) (xy 369.643704 -294.133176) (xy 369.673269 -294.17252) (xy 369.69614 -294.216097)
			(xy 369.711724 -294.262778) (xy 369.719619 -294.311355) (xy 369.720114 -294.335962) (xy 370.049056 -294.335962)
			(xy 370.053016 -294.286908) (xy 370.064793 -294.239124) (xy 370.084084 -294.193848) (xy 370.110387 -294.152252)
			(xy 370.143022 -294.115415) (xy 370.181143 -294.08429) (xy 370.223764 -294.059683) (xy 370.26978 -294.042231)
			(xy 370.317999 -294.032387) (xy 370.367174 -294.030406) (xy 370.416029 -294.036338) (xy 370.4633 -294.05003)
			(xy 370.507762 -294.071128) (xy 370.548265 -294.099084) (xy 370.583758 -294.133176) (xy 370.613323 -294.17252)
			(xy 370.636194 -294.216097) (xy 370.651778 -294.262778) (xy 370.659673 -294.311355) (xy 370.660168 -294.335962)
			(xy 370.98911 -294.335962) (xy 370.99307 -294.286908) (xy 371.004847 -294.239124) (xy 371.024138 -294.193848)
			(xy 371.050441 -294.152252) (xy 371.083076 -294.115415) (xy 371.121197 -294.08429) (xy 371.163818 -294.059683)
			(xy 371.209834 -294.042231) (xy 371.258053 -294.032387) (xy 371.307228 -294.030406) (xy 371.356083 -294.036338)
			(xy 371.403354 -294.05003) (xy 371.447816 -294.071128) (xy 371.488319 -294.099084) (xy 371.523812 -294.133176)
			(xy 371.553377 -294.17252) (xy 371.576248 -294.216097) (xy 371.591832 -294.262778) (xy 371.599727 -294.311355)
			(xy 371.600222 -294.335962) (xy 371.92891 -294.335962) (xy 371.93287 -294.286908) (xy 371.944647 -294.239124)
			(xy 371.963938 -294.193848) (xy 371.990241 -294.152252) (xy 372.022876 -294.115415) (xy 372.060997 -294.08429)
			(xy 372.103618 -294.059683) (xy 372.149634 -294.042231) (xy 372.197853 -294.032387) (xy 372.247028 -294.030406)
			(xy 372.295883 -294.036338) (xy 372.343154 -294.05003) (xy 372.387616 -294.071128) (xy 372.428119 -294.099084)
			(xy 372.463612 -294.133176) (xy 372.493177 -294.17252) (xy 372.516048 -294.216097) (xy 372.531632 -294.262778)
			(xy 372.539527 -294.311355) (xy 372.540022 -294.335962) (xy 372.868964 -294.335962) (xy 372.872924 -294.286908)
			(xy 372.884701 -294.239124) (xy 372.903992 -294.193848) (xy 372.930295 -294.152252) (xy 372.96293 -294.115415)
			(xy 373.001051 -294.08429) (xy 373.043672 -294.059683) (xy 373.089688 -294.042231) (xy 373.137907 -294.032387)
			(xy 373.187082 -294.030406) (xy 373.235937 -294.036338) (xy 373.283208 -294.05003) (xy 373.32767 -294.071128)
			(xy 373.368173 -294.099084) (xy 373.403666 -294.133176) (xy 373.433231 -294.17252) (xy 373.456102 -294.216097)
			(xy 373.471686 -294.262778) (xy 373.479581 -294.311355) (xy 373.480076 -294.335962) (xy 373.809018 -294.335962)
			(xy 373.812978 -294.286908) (xy 373.824755 -294.239124) (xy 373.844046 -294.193848) (xy 373.870349 -294.152252)
			(xy 373.902984 -294.115415) (xy 373.941105 -294.08429) (xy 373.983726 -294.059683) (xy 374.029742 -294.042231)
			(xy 374.077961 -294.032387) (xy 374.127136 -294.030406) (xy 374.175991 -294.036338) (xy 374.223262 -294.05003)
			(xy 374.267724 -294.071128) (xy 374.308227 -294.099084) (xy 374.34372 -294.133176) (xy 374.373285 -294.17252)
			(xy 374.396156 -294.216097) (xy 374.41174 -294.262778) (xy 374.419635 -294.311355) (xy 374.42013 -294.335962)
			(xy 374.749072 -294.335962) (xy 374.753032 -294.286908) (xy 374.764809 -294.239124) (xy 374.7841 -294.193848)
			(xy 374.810403 -294.152252) (xy 374.843038 -294.115415) (xy 374.881159 -294.08429) (xy 374.92378 -294.059683)
			(xy 374.969796 -294.042231) (xy 375.018015 -294.032387) (xy 375.06719 -294.030406) (xy 375.116045 -294.036338)
			(xy 375.163316 -294.05003) (xy 375.207778 -294.071128) (xy 375.248281 -294.099084) (xy 375.283774 -294.133176)
			(xy 375.313339 -294.17252) (xy 375.33621 -294.216097) (xy 375.351794 -294.262778) (xy 375.359689 -294.311355)
			(xy 375.360184 -294.335962) (xy 375.689126 -294.335962) (xy 375.693086 -294.286908) (xy 375.704863 -294.239124)
			(xy 375.724154 -294.193848) (xy 375.750457 -294.152252) (xy 375.783092 -294.115415) (xy 375.821213 -294.08429)
			(xy 375.863834 -294.059683) (xy 375.90985 -294.042231) (xy 375.958069 -294.032387) (xy 376.007244 -294.030406)
			(xy 376.056099 -294.036338) (xy 376.10337 -294.05003) (xy 376.147832 -294.071128) (xy 376.188335 -294.099084)
			(xy 376.223828 -294.133176) (xy 376.253393 -294.17252) (xy 376.276264 -294.216097) (xy 376.291848 -294.262778)
			(xy 376.299743 -294.311355) (xy 376.300238 -294.335962) (xy 376.628926 -294.335962) (xy 376.632886 -294.286908)
			(xy 376.644663 -294.239124) (xy 376.663954 -294.193848) (xy 376.690257 -294.152252) (xy 376.722892 -294.115415)
			(xy 376.761013 -294.08429) (xy 376.803634 -294.059683) (xy 376.84965 -294.042231) (xy 376.897869 -294.032387)
			(xy 376.947044 -294.030406) (xy 376.995899 -294.036338) (xy 377.04317 -294.05003) (xy 377.087632 -294.071128)
			(xy 377.128135 -294.099084) (xy 377.163628 -294.133176) (xy 377.193193 -294.17252) (xy 377.216064 -294.216097)
			(xy 377.231648 -294.262778) (xy 377.239543 -294.311355) (xy 377.240038 -294.335962) (xy 377.239543 -294.360569)
			(xy 377.231648 -294.409146) (xy 377.216064 -294.455827) (xy 377.193193 -294.499404) (xy 377.163628 -294.538748)
			(xy 377.128135 -294.57284) (xy 377.087632 -294.600796) (xy 377.04317 -294.621894) (xy 376.995899 -294.635586)
			(xy 376.947044 -294.641518) (xy 376.897869 -294.639537) (xy 376.84965 -294.629693) (xy 376.803634 -294.612241)
			(xy 376.761013 -294.587634) (xy 376.722892 -294.556509) (xy 376.690257 -294.519672) (xy 376.663954 -294.478076)
			(xy 376.644663 -294.4328) (xy 376.632886 -294.385016) (xy 376.628926 -294.335962) (xy 376.300238 -294.335962)
			(xy 376.299743 -294.360569) (xy 376.291848 -294.409146) (xy 376.276264 -294.455827) (xy 376.253393 -294.499404)
			(xy 376.223828 -294.538748) (xy 376.188335 -294.57284) (xy 376.147832 -294.600796) (xy 376.10337 -294.621894)
			(xy 376.056099 -294.635586) (xy 376.007244 -294.641518) (xy 375.958069 -294.639537) (xy 375.90985 -294.629693)
			(xy 375.863834 -294.612241) (xy 375.821213 -294.587634) (xy 375.783092 -294.556509) (xy 375.750457 -294.519672)
			(xy 375.724154 -294.478076) (xy 375.704863 -294.4328) (xy 375.693086 -294.385016) (xy 375.689126 -294.335962)
			(xy 375.360184 -294.335962) (xy 375.359689 -294.360569) (xy 375.351794 -294.409146) (xy 375.33621 -294.455827)
			(xy 375.313339 -294.499404) (xy 375.283774 -294.538748) (xy 375.248281 -294.57284) (xy 375.207778 -294.600796)
			(xy 375.163316 -294.621894) (xy 375.116045 -294.635586) (xy 375.06719 -294.641518) (xy 375.018015 -294.639537)
			(xy 374.969796 -294.629693) (xy 374.92378 -294.612241) (xy 374.881159 -294.587634) (xy 374.843038 -294.556509)
			(xy 374.810403 -294.519672) (xy 374.7841 -294.478076) (xy 374.764809 -294.4328) (xy 374.753032 -294.385016)
			(xy 374.749072 -294.335962) (xy 374.42013 -294.335962) (xy 374.419635 -294.360569) (xy 374.41174 -294.409146)
			(xy 374.396156 -294.455827) (xy 374.373285 -294.499404) (xy 374.34372 -294.538748) (xy 374.308227 -294.57284)
			(xy 374.267724 -294.600796) (xy 374.223262 -294.621894) (xy 374.175991 -294.635586) (xy 374.127136 -294.641518)
			(xy 374.077961 -294.639537) (xy 374.029742 -294.629693) (xy 373.983726 -294.612241) (xy 373.941105 -294.587634)
			(xy 373.902984 -294.556509) (xy 373.870349 -294.519672) (xy 373.844046 -294.478076) (xy 373.824755 -294.4328)
			(xy 373.812978 -294.385016) (xy 373.809018 -294.335962) (xy 373.480076 -294.335962) (xy 373.479581 -294.360569)
			(xy 373.471686 -294.409146) (xy 373.456102 -294.455827) (xy 373.433231 -294.499404) (xy 373.403666 -294.538748)
			(xy 373.368173 -294.57284) (xy 373.32767 -294.600796) (xy 373.283208 -294.621894) (xy 373.235937 -294.635586)
			(xy 373.187082 -294.641518) (xy 373.137907 -294.639537) (xy 373.089688 -294.629693) (xy 373.043672 -294.612241)
			(xy 373.001051 -294.587634) (xy 372.96293 -294.556509) (xy 372.930295 -294.519672) (xy 372.903992 -294.478076)
			(xy 372.884701 -294.4328) (xy 372.872924 -294.385016) (xy 372.868964 -294.335962) (xy 372.540022 -294.335962)
			(xy 372.539527 -294.360569) (xy 372.531632 -294.409146) (xy 372.516048 -294.455827) (xy 372.493177 -294.499404)
			(xy 372.463612 -294.538748) (xy 372.428119 -294.57284) (xy 372.387616 -294.600796) (xy 372.343154 -294.621894)
			(xy 372.295883 -294.635586) (xy 372.247028 -294.641518) (xy 372.197853 -294.639537) (xy 372.149634 -294.629693)
			(xy 372.103618 -294.612241) (xy 372.060997 -294.587634) (xy 372.022876 -294.556509) (xy 371.990241 -294.519672)
			(xy 371.963938 -294.478076) (xy 371.944647 -294.4328) (xy 371.93287 -294.385016) (xy 371.92891 -294.335962)
			(xy 371.600222 -294.335962) (xy 371.599727 -294.360569) (xy 371.591832 -294.409146) (xy 371.576248 -294.455827)
			(xy 371.553377 -294.499404) (xy 371.523812 -294.538748) (xy 371.488319 -294.57284) (xy 371.447816 -294.600796)
			(xy 371.403354 -294.621894) (xy 371.356083 -294.635586) (xy 371.307228 -294.641518) (xy 371.258053 -294.639537)
			(xy 371.209834 -294.629693) (xy 371.163818 -294.612241) (xy 371.121197 -294.587634) (xy 371.083076 -294.556509)
			(xy 371.050441 -294.519672) (xy 371.024138 -294.478076) (xy 371.004847 -294.4328) (xy 370.99307 -294.385016)
			(xy 370.98911 -294.335962) (xy 370.660168 -294.335962) (xy 370.659673 -294.360569) (xy 370.651778 -294.409146)
			(xy 370.636194 -294.455827) (xy 370.613323 -294.499404) (xy 370.583758 -294.538748) (xy 370.548265 -294.57284)
			(xy 370.507762 -294.600796) (xy 370.4633 -294.621894) (xy 370.416029 -294.635586) (xy 370.367174 -294.641518)
			(xy 370.317999 -294.639537) (xy 370.26978 -294.629693) (xy 370.223764 -294.612241) (xy 370.181143 -294.587634)
			(xy 370.143022 -294.556509) (xy 370.110387 -294.519672) (xy 370.084084 -294.478076) (xy 370.064793 -294.4328)
			(xy 370.053016 -294.385016) (xy 370.049056 -294.335962) (xy 369.720114 -294.335962) (xy 369.719619 -294.360569)
			(xy 369.711724 -294.409146) (xy 369.69614 -294.455827) (xy 369.673269 -294.499404) (xy 369.643704 -294.538748)
			(xy 369.608211 -294.57284) (xy 369.567708 -294.600796) (xy 369.523246 -294.621894) (xy 369.475975 -294.635586)
			(xy 369.42712 -294.641518) (xy 369.377945 -294.639537) (xy 369.329726 -294.629693) (xy 369.28371 -294.612241)
			(xy 369.241089 -294.587634) (xy 369.202968 -294.556509) (xy 369.170333 -294.519672) (xy 369.14403 -294.478076)
			(xy 369.124739 -294.4328) (xy 369.112962 -294.385016) (xy 369.109002 -294.335962) (xy 367.840006 -294.335962)
			(xy 367.839548 -294.360062) (xy 367.831969 -294.407664) (xy 367.81701 -294.453485) (xy 367.79504 -294.496388)
			(xy 367.766607 -294.53531) (xy 367.749836 -294.552624) (xy 367.743305 -294.559694) (xy 367.735609 -294.577319)
			(xy 367.73485 -294.586914) (xy 367.733072 -294.64) (xy 367.735358 -294.642032) (xy 367.752435 -294.659733)
			(xy 367.781365 -294.699508) (xy 367.803708 -294.743323) (xy 367.818913 -294.790097) (xy 367.826606 -294.838674)
			(xy 367.827052 -294.863266) (xy 367.827052 -295.043098) (xy 367.827052 -295.402) (xy 367.827539 -295.412011)
			(xy 367.835197 -295.430511) (xy 367.849348 -295.444676) (xy 367.867841 -295.452351) (xy 367.877852 -295.4528)
			(xy 373.29364 -295.4528) (xy 373.302532 -295.452468) (xy 373.319244 -295.446386) (xy 373.332854 -295.434939)
			(xy 373.337582 -295.4274) (xy 373.38127 -295.3512) (xy 373.384417 -295.345324) (xy 373.3879 -295.332461)
			(xy 373.388128 -295.3258) (xy 373.388128 -295.31183) (xy 373.379746 -295.297352) (xy 373.375428 -295.289224)
			(xy 373.364168 -295.26704) (xy 373.348215 -295.219922) (xy 373.340118 -295.17084) (xy 373.339614 -295.145968)
			(xy 373.340136 -295.120713) (xy 373.348449 -295.070891) (xy 373.36485 -295.023117) (xy 373.388891 -294.978694)
			(xy 373.419915 -294.938834) (xy 373.457077 -294.904624) (xy 373.499363 -294.876998) (xy 373.545619 -294.856708)
			(xy 373.594584 -294.844308) (xy 373.644922 -294.840137) (xy 373.69526 -294.844308) (xy 373.744225 -294.856708)
			(xy 373.790481 -294.876998) (xy 373.832767 -294.904624) (xy 373.869929 -294.938834) (xy 373.900953 -294.978694)
			(xy 373.924994 -295.023117) (xy 373.941395 -295.070891) (xy 373.949708 -295.120713) (xy 373.95023 -295.145968)
			(xy 373.949663 -295.172877) (xy 373.940232 -295.225861) (xy 373.921658 -295.276372) (xy 373.908574 -295.299892)
			(xy 373.901716 -295.31183) (xy 373.901462 -295.339008) (xy 373.952262 -295.4274) (xy 373.957041 -295.434892)
			(xy 373.970646 -295.446302) (xy 373.987327 -295.452389) (xy 373.996204 -295.4528) (xy 378.433838 -295.4528)
			(xy 378.443905 -295.45237) (xy 378.462499 -295.444646) (xy 378.469906 -295.437814) (xy 378.566934 -295.340786)
			(xy 378.573785 -295.33339) (xy 378.581525 -295.314791) (xy 378.58192 -295.304718) (xy 378.58192 -294.559736)
			(xy 378.581865 -294.555665) (xy 378.580585 -294.547624) (xy 378.57938 -294.543734) (xy 378.571506 -294.520366)
			(xy 378.566934 -294.51427) (xy 378.553413 -294.494667) (xy 378.531967 -294.452151) (xy 378.517376 -294.406822)
			(xy 378.509993 -294.359779) (xy 378.509998 -294.31216) (xy 378.51739 -294.265118) (xy 378.53199 -294.219792)
			(xy 378.553445 -294.17728) (xy 378.566934 -294.157654) (xy 378.571506 -294.151558) (xy 378.57938 -294.12819)
			(xy 378.58056 -294.124295) (xy 378.581836 -294.116257) (xy 378.58192 -294.112188) (xy 378.58192 -293.90975)
			(xy 378.581219 -293.897592) (xy 378.570077 -293.875977) (xy 378.560584 -293.868348) (xy 378.492766 -293.820088)
			(xy 378.492258 -293.819834) (xy 378.483281 -293.814242) (xy 378.46255 -293.810173) (xy 378.452126 -293.81196)
			(xy 378.426437 -293.82093) (xy 378.372903 -293.830636) (xy 378.3457 -293.831264) (xy 378.344938 -293.831264)
			(xy 378.320944 -293.830821) (xy 378.273547 -293.823318) (xy 378.227907 -293.808493) (xy 378.185149 -293.786709)
			(xy 378.146325 -293.758503) (xy 378.112393 -293.72457) (xy 378.084188 -293.685746) (xy 378.062405 -293.642988)
			(xy 378.04758 -293.597347) (xy 378.040079 -293.54995) (xy 378.03963 -293.525956) (xy 378.040122 -293.501096)
			(xy 378.048184 -293.452033) (xy 378.064088 -293.404924) (xy 378.087414 -293.361015) (xy 378.117545 -293.321464)
			(xy 378.153685 -293.287317) (xy 378.173996 -293.272972) (xy 378.183648 -293.266622) (xy 378.195078 -293.247064)
			(xy 378.203714 -293.157656) (xy 378.20419 -293.146466) (xy 378.196668 -293.125397) (xy 378.189236 -293.117016)
			(xy 378.0663 -292.99408) (xy 378.033788 -292.989) (xy 378.019056 -292.99662) (xy 377.996617 -293.007634)
			(xy 377.949127 -293.023226) (xy 377.899775 -293.031151) (xy 377.874784 -293.031672) (xy 377.84998 -293.031209)
			(xy 377.800985 -293.023442) (xy 377.753809 -293.008104) (xy 377.709615 -292.98557) (xy 377.669492 -292.956398)
			(xy 377.634429 -292.921306) (xy 377.605291 -292.881158) (xy 377.582795 -292.836945) (xy 377.567496 -292.789756)
			(xy 377.55977 -292.740754) (xy 377.559316 -292.71595) (xy 377.559773 -292.690966) (xy 377.567612 -292.641619)
			(xy 377.583135 -292.594125) (xy 377.594114 -292.571678) (xy 377.601734 -292.556946) (xy 377.596654 -292.524434)
			(xy 377.257056 -292.184836) (xy 377.25096 -292.181534) (xy 377.22591 -292.16678) (xy 377.18121 -292.129621)
			(xy 377.144064 -292.084909) (xy 377.129294 -292.059868) (xy 377.125992 -292.053772) (xy 377.01982 -291.9476)
			(xy 377.013179 -291.941495) (xy 376.996794 -291.933978) (xy 376.97882 -291.932585) (xy 376.970036 -291.934646)
			(xy 376.87123 -291.96284) (xy 376.85218 -291.982652) (xy 376.849132 -291.996114) (xy 376.841889 -292.024621)
			(xy 376.820111 -292.079255) (xy 376.790465 -292.130052) (xy 376.75361 -292.175887) (xy 376.71036 -292.215744)
			(xy 376.661674 -292.248742) (xy 376.60863 -292.274149) (xy 376.552403 -292.291403) (xy 376.494238 -292.300121)
			(xy 376.46483 -292.30066) (xy 376.436633 -292.300159) (xy 376.380812 -292.292138) (xy 376.326701 -292.276254)
			(xy 376.2754 -292.252831) (xy 376.227956 -292.222347) (xy 376.185332 -292.18542) (xy 376.148398 -292.142804)
			(xy 376.117904 -292.095365) (xy 376.094472 -292.044069) (xy 376.078578 -291.989961) (xy 376.070546 -291.934141)
			(xy 376.070114 -291.905944) (xy 376.07066 -291.876539) (xy 376.079392 -291.818382) (xy 376.096655 -291.762163)
			(xy 376.122067 -291.709127) (xy 376.155065 -291.660448) (xy 376.19492 -291.617202) (xy 376.240749 -291.580348)
			(xy 376.291538 -291.550699) (xy 376.346163 -291.528913) (xy 376.37466 -291.521642) (xy 376.388122 -291.518594)
			(xy 376.407934 -291.499544) (xy 376.436128 -291.400738) (xy 376.438267 -291.391964) (xy 376.436884 -291.373969)
			(xy 376.429301 -291.357592) (xy 376.423174 -291.350954) (xy 376.371866 -291.299646) (xy 376.364249 -291.292668)
			(xy 376.345109 -291.284953) (xy 376.334782 -291.28466) (xy 376.292364 -291.285676) (xy 376.258836 -291.286438)
			(xy 376.239786 -291.295328) (xy 376.232674 -291.30371) (xy 376.214537 -291.323633) (xy 376.172714 -291.357593)
			(xy 376.125735 -291.383962) (xy 376.074961 -291.401973) (xy 376.021867 -291.411106) (xy 375.99493 -291.41166)
			(xy 375.970118 -291.411176) (xy 375.921104 -291.403417) (xy 375.873907 -291.388087) (xy 375.829689 -291.365563)
			(xy 375.789539 -291.336399) (xy 375.754446 -291.301313) (xy 375.725273 -291.261169) (xy 375.702739 -291.216956)
			(xy 375.687399 -291.169762) (xy 375.67963 -291.12075) (xy 375.679208 -291.095938) (xy 375.679759 -291.069003)
			(xy 375.688908 -291.015916) (xy 375.70693 -290.96515) (xy 375.733303 -290.918178) (xy 375.767263 -290.87636)
			(xy 375.787158 -290.858194) (xy 375.79554 -290.851082) (xy 375.80443 -290.832032) (xy 375.805192 -290.798504)
			(xy 375.806208 -290.756086) (xy 375.805932 -290.745759) (xy 375.798195 -290.726625) (xy 375.791222 -290.719002)
			(xy 375.6533 -290.58108) (xy 375.626122 -290.574222) (xy 375.61266 -290.578286) (xy 375.591189 -290.584311)
			(xy 375.547072 -290.590808) (xy 375.524776 -290.59124) (xy 375.500785 -290.590768) (xy 375.453394 -290.583259)
			(xy 375.407762 -290.56843) (xy 375.36501 -290.546645) (xy 375.326192 -290.518442) (xy 375.292263 -290.484514)
			(xy 375.264059 -290.445697) (xy 375.242273 -290.402946) (xy 375.227443 -290.357313) (xy 375.219933 -290.309923)
			(xy 375.219468 -290.285932) (xy 375.21985 -290.263632) (xy 375.226349 -290.219508) (xy 375.232422 -290.198048)
			(xy 375.2342 -290.191698) (xy 375.234708 -290.178998) (xy 375.233184 -290.17214) (xy 375.231344 -290.165164)
			(xy 375.224377 -290.152536) (xy 375.219468 -290.147248) (xy 374.822466 -289.750246) (xy 374.815621 -289.742848)
			(xy 374.807896 -289.724249) (xy 374.80748 -289.714178) (xy 374.80748 -289.663632) (xy 374.803416 -289.649408)
			(xy 374.799098 -289.643312) (xy 374.786359 -289.622916) (xy 374.766769 -289.579) (xy 374.754308 -289.532556)
			(xy 374.751346 -289.508692) (xy 374.751092 -289.50666) (xy 374.751092 -289.506406) (xy 374.749568 -289.475926)
			(xy 374.749568 -289.460432) (xy 374.749822 -289.454336) (xy 374.7516 -289.439096) (xy 374.753632 -289.42538)
			(xy 374.759264 -289.39609) (xy 374.780362 -289.34031) (xy 374.795542 -289.314636) (xy 374.79986 -289.307778)
			(xy 374.803382 -289.301612) (xy 374.807235 -289.287951) (xy 374.80748 -289.280854) (xy 374.80748 -289.054032)
			(xy 374.806842 -289.042048) (xy 374.795979 -289.020687) (xy 374.786652 -289.013138) (xy 374.720612 -288.964878)
			(xy 374.71096 -288.95929) (xy 374.703506 -288.956384) (xy 374.687592 -288.954824) (xy 374.679718 -288.956242)
			(xy 374.656604 -288.963278) (xy 374.60888 -288.970799) (xy 374.584722 -288.971228) (xy 374.559461 -288.970737)
			(xy 374.509629 -288.962425) (xy 374.461844 -288.946023) (xy 374.417411 -288.92198) (xy 374.377542 -288.890951)
			(xy 374.343323 -288.853783) (xy 374.31569 -288.811489) (xy 374.295395 -288.765223) (xy 374.282992 -288.716248)
			(xy 374.27882 -288.6659) (xy 374.282992 -288.615552) (xy 374.295395 -288.566577) (xy 374.31569 -288.520311)
			(xy 374.343323 -288.478017) (xy 374.377542 -288.440849) (xy 374.417411 -288.40982) (xy 374.461844 -288.385777)
			(xy 374.509629 -288.369375) (xy 374.559461 -288.361063) (xy 374.584722 -288.360612) (xy 374.606948 -288.360972)
			(xy 374.65094 -288.367341) (xy 374.672352 -288.373312) (xy 374.675908 -288.374328) (xy 374.683528 -288.375598)
			(xy 374.693439 -288.376609) (xy 374.712774 -288.371896) (xy 374.72112 -288.366454) (xy 374.786398 -288.318702)
			(xy 374.792262 -288.314243) (xy 374.801317 -288.30263) (xy 374.804178 -288.295842) (xy 374.80748 -288.286698)
			(xy 374.80748 -288.058352) (xy 374.807401 -288.054609) (xy 374.806255 -288.04721) (xy 374.805194 -288.04362)
			(xy 374.799098 -288.023554) (xy 374.795542 -288.017966) (xy 374.784699 -287.999809) (xy 374.767567 -287.961145)
			(xy 374.755919 -287.92049) (xy 374.752616 -287.899602) (xy 374.751092 -287.886394) (xy 374.750584 -287.882076)
			(xy 374.749568 -287.857946) (xy 374.749568 -287.852866) (xy 374.749784 -287.841) (xy 374.751819 -287.817351)
			(xy 374.753632 -287.805622) (xy 374.75927 -287.776334) (xy 374.780376 -287.72056) (xy 374.795542 -287.694878)
			(xy 374.79986 -287.68802) (xy 374.803387 -287.681855) (xy 374.807252 -287.668195) (xy 374.80748 -287.661096)
			(xy 374.80748 -286.43834) (xy 374.8074 -286.434597) (xy 374.806253 -286.427199) (xy 374.805194 -286.423608)
			(xy 374.799098 -286.403542) (xy 374.795542 -286.397954) (xy 374.7847 -286.379797) (xy 374.767569 -286.341132)
			(xy 374.755923 -286.300477) (xy 374.752616 -286.27959) (xy 374.751092 -286.266382) (xy 374.750584 -286.262064)
			(xy 374.749568 -286.237934) (xy 374.749568 -286.232854) (xy 374.749784 -286.220988) (xy 374.75182 -286.197339)
			(xy 374.753632 -286.18561) (xy 374.759271 -286.156322) (xy 374.780379 -286.10055) (xy 374.795542 -286.074866)
			(xy 374.79986 -286.068008) (xy 374.803385 -286.061843) (xy 374.807247 -286.048182) (xy 374.80748 -286.041084)
			(xy 374.80748 -285.814262) (xy 374.806827 -285.802286) (xy 374.795947 -285.78095) (xy 374.786652 -285.773368)
			(xy 374.720612 -285.725108) (xy 374.71096 -285.71952) (xy 374.703506 -285.716612) (xy 374.687592 -285.715052)
			(xy 374.679718 -285.716472) (xy 374.656604 -285.723507) (xy 374.60888 -285.731028) (xy 374.584722 -285.731458)
			(xy 374.559459 -285.730967) (xy 374.509622 -285.722654) (xy 374.461832 -285.706251) (xy 374.417395 -285.682205)
			(xy 374.377521 -285.651173) (xy 374.3433 -285.614001) (xy 374.315663 -285.571703) (xy 374.295367 -285.525433)
			(xy 374.282963 -285.476453) (xy 374.27879 -285.4261) (xy 374.282963 -285.375747) (xy 374.295367 -285.326767)
			(xy 374.315663 -285.280497) (xy 374.3433 -285.238199) (xy 374.377521 -285.201027) (xy 374.417395 -285.169995)
			(xy 374.461832 -285.145949) (xy 374.509622 -285.129546) (xy 374.559459 -285.121233) (xy 374.584722 -285.120842)
			(xy 374.606948 -285.121202) (xy 374.65094 -285.127572) (xy 374.672352 -285.133542) (xy 374.675908 -285.134558)
			(xy 374.683528 -285.135828) (xy 374.693438 -285.13684) (xy 374.712771 -285.132121) (xy 374.72112 -285.126684)
			(xy 374.786398 -285.078932) (xy 374.792257 -285.074469) (xy 374.801296 -285.06285) (xy 374.804178 -285.056072)
			(xy 374.80748 -285.046928) (xy 374.80748 -284.818328) (xy 374.807399 -284.814585) (xy 374.80625 -284.807188)
			(xy 374.805194 -284.803596) (xy 374.799098 -284.78353) (xy 374.795542 -284.777942) (xy 374.784701 -284.759785)
			(xy 374.767571 -284.72112) (xy 374.755927 -284.680465) (xy 374.752616 -284.659578) (xy 374.751092 -284.64637)
			(xy 374.750584 -284.642052) (xy 374.749568 -284.617922) (xy 374.749568 -284.612842) (xy 374.749784 -284.600976)
			(xy 374.751821 -284.577328) (xy 374.753632 -284.565598) (xy 374.759272 -284.536311) (xy 374.780382 -284.480539)
			(xy 374.795542 -284.454854) (xy 374.79986 -284.447996) (xy 374.803384 -284.441831) (xy 374.807242 -284.42817)
			(xy 374.80748 -284.421072) (xy 374.80748 -283.198316) (xy 374.807398 -283.194573) (xy 374.806248 -283.187176)
			(xy 374.805194 -283.183584) (xy 374.799098 -283.163518) (xy 374.795542 -283.15793) (xy 374.784701 -283.139772)
			(xy 374.767573 -283.101107) (xy 374.755931 -283.060452) (xy 374.752616 -283.039566) (xy 374.751092 -283.026358)
			(xy 374.750584 -283.02204) (xy 374.749568 -282.99791) (xy 374.749568 -282.99283) (xy 374.749785 -282.980964)
			(xy 374.751823 -282.957316) (xy 374.753632 -282.945586) (xy 374.759273 -282.916299) (xy 374.780385 -282.860529)
			(xy 374.795542 -282.834842) (xy 374.79986 -282.827984) (xy 374.803382 -282.821818) (xy 374.807238 -282.808157)
			(xy 374.80748 -282.80106) (xy 374.80748 -282.574238) (xy 374.806843 -282.562253) (xy 374.795982 -282.54089)
			(xy 374.786652 -282.533344) (xy 374.720612 -282.485084) (xy 374.71096 -282.479496) (xy 374.703506 -282.476589)
			(xy 374.687592 -282.47503) (xy 374.679718 -282.476448) (xy 374.656604 -282.483484) (xy 374.60888 -282.491005)
			(xy 374.584722 -282.491434) (xy 374.559461 -282.490943) (xy 374.509627 -282.482631) (xy 374.461842 -282.466229)
			(xy 374.417408 -282.442185) (xy 374.377538 -282.411156) (xy 374.343319 -282.373986) (xy 374.315685 -282.331692)
			(xy 374.295389 -282.285425) (xy 374.282986 -282.236449) (xy 374.278814 -282.1861) (xy 374.282986 -282.135751)
			(xy 374.295389 -282.086775) (xy 374.315685 -282.040508) (xy 374.343319 -281.998214) (xy 374.377538 -281.961044)
			(xy 374.417408 -281.930015) (xy 374.461842 -281.905971) (xy 374.509627 -281.889569) (xy 374.559461 -281.881257)
			(xy 374.584722 -281.880818) (xy 374.606948 -281.881178) (xy 374.65094 -281.887547) (xy 374.672352 -281.893518)
			(xy 374.675908 -281.894534) (xy 374.683528 -281.895804) (xy 374.693439 -281.896815) (xy 374.712775 -281.892102)
			(xy 374.72112 -281.88666) (xy 374.786398 -281.838908) (xy 374.792255 -281.834443) (xy 374.801289 -281.822823)
			(xy 374.804178 -281.816048) (xy 374.80748 -281.806904) (xy 374.80748 -281.578304) (xy 374.807397 -281.574561)
			(xy 374.806245 -281.567165) (xy 374.805194 -281.563572) (xy 374.799098 -281.543506) (xy 374.795542 -281.537918)
			(xy 374.784702 -281.51976) (xy 374.767576 -281.481094) (xy 374.755935 -281.440439) (xy 374.752616 -281.419554)
			(xy 374.751092 -281.406346) (xy 374.750584 -281.402028) (xy 374.749568 -281.377898) (xy 374.749568 -281.372818)
			(xy 374.749782 -281.360951) (xy 374.751813 -281.337302) (xy 374.753632 -281.325574) (xy 374.759265 -281.296284)
			(xy 374.780363 -281.240505) (xy 374.795542 -281.21483) (xy 374.79986 -281.207972) (xy 374.803393 -281.201809)
			(xy 374.807272 -281.188148) (xy 374.80748 -281.181048) (xy 374.80748 -280.954226) (xy 374.80684 -280.942243)
			(xy 374.795976 -280.920884) (xy 374.786652 -280.913332) (xy 374.720612 -280.865072) (xy 374.71096 -280.859484)
			(xy 374.703506 -280.856578) (xy 374.687592 -280.855019) (xy 374.679718 -280.856436) (xy 374.656604 -280.863472)
			(xy 374.60888 -280.870993) (xy 374.584722 -280.871422) (xy 374.559462 -280.870931) (xy 374.50963 -280.862619)
			(xy 374.461847 -280.846218) (xy 374.417414 -280.822175) (xy 374.377546 -280.791147) (xy 374.343328 -280.753979)
			(xy 374.315695 -280.711686) (xy 374.295401 -280.665422) (xy 374.282998 -280.616447) (xy 374.278826 -280.5661)
			(xy 374.282998 -280.515753) (xy 374.295401 -280.466778) (xy 374.315695 -280.420514) (xy 374.343328 -280.378221)
			(xy 374.377546 -280.341053) (xy 374.417414 -280.310025) (xy 374.461847 -280.285982) (xy 374.50963 -280.269581)
			(xy 374.559462 -280.261269) (xy 374.584722 -280.260806) (xy 374.606948 -280.261166) (xy 374.65094 -280.267535)
			(xy 374.672352 -280.273506) (xy 374.675908 -280.274522) (xy 374.683528 -280.275792) (xy 374.693438 -280.276804)
			(xy 374.712774 -280.272089) (xy 374.72112 -280.266648) (xy 374.786398 -280.218896) (xy 374.792262 -280.214436)
			(xy 374.801316 -280.202823) (xy 374.804178 -280.196036) (xy 374.80748 -280.186892) (xy 374.80748 -279.958292)
			(xy 374.807396 -279.95455) (xy 374.806242 -279.947154) (xy 374.805194 -279.94356) (xy 374.799098 -279.923494)
			(xy 374.795542 -279.917906) (xy 374.784703 -279.899748) (xy 374.767578 -279.861082) (xy 374.755939 -279.820427)
			(xy 374.752616 -279.799542) (xy 374.751092 -279.786334) (xy 374.750584 -279.782016) (xy 374.749568 -279.757886)
			(xy 374.749568 -279.752806) (xy 374.749782 -279.740939) (xy 374.751814 -279.71729) (xy 374.753632 -279.705562)
			(xy 374.759266 -279.676272) (xy 374.780366 -279.620495) (xy 374.795542 -279.594818) (xy 374.79986 -279.58796)
			(xy 374.803392 -279.581797) (xy 374.807268 -279.568136) (xy 374.80748 -279.561036) (xy 374.80748 -278.33828)
			(xy 374.807403 -278.334537) (xy 374.806261 -278.327137) (xy 374.805194 -278.323548) (xy 374.799098 -278.303482)
			(xy 374.795542 -278.297894) (xy 374.784704 -278.279735) (xy 374.76758 -278.241069) (xy 374.755943 -278.200414)
			(xy 374.752616 -278.17953) (xy 374.751092 -278.166322) (xy 374.750584 -278.162004) (xy 374.749568 -278.137874)
			(xy 374.749568 -278.132794) (xy 374.749782 -278.120927) (xy 374.751815 -278.097279) (xy 374.753632 -278.08555)
			(xy 374.759267 -278.056261) (xy 374.780369 -278.000484) (xy 374.795542 -277.974806) (xy 374.79986 -277.967948)
			(xy 374.80339 -277.961784) (xy 374.807262 -277.948123) (xy 374.80748 -277.941024) (xy 374.80748 -277.714202)
			(xy 374.806835 -277.702221) (xy 374.795965 -277.680871) (xy 374.786652 -277.673308) (xy 374.720612 -277.625048)
			(xy 374.71096 -277.61946) (xy 374.703505 -277.616555) (xy 374.687592 -277.614996) (xy 374.679718 -277.616412)
			(xy 374.656604 -277.623449) (xy 374.60888 -277.630971) (xy 374.584722 -277.631398) (xy 374.559464 -277.630907)
			(xy 374.509636 -277.622596) (xy 374.461856 -277.606196) (xy 374.417428 -277.582155) (xy 374.377562 -277.551129)
			(xy 374.343347 -277.513964) (xy 374.315716 -277.471675) (xy 374.295423 -277.425414) (xy 374.283022 -277.376444)
			(xy 374.27885 -277.3261) (xy 374.283022 -277.275756) (xy 374.295423 -277.226786) (xy 374.315716 -277.180525)
			(xy 374.343347 -277.138236) (xy 374.377562 -277.101071) (xy 374.417428 -277.070045) (xy 374.461856 -277.046004)
			(xy 374.509636 -277.029604) (xy 374.559464 -277.021293) (xy 374.584722 -277.020782) (xy 374.606948 -277.021142)
			(xy 374.65094 -277.02751) (xy 374.672352 -277.033482) (xy 374.675908 -277.034498) (xy 374.683528 -277.035768)
			(xy 374.693438 -277.03678) (xy 374.712773 -277.032064) (xy 374.72112 -277.026624) (xy 374.786398 -276.978872)
			(xy 374.79226 -276.974411) (xy 374.801308 -276.962796) (xy 374.804178 -276.956012) (xy 374.80748 -276.946868)
			(xy 374.80748 -276.718268) (xy 374.807402 -276.714525) (xy 374.806259 -276.707125) (xy 374.805194 -276.703536)
			(xy 374.799098 -276.68347) (xy 374.795542 -276.677882) (xy 374.784704 -276.659723) (xy 374.767583 -276.621057)
			(xy 374.755946 -276.580401) (xy 374.752616 -276.559518) (xy 374.751092 -276.54631) (xy 374.750584 -276.541992)
			(xy 374.749568 -276.517862) (xy 374.749568 -276.512782) (xy 374.749783 -276.500915) (xy 374.751817 -276.477267)
			(xy 374.753632 -276.465538) (xy 374.759268 -276.436249) (xy 374.780372 -276.380474) (xy 374.795542 -276.354794)
			(xy 374.79986 -276.347936) (xy 374.803389 -276.341772) (xy 374.807258 -276.328111) (xy 374.80748 -276.321012)
			(xy 374.80748 -275.098256) (xy 374.807401 -275.094513) (xy 374.806256 -275.087114) (xy 374.805194 -275.083524)
			(xy 374.799098 -275.063458) (xy 374.795542 -275.05787) (xy 374.784699 -275.039713) (xy 374.767566 -275.001049)
			(xy 374.755918 -274.960394) (xy 374.752616 -274.939506) (xy 374.751092 -274.926298) (xy 374.750584 -274.92198)
			(xy 374.749568 -274.89785) (xy 374.749568 -274.89277) (xy 374.749783 -274.880903) (xy 374.751818 -274.857255)
			(xy 374.753632 -274.845526) (xy 374.759269 -274.816238) (xy 374.780375 -274.760464) (xy 374.795542 -274.734782)
			(xy 374.79986 -274.727924) (xy 374.803387 -274.72176) (xy 374.807253 -274.708099) (xy 374.80748 -274.701)
			(xy 374.80748 -274.474178) (xy 374.80683 -274.4622) (xy 374.795954 -274.440858) (xy 374.786652 -274.433284)
			(xy 374.720612 -274.385024) (xy 374.71096 -274.379436) (xy 374.703506 -274.376527) (xy 374.687591 -274.374966)
			(xy 374.679718 -274.376388) (xy 374.656604 -274.383425) (xy 374.60888 -274.390948) (xy 374.584722 -274.391374)
			(xy 374.559466 -274.390883) (xy 374.509642 -274.382572) (xy 374.461866 -274.366174) (xy 374.417441 -274.342135)
			(xy 374.377578 -274.311111) (xy 374.343366 -274.27395) (xy 374.315737 -274.231663) (xy 374.295446 -274.185406)
			(xy 374.283045 -274.13644) (xy 374.278874 -274.0861) (xy 374.283045 -274.03576) (xy 374.295446 -273.986794)
			(xy 374.315737 -273.940537) (xy 374.343366 -273.89825) (xy 374.377578 -273.861089) (xy 374.417441 -273.830065)
			(xy 374.461866 -273.806026) (xy 374.509642 -273.789628) (xy 374.559466 -273.781317) (xy 374.584722 -273.780758)
			(xy 374.606948 -273.781118) (xy 374.65094 -273.787486) (xy 374.672352 -273.793458) (xy 374.675908 -273.794474)
			(xy 374.683528 -273.795744) (xy 374.693438 -273.796756) (xy 374.712772 -273.792038) (xy 374.72112 -273.7866)
			(xy 374.786398 -273.738848) (xy 374.792258 -273.734385) (xy 374.801301 -273.722768) (xy 374.804178 -273.715988)
			(xy 374.80748 -273.706844) (xy 374.80748 -273.478244) (xy 374.8074 -273.474501) (xy 374.806254 -273.467103)
			(xy 374.805194 -273.463512) (xy 374.799098 -273.443446) (xy 374.795542 -273.437858) (xy 374.7847 -273.419701)
			(xy 374.767568 -273.381036) (xy 374.755922 -273.340382) (xy 374.752616 -273.319494) (xy 374.751092 -273.306286)
			(xy 374.750584 -273.301968) (xy 374.749568 -273.277838) (xy 374.749568 -273.272758) (xy 374.749784 -273.260892)
			(xy 374.75182 -273.237243) (xy 374.753632 -273.225514) (xy 374.75927 -273.196226) (xy 374.780378 -273.140453)
			(xy 374.795542 -273.11477) (xy 374.79986 -273.107912) (xy 374.803386 -273.101747) (xy 374.807249 -273.088086)
			(xy 374.80748 -273.080988) (xy 374.80748 -271.858232) (xy 374.807399 -271.854489) (xy 374.806251 -271.847091)
			(xy 374.805194 -271.8435) (xy 374.799098 -271.823434) (xy 374.795542 -271.817846) (xy 374.7847 -271.799689)
			(xy 374.76757 -271.761024) (xy 374.755926 -271.720369) (xy 374.752616 -271.699482) (xy 374.751092 -271.686274)
			(xy 374.750584 -271.681956) (xy 374.749568 -271.657826) (xy 374.749568 -271.652746) (xy 374.749784 -271.64088)
			(xy 374.751821 -271.617231) (xy 374.753632 -271.605502) (xy 374.759271 -271.576215) (xy 374.780381 -271.520443)
			(xy 374.795542 -271.494758) (xy 374.79986 -271.4879) (xy 374.803384 -271.481735) (xy 374.807244 -271.468074)
			(xy 374.80748 -271.460976) (xy 374.80748 -271.234154) (xy 374.806846 -271.222168) (xy 374.795989 -271.200798)
			(xy 374.786652 -271.19326) (xy 374.720612 -271.145) (xy 374.71096 -271.139412) (xy 374.703506 -271.136505)
			(xy 374.687592 -271.134944) (xy 374.679718 -271.136364) (xy 374.656604 -271.1434) (xy 374.60888 -271.15092)
			(xy 374.584722 -271.15135) (xy 374.55946 -271.150859) (xy 374.509623 -271.142546) (xy 374.461835 -271.126143)
			(xy 374.417399 -271.102099) (xy 374.377527 -271.071067) (xy 374.343306 -271.033896) (xy 374.315671 -270.991599)
			(xy 374.295374 -270.945331) (xy 374.28297 -270.896352) (xy 374.278798 -270.846) (xy 374.28297 -270.795648)
			(xy 374.295374 -270.746669) (xy 374.315671 -270.700401) (xy 374.343306 -270.658104) (xy 374.377527 -270.620933)
			(xy 374.417399 -270.589901) (xy 374.461835 -270.565857) (xy 374.509623 -270.549454) (xy 374.55946 -270.541141)
			(xy 374.584722 -270.540734) (xy 374.606948 -270.541094) (xy 374.65094 -270.547464) (xy 374.672352 -270.553434)
			(xy 374.675908 -270.55445) (xy 374.683528 -270.55572) (xy 374.693439 -270.556732) (xy 374.712776 -270.55202)
			(xy 374.72112 -270.546576) (xy 374.786398 -270.498824) (xy 374.792256 -270.49436) (xy 374.801294 -270.482741)
			(xy 374.804178 -270.475964) (xy 374.80748 -270.46682) (xy 374.80748 -270.23822) (xy 374.807398 -270.234477)
			(xy 374.806248 -270.22708) (xy 374.805194 -270.223488) (xy 374.799098 -270.203422) (xy 374.795542 -270.197834)
			(xy 374.784701 -270.179676) (xy 374.767573 -270.141011) (xy 374.75593 -270.100356) (xy 374.752616 -270.07947)
			(xy 374.751092 -270.066262) (xy 374.750584 -270.061944) (xy 374.749568 -270.037814) (xy 374.749568 -270.032734)
			(xy 374.749785 -270.020868) (xy 374.751822 -269.99722) (xy 374.753632 -269.98549) (xy 374.759272 -269.956203)
			(xy 374.780384 -269.900432) (xy 374.795542 -269.874746) (xy 374.79986 -269.867888) (xy 374.803383 -269.861722)
			(xy 374.807239 -269.848062) (xy 374.80748 -269.840964) (xy 374.80748 -268.618208) (xy 374.807398 -268.614465)
			(xy 374.806246 -268.607069) (xy 374.805194 -268.603476) (xy 374.799098 -268.58341) (xy 374.795542 -268.577822)
			(xy 374.784702 -268.559664) (xy 374.767575 -268.520999) (xy 374.755933 -268.480344) (xy 374.752616 -268.459458)
			(xy 374.751092 -268.44625) (xy 374.750584 -268.441932) (xy 374.749568 -268.417802) (xy 374.749568 -268.412722)
			(xy 374.749781 -268.400855) (xy 374.751812 -268.377206) (xy 374.753632 -268.365478) (xy 374.759265 -268.336188)
			(xy 374.780362 -268.280409) (xy 374.795542 -268.254734) (xy 374.79986 -268.247876) (xy 374.803394 -268.241713)
			(xy 374.807274 -268.228052) (xy 374.80748 -268.220952) (xy 374.80748 -267.99413) (xy 374.806841 -267.982146)
			(xy 374.795978 -267.960786) (xy 374.786652 -267.953236) (xy 374.720612 -267.904976) (xy 374.71096 -267.899388)
			(xy 374.703506 -267.896482) (xy 374.687592 -267.894922) (xy 374.679718 -267.89634) (xy 374.656604 -267.903376)
			(xy 374.60888 -267.910897) (xy 374.584722 -267.911326) (xy 374.560727 -267.910881) (xy 374.513328 -267.903378)
			(xy 374.467686 -267.888551) (xy 374.424926 -267.866767) (xy 374.3861 -267.838562) (xy 374.352164 -267.804631)
			(xy 374.323954 -267.765808) (xy 374.302164 -267.723051) (xy 374.287332 -267.677411) (xy 374.279822 -267.630013)
			(xy 374.279414 -267.606018) (xy 374.279541 -267.594478) (xy 374.281318 -267.571466) (xy 374.28297 -267.560044)
			(xy 374.283478 -267.556234) (xy 374.283478 -267.555218) (xy 374.288459 -267.52913) (xy 374.306212 -267.479078)
			(xy 374.332345 -267.432845) (xy 374.348756 -267.411962) (xy 374.354852 -267.404596) (xy 374.360694 -267.38707)
			(xy 374.35917 -267.35659) (xy 374.35663 -267.309092) (xy 374.355746 -267.299793) (xy 374.34818 -267.282732)
			(xy 374.341898 -267.275818) (xy 374.172988 -267.106908) (xy 374.151906 -267.099288) (xy 374.14073 -267.100304)
			(xy 374.114822 -267.10132) (xy 374.090827 -267.100875) (xy 374.043429 -267.093372) (xy 373.997787 -267.078545)
			(xy 373.955027 -267.056761) (xy 373.916201 -267.028556) (xy 373.882266 -266.994624) (xy 373.854057 -266.955802)
			(xy 373.832268 -266.913044) (xy 373.817436 -266.867405) (xy 373.809927 -266.820007) (xy 373.809514 -266.796012)
			(xy 373.81053 -266.770104) (xy 373.811546 -266.758928) (xy 373.803926 -266.737846) (xy 373.659146 -266.593066)
			(xy 373.651748 -266.586221) (xy 373.633149 -266.578496) (xy 373.623078 -266.57808) (xy 373.564658 -266.57808)
			(xy 373.552721 -266.578721) (xy 373.531392 -266.58945) (xy 373.523764 -266.598654) (xy 373.468138 -266.673838)
			(xy 373.46382 -266.697206) (xy 373.467376 -266.70889) (xy 373.473102 -266.729445) (xy 373.479469 -266.771635)
			(xy 373.480076 -266.792964) (xy 373.480076 -266.799314) (xy 373.479297 -266.82439) (xy 373.470562 -266.873791)
			(xy 373.453868 -266.921098) (xy 373.429666 -266.96504) (xy 373.398606 -267.004435) (xy 373.361523 -267.038223)
			(xy 373.319416 -267.065494) (xy 373.273418 -267.085514) (xy 373.224766 -267.097747) (xy 373.174768 -267.101861)
			(xy 373.12477 -267.097747) (xy 373.076118 -267.085514) (xy 373.03012 -267.065494) (xy 372.988013 -267.038223)
			(xy 372.95093 -267.004435) (xy 372.91987 -266.96504) (xy 372.895668 -266.921098) (xy 372.878974 -266.873791)
			(xy 372.870239 -266.82439) (xy 372.86946 -266.799314) (xy 372.86946 -266.795758) (xy 372.869865 -266.773724)
			(xy 372.876241 -266.730118) (xy 372.88216 -266.70889) (xy 372.885716 -266.697206) (xy 372.881398 -266.673838)
			(xy 372.825772 -266.598654) (xy 372.818163 -266.589423) (xy 372.796825 -266.578674) (xy 372.784878 -266.57808)
			(xy 372.624604 -266.57808) (xy 372.612673 -266.578732) (xy 372.591363 -266.589475) (xy 372.58371 -266.598654)
			(xy 372.528084 -266.673838) (xy 372.523766 -266.697206) (xy 372.527322 -266.70889) (xy 372.533049 -266.729444)
			(xy 372.539417 -266.771635) (xy 372.540022 -266.792964) (xy 372.540022 -266.799314) (xy 372.539243 -266.82439)
			(xy 372.530508 -266.873791) (xy 372.513814 -266.921098) (xy 372.489612 -266.96504) (xy 372.458552 -267.004435)
			(xy 372.421469 -267.038223) (xy 372.379362 -267.065494) (xy 372.333364 -267.085514) (xy 372.284712 -267.097747)
			(xy 372.234714 -267.101861) (xy 372.184716 -267.097747) (xy 372.136064 -267.085514) (xy 372.090066 -267.065494)
			(xy 372.047959 -267.038223) (xy 372.010876 -267.004435) (xy 371.979816 -266.96504) (xy 371.955614 -266.921098)
			(xy 371.93892 -266.873791) (xy 371.930185 -266.82439) (xy 371.929406 -266.799314) (xy 371.929406 -266.795758)
			(xy 371.929811 -266.773724) (xy 371.936186 -266.730118) (xy 371.942106 -266.70889) (xy 371.945662 -266.697206)
			(xy 371.941344 -266.673838) (xy 371.885718 -266.598654) (xy 371.878105 -266.589432) (xy 371.856767 -266.578706)
			(xy 371.844824 -266.57808) (xy 371.684804 -266.57808) (xy 371.672873 -266.578732) (xy 371.651563 -266.589475)
			(xy 371.64391 -266.598654) (xy 371.588284 -266.673838) (xy 371.583966 -266.697206) (xy 371.587522 -266.70889)
			(xy 371.593249 -266.729444) (xy 371.599617 -266.771635) (xy 371.600222 -266.792964) (xy 371.600222 -266.799314)
			(xy 371.599443 -266.82439) (xy 371.590708 -266.873791) (xy 371.574014 -266.921098) (xy 371.549812 -266.96504)
			(xy 371.518752 -267.004435) (xy 371.481669 -267.038223) (xy 371.439562 -267.065494) (xy 371.393564 -267.085514)
			(xy 371.344912 -267.097747) (xy 371.294914 -267.101861) (xy 371.244916 -267.097747) (xy 371.196264 -267.085514)
			(xy 371.150266 -267.065494) (xy 371.108159 -267.038223) (xy 371.071076 -267.004435) (xy 371.040016 -266.96504)
			(xy 371.015814 -266.921098) (xy 370.99912 -266.873791) (xy 370.990385 -266.82439) (xy 370.989606 -266.799314)
			(xy 370.989606 -266.795758) (xy 370.990011 -266.773724) (xy 370.996386 -266.730118) (xy 371.002306 -266.70889)
			(xy 371.005862 -266.697206) (xy 371.001544 -266.673838) (xy 370.945918 -266.598654) (xy 370.938305 -266.589432)
			(xy 370.916967 -266.578706) (xy 370.905024 -266.57808) (xy 369.804696 -266.57808) (xy 369.792766 -266.578734)
			(xy 369.771458 -266.589478) (xy 369.763802 -266.598654) (xy 369.708176 -266.673838) (xy 369.703858 -266.697206)
			(xy 369.707414 -266.70889) (xy 369.713141 -266.729444) (xy 369.719509 -266.771635) (xy 369.720114 -266.792964)
			(xy 369.720114 -266.799314) (xy 369.719335 -266.82439) (xy 369.7106 -266.873791) (xy 369.693906 -266.921098)
			(xy 369.669704 -266.96504) (xy 369.638644 -267.004435) (xy 369.601561 -267.038223) (xy 369.559454 -267.065494)
			(xy 369.513456 -267.085514) (xy 369.464804 -267.097747) (xy 369.414806 -267.101861) (xy 369.364808 -267.097747)
			(xy 369.316156 -267.085514) (xy 369.270158 -267.065494) (xy 369.228051 -267.038223) (xy 369.190968 -267.004435)
			(xy 369.159908 -266.96504) (xy 369.135706 -266.921098) (xy 369.119012 -266.873791) (xy 369.110277 -266.82439)
			(xy 369.109498 -266.799314) (xy 369.109498 -266.795758) (xy 369.109903 -266.773724) (xy 369.116278 -266.730118)
			(xy 369.122198 -266.70889) (xy 369.125754 -266.697206) (xy 369.121436 -266.673838) (xy 369.06581 -266.598654)
			(xy 369.058196 -266.589433) (xy 369.036859 -266.57871) (xy 369.024916 -266.57808) (xy 368.864642 -266.57808)
			(xy 368.852707 -266.578724) (xy 368.831383 -266.589457) (xy 368.823748 -266.598654) (xy 368.768122 -266.673838)
			(xy 368.763804 -266.697206) (xy 368.76736 -266.70889) (xy 368.773086 -266.729445) (xy 368.779453 -266.771635)
			(xy 368.78006 -266.792964) (xy 368.78006 -266.799314) (xy 368.779281 -266.82439) (xy 368.770546 -266.873791)
			(xy 368.753852 -266.921098) (xy 368.72965 -266.96504) (xy 368.69859 -267.004435) (xy 368.661507 -267.038223)
			(xy 368.6194 -267.065494) (xy 368.573402 -267.085514) (xy 368.52475 -267.097747) (xy 368.474752 -267.101861)
			(xy 368.424754 -267.097747) (xy 368.376102 -267.085514) (xy 368.330104 -267.065494) (xy 368.287997 -267.038223)
			(xy 368.250914 -267.004435) (xy 368.219854 -266.96504) (xy 368.195652 -266.921098) (xy 368.178958 -266.873791)
			(xy 368.170223 -266.82439) (xy 368.169444 -266.799314) (xy 368.169444 -266.795758) (xy 368.169849 -266.773724)
			(xy 368.176225 -266.730118) (xy 368.182144 -266.70889) (xy 368.1857 -266.697206) (xy 368.181382 -266.673838)
			(xy 368.125756 -266.598654) (xy 368.118145 -266.589425) (xy 368.096808 -266.578683) (xy 368.084862 -266.57808)
			(xy 367.924588 -266.57808) (xy 367.912648 -266.578715) (xy 367.891308 -266.589436) (xy 367.883694 -266.598654)
			(xy 367.828068 -266.673838) (xy 367.82375 -266.697206) (xy 367.827306 -266.70889) (xy 367.833033 -266.729444)
			(xy 367.839401 -266.771635) (xy 367.840006 -266.792964) (xy 367.840006 -266.799314) (xy 367.839227 -266.82439)
			(xy 367.830492 -266.873791) (xy 367.813798 -266.921098) (xy 367.789596 -266.96504) (xy 367.758536 -267.004435)
			(xy 367.721453 -267.038223) (xy 367.679346 -267.065494) (xy 367.633348 -267.085514) (xy 367.584696 -267.097747)
			(xy 367.534698 -267.101861) (xy 367.4847 -267.097747) (xy 367.436048 -267.085514) (xy 367.39005 -267.065494)
			(xy 367.347943 -267.038223) (xy 367.31086 -267.004435) (xy 367.2798 -266.96504) (xy 367.255598 -266.921098)
			(xy 367.238904 -266.873791) (xy 367.230169 -266.82439) (xy 367.22939 -266.799314) (xy 367.22939 -266.795758)
			(xy 367.229795 -266.773724) (xy 367.23617 -266.730118) (xy 367.24209 -266.70889) (xy 367.245646 -266.697206)
			(xy 367.241328 -266.673838) (xy 367.185702 -266.598654) (xy 367.178088 -266.589434) (xy 367.15675 -266.578715)
			(xy 367.144808 -266.57808) (xy 366.044734 -266.57808) (xy 366.0328 -266.578726) (xy 366.011479 -266.589461)
			(xy 366.00384 -266.598654) (xy 365.948214 -266.673838) (xy 365.943896 -266.697206) (xy 365.947452 -266.70889)
			(xy 365.953179 -266.729445) (xy 365.959546 -266.771635) (xy 365.960152 -266.792964) (xy 365.960152 -266.799314)
			(xy 365.959373 -266.82439) (xy 365.950638 -266.873791) (xy 365.933944 -266.921098) (xy 365.909742 -266.96504)
			(xy 365.878682 -267.004435) (xy 365.841599 -267.038223) (xy 365.799492 -267.065494) (xy 365.753494 -267.085514)
			(xy 365.704842 -267.097747) (xy 365.654844 -267.101861) (xy 365.604846 -267.097747) (xy 365.556194 -267.085514)
			(xy 365.510196 -267.065494) (xy 365.468089 -267.038223) (xy 365.431006 -267.004435) (xy 365.399946 -266.96504)
			(xy 365.375744 -266.921098) (xy 365.35905 -266.873791) (xy 365.350315 -266.82439) (xy 365.349536 -266.799314)
			(xy 365.349536 -266.795758) (xy 365.349941 -266.773724) (xy 365.356317 -266.730118) (xy 365.362236 -266.70889)
			(xy 365.365792 -266.697206) (xy 365.361474 -266.673838) (xy 365.305848 -266.598654) (xy 365.298237 -266.589427)
			(xy 365.276899 -266.578688) (xy 365.264954 -266.57808) (xy 365.10468 -266.57808) (xy 365.09274 -266.578716)
			(xy 365.071404 -266.58944) (xy 365.063786 -266.598654) (xy 365.00816 -266.673838) (xy 365.003842 -266.697206)
			(xy 365.007398 -266.70889) (xy 365.013126 -266.729444) (xy 365.019494 -266.771635) (xy 365.020098 -266.792964)
			(xy 365.020098 -266.799314) (xy 365.019319 -266.82439) (xy 365.010584 -266.873791) (xy 364.99389 -266.921098)
			(xy 364.969688 -266.96504) (xy 364.938628 -267.004435) (xy 364.901545 -267.038223) (xy 364.859438 -267.065494)
			(xy 364.81344 -267.085514) (xy 364.764788 -267.097747) (xy 364.71479 -267.101861) (xy 364.664792 -267.097747)
			(xy 364.61614 -267.085514) (xy 364.570142 -267.065494) (xy 364.528035 -267.038223) (xy 364.490952 -267.004435)
			(xy 364.459892 -266.96504) (xy 364.43569 -266.921098) (xy 364.418996 -266.873791) (xy 364.410261 -266.82439)
			(xy 364.409482 -266.799314) (xy 364.409482 -266.795758) (xy 364.409887 -266.773724) (xy 364.416262 -266.730118)
			(xy 364.422182 -266.70889) (xy 364.425738 -266.697206) (xy 364.42142 -266.673838) (xy 364.365794 -266.598654)
			(xy 364.358179 -266.589436) (xy 364.336841 -266.578719) (xy 364.3249 -266.57808) (xy 364.164626 -266.57808)
			(xy 364.152692 -266.578728) (xy 364.131375 -266.589465) (xy 364.123732 -266.598654) (xy 364.068106 -266.673838)
			(xy 364.063788 -266.697206) (xy 364.067344 -266.70889) (xy 364.073071 -266.729444) (xy 364.079438 -266.771635)
			(xy 364.080044 -266.792964) (xy 364.080044 -266.799314) (xy 364.079265 -266.82439) (xy 364.07053 -266.873791)
			(xy 364.053836 -266.921098) (xy 364.029634 -266.96504) (xy 363.998574 -267.004435) (xy 363.961491 -267.038223)
			(xy 363.919384 -267.065494) (xy 363.873386 -267.085514) (xy 363.824734 -267.097747) (xy 363.774736 -267.101861)
			(xy 363.724738 -267.097747) (xy 363.676086 -267.085514) (xy 363.630088 -267.065494) (xy 363.587981 -267.038223)
			(xy 363.550898 -267.004435) (xy 363.519838 -266.96504) (xy 363.495636 -266.921098) (xy 363.478942 -266.873791)
			(xy 363.470207 -266.82439) (xy 363.469428 -266.799314) (xy 363.469428 -266.795758) (xy 363.469833 -266.773724)
			(xy 363.476209 -266.730118) (xy 363.482128 -266.70889) (xy 363.485684 -266.697206) (xy 363.481366 -266.673838)
			(xy 363.42574 -266.598654) (xy 363.418128 -266.589428) (xy 363.396791 -266.578693) (xy 363.384846 -266.57808)
			(xy 362.284772 -266.57808) (xy 362.272833 -266.578718) (xy 362.2515 -266.589444) (xy 362.243878 -266.598654)
			(xy 362.188252 -266.673838) (xy 362.183934 -266.697206) (xy 362.18749 -266.70889) (xy 362.193218 -266.729444)
			(xy 362.199586 -266.771635) (xy 362.20019 -266.792964) (xy 362.20019 -266.799314) (xy 362.199411 -266.82439)
			(xy 362.190676 -266.873791) (xy 362.173982 -266.921098) (xy 362.14978 -266.96504) (xy 362.11872 -267.004435)
			(xy 362.081637 -267.038223) (xy 362.03953 -267.065494) (xy 361.993532 -267.085514) (xy 361.94488 -267.097747)
			(xy 361.894882 -267.101861) (xy 361.844884 -267.097747) (xy 361.796232 -267.085514) (xy 361.750234 -267.065494)
			(xy 361.708127 -267.038223) (xy 361.671044 -267.004435) (xy 361.639984 -266.96504) (xy 361.615782 -266.921098)
			(xy 361.599088 -266.873791) (xy 361.590353 -266.82439) (xy 361.589574 -266.799314) (xy 361.589574 -266.795758)
			(xy 361.589979 -266.773724) (xy 361.596354 -266.730118) (xy 361.602274 -266.70889) (xy 361.60583 -266.697206)
			(xy 361.601512 -266.673838) (xy 361.545886 -266.598654) (xy 361.538271 -266.589437) (xy 361.516933 -266.578724)
			(xy 361.504992 -266.57808) (xy 358.530906 -266.57808) (xy 358.518975 -266.578732) (xy 358.497664 -266.589474)
			(xy 358.490012 -266.598654) (xy 358.434386 -266.673838) (xy 358.430068 -266.697206) (xy 358.433624 -266.70889)
			(xy 358.439351 -266.729444) (xy 358.445719 -266.771635) (xy 358.446324 -266.792964) (xy 358.446324 -266.799314)
			(xy 358.445545 -266.82439) (xy 358.43681 -266.873791) (xy 358.420116 -266.921098) (xy 358.395914 -266.96504)
			(xy 358.364854 -267.004435) (xy 358.327771 -267.038223) (xy 358.285664 -267.065494) (xy 358.239666 -267.085514)
			(xy 358.191014 -267.097747) (xy 358.141016 -267.101861) (xy 358.091018 -267.097747) (xy 358.042366 -267.085514)
			(xy 357.996368 -267.065494) (xy 357.954261 -267.038223) (xy 357.917178 -267.004435) (xy 357.886118 -266.96504)
			(xy 357.861916 -266.921098) (xy 357.845222 -266.873791) (xy 357.836487 -266.82439) (xy 357.835708 -266.799314)
			(xy 357.835708 -266.795758) (xy 357.836113 -266.773724) (xy 357.842488 -266.730118) (xy 357.848408 -266.70889)
			(xy 357.851964 -266.697206) (xy 357.847646 -266.673838) (xy 357.79202 -266.598654) (xy 357.784407 -266.589432)
			(xy 357.763069 -266.578704) (xy 357.751126 -266.57808) (xy 357.591106 -266.57808) (xy 357.579175 -266.578732)
			(xy 357.557864 -266.589474) (xy 357.550212 -266.598654) (xy 357.494586 -266.673838) (xy 357.490268 -266.697206)
			(xy 357.493824 -266.70889) (xy 357.499551 -266.729444) (xy 357.505919 -266.771635) (xy 357.506524 -266.792964)
			(xy 357.506524 -266.799314) (xy 357.505745 -266.82439) (xy 357.49701 -266.873791) (xy 357.480316 -266.921098)
			(xy 357.456114 -266.96504) (xy 357.425054 -267.004435) (xy 357.387971 -267.038223) (xy 357.345864 -267.065494)
			(xy 357.299866 -267.085514) (xy 357.251214 -267.097747) (xy 357.201216 -267.101861) (xy 357.151218 -267.097747)
			(xy 357.102566 -267.085514) (xy 357.056568 -267.065494) (xy 357.014461 -267.038223) (xy 356.977378 -267.004435)
			(xy 356.946318 -266.96504) (xy 356.922116 -266.921098) (xy 356.905422 -266.873791) (xy 356.896687 -266.82439)
			(xy 356.895908 -266.799314) (xy 356.895908 -266.795758) (xy 356.896313 -266.773724) (xy 356.902688 -266.730118)
			(xy 356.908608 -266.70889) (xy 356.912164 -266.697206) (xy 356.907846 -266.673838) (xy 356.85222 -266.598654)
			(xy 356.844607 -266.589432) (xy 356.823269 -266.578704) (xy 356.811326 -266.57808) (xy 355.710998 -266.57808)
			(xy 355.699068 -266.578734) (xy 355.67776 -266.589477) (xy 355.670104 -266.598654) (xy 355.614478 -266.673838)
			(xy 355.61016 -266.697206) (xy 355.613716 -266.70889) (xy 355.619443 -266.729444) (xy 355.625811 -266.771635)
			(xy 355.626416 -266.792964) (xy 355.626416 -266.799314) (xy 355.625637 -266.82439) (xy 355.616902 -266.873791)
			(xy 355.600208 -266.921098) (xy 355.576006 -266.96504) (xy 355.544946 -267.004435) (xy 355.507863 -267.038223)
			(xy 355.465756 -267.065494) (xy 355.419758 -267.085514) (xy 355.371106 -267.097747) (xy 355.321108 -267.101861)
			(xy 355.27111 -267.097747) (xy 355.222458 -267.085514) (xy 355.17646 -267.065494) (xy 355.134353 -267.038223)
			(xy 355.09727 -267.004435) (xy 355.06621 -266.96504) (xy 355.042008 -266.921098) (xy 355.025314 -266.873791)
			(xy 355.016579 -266.82439) (xy 355.0158 -266.799314) (xy 355.0158 -266.795758) (xy 355.016205 -266.773724)
			(xy 355.02258 -266.730118) (xy 355.0285 -266.70889) (xy 355.032056 -266.697206) (xy 355.027738 -266.673838)
			(xy 354.972112 -266.598654) (xy 354.964498 -266.589433) (xy 354.943161 -266.578709) (xy 354.931218 -266.57808)
			(xy 354.770944 -266.57808) (xy 354.759008 -266.578724) (xy 354.737685 -266.589456) (xy 354.73005 -266.598654)
			(xy 354.674424 -266.673838) (xy 354.670106 -266.697206) (xy 354.673662 -266.70889) (xy 354.679388 -266.729445)
			(xy 354.685755 -266.771635) (xy 354.686362 -266.792964) (xy 354.686362 -266.799314) (xy 354.685583 -266.82439)
			(xy 354.676848 -266.873791) (xy 354.660154 -266.921098) (xy 354.635952 -266.96504) (xy 354.604892 -267.004435)
			(xy 354.567809 -267.038223) (xy 354.525702 -267.065494) (xy 354.479704 -267.085514) (xy 354.431052 -267.097747)
			(xy 354.381054 -267.101861) (xy 354.331056 -267.097747) (xy 354.282404 -267.085514) (xy 354.236406 -267.065494)
			(xy 354.194299 -267.038223) (xy 354.157216 -267.004435) (xy 354.126156 -266.96504) (xy 354.101954 -266.921098)
			(xy 354.08526 -266.873791) (xy 354.076525 -266.82439) (xy 354.075746 -266.799314) (xy 354.075746 -266.795758)
			(xy 354.076151 -266.773724) (xy 354.082527 -266.730118) (xy 354.088446 -266.70889) (xy 354.092002 -266.697206)
			(xy 354.087684 -266.673838) (xy 354.032058 -266.598654) (xy 354.024447 -266.589425) (xy 354.00311 -266.578682)
			(xy 353.991164 -266.57808) (xy 353.83089 -266.57808) (xy 353.818949 -266.578714) (xy 353.79761 -266.589435)
			(xy 353.789996 -266.598654) (xy 353.73437 -266.673838) (xy 353.730052 -266.697206) (xy 353.733608 -266.70889)
			(xy 353.739335 -266.729444) (xy 353.745703 -266.771635) (xy 353.746308 -266.792964) (xy 353.746308 -266.799314)
			(xy 353.745529 -266.82439) (xy 353.736794 -266.873791) (xy 353.7201 -266.921098) (xy 353.695898 -266.96504)
			(xy 353.664838 -267.004435) (xy 353.627755 -267.038223) (xy 353.585648 -267.065494) (xy 353.53965 -267.085514)
			(xy 353.490998 -267.097747) (xy 353.441 -267.101861) (xy 353.391002 -267.097747) (xy 353.34235 -267.085514)
			(xy 353.296352 -267.065494) (xy 353.254245 -267.038223) (xy 353.217162 -267.004435) (xy 353.186102 -266.96504)
			(xy 353.1619 -266.921098) (xy 353.145206 -266.873791) (xy 353.136471 -266.82439) (xy 353.135692 -266.799314)
			(xy 353.135692 -266.795758) (xy 353.136097 -266.773724) (xy 353.142472 -266.730118) (xy 353.148392 -266.70889)
			(xy 353.151948 -266.697206) (xy 353.14763 -266.673838) (xy 353.092004 -266.598654) (xy 353.08439 -266.589434)
			(xy 353.063052 -266.578714) (xy 353.05111 -266.57808) (xy 351.951036 -266.57808) (xy 351.939101 -266.578726)
			(xy 351.91778 -266.58946) (xy 351.910142 -266.598654) (xy 351.854516 -266.673838) (xy 351.850198 -266.697206)
			(xy 351.853754 -266.70889) (xy 351.859481 -266.729445) (xy 351.865848 -266.771635) (xy 351.866454 -266.792964)
			(xy 351.866454 -266.799314) (xy 351.865675 -266.82439) (xy 351.85694 -266.873791) (xy 351.840246 -266.921098)
			(xy 351.816044 -266.96504) (xy 351.784984 -267.004435) (xy 351.747901 -267.038223) (xy 351.705794 -267.065494)
			(xy 351.659796 -267.085514) (xy 351.611144 -267.097747) (xy 351.561146 -267.101861) (xy 351.511148 -267.097747)
			(xy 351.462496 -267.085514) (xy 351.416498 -267.065494) (xy 351.374391 -267.038223) (xy 351.337308 -267.004435)
			(xy 351.306248 -266.96504) (xy 351.282046 -266.921098) (xy 351.265352 -266.873791) (xy 351.256617 -266.82439)
			(xy 351.255838 -266.799314) (xy 351.255838 -266.795758) (xy 351.256243 -266.773724) (xy 351.262619 -266.730118)
			(xy 351.268538 -266.70889) (xy 351.272094 -266.697206) (xy 351.267776 -266.673838) (xy 351.21215 -266.598654)
			(xy 351.204539 -266.589426) (xy 351.183202 -266.578687) (xy 351.171256 -266.57808) (xy 351.010982 -266.57808)
			(xy 350.999042 -266.578716) (xy 350.977705 -266.589439) (xy 350.970088 -266.598654) (xy 350.914462 -266.673838)
			(xy 350.910144 -266.697206) (xy 350.9137 -266.70889) (xy 350.919427 -266.729444) (xy 350.925796 -266.771635)
			(xy 350.9264 -266.792964) (xy 350.9264 -266.799314) (xy 350.925621 -266.82439) (xy 350.916886 -266.873791)
			(xy 350.900192 -266.921098) (xy 350.87599 -266.96504) (xy 350.84493 -267.004435) (xy 350.807847 -267.038223)
			(xy 350.76574 -267.065494) (xy 350.719742 -267.085514) (xy 350.67109 -267.097747) (xy 350.621092 -267.101861)
			(xy 350.571094 -267.097747) (xy 350.522442 -267.085514) (xy 350.476444 -267.065494) (xy 350.434337 -267.038223)
			(xy 350.397254 -267.004435) (xy 350.366194 -266.96504) (xy 350.341992 -266.921098) (xy 350.325298 -266.873791)
			(xy 350.316563 -266.82439) (xy 350.315784 -266.799314) (xy 350.315784 -266.795758) (xy 350.316189 -266.773724)
			(xy 350.322564 -266.730118) (xy 350.328484 -266.70889) (xy 350.33204 -266.697206) (xy 350.327722 -266.673838)
			(xy 350.272096 -266.598654) (xy 350.264481 -266.589435) (xy 350.243144 -266.578718) (xy 350.231202 -266.57808)
			(xy 350.070928 -266.57808) (xy 350.058994 -266.578727) (xy 350.037676 -266.589464) (xy 350.030034 -266.598654)
			(xy 349.974408 -266.673838) (xy 349.97009 -266.697206) (xy 349.973646 -266.70889) (xy 349.979373 -266.729444)
			(xy 349.98574 -266.771635) (xy 349.986346 -266.792964) (xy 349.986346 -266.799314) (xy 349.985567 -266.82439)
			(xy 349.976832 -266.873791) (xy 349.960138 -266.921098) (xy 349.935936 -266.96504) (xy 349.904876 -267.004435)
			(xy 349.867793 -267.038223) (xy 349.825686 -267.065494) (xy 349.779688 -267.085514) (xy 349.731036 -267.097747)
			(xy 349.681038 -267.101861) (xy 349.63104 -267.097747) (xy 349.582388 -267.085514) (xy 349.53639 -267.065494)
			(xy 349.494283 -267.038223) (xy 349.4572 -267.004435) (xy 349.42614 -266.96504) (xy 349.401938 -266.921098)
			(xy 349.385244 -266.873791) (xy 349.376509 -266.82439) (xy 349.37573 -266.799314) (xy 349.37573 -266.795758)
			(xy 349.376135 -266.773724) (xy 349.382511 -266.730118) (xy 349.38843 -266.70889) (xy 349.391986 -266.697206)
			(xy 349.387668 -266.673838) (xy 349.332042 -266.598654) (xy 349.32443 -266.589428) (xy 349.303093 -266.578691)
			(xy 349.291148 -266.57808) (xy 348.300802 -266.57808) (xy 348.290731 -266.578502) (xy 348.272124 -266.586214)
			(xy 348.264734 -266.593066) (xy 348.120716 -266.737084) (xy 348.117079 -266.740906) (xy 348.111308 -266.749737)
			(xy 348.109286 -266.75461) (xy 348.105222 -266.765278) (xy 348.105984 -266.776454) (xy 348.106492 -266.795758)
			(xy 348.106492 -266.796266) (xy 348.106002 -266.820243) (xy 348.098462 -266.867602) (xy 348.083611 -266.913199)
			(xy 348.061813 -266.955914) (xy 348.033605 -266.994695) (xy 347.99968 -267.028588) (xy 347.960873 -267.056761)
			(xy 347.918138 -267.078519) (xy 347.872527 -267.093328) (xy 347.825162 -267.100824) (xy 347.801184 -267.10132)
			(xy 347.774644 -267.100775) (xy 347.722354 -267.091651) (xy 347.672427 -267.073628) (xy 347.626366 -267.047249)
			(xy 347.605604 -267.030708) (xy 347.599254 -267.02512) (xy 347.574362 -267.015722) (xy 347.570014 -267.014182)
			(xy 347.56094 -267.012526) (xy 347.556328 -267.01242) (xy 347.105986 -267.01242) (xy 347.101374 -267.012521)
			(xy 347.092301 -267.014182) (xy 347.087952 -267.015722) (xy 347.06306 -267.02512) (xy 347.05671 -267.030708)
			(xy 347.038079 -267.045569) (xy 346.997127 -267.069942) (xy 346.975176 -267.079222) (xy 346.953315 -267.087544)
			(xy 346.907768 -267.098193) (xy 346.86113 -267.101771) (xy 346.814492 -267.098193) (xy 346.768945 -267.087544)
			(xy 346.747084 -267.079222) (xy 346.725133 -267.069942) (xy 346.684184 -267.045565) (xy 346.66555 -267.030708)
			(xy 346.6592 -267.02512) (xy 346.634308 -267.015722) (xy 346.62996 -267.014178) (xy 346.620887 -267.012514)
			(xy 346.616274 -267.01242) (xy 346.339922 -267.01242) (xy 346.329859 -267.012858) (xy 346.311277 -267.020594)
			(xy 346.303854 -267.027406) (xy 345.763596 -267.567664) (xy 345.755976 -267.587476) (xy 345.756484 -267.597382)
			(xy 345.756484 -267.606018) (xy 346.085426 -267.606018) (xy 346.089386 -267.556964) (xy 346.101163 -267.50918)
			(xy 346.120454 -267.463904) (xy 346.146757 -267.422308) (xy 346.179392 -267.385471) (xy 346.217513 -267.354346)
			(xy 346.260134 -267.329739) (xy 346.30615 -267.312287) (xy 346.354369 -267.302443) (xy 346.403544 -267.300462)
			(xy 346.452399 -267.306394) (xy 346.49967 -267.320086) (xy 346.544132 -267.341184) (xy 346.584635 -267.36914)
			(xy 346.620128 -267.403232) (xy 346.649693 -267.442576) (xy 346.672564 -267.486153) (xy 346.688148 -267.532834)
			(xy 346.696043 -267.581411) (xy 346.696538 -267.606018) (xy 347.025226 -267.606018) (xy 347.029186 -267.556964)
			(xy 347.040963 -267.50918) (xy 347.060254 -267.463904) (xy 347.086557 -267.422308) (xy 347.119192 -267.385471)
			(xy 347.157313 -267.354346) (xy 347.199934 -267.329739) (xy 347.24595 -267.312287) (xy 347.294169 -267.302443)
			(xy 347.343344 -267.300462) (xy 347.392199 -267.306394) (xy 347.43947 -267.320086) (xy 347.483932 -267.341184)
			(xy 347.524435 -267.36914) (xy 347.559928 -267.403232) (xy 347.589493 -267.442576) (xy 347.612364 -267.486153)
			(xy 347.627948 -267.532834) (xy 347.635843 -267.581411) (xy 347.636338 -267.606018) (xy 347.96528 -267.606018)
			(xy 347.96924 -267.556964) (xy 347.981017 -267.50918) (xy 348.000308 -267.463904) (xy 348.026611 -267.422308)
			(xy 348.059246 -267.385471) (xy 348.097367 -267.354346) (xy 348.139988 -267.329739) (xy 348.186004 -267.312287)
			(xy 348.234223 -267.302443) (xy 348.283398 -267.300462) (xy 348.332253 -267.306394) (xy 348.379524 -267.320086)
			(xy 348.423986 -267.341184) (xy 348.464489 -267.36914) (xy 348.499982 -267.403232) (xy 348.529547 -267.442576)
			(xy 348.552418 -267.486153) (xy 348.568002 -267.532834) (xy 348.575897 -267.581411) (xy 348.576392 -267.606018)
			(xy 349.845388 -267.606018) (xy 349.849348 -267.556964) (xy 349.861125 -267.50918) (xy 349.880416 -267.463904)
			(xy 349.906719 -267.422308) (xy 349.939354 -267.385471) (xy 349.977475 -267.354346) (xy 350.020096 -267.329739)
			(xy 350.066112 -267.312287) (xy 350.114331 -267.302443) (xy 350.163506 -267.300462) (xy 350.212361 -267.306394)
			(xy 350.259632 -267.320086) (xy 350.304094 -267.341184) (xy 350.344597 -267.36914) (xy 350.38009 -267.403232)
			(xy 350.409655 -267.442576) (xy 350.432526 -267.486153) (xy 350.44811 -267.532834) (xy 350.456005 -267.581411)
			(xy 350.4565 -267.606018) (xy 351.725242 -267.606018) (xy 351.729202 -267.556964) (xy 351.740979 -267.50918)
			(xy 351.76027 -267.463904) (xy 351.786573 -267.422308) (xy 351.819208 -267.385471) (xy 351.857329 -267.354346)
			(xy 351.89995 -267.329739) (xy 351.945966 -267.312287) (xy 351.994185 -267.302443) (xy 352.04336 -267.300462)
			(xy 352.092215 -267.306394) (xy 352.139486 -267.320086) (xy 352.183948 -267.341184) (xy 352.224451 -267.36914)
			(xy 352.259944 -267.403232) (xy 352.289509 -267.442576) (xy 352.31238 -267.486153) (xy 352.327964 -267.532834)
			(xy 352.335859 -267.581411) (xy 352.336354 -267.606018) (xy 353.60535 -267.606018) (xy 353.60931 -267.556964)
			(xy 353.621087 -267.50918) (xy 353.640378 -267.463904) (xy 353.666681 -267.422308) (xy 353.699316 -267.385471)
			(xy 353.737437 -267.354346) (xy 353.780058 -267.329739) (xy 353.826074 -267.312287) (xy 353.874293 -267.302443)
			(xy 353.923468 -267.300462) (xy 353.972323 -267.306394) (xy 354.019594 -267.320086) (xy 354.064056 -267.341184)
			(xy 354.104559 -267.36914) (xy 354.140052 -267.403232) (xy 354.169617 -267.442576) (xy 354.192488 -267.486153)
			(xy 354.208072 -267.532834) (xy 354.215967 -267.581411) (xy 354.216462 -267.606018) (xy 355.485204 -267.606018)
			(xy 355.489164 -267.556964) (xy 355.500941 -267.50918) (xy 355.520232 -267.463904) (xy 355.546535 -267.422308)
			(xy 355.57917 -267.385471) (xy 355.617291 -267.354346) (xy 355.659912 -267.329739) (xy 355.705928 -267.312287)
			(xy 355.754147 -267.302443) (xy 355.803322 -267.300462) (xy 355.852177 -267.306394) (xy 355.899448 -267.320086)
			(xy 355.94391 -267.341184) (xy 355.984413 -267.36914) (xy 356.019906 -267.403232) (xy 356.049471 -267.442576)
			(xy 356.072342 -267.486153) (xy 356.087926 -267.532834) (xy 356.095821 -267.581411) (xy 356.096316 -267.606018)
			(xy 357.365312 -267.606018) (xy 357.369272 -267.556964) (xy 357.381049 -267.50918) (xy 357.40034 -267.463904)
			(xy 357.426643 -267.422308) (xy 357.459278 -267.385471) (xy 357.497399 -267.354346) (xy 357.54002 -267.329739)
			(xy 357.586036 -267.312287) (xy 357.634255 -267.302443) (xy 357.68343 -267.300462) (xy 357.732285 -267.306394)
			(xy 357.779556 -267.320086) (xy 357.824018 -267.341184) (xy 357.864521 -267.36914) (xy 357.900014 -267.403232)
			(xy 357.929579 -267.442576) (xy 357.95245 -267.486153) (xy 357.968034 -267.532834) (xy 357.975929 -267.581411)
			(xy 357.976424 -267.606018) (xy 361.118924 -267.606018) (xy 361.122884 -267.556964) (xy 361.134661 -267.50918)
			(xy 361.153952 -267.463904) (xy 361.180255 -267.422308) (xy 361.21289 -267.385471) (xy 361.251011 -267.354346)
			(xy 361.293632 -267.329739) (xy 361.339648 -267.312287) (xy 361.387867 -267.302443) (xy 361.437042 -267.300462)
			(xy 361.485897 -267.306394) (xy 361.533168 -267.320086) (xy 361.57763 -267.341184) (xy 361.618133 -267.36914)
			(xy 361.653626 -267.403232) (xy 361.683191 -267.442576) (xy 361.706062 -267.486153) (xy 361.721646 -267.532834)
			(xy 361.729541 -267.581411) (xy 361.730036 -267.606018) (xy 362.999032 -267.606018) (xy 363.002992 -267.556964)
			(xy 363.014769 -267.50918) (xy 363.03406 -267.463904) (xy 363.060363 -267.422308) (xy 363.092998 -267.385471)
			(xy 363.131119 -267.354346) (xy 363.17374 -267.329739) (xy 363.219756 -267.312287) (xy 363.267975 -267.302443)
			(xy 363.31715 -267.300462) (xy 363.366005 -267.306394) (xy 363.413276 -267.320086) (xy 363.457738 -267.341184)
			(xy 363.498241 -267.36914) (xy 363.533734 -267.403232) (xy 363.563299 -267.442576) (xy 363.58617 -267.486153)
			(xy 363.601754 -267.532834) (xy 363.609649 -267.581411) (xy 363.610144 -267.606018) (xy 364.878886 -267.606018)
			(xy 364.882846 -267.556964) (xy 364.894623 -267.50918) (xy 364.913914 -267.463904) (xy 364.940217 -267.422308)
			(xy 364.972852 -267.385471) (xy 365.010973 -267.354346) (xy 365.053594 -267.329739) (xy 365.09961 -267.312287)
			(xy 365.147829 -267.302443) (xy 365.197004 -267.300462) (xy 365.245859 -267.306394) (xy 365.29313 -267.320086)
			(xy 365.337592 -267.341184) (xy 365.378095 -267.36914) (xy 365.413588 -267.403232) (xy 365.443153 -267.442576)
			(xy 365.466024 -267.486153) (xy 365.481608 -267.532834) (xy 365.489503 -267.581411) (xy 365.489998 -267.606018)
			(xy 366.758994 -267.606018) (xy 366.762954 -267.556964) (xy 366.774731 -267.50918) (xy 366.794022 -267.463904)
			(xy 366.820325 -267.422308) (xy 366.85296 -267.385471) (xy 366.891081 -267.354346) (xy 366.933702 -267.329739)
			(xy 366.979718 -267.312287) (xy 367.027937 -267.302443) (xy 367.077112 -267.300462) (xy 367.125967 -267.306394)
			(xy 367.173238 -267.320086) (xy 367.2177 -267.341184) (xy 367.258203 -267.36914) (xy 367.293696 -267.403232)
			(xy 367.323261 -267.442576) (xy 367.346132 -267.486153) (xy 367.361716 -267.532834) (xy 367.369611 -267.581411)
			(xy 367.370106 -267.606018) (xy 368.639102 -267.606018) (xy 368.643062 -267.556964) (xy 368.654839 -267.50918)
			(xy 368.67413 -267.463904) (xy 368.700433 -267.422308) (xy 368.733068 -267.385471) (xy 368.771189 -267.354346)
			(xy 368.81381 -267.329739) (xy 368.859826 -267.312287) (xy 368.908045 -267.302443) (xy 368.95722 -267.300462)
			(xy 369.006075 -267.306394) (xy 369.053346 -267.320086) (xy 369.097808 -267.341184) (xy 369.138311 -267.36914)
			(xy 369.173804 -267.403232) (xy 369.203369 -267.442576) (xy 369.22624 -267.486153) (xy 369.241824 -267.532834)
			(xy 369.249719 -267.581411) (xy 369.250214 -267.606018) (xy 370.518956 -267.606018) (xy 370.522916 -267.556964)
			(xy 370.534693 -267.50918) (xy 370.553984 -267.463904) (xy 370.580287 -267.422308) (xy 370.612922 -267.385471)
			(xy 370.651043 -267.354346) (xy 370.693664 -267.329739) (xy 370.73968 -267.312287) (xy 370.787899 -267.302443)
			(xy 370.837074 -267.300462) (xy 370.885929 -267.306394) (xy 370.9332 -267.320086) (xy 370.977662 -267.341184)
			(xy 371.018165 -267.36914) (xy 371.053658 -267.403232) (xy 371.083223 -267.442576) (xy 371.106094 -267.486153)
			(xy 371.121678 -267.532834) (xy 371.129573 -267.581411) (xy 371.130068 -267.606018) (xy 372.399064 -267.606018)
			(xy 372.403024 -267.556964) (xy 372.414801 -267.50918) (xy 372.434092 -267.463904) (xy 372.460395 -267.422308)
			(xy 372.49303 -267.385471) (xy 372.531151 -267.354346) (xy 372.573772 -267.329739) (xy 372.619788 -267.312287)
			(xy 372.668007 -267.302443) (xy 372.717182 -267.300462) (xy 372.766037 -267.306394) (xy 372.813308 -267.320086)
			(xy 372.85777 -267.341184) (xy 372.898273 -267.36914) (xy 372.933766 -267.403232) (xy 372.963331 -267.442576)
			(xy 372.986202 -267.486153) (xy 373.001786 -267.532834) (xy 373.009681 -267.581411) (xy 373.010176 -267.606018)
			(xy 373.009681 -267.630625) (xy 373.001786 -267.679202) (xy 372.986202 -267.725883) (xy 372.963331 -267.76946)
			(xy 372.933766 -267.808804) (xy 372.898273 -267.842896) (xy 372.85777 -267.870852) (xy 372.813308 -267.89195)
			(xy 372.766037 -267.905642) (xy 372.717182 -267.911574) (xy 372.668007 -267.909593) (xy 372.619788 -267.899749)
			(xy 372.573772 -267.882297) (xy 372.531151 -267.85769) (xy 372.49303 -267.826565) (xy 372.460395 -267.789728)
			(xy 372.434092 -267.748132) (xy 372.414801 -267.702856) (xy 372.403024 -267.655072) (xy 372.399064 -267.606018)
			(xy 371.130068 -267.606018) (xy 371.129573 -267.630625) (xy 371.121678 -267.679202) (xy 371.106094 -267.725883)
			(xy 371.083223 -267.76946) (xy 371.053658 -267.808804) (xy 371.018165 -267.842896) (xy 370.977662 -267.870852)
			(xy 370.9332 -267.89195) (xy 370.885929 -267.905642) (xy 370.837074 -267.911574) (xy 370.787899 -267.909593)
			(xy 370.73968 -267.899749) (xy 370.693664 -267.882297) (xy 370.651043 -267.85769) (xy 370.612922 -267.826565)
			(xy 370.580287 -267.789728) (xy 370.553984 -267.748132) (xy 370.534693 -267.702856) (xy 370.522916 -267.655072)
			(xy 370.518956 -267.606018) (xy 369.250214 -267.606018) (xy 369.249719 -267.630625) (xy 369.241824 -267.679202)
			(xy 369.22624 -267.725883) (xy 369.203369 -267.76946) (xy 369.173804 -267.808804) (xy 369.138311 -267.842896)
			(xy 369.097808 -267.870852) (xy 369.053346 -267.89195) (xy 369.006075 -267.905642) (xy 368.95722 -267.911574)
			(xy 368.908045 -267.909593) (xy 368.859826 -267.899749) (xy 368.81381 -267.882297) (xy 368.771189 -267.85769)
			(xy 368.733068 -267.826565) (xy 368.700433 -267.789728) (xy 368.67413 -267.748132) (xy 368.654839 -267.702856)
			(xy 368.643062 -267.655072) (xy 368.639102 -267.606018) (xy 367.370106 -267.606018) (xy 367.369611 -267.630625)
			(xy 367.361716 -267.679202) (xy 367.346132 -267.725883) (xy 367.323261 -267.76946) (xy 367.293696 -267.808804)
			(xy 367.258203 -267.842896) (xy 367.2177 -267.870852) (xy 367.173238 -267.89195) (xy 367.125967 -267.905642)
			(xy 367.077112 -267.911574) (xy 367.027937 -267.909593) (xy 366.979718 -267.899749) (xy 366.933702 -267.882297)
			(xy 366.891081 -267.85769) (xy 366.85296 -267.826565) (xy 366.820325 -267.789728) (xy 366.794022 -267.748132)
			(xy 366.774731 -267.702856) (xy 366.762954 -267.655072) (xy 366.758994 -267.606018) (xy 365.489998 -267.606018)
			(xy 365.489503 -267.630625) (xy 365.481608 -267.679202) (xy 365.466024 -267.725883) (xy 365.443153 -267.76946)
			(xy 365.413588 -267.808804) (xy 365.378095 -267.842896) (xy 365.337592 -267.870852) (xy 365.29313 -267.89195)
			(xy 365.245859 -267.905642) (xy 365.197004 -267.911574) (xy 365.147829 -267.909593) (xy 365.09961 -267.899749)
			(xy 365.053594 -267.882297) (xy 365.010973 -267.85769) (xy 364.972852 -267.826565) (xy 364.940217 -267.789728)
			(xy 364.913914 -267.748132) (xy 364.894623 -267.702856) (xy 364.882846 -267.655072) (xy 364.878886 -267.606018)
			(xy 363.610144 -267.606018) (xy 363.609649 -267.630625) (xy 363.601754 -267.679202) (xy 363.58617 -267.725883)
			(xy 363.563299 -267.76946) (xy 363.533734 -267.808804) (xy 363.498241 -267.842896) (xy 363.457738 -267.870852)
			(xy 363.413276 -267.89195) (xy 363.366005 -267.905642) (xy 363.31715 -267.911574) (xy 363.267975 -267.909593)
			(xy 363.219756 -267.899749) (xy 363.17374 -267.882297) (xy 363.131119 -267.85769) (xy 363.092998 -267.826565)
			(xy 363.060363 -267.789728) (xy 363.03406 -267.748132) (xy 363.014769 -267.702856) (xy 363.002992 -267.655072)
			(xy 362.999032 -267.606018) (xy 361.730036 -267.606018) (xy 361.729541 -267.630625) (xy 361.721646 -267.679202)
			(xy 361.706062 -267.725883) (xy 361.683191 -267.76946) (xy 361.653626 -267.808804) (xy 361.618133 -267.842896)
			(xy 361.57763 -267.870852) (xy 361.533168 -267.89195) (xy 361.485897 -267.905642) (xy 361.437042 -267.911574)
			(xy 361.387867 -267.909593) (xy 361.339648 -267.899749) (xy 361.293632 -267.882297) (xy 361.251011 -267.85769)
			(xy 361.21289 -267.826565) (xy 361.180255 -267.789728) (xy 361.153952 -267.748132) (xy 361.134661 -267.702856)
			(xy 361.122884 -267.655072) (xy 361.118924 -267.606018) (xy 357.976424 -267.606018) (xy 357.975929 -267.630625)
			(xy 357.968034 -267.679202) (xy 357.95245 -267.725883) (xy 357.929579 -267.76946) (xy 357.900014 -267.808804)
			(xy 357.864521 -267.842896) (xy 357.824018 -267.870852) (xy 357.779556 -267.89195) (xy 357.732285 -267.905642)
			(xy 357.68343 -267.911574) (xy 357.634255 -267.909593) (xy 357.586036 -267.899749) (xy 357.54002 -267.882297)
			(xy 357.497399 -267.85769) (xy 357.459278 -267.826565) (xy 357.426643 -267.789728) (xy 357.40034 -267.748132)
			(xy 357.381049 -267.702856) (xy 357.369272 -267.655072) (xy 357.365312 -267.606018) (xy 356.096316 -267.606018)
			(xy 356.095821 -267.630625) (xy 356.087926 -267.679202) (xy 356.072342 -267.725883) (xy 356.049471 -267.76946)
			(xy 356.019906 -267.808804) (xy 355.984413 -267.842896) (xy 355.94391 -267.870852) (xy 355.899448 -267.89195)
			(xy 355.852177 -267.905642) (xy 355.803322 -267.911574) (xy 355.754147 -267.909593) (xy 355.705928 -267.899749)
			(xy 355.659912 -267.882297) (xy 355.617291 -267.85769) (xy 355.57917 -267.826565) (xy 355.546535 -267.789728)
			(xy 355.520232 -267.748132) (xy 355.500941 -267.702856) (xy 355.489164 -267.655072) (xy 355.485204 -267.606018)
			(xy 354.216462 -267.606018) (xy 354.215967 -267.630625) (xy 354.208072 -267.679202) (xy 354.192488 -267.725883)
			(xy 354.169617 -267.76946) (xy 354.140052 -267.808804) (xy 354.104559 -267.842896) (xy 354.064056 -267.870852)
			(xy 354.019594 -267.89195) (xy 353.972323 -267.905642) (xy 353.923468 -267.911574) (xy 353.874293 -267.909593)
			(xy 353.826074 -267.899749) (xy 353.780058 -267.882297) (xy 353.737437 -267.85769) (xy 353.699316 -267.826565)
			(xy 353.666681 -267.789728) (xy 353.640378 -267.748132) (xy 353.621087 -267.702856) (xy 353.60931 -267.655072)
			(xy 353.60535 -267.606018) (xy 352.336354 -267.606018) (xy 352.335859 -267.630625) (xy 352.327964 -267.679202)
			(xy 352.31238 -267.725883) (xy 352.289509 -267.76946) (xy 352.259944 -267.808804) (xy 352.224451 -267.842896)
			(xy 352.183948 -267.870852) (xy 352.139486 -267.89195) (xy 352.092215 -267.905642) (xy 352.04336 -267.911574)
			(xy 351.994185 -267.909593) (xy 351.945966 -267.899749) (xy 351.89995 -267.882297) (xy 351.857329 -267.85769)
			(xy 351.819208 -267.826565) (xy 351.786573 -267.789728) (xy 351.76027 -267.748132) (xy 351.740979 -267.702856)
			(xy 351.729202 -267.655072) (xy 351.725242 -267.606018) (xy 350.4565 -267.606018) (xy 350.456005 -267.630625)
			(xy 350.44811 -267.679202) (xy 350.432526 -267.725883) (xy 350.409655 -267.76946) (xy 350.38009 -267.808804)
			(xy 350.344597 -267.842896) (xy 350.304094 -267.870852) (xy 350.259632 -267.89195) (xy 350.212361 -267.905642)
			(xy 350.163506 -267.911574) (xy 350.114331 -267.909593) (xy 350.066112 -267.899749) (xy 350.020096 -267.882297)
			(xy 349.977475 -267.85769) (xy 349.939354 -267.826565) (xy 349.906719 -267.789728) (xy 349.880416 -267.748132)
			(xy 349.861125 -267.702856) (xy 349.849348 -267.655072) (xy 349.845388 -267.606018) (xy 348.576392 -267.606018)
			(xy 348.575897 -267.630625) (xy 348.568002 -267.679202) (xy 348.552418 -267.725883) (xy 348.529547 -267.76946)
			(xy 348.499982 -267.808804) (xy 348.464489 -267.842896) (xy 348.423986 -267.870852) (xy 348.379524 -267.89195)
			(xy 348.332253 -267.905642) (xy 348.283398 -267.911574) (xy 348.234223 -267.909593) (xy 348.186004 -267.899749)
			(xy 348.139988 -267.882297) (xy 348.097367 -267.85769) (xy 348.059246 -267.826565) (xy 348.026611 -267.789728)
			(xy 348.000308 -267.748132) (xy 347.981017 -267.702856) (xy 347.96924 -267.655072) (xy 347.96528 -267.606018)
			(xy 347.636338 -267.606018) (xy 347.635843 -267.630625) (xy 347.627948 -267.679202) (xy 347.612364 -267.725883)
			(xy 347.589493 -267.76946) (xy 347.559928 -267.808804) (xy 347.524435 -267.842896) (xy 347.483932 -267.870852)
			(xy 347.43947 -267.89195) (xy 347.392199 -267.905642) (xy 347.343344 -267.911574) (xy 347.294169 -267.909593)
			(xy 347.24595 -267.899749) (xy 347.199934 -267.882297) (xy 347.157313 -267.85769) (xy 347.119192 -267.826565)
			(xy 347.086557 -267.789728) (xy 347.060254 -267.748132) (xy 347.040963 -267.702856) (xy 347.029186 -267.655072)
			(xy 347.025226 -267.606018) (xy 346.696538 -267.606018) (xy 346.696043 -267.630625) (xy 346.688148 -267.679202)
			(xy 346.672564 -267.725883) (xy 346.649693 -267.76946) (xy 346.620128 -267.808804) (xy 346.584635 -267.842896)
			(xy 346.544132 -267.870852) (xy 346.49967 -267.89195) (xy 346.452399 -267.905642) (xy 346.403544 -267.911574)
			(xy 346.354369 -267.909593) (xy 346.30615 -267.899749) (xy 346.260134 -267.882297) (xy 346.217513 -267.85769)
			(xy 346.179392 -267.826565) (xy 346.146757 -267.789728) (xy 346.120454 -267.748132) (xy 346.101163 -267.702856)
			(xy 346.089386 -267.655072) (xy 346.085426 -267.606018) (xy 345.756484 -267.606018) (xy 345.756036 -267.63001)
			(xy 345.748527 -267.677401) (xy 345.733697 -267.723035) (xy 345.71191 -267.765787) (xy 345.683704 -267.804604)
			(xy 345.649772 -267.838531) (xy 345.610951 -267.866732) (xy 345.568196 -267.888513) (xy 345.522561 -267.903337)
			(xy 345.475168 -267.91084) (xy 345.451176 -267.911326) (xy 345.44254 -267.911326) (xy 345.432634 -267.910818)
			(xy 345.412822 -267.918438) (xy 345.3257 -268.00556) (xy 359.650541 -268.00556) (xy 359.654571 -267.953062)
			(xy 359.666568 -267.901794) (xy 359.686251 -267.852959) (xy 359.713157 -267.8077) (xy 359.746657 -267.767079)
			(xy 359.785965 -267.732048) (xy 359.83016 -267.703428) (xy 359.878205 -267.681889) (xy 359.928976 -267.667937)
			(xy 359.981281 -267.661899) (xy 360.033895 -267.663916) (xy 360.085585 -267.67394) (xy 360.135138 -267.691738)
			(xy 360.181394 -267.716891) (xy 360.223268 -267.74881) (xy 360.25978 -267.786748) (xy 360.290072 -267.829814)
			(xy 360.313435 -267.876999) (xy 360.329321 -267.927198) (xy 360.337358 -267.979234) (xy 360.337862 -268.00556)
			(xy 360.337358 -268.031886) (xy 360.329321 -268.083922) (xy 360.313435 -268.134121) (xy 360.290072 -268.181306)
			(xy 360.25978 -268.224372) (xy 360.223268 -268.26231) (xy 360.181394 -268.294229) (xy 360.135138 -268.319382)
			(xy 360.085585 -268.33718) (xy 360.033895 -268.347204) (xy 359.981281 -268.349221) (xy 359.928976 -268.343183)
			(xy 359.878205 -268.329231) (xy 359.83016 -268.307692) (xy 359.785965 -268.279072) (xy 359.746657 -268.244041)
			(xy 359.713157 -268.20342) (xy 359.686251 -268.158161) (xy 359.666568 -268.109326) (xy 359.654571 -268.058058)
			(xy 359.650541 -268.00556) (xy 345.3257 -268.00556) (xy 345.218766 -268.112494) (xy 345.211911 -268.119889)
			(xy 345.204164 -268.138488) (xy 345.20378 -268.148562) (xy 345.20378 -268.187932) (xy 345.206828 -268.20495)
			(xy 345.212162 -268.21638) (xy 345.21648 -268.22146) (xy 345.232628 -268.241817) (xy 345.258474 -268.286888)
			(xy 345.276321 -268.335683) (xy 345.285654 -268.386795) (xy 345.285963 -268.416024) (xy 345.615272 -268.416024)
			(xy 345.619232 -268.36697) (xy 345.631009 -268.319186) (xy 345.6503 -268.27391) (xy 345.676603 -268.232314)
			(xy 345.709238 -268.195477) (xy 345.747359 -268.164352) (xy 345.78998 -268.139745) (xy 345.835996 -268.122293)
			(xy 345.884215 -268.112449) (xy 345.93339 -268.110468) (xy 345.982245 -268.1164) (xy 346.029516 -268.130092)
			(xy 346.073978 -268.15119) (xy 346.114481 -268.179146) (xy 346.149974 -268.213238) (xy 346.179539 -268.252582)
			(xy 346.20241 -268.296159) (xy 346.217994 -268.34284) (xy 346.225889 -268.391417) (xy 346.226384 -268.416024)
			(xy 347.49538 -268.416024) (xy 347.49934 -268.36697) (xy 347.511117 -268.319186) (xy 347.530408 -268.27391)
			(xy 347.556711 -268.232314) (xy 347.589346 -268.195477) (xy 347.627467 -268.164352) (xy 347.670088 -268.139745)
			(xy 347.716104 -268.122293) (xy 347.764323 -268.112449) (xy 347.813498 -268.110468) (xy 347.862353 -268.1164)
			(xy 347.909624 -268.130092) (xy 347.954086 -268.15119) (xy 347.994589 -268.179146) (xy 348.030082 -268.213238)
			(xy 348.059647 -268.252582) (xy 348.082518 -268.296159) (xy 348.098102 -268.34284) (xy 348.105997 -268.391417)
			(xy 348.106492 -268.416024) (xy 349.375234 -268.416024) (xy 349.379194 -268.36697) (xy 349.390971 -268.319186)
			(xy 349.410262 -268.27391) (xy 349.436565 -268.232314) (xy 349.4692 -268.195477) (xy 349.507321 -268.164352)
			(xy 349.549942 -268.139745) (xy 349.595958 -268.122293) (xy 349.644177 -268.112449) (xy 349.693352 -268.110468)
			(xy 349.742207 -268.1164) (xy 349.789478 -268.130092) (xy 349.83394 -268.15119) (xy 349.874443 -268.179146)
			(xy 349.909936 -268.213238) (xy 349.939501 -268.252582) (xy 349.962372 -268.296159) (xy 349.977956 -268.34284)
			(xy 349.985851 -268.391417) (xy 349.986346 -268.416024) (xy 351.255342 -268.416024) (xy 351.259302 -268.36697)
			(xy 351.271079 -268.319186) (xy 351.29037 -268.27391) (xy 351.316673 -268.232314) (xy 351.349308 -268.195477)
			(xy 351.387429 -268.164352) (xy 351.43005 -268.139745) (xy 351.476066 -268.122293) (xy 351.524285 -268.112449)
			(xy 351.57346 -268.110468) (xy 351.622315 -268.1164) (xy 351.669586 -268.130092) (xy 351.714048 -268.15119)
			(xy 351.754551 -268.179146) (xy 351.790044 -268.213238) (xy 351.819609 -268.252582) (xy 351.84248 -268.296159)
			(xy 351.858064 -268.34284) (xy 351.865959 -268.391417) (xy 351.866454 -268.416024) (xy 353.135196 -268.416024)
			(xy 353.139156 -268.36697) (xy 353.150933 -268.319186) (xy 353.170224 -268.27391) (xy 353.196527 -268.232314)
			(xy 353.229162 -268.195477) (xy 353.267283 -268.164352) (xy 353.309904 -268.139745) (xy 353.35592 -268.122293)
			(xy 353.404139 -268.112449) (xy 353.453314 -268.110468) (xy 353.502169 -268.1164) (xy 353.54944 -268.130092)
			(xy 353.593902 -268.15119) (xy 353.634405 -268.179146) (xy 353.669898 -268.213238) (xy 353.699463 -268.252582)
			(xy 353.722334 -268.296159) (xy 353.737918 -268.34284) (xy 353.745813 -268.391417) (xy 353.746308 -268.416024)
			(xy 355.015304 -268.416024) (xy 355.019264 -268.36697) (xy 355.031041 -268.319186) (xy 355.050332 -268.27391)
			(xy 355.076635 -268.232314) (xy 355.10927 -268.195477) (xy 355.147391 -268.164352) (xy 355.190012 -268.139745)
			(xy 355.236028 -268.122293) (xy 355.284247 -268.112449) (xy 355.333422 -268.110468) (xy 355.382277 -268.1164)
			(xy 355.429548 -268.130092) (xy 355.47401 -268.15119) (xy 355.514513 -268.179146) (xy 355.550006 -268.213238)
			(xy 355.579571 -268.252582) (xy 355.602442 -268.296159) (xy 355.618026 -268.34284) (xy 355.625921 -268.391417)
			(xy 355.626416 -268.416024) (xy 355.625921 -268.440631) (xy 355.618026 -268.489208) (xy 355.602442 -268.535889)
			(xy 355.579571 -268.579466) (xy 355.550006 -268.61881) (xy 355.514513 -268.652902) (xy 355.47401 -268.680858)
			(xy 355.429548 -268.701956) (xy 355.382277 -268.715648) (xy 355.333422 -268.72158) (xy 355.284247 -268.719599)
			(xy 355.236028 -268.709755) (xy 355.190012 -268.692303) (xy 355.147391 -268.667696) (xy 355.10927 -268.636571)
			(xy 355.076635 -268.599734) (xy 355.050332 -268.558138) (xy 355.031041 -268.512862) (xy 355.019264 -268.465078)
			(xy 355.015304 -268.416024) (xy 353.746308 -268.416024) (xy 353.745813 -268.440631) (xy 353.737918 -268.489208)
			(xy 353.722334 -268.535889) (xy 353.699463 -268.579466) (xy 353.669898 -268.61881) (xy 353.634405 -268.652902)
			(xy 353.593902 -268.680858) (xy 353.54944 -268.701956) (xy 353.502169 -268.715648) (xy 353.453314 -268.72158)
			(xy 353.404139 -268.719599) (xy 353.35592 -268.709755) (xy 353.309904 -268.692303) (xy 353.267283 -268.667696)
			(xy 353.229162 -268.636571) (xy 353.196527 -268.599734) (xy 353.170224 -268.558138) (xy 353.150933 -268.512862)
			(xy 353.139156 -268.465078) (xy 353.135196 -268.416024) (xy 351.866454 -268.416024) (xy 351.865959 -268.440631)
			(xy 351.858064 -268.489208) (xy 351.84248 -268.535889) (xy 351.819609 -268.579466) (xy 351.790044 -268.61881)
			(xy 351.754551 -268.652902) (xy 351.714048 -268.680858) (xy 351.669586 -268.701956) (xy 351.622315 -268.715648)
			(xy 351.57346 -268.72158) (xy 351.524285 -268.719599) (xy 351.476066 -268.709755) (xy 351.43005 -268.692303)
			(xy 351.387429 -268.667696) (xy 351.349308 -268.636571) (xy 351.316673 -268.599734) (xy 351.29037 -268.558138)
			(xy 351.271079 -268.512862) (xy 351.259302 -268.465078) (xy 351.255342 -268.416024) (xy 349.986346 -268.416024)
			(xy 349.985851 -268.440631) (xy 349.977956 -268.489208) (xy 349.962372 -268.535889) (xy 349.939501 -268.579466)
			(xy 349.909936 -268.61881) (xy 349.874443 -268.652902) (xy 349.83394 -268.680858) (xy 349.789478 -268.701956)
			(xy 349.742207 -268.715648) (xy 349.693352 -268.72158) (xy 349.644177 -268.719599) (xy 349.595958 -268.709755)
			(xy 349.549942 -268.692303) (xy 349.507321 -268.667696) (xy 349.4692 -268.636571) (xy 349.436565 -268.599734)
			(xy 349.410262 -268.558138) (xy 349.390971 -268.512862) (xy 349.379194 -268.465078) (xy 349.375234 -268.416024)
			(xy 348.106492 -268.416024) (xy 348.105997 -268.440631) (xy 348.098102 -268.489208) (xy 348.082518 -268.535889)
			(xy 348.059647 -268.579466) (xy 348.030082 -268.61881) (xy 347.994589 -268.652902) (xy 347.954086 -268.680858)
			(xy 347.909624 -268.701956) (xy 347.862353 -268.715648) (xy 347.813498 -268.72158) (xy 347.764323 -268.719599)
			(xy 347.716104 -268.709755) (xy 347.670088 -268.692303) (xy 347.627467 -268.667696) (xy 347.589346 -268.636571)
			(xy 347.556711 -268.599734) (xy 347.530408 -268.558138) (xy 347.511117 -268.512862) (xy 347.49934 -268.465078)
			(xy 347.49538 -268.416024) (xy 346.226384 -268.416024) (xy 346.225889 -268.440631) (xy 346.217994 -268.489208)
			(xy 346.20241 -268.535889) (xy 346.179539 -268.579466) (xy 346.149974 -268.61881) (xy 346.114481 -268.652902)
			(xy 346.073978 -268.680858) (xy 346.029516 -268.701956) (xy 345.982245 -268.715648) (xy 345.93339 -268.72158)
			(xy 345.884215 -268.719599) (xy 345.835996 -268.709755) (xy 345.78998 -268.692303) (xy 345.747359 -268.667696)
			(xy 345.709238 -268.636571) (xy 345.676603 -268.599734) (xy 345.6503 -268.558138) (xy 345.631009 -268.512862)
			(xy 345.619232 -268.465078) (xy 345.615272 -268.416024) (xy 345.285963 -268.416024) (xy 345.286204 -268.438748)
			(xy 345.277956 -268.490046) (xy 345.261146 -268.539208) (xy 345.23626 -268.584817) (xy 345.220544 -268.605508)
			(xy 345.215464 -268.612112) (xy 345.206828 -268.63548) (xy 345.20542 -268.639659) (xy 345.203891 -268.648343)
			(xy 345.20378 -268.652752) (xy 345.20378 -269.269718) (xy 345.204206 -269.279787) (xy 345.211923 -269.298389)
			(xy 345.218766 -269.305786) (xy 345.346274 -269.433294) (xy 345.353676 -269.440129) (xy 345.372275 -269.447838)
			(xy 345.382342 -269.44828) (xy 346.94241 -269.44828) (xy 346.954353 -269.447648) (xy 346.975702 -269.436935)
			(xy 346.983304 -269.427706) (xy 347.03893 -269.352268) (xy 347.042994 -269.328392) (xy 347.039438 -269.316708)
			(xy 347.033082 -269.294772) (xy 347.026195 -269.249625) (xy 347.025722 -269.226792) (xy 347.025722 -269.22603)
			(xy 347.026166 -269.202036) (xy 347.033669 -269.154639) (xy 347.048495 -269.108999) (xy 347.07028 -269.066241)
			(xy 347.098485 -269.027418) (xy 347.132418 -268.993485) (xy 347.171241 -268.96528) (xy 347.213999 -268.943495)
			(xy 347.259639 -268.928669) (xy 347.307036 -268.921166) (xy 347.33103 -268.920722) (xy 347.354917 -268.921187)
			(xy 347.402108 -268.928634) (xy 347.447563 -268.943341) (xy 347.490172 -268.96495) (xy 347.528895 -268.992932)
			(xy 347.562785 -269.026604) (xy 347.591017 -269.065145) (xy 347.6129 -269.107614) (xy 347.627901 -269.152973)
			(xy 347.635652 -269.200115) (xy 347.636338 -269.223998) (xy 347.636338 -269.226284) (xy 347.635911 -269.249184)
			(xy 347.629025 -269.294464) (xy 347.622622 -269.316454) (xy 347.622622 -269.316708) (xy 347.61972 -269.328321)
			(xy 347.6237 -269.351894) (xy 347.630242 -269.36192) (xy 347.678756 -269.427706) (xy 347.686364 -269.436938)
			(xy 347.707703 -269.447684) (xy 347.71965 -269.44828) (xy 349.762572 -269.44828) (xy 349.774508 -269.447635)
			(xy 349.795835 -269.436907) (xy 349.803466 -269.427706) (xy 349.859092 -269.352268) (xy 349.863156 -269.328392)
			(xy 349.8596 -269.316708) (xy 349.853245 -269.294772) (xy 349.846358 -269.249625) (xy 349.845884 -269.226792)
			(xy 349.845884 -269.22603) (xy 349.846328 -269.202035) (xy 349.853831 -269.154635) (xy 349.868657 -269.108993)
			(xy 349.89044 -269.066232) (xy 349.918645 -269.027406) (xy 349.952577 -268.99347) (xy 349.9914 -268.96526)
			(xy 350.034158 -268.943471) (xy 350.079798 -268.92864) (xy 350.127197 -268.921131) (xy 350.151192 -268.920722)
			(xy 350.175081 -268.921184) (xy 350.222277 -268.928626) (xy 350.267737 -268.94333) (xy 350.310351 -268.964937)
			(xy 350.349078 -268.992918) (xy 350.382974 -269.026591) (xy 350.41121 -269.065134) (xy 350.433097 -269.107605)
			(xy 350.448099 -269.152967) (xy 350.455852 -269.200112) (xy 350.4565 -269.223998) (xy 350.4565 -269.226284)
			(xy 350.456073 -269.249184) (xy 350.449186 -269.294463) (xy 350.442784 -269.316454) (xy 350.442784 -269.316708)
			(xy 350.439883 -269.328321) (xy 350.443861 -269.351896) (xy 350.450404 -269.36192) (xy 350.498918 -269.427706)
			(xy 350.50653 -269.436928) (xy 350.527869 -269.447648) (xy 350.539812 -269.44828) (xy 352.58248 -269.44828)
			(xy 352.594415 -269.447633) (xy 352.61574 -269.436903) (xy 352.623374 -269.427706) (xy 352.679 -269.352268)
			(xy 352.683064 -269.328392) (xy 352.679508 -269.316708) (xy 352.673153 -269.294772) (xy 352.666266 -269.249625)
			(xy 352.665792 -269.226792) (xy 352.665792 -269.22603) (xy 352.666236 -269.202035) (xy 352.673739 -269.154636)
			(xy 352.688565 -269.108995) (xy 352.710349 -269.066234) (xy 352.738554 -269.027408) (xy 352.772486 -268.993473)
			(xy 352.811309 -268.965264) (xy 352.854067 -268.943476) (xy 352.899707 -268.928646) (xy 352.947105 -268.921138)
			(xy 352.9711 -268.920722) (xy 352.994989 -268.921185) (xy 353.042183 -268.928628) (xy 353.087642 -268.943332)
			(xy 353.130255 -268.964939) (xy 353.168982 -268.992921) (xy 353.202876 -269.026594) (xy 353.231111 -269.065136)
			(xy 353.252997 -269.107607) (xy 353.268 -269.152968) (xy 353.275752 -269.200113) (xy 353.276408 -269.223998)
			(xy 353.276408 -269.226284) (xy 353.275981 -269.249184) (xy 353.269095 -269.294463) (xy 353.262692 -269.316454)
			(xy 353.262692 -269.316708) (xy 353.25979 -269.328321) (xy 353.263769 -269.351895) (xy 353.270312 -269.36192)
			(xy 353.318826 -269.427706) (xy 353.326432 -269.436944) (xy 353.34777 -269.447702) (xy 353.35972 -269.44828)
			(xy 355.103938 -269.44828) (xy 355.114005 -269.447849) (xy 355.132597 -269.440123) (xy 355.140006 -269.433294)
			(xy 355.874574 -268.698726) (xy 355.881975 -268.691888) (xy 355.900574 -268.684177) (xy 355.910642 -268.68374)
			(xy 356.570026 -268.68374) (xy 356.576884 -268.681708) (xy 356.614518 -268.671745) (xy 356.691629 -268.66104)
			(xy 356.730554 -268.660372) (xy 356.819962 -268.660372) (xy 356.832284 -268.659772) (xy 356.854098 -268.64831)
			(xy 356.861618 -268.638528) (xy 356.90937 -268.569948) (xy 356.915927 -268.559472) (xy 356.918997 -268.534976)
			(xy 356.915212 -268.523212) (xy 356.906244 -268.497523) (xy 356.896541 -268.443989) (xy 356.895908 -268.416786)
			(xy 356.895908 -268.416024) (xy 356.89643 -268.390769) (xy 356.904743 -268.340947) (xy 356.921144 -268.293173)
			(xy 356.945185 -268.24875) (xy 356.976209 -268.20889) (xy 357.013371 -268.17468) (xy 357.055657 -268.147054)
			(xy 357.101913 -268.126764) (xy 357.150878 -268.114364) (xy 357.201216 -268.110193) (xy 357.251554 -268.114364)
			(xy 357.300519 -268.126764) (xy 357.346775 -268.147054) (xy 357.389061 -268.17468) (xy 357.426223 -268.20889)
			(xy 357.457247 -268.24875) (xy 357.481288 -268.293173) (xy 357.497689 -268.340947) (xy 357.506002 -268.390769)
			(xy 357.506524 -268.416024) (xy 361.589078 -268.416024) (xy 361.593038 -268.36697) (xy 361.604815 -268.319186)
			(xy 361.624106 -268.27391) (xy 361.650409 -268.232314) (xy 361.683044 -268.195477) (xy 361.721165 -268.164352)
			(xy 361.763786 -268.139745) (xy 361.809802 -268.122293) (xy 361.858021 -268.112449) (xy 361.907196 -268.110468)
			(xy 361.956051 -268.1164) (xy 362.003322 -268.130092) (xy 362.047784 -268.15119) (xy 362.088287 -268.179146)
			(xy 362.12378 -268.213238) (xy 362.153345 -268.252582) (xy 362.176216 -268.296159) (xy 362.1918 -268.34284)
			(xy 362.199695 -268.391417) (xy 362.20019 -268.416024) (xy 363.468932 -268.416024) (xy 363.472892 -268.36697)
			(xy 363.484669 -268.319186) (xy 363.50396 -268.27391) (xy 363.530263 -268.232314) (xy 363.562898 -268.195477)
			(xy 363.601019 -268.164352) (xy 363.64364 -268.139745) (xy 363.689656 -268.122293) (xy 363.737875 -268.112449)
			(xy 363.78705 -268.110468) (xy 363.835905 -268.1164) (xy 363.883176 -268.130092) (xy 363.927638 -268.15119)
			(xy 363.968141 -268.179146) (xy 364.003634 -268.213238) (xy 364.033199 -268.252582) (xy 364.05607 -268.296159)
			(xy 364.071654 -268.34284) (xy 364.079549 -268.391417) (xy 364.080044 -268.416024) (xy 365.34904 -268.416024)
			(xy 365.353 -268.36697) (xy 365.364777 -268.319186) (xy 365.384068 -268.27391) (xy 365.410371 -268.232314)
			(xy 365.443006 -268.195477) (xy 365.481127 -268.164352) (xy 365.523748 -268.139745) (xy 365.569764 -268.122293)
			(xy 365.617983 -268.112449) (xy 365.667158 -268.110468) (xy 365.716013 -268.1164) (xy 365.763284 -268.130092)
			(xy 365.807746 -268.15119) (xy 365.848249 -268.179146) (xy 365.883742 -268.213238) (xy 365.913307 -268.252582)
			(xy 365.936178 -268.296159) (xy 365.951762 -268.34284) (xy 365.959657 -268.391417) (xy 365.960152 -268.416024)
			(xy 367.228894 -268.416024) (xy 367.232854 -268.36697) (xy 367.244631 -268.319186) (xy 367.263922 -268.27391)
			(xy 367.290225 -268.232314) (xy 367.32286 -268.195477) (xy 367.360981 -268.164352) (xy 367.403602 -268.139745)
			(xy 367.449618 -268.122293) (xy 367.497837 -268.112449) (xy 367.547012 -268.110468) (xy 367.595867 -268.1164)
			(xy 367.643138 -268.130092) (xy 367.6876 -268.15119) (xy 367.728103 -268.179146) (xy 367.763596 -268.213238)
			(xy 367.793161 -268.252582) (xy 367.816032 -268.296159) (xy 367.831616 -268.34284) (xy 367.839511 -268.391417)
			(xy 367.840006 -268.416024) (xy 369.109002 -268.416024) (xy 369.112962 -268.36697) (xy 369.124739 -268.319186)
			(xy 369.14403 -268.27391) (xy 369.170333 -268.232314) (xy 369.202968 -268.195477) (xy 369.241089 -268.164352)
			(xy 369.28371 -268.139745) (xy 369.329726 -268.122293) (xy 369.377945 -268.112449) (xy 369.42712 -268.110468)
			(xy 369.475975 -268.1164) (xy 369.523246 -268.130092) (xy 369.567708 -268.15119) (xy 369.608211 -268.179146)
			(xy 369.643704 -268.213238) (xy 369.673269 -268.252582) (xy 369.69614 -268.296159) (xy 369.711724 -268.34284)
			(xy 369.719619 -268.391417) (xy 369.720114 -268.416024) (xy 370.98911 -268.416024) (xy 370.99307 -268.36697)
			(xy 371.004847 -268.319186) (xy 371.024138 -268.27391) (xy 371.050441 -268.232314) (xy 371.083076 -268.195477)
			(xy 371.121197 -268.164352) (xy 371.163818 -268.139745) (xy 371.209834 -268.122293) (xy 371.258053 -268.112449)
			(xy 371.307228 -268.110468) (xy 371.356083 -268.1164) (xy 371.403354 -268.130092) (xy 371.447816 -268.15119)
			(xy 371.488319 -268.179146) (xy 371.523812 -268.213238) (xy 371.553377 -268.252582) (xy 371.576248 -268.296159)
			(xy 371.591832 -268.34284) (xy 371.599727 -268.391417) (xy 371.600222 -268.416024) (xy 372.868964 -268.416024)
			(xy 372.872924 -268.36697) (xy 372.884701 -268.319186) (xy 372.903992 -268.27391) (xy 372.930295 -268.232314)
			(xy 372.96293 -268.195477) (xy 373.001051 -268.164352) (xy 373.043672 -268.139745) (xy 373.089688 -268.122293)
			(xy 373.137907 -268.112449) (xy 373.187082 -268.110468) (xy 373.235937 -268.1164) (xy 373.283208 -268.130092)
			(xy 373.32767 -268.15119) (xy 373.368173 -268.179146) (xy 373.403666 -268.213238) (xy 373.433231 -268.252582)
			(xy 373.456102 -268.296159) (xy 373.471686 -268.34284) (xy 373.479581 -268.391417) (xy 373.480076 -268.416024)
			(xy 373.479581 -268.440631) (xy 373.471686 -268.489208) (xy 373.456102 -268.535889) (xy 373.433231 -268.579466)
			(xy 373.403666 -268.61881) (xy 373.368173 -268.652902) (xy 373.32767 -268.680858) (xy 373.283208 -268.701956)
			(xy 373.235937 -268.715648) (xy 373.187082 -268.72158) (xy 373.137907 -268.719599) (xy 373.089688 -268.709755)
			(xy 373.043672 -268.692303) (xy 373.001051 -268.667696) (xy 372.96293 -268.636571) (xy 372.930295 -268.599734)
			(xy 372.903992 -268.558138) (xy 372.884701 -268.512862) (xy 372.872924 -268.465078) (xy 372.868964 -268.416024)
			(xy 371.600222 -268.416024) (xy 371.599727 -268.440631) (xy 371.591832 -268.489208) (xy 371.576248 -268.535889)
			(xy 371.553377 -268.579466) (xy 371.523812 -268.61881) (xy 371.488319 -268.652902) (xy 371.447816 -268.680858)
			(xy 371.403354 -268.701956) (xy 371.356083 -268.715648) (xy 371.307228 -268.72158) (xy 371.258053 -268.719599)
			(xy 371.209834 -268.709755) (xy 371.163818 -268.692303) (xy 371.121197 -268.667696) (xy 371.083076 -268.636571)
			(xy 371.050441 -268.599734) (xy 371.024138 -268.558138) (xy 371.004847 -268.512862) (xy 370.99307 -268.465078)
			(xy 370.98911 -268.416024) (xy 369.720114 -268.416024) (xy 369.719619 -268.440631) (xy 369.711724 -268.489208)
			(xy 369.69614 -268.535889) (xy 369.673269 -268.579466) (xy 369.643704 -268.61881) (xy 369.608211 -268.652902)
			(xy 369.567708 -268.680858) (xy 369.523246 -268.701956) (xy 369.475975 -268.715648) (xy 369.42712 -268.72158)
			(xy 369.377945 -268.719599) (xy 369.329726 -268.709755) (xy 369.28371 -268.692303) (xy 369.241089 -268.667696)
			(xy 369.202968 -268.636571) (xy 369.170333 -268.599734) (xy 369.14403 -268.558138) (xy 369.124739 -268.512862)
			(xy 369.112962 -268.465078) (xy 369.109002 -268.416024) (xy 367.840006 -268.416024) (xy 367.839511 -268.440631)
			(xy 367.831616 -268.489208) (xy 367.816032 -268.535889) (xy 367.793161 -268.579466) (xy 367.763596 -268.61881)
			(xy 367.728103 -268.652902) (xy 367.6876 -268.680858) (xy 367.643138 -268.701956) (xy 367.595867 -268.715648)
			(xy 367.547012 -268.72158) (xy 367.497837 -268.719599) (xy 367.449618 -268.709755) (xy 367.403602 -268.692303)
			(xy 367.360981 -268.667696) (xy 367.32286 -268.636571) (xy 367.290225 -268.599734) (xy 367.263922 -268.558138)
			(xy 367.244631 -268.512862) (xy 367.232854 -268.465078) (xy 367.228894 -268.416024) (xy 365.960152 -268.416024)
			(xy 365.959657 -268.440631) (xy 365.951762 -268.489208) (xy 365.936178 -268.535889) (xy 365.913307 -268.579466)
			(xy 365.883742 -268.61881) (xy 365.848249 -268.652902) (xy 365.807746 -268.680858) (xy 365.763284 -268.701956)
			(xy 365.716013 -268.715648) (xy 365.667158 -268.72158) (xy 365.617983 -268.719599) (xy 365.569764 -268.709755)
			(xy 365.523748 -268.692303) (xy 365.481127 -268.667696) (xy 365.443006 -268.636571) (xy 365.410371 -268.599734)
			(xy 365.384068 -268.558138) (xy 365.364777 -268.512862) (xy 365.353 -268.465078) (xy 365.34904 -268.416024)
			(xy 364.080044 -268.416024) (xy 364.079549 -268.440631) (xy 364.071654 -268.489208) (xy 364.05607 -268.535889)
			(xy 364.033199 -268.579466) (xy 364.003634 -268.61881) (xy 363.968141 -268.652902) (xy 363.927638 -268.680858)
			(xy 363.883176 -268.701956) (xy 363.835905 -268.715648) (xy 363.78705 -268.72158) (xy 363.737875 -268.719599)
			(xy 363.689656 -268.709755) (xy 363.64364 -268.692303) (xy 363.601019 -268.667696) (xy 363.562898 -268.636571)
			(xy 363.530263 -268.599734) (xy 363.50396 -268.558138) (xy 363.484669 -268.512862) (xy 363.472892 -268.465078)
			(xy 363.468932 -268.416024) (xy 362.20019 -268.416024) (xy 362.199695 -268.440631) (xy 362.1918 -268.489208)
			(xy 362.176216 -268.535889) (xy 362.153345 -268.579466) (xy 362.12378 -268.61881) (xy 362.088287 -268.652902)
			(xy 362.047784 -268.680858) (xy 362.003322 -268.701956) (xy 361.956051 -268.715648) (xy 361.907196 -268.72158)
			(xy 361.858021 -268.719599) (xy 361.809802 -268.709755) (xy 361.763786 -268.692303) (xy 361.721165 -268.667696)
			(xy 361.683044 -268.636571) (xy 361.650409 -268.599734) (xy 361.624106 -268.558138) (xy 361.604815 -268.512862)
			(xy 361.593038 -268.465078) (xy 361.589078 -268.416024) (xy 357.506524 -268.416024) (xy 357.506524 -268.416786)
			(xy 357.505884 -268.443988) (xy 357.496179 -268.497521) (xy 357.48722 -268.523212) (xy 357.482648 -268.53515)
			(xy 357.48595 -268.559788) (xy 357.540814 -268.638528) (xy 357.548428 -268.648195) (xy 357.570188 -268.659607)
			(xy 357.58247 -268.660372) (xy 357.671624 -268.660372) (xy 357.710549 -268.661035) (xy 357.787662 -268.671737)
			(xy 357.825294 -268.681708) (xy 357.832152 -268.68374) (xy 357.999538 -268.68374) (xy 358.009604 -268.684171)
			(xy 358.028195 -268.6919) (xy 358.035606 -268.698726) (xy 358.321102 -268.984222) (xy 358.321864 -268.984984)
			(xy 358.329052 -268.991369) (xy 358.346809 -268.998699) (xy 358.356408 -268.999208) (xy 358.378506 -268.999462)
			(xy 358.383032 -268.999443) (xy 358.39197 -268.998032) (xy 358.396286 -268.996668) (xy 358.418892 -268.988794)
			(xy 358.425242 -268.983714) (xy 358.445388 -268.968907) (xy 358.489494 -268.945367) (xy 358.536843 -268.92932)
			(xy 358.586173 -268.921193) (xy 358.61117 -268.920722) (xy 358.635164 -268.921166) (xy 358.682561 -268.928669)
			(xy 358.728201 -268.943495) (xy 358.770959 -268.96528) (xy 358.809782 -268.993485) (xy 358.843715 -269.027418)
			(xy 358.87192 -269.066241) (xy 358.893705 -269.108999) (xy 358.908531 -269.154639) (xy 358.916034 -269.202036)
			(xy 358.916478 -269.22603) (xy 361.118924 -269.22603) (xy 361.122884 -269.176976) (xy 361.134661 -269.129192)
			(xy 361.153952 -269.083916) (xy 361.180255 -269.04232) (xy 361.21289 -269.005483) (xy 361.251011 -268.974358)
			(xy 361.293632 -268.949751) (xy 361.339648 -268.932299) (xy 361.387867 -268.922455) (xy 361.437042 -268.920474)
			(xy 361.485897 -268.926406) (xy 361.533168 -268.940098) (xy 361.57763 -268.961196) (xy 361.618133 -268.989152)
			(xy 361.653626 -269.023244) (xy 361.683191 -269.062588) (xy 361.706062 -269.106165) (xy 361.721646 -269.152846)
			(xy 361.729541 -269.201423) (xy 361.730036 -269.22603) (xy 362.048547 -269.22603) (xy 362.052642 -269.175302)
			(xy 362.064821 -269.125888) (xy 362.084769 -269.079068) (xy 362.11197 -269.036054) (xy 362.145718 -268.99796)
			(xy 362.18514 -268.965773) (xy 362.229214 -268.940327) (xy 362.2768 -268.92228) (xy 362.326664 -268.9121)
			(xy 362.377516 -268.910051) (xy 362.428037 -268.916185) (xy 362.476921 -268.930345) (xy 362.5229 -268.952162)
			(xy 362.564784 -268.981072) (xy 362.601488 -269.016327) (xy 362.632061 -269.057013) (xy 362.655712 -269.102076)
			(xy 362.671828 -269.15035) (xy 362.679992 -269.200584) (xy 362.680504 -269.22603) (xy 362.988601 -269.22603)
			(xy 362.992696 -269.175302) (xy 363.004875 -269.125888) (xy 363.024823 -269.079068) (xy 363.052024 -269.036054)
			(xy 363.085772 -268.99796) (xy 363.125194 -268.965773) (xy 363.169268 -268.940327) (xy 363.216854 -268.92228)
			(xy 363.266718 -268.9121) (xy 363.31757 -268.910051) (xy 363.368091 -268.916185) (xy 363.416975 -268.930345)
			(xy 363.462954 -268.952162) (xy 363.504838 -268.981072) (xy 363.541542 -269.016327) (xy 363.572115 -269.057013)
			(xy 363.595766 -269.102076) (xy 363.611882 -269.15035) (xy 363.620046 -269.200584) (xy 363.620558 -269.22603)
			(xy 363.939086 -269.22603) (xy 363.943046 -269.176976) (xy 363.954823 -269.129192) (xy 363.974114 -269.083916)
			(xy 364.000417 -269.04232) (xy 364.033052 -269.005483) (xy 364.071173 -268.974358) (xy 364.113794 -268.949751)
			(xy 364.15981 -268.932299) (xy 364.208029 -268.922455) (xy 364.257204 -268.920474) (xy 364.306059 -268.926406)
			(xy 364.35333 -268.940098) (xy 364.397792 -268.961196) (xy 364.438295 -268.989152) (xy 364.473788 -269.023244)
			(xy 364.503353 -269.062588) (xy 364.526224 -269.106165) (xy 364.541808 -269.152846) (xy 364.549703 -269.201423)
			(xy 364.550198 -269.22603) (xy 366.758994 -269.22603) (xy 366.762954 -269.176976) (xy 366.774731 -269.129192)
			(xy 366.794022 -269.083916) (xy 366.820325 -269.04232) (xy 366.85296 -269.005483) (xy 366.891081 -268.974358)
			(xy 366.933702 -268.949751) (xy 366.979718 -268.932299) (xy 367.027937 -268.922455) (xy 367.077112 -268.920474)
			(xy 367.125967 -268.926406) (xy 367.173238 -268.940098) (xy 367.2177 -268.961196) (xy 367.258203 -268.989152)
			(xy 367.293696 -269.023244) (xy 367.323261 -269.062588) (xy 367.346132 -269.106165) (xy 367.361716 -269.152846)
			(xy 367.369611 -269.201423) (xy 367.370106 -269.22603) (xy 369.578902 -269.22603) (xy 369.582862 -269.176976)
			(xy 369.594639 -269.129192) (xy 369.61393 -269.083916) (xy 369.640233 -269.04232) (xy 369.672868 -269.005483)
			(xy 369.710989 -268.974358) (xy 369.75361 -268.949751) (xy 369.799626 -268.932299) (xy 369.847845 -268.922455)
			(xy 369.89702 -268.920474) (xy 369.945875 -268.926406) (xy 369.993146 -268.940098) (xy 370.037608 -268.961196)
			(xy 370.078111 -268.989152) (xy 370.113604 -269.023244) (xy 370.143169 -269.062588) (xy 370.16604 -269.106165)
			(xy 370.181624 -269.152846) (xy 370.189519 -269.201423) (xy 370.190014 -269.22603) (xy 372.399064 -269.22603)
			(xy 372.403024 -269.176976) (xy 372.414801 -269.129192) (xy 372.434092 -269.083916) (xy 372.460395 -269.04232)
			(xy 372.49303 -269.005483) (xy 372.531151 -268.974358) (xy 372.573772 -268.949751) (xy 372.619788 -268.932299)
			(xy 372.668007 -268.922455) (xy 372.717182 -268.920474) (xy 372.766037 -268.926406) (xy 372.813308 -268.940098)
			(xy 372.85777 -268.961196) (xy 372.898273 -268.989152) (xy 372.933766 -269.023244) (xy 372.963331 -269.062588)
			(xy 372.986202 -269.106165) (xy 373.001786 -269.152846) (xy 373.009681 -269.201423) (xy 373.010176 -269.22603)
			(xy 373.009681 -269.250637) (xy 373.001786 -269.299214) (xy 372.986202 -269.345895) (xy 372.963331 -269.389472)
			(xy 372.933766 -269.428816) (xy 372.898273 -269.462908) (xy 372.85777 -269.490864) (xy 372.813308 -269.511962)
			(xy 372.766037 -269.525654) (xy 372.717182 -269.531586) (xy 372.668007 -269.529605) (xy 372.619788 -269.519761)
			(xy 372.573772 -269.502309) (xy 372.531151 -269.477702) (xy 372.49303 -269.446577) (xy 372.460395 -269.40974)
			(xy 372.434092 -269.368144) (xy 372.414801 -269.322868) (xy 372.403024 -269.275084) (xy 372.399064 -269.22603)
			(xy 370.190014 -269.22603) (xy 370.189519 -269.250637) (xy 370.181624 -269.299214) (xy 370.16604 -269.345895)
			(xy 370.143169 -269.389472) (xy 370.113604 -269.428816) (xy 370.078111 -269.462908) (xy 370.037608 -269.490864)
			(xy 369.993146 -269.511962) (xy 369.945875 -269.525654) (xy 369.89702 -269.531586) (xy 369.847845 -269.529605)
			(xy 369.799626 -269.519761) (xy 369.75361 -269.502309) (xy 369.710989 -269.477702) (xy 369.672868 -269.446577)
			(xy 369.640233 -269.40974) (xy 369.61393 -269.368144) (xy 369.594639 -269.322868) (xy 369.582862 -269.275084)
			(xy 369.578902 -269.22603) (xy 367.370106 -269.22603) (xy 367.369611 -269.250637) (xy 367.361716 -269.299214)
			(xy 367.346132 -269.345895) (xy 367.323261 -269.389472) (xy 367.293696 -269.428816) (xy 367.258203 -269.462908)
			(xy 367.2177 -269.490864) (xy 367.173238 -269.511962) (xy 367.125967 -269.525654) (xy 367.077112 -269.531586)
			(xy 367.027937 -269.529605) (xy 366.979718 -269.519761) (xy 366.933702 -269.502309) (xy 366.891081 -269.477702)
			(xy 366.85296 -269.446577) (xy 366.820325 -269.40974) (xy 366.794022 -269.368144) (xy 366.774731 -269.322868)
			(xy 366.762954 -269.275084) (xy 366.758994 -269.22603) (xy 364.550198 -269.22603) (xy 364.549703 -269.250637)
			(xy 364.541808 -269.299214) (xy 364.526224 -269.345895) (xy 364.503353 -269.389472) (xy 364.473788 -269.428816)
			(xy 364.438295 -269.462908) (xy 364.397792 -269.490864) (xy 364.35333 -269.511962) (xy 364.306059 -269.525654)
			(xy 364.257204 -269.531586) (xy 364.208029 -269.529605) (xy 364.15981 -269.519761) (xy 364.113794 -269.502309)
			(xy 364.071173 -269.477702) (xy 364.033052 -269.446577) (xy 364.000417 -269.40974) (xy 363.974114 -269.368144)
			(xy 363.954823 -269.322868) (xy 363.943046 -269.275084) (xy 363.939086 -269.22603) (xy 363.620558 -269.22603)
			(xy 363.620046 -269.251476) (xy 363.611882 -269.30171) (xy 363.595766 -269.349984) (xy 363.572115 -269.395047)
			(xy 363.541542 -269.435733) (xy 363.504838 -269.470988) (xy 363.462954 -269.499898) (xy 363.416975 -269.521715)
			(xy 363.368091 -269.535875) (xy 363.31757 -269.542009) (xy 363.266718 -269.53996) (xy 363.216854 -269.52978)
			(xy 363.169268 -269.511733) (xy 363.125194 -269.486287) (xy 363.085772 -269.4541) (xy 363.052024 -269.416006)
			(xy 363.024823 -269.372992) (xy 363.004875 -269.326172) (xy 362.992696 -269.276758) (xy 362.988601 -269.22603)
			(xy 362.680504 -269.22603) (xy 362.679992 -269.251476) (xy 362.671828 -269.30171) (xy 362.655712 -269.349984)
			(xy 362.632061 -269.395047) (xy 362.601488 -269.435733) (xy 362.564784 -269.470988) (xy 362.5229 -269.499898)
			(xy 362.476921 -269.521715) (xy 362.428037 -269.535875) (xy 362.377516 -269.542009) (xy 362.326664 -269.53996)
			(xy 362.2768 -269.52978) (xy 362.229214 -269.511733) (xy 362.18514 -269.486287) (xy 362.145718 -269.4541)
			(xy 362.11197 -269.416006) (xy 362.084769 -269.372992) (xy 362.064821 -269.326172) (xy 362.052642 -269.276758)
			(xy 362.048547 -269.22603) (xy 361.730036 -269.22603) (xy 361.729541 -269.250637) (xy 361.721646 -269.299214)
			(xy 361.706062 -269.345895) (xy 361.683191 -269.389472) (xy 361.653626 -269.428816) (xy 361.618133 -269.462908)
			(xy 361.57763 -269.490864) (xy 361.533168 -269.511962) (xy 361.485897 -269.525654) (xy 361.437042 -269.531586)
			(xy 361.387867 -269.529605) (xy 361.339648 -269.519761) (xy 361.293632 -269.502309) (xy 361.251011 -269.477702)
			(xy 361.21289 -269.446577) (xy 361.180255 -269.40974) (xy 361.153952 -269.368144) (xy 361.134661 -269.322868)
			(xy 361.122884 -269.275084) (xy 361.118924 -269.22603) (xy 358.916478 -269.22603) (xy 358.915998 -269.251028)
			(xy 358.907888 -269.30036) (xy 358.89184 -269.347708) (xy 358.868285 -269.391806) (xy 358.853486 -269.411958)
			(xy 358.848406 -269.418308) (xy 358.840532 -269.440914) (xy 358.839122 -269.445218) (xy 358.837711 -269.454165)
			(xy 358.837738 -269.458694) (xy 358.837992 -269.480792) (xy 358.838544 -269.490384) (xy 358.845851 -269.508139)
			(xy 358.852216 -269.515336) (xy 358.85247 -269.51559) (xy 359.052368 -269.715488) (xy 359.05821 -269.7226)
			(xy 359.275454 -270.036036) (xy 361.589078 -270.036036) (xy 361.593038 -269.986982) (xy 361.604815 -269.939198)
			(xy 361.624106 -269.893922) (xy 361.650409 -269.852326) (xy 361.683044 -269.815489) (xy 361.721165 -269.784364)
			(xy 361.763786 -269.759757) (xy 361.809802 -269.742305) (xy 361.858021 -269.732461) (xy 361.907196 -269.73048)
			(xy 361.956051 -269.736412) (xy 362.003322 -269.750104) (xy 362.047784 -269.771202) (xy 362.088287 -269.799158)
			(xy 362.12378 -269.83325) (xy 362.153345 -269.872594) (xy 362.176216 -269.916171) (xy 362.1918 -269.962852)
			(xy 362.199695 -270.011429) (xy 362.20019 -270.036036) (xy 362.528878 -270.036036) (xy 362.532838 -269.986982)
			(xy 362.544615 -269.939198) (xy 362.563906 -269.893922) (xy 362.590209 -269.852326) (xy 362.622844 -269.815489)
			(xy 362.660965 -269.784364) (xy 362.703586 -269.759757) (xy 362.749602 -269.742305) (xy 362.797821 -269.732461)
			(xy 362.846996 -269.73048) (xy 362.895851 -269.736412) (xy 362.943122 -269.750104) (xy 362.987584 -269.771202)
			(xy 363.028087 -269.799158) (xy 363.06358 -269.83325) (xy 363.093145 -269.872594) (xy 363.116016 -269.916171)
			(xy 363.1316 -269.962852) (xy 363.139495 -270.011429) (xy 363.13999 -270.036036) (xy 363.468932 -270.036036)
			(xy 363.472892 -269.986982) (xy 363.484669 -269.939198) (xy 363.50396 -269.893922) (xy 363.530263 -269.852326)
			(xy 363.562898 -269.815489) (xy 363.601019 -269.784364) (xy 363.64364 -269.759757) (xy 363.689656 -269.742305)
			(xy 363.737875 -269.732461) (xy 363.78705 -269.73048) (xy 363.835905 -269.736412) (xy 363.883176 -269.750104)
			(xy 363.927638 -269.771202) (xy 363.968141 -269.799158) (xy 364.003634 -269.83325) (xy 364.033199 -269.872594)
			(xy 364.05607 -269.916171) (xy 364.071654 -269.962852) (xy 364.079549 -270.011429) (xy 364.080044 -270.036036)
			(xy 364.398555 -270.036036) (xy 364.40265 -269.985308) (xy 364.414829 -269.935894) (xy 364.434777 -269.889074)
			(xy 364.461978 -269.84606) (xy 364.495726 -269.807966) (xy 364.535148 -269.775779) (xy 364.579222 -269.750333)
			(xy 364.626808 -269.732286) (xy 364.676672 -269.722106) (xy 364.727524 -269.720057) (xy 364.778045 -269.726191)
			(xy 364.826929 -269.740351) (xy 364.872908 -269.762168) (xy 364.914792 -269.791078) (xy 364.951496 -269.826333)
			(xy 364.982069 -269.867019) (xy 365.00572 -269.912082) (xy 365.021836 -269.960356) (xy 365.03 -270.01059)
			(xy 365.030512 -270.036036) (xy 365.338609 -270.036036) (xy 365.342704 -269.985308) (xy 365.354883 -269.935894)
			(xy 365.374831 -269.889074) (xy 365.402032 -269.84606) (xy 365.43578 -269.807966) (xy 365.475202 -269.775779)
			(xy 365.519276 -269.750333) (xy 365.566862 -269.732286) (xy 365.616726 -269.722106) (xy 365.667578 -269.720057)
			(xy 365.718099 -269.726191) (xy 365.766983 -269.740351) (xy 365.812962 -269.762168) (xy 365.854846 -269.791078)
			(xy 365.89155 -269.826333) (xy 365.922123 -269.867019) (xy 365.945774 -269.912082) (xy 365.96189 -269.960356)
			(xy 365.970054 -270.01059) (xy 365.970566 -270.036036) (xy 366.289094 -270.036036) (xy 366.293054 -269.986982)
			(xy 366.304831 -269.939198) (xy 366.324122 -269.893922) (xy 366.350425 -269.852326) (xy 366.38306 -269.815489)
			(xy 366.421181 -269.784364) (xy 366.463802 -269.759757) (xy 366.509818 -269.742305) (xy 366.558037 -269.732461)
			(xy 366.607212 -269.73048) (xy 366.656067 -269.736412) (xy 366.703338 -269.750104) (xy 366.7478 -269.771202)
			(xy 366.788303 -269.799158) (xy 366.823796 -269.83325) (xy 366.853361 -269.872594) (xy 366.876232 -269.916171)
			(xy 366.891816 -269.962852) (xy 366.899711 -270.011429) (xy 366.900206 -270.036036) (xy 367.218463 -270.036036)
			(xy 367.222558 -269.985308) (xy 367.234737 -269.935894) (xy 367.254685 -269.889074) (xy 367.281886 -269.84606)
			(xy 367.315634 -269.807966) (xy 367.355056 -269.775779) (xy 367.39913 -269.750333) (xy 367.446716 -269.732286)
			(xy 367.49658 -269.722106) (xy 367.547432 -269.720057) (xy 367.597953 -269.726191) (xy 367.646837 -269.740351)
			(xy 367.692816 -269.762168) (xy 367.7347 -269.791078) (xy 367.771404 -269.826333) (xy 367.801977 -269.867019)
			(xy 367.825628 -269.912082) (xy 367.841744 -269.960356) (xy 367.849908 -270.01059) (xy 367.85042 -270.036036)
			(xy 368.158517 -270.036036) (xy 368.162612 -269.985308) (xy 368.174791 -269.935894) (xy 368.194739 -269.889074)
			(xy 368.22194 -269.84606) (xy 368.255688 -269.807966) (xy 368.29511 -269.775779) (xy 368.339184 -269.750333)
			(xy 368.38677 -269.732286) (xy 368.436634 -269.722106) (xy 368.487486 -269.720057) (xy 368.538007 -269.726191)
			(xy 368.586891 -269.740351) (xy 368.63287 -269.762168) (xy 368.674754 -269.791078) (xy 368.711458 -269.826333)
			(xy 368.742031 -269.867019) (xy 368.765682 -269.912082) (xy 368.781798 -269.960356) (xy 368.789962 -270.01059)
			(xy 368.790474 -270.036036) (xy 369.109002 -270.036036) (xy 369.112962 -269.986982) (xy 369.124739 -269.939198)
			(xy 369.14403 -269.893922) (xy 369.170333 -269.852326) (xy 369.202968 -269.815489) (xy 369.241089 -269.784364)
			(xy 369.28371 -269.759757) (xy 369.329726 -269.742305) (xy 369.377945 -269.732461) (xy 369.42712 -269.73048)
			(xy 369.475975 -269.736412) (xy 369.523246 -269.750104) (xy 369.567708 -269.771202) (xy 369.608211 -269.799158)
			(xy 369.643704 -269.83325) (xy 369.673269 -269.872594) (xy 369.69614 -269.916171) (xy 369.711724 -269.962852)
			(xy 369.719619 -270.011429) (xy 369.720114 -270.036036) (xy 370.038625 -270.036036) (xy 370.04272 -269.985308)
			(xy 370.054899 -269.935894) (xy 370.074847 -269.889074) (xy 370.102048 -269.84606) (xy 370.135796 -269.807966)
			(xy 370.175218 -269.775779) (xy 370.219292 -269.750333) (xy 370.266878 -269.732286) (xy 370.316742 -269.722106)
			(xy 370.367594 -269.720057) (xy 370.418115 -269.726191) (xy 370.466999 -269.740351) (xy 370.512978 -269.762168)
			(xy 370.554862 -269.791078) (xy 370.591566 -269.826333) (xy 370.622139 -269.867019) (xy 370.64579 -269.912082)
			(xy 370.661906 -269.960356) (xy 370.67007 -270.01059) (xy 370.670582 -270.036036) (xy 370.978679 -270.036036)
			(xy 370.982774 -269.985308) (xy 370.994953 -269.935894) (xy 371.014901 -269.889074) (xy 371.042102 -269.84606)
			(xy 371.07585 -269.807966) (xy 371.115272 -269.775779) (xy 371.159346 -269.750333) (xy 371.206932 -269.732286)
			(xy 371.256796 -269.722106) (xy 371.307648 -269.720057) (xy 371.358169 -269.726191) (xy 371.407053 -269.740351)
			(xy 371.453032 -269.762168) (xy 371.494916 -269.791078) (xy 371.53162 -269.826333) (xy 371.562193 -269.867019)
			(xy 371.585844 -269.912082) (xy 371.60196 -269.960356) (xy 371.610124 -270.01059) (xy 371.610636 -270.036036)
			(xy 371.92891 -270.036036) (xy 371.93287 -269.986982) (xy 371.944647 -269.939198) (xy 371.963938 -269.893922)
			(xy 371.990241 -269.852326) (xy 372.022876 -269.815489) (xy 372.060997 -269.784364) (xy 372.103618 -269.759757)
			(xy 372.149634 -269.742305) (xy 372.197853 -269.732461) (xy 372.247028 -269.73048) (xy 372.295883 -269.736412)
			(xy 372.343154 -269.750104) (xy 372.387616 -269.771202) (xy 372.428119 -269.799158) (xy 372.463612 -269.83325)
			(xy 372.493177 -269.872594) (xy 372.516048 -269.916171) (xy 372.531632 -269.962852) (xy 372.539527 -270.011429)
			(xy 372.540022 -270.036036) (xy 372.858533 -270.036036) (xy 372.862628 -269.985308) (xy 372.874807 -269.935894)
			(xy 372.894755 -269.889074) (xy 372.921956 -269.84606) (xy 372.955704 -269.807966) (xy 372.995126 -269.775779)
			(xy 373.0392 -269.750333) (xy 373.086786 -269.732286) (xy 373.13665 -269.722106) (xy 373.187502 -269.720057)
			(xy 373.238023 -269.726191) (xy 373.286907 -269.740351) (xy 373.332886 -269.762168) (xy 373.37477 -269.791078)
			(xy 373.411474 -269.826333) (xy 373.442047 -269.867019) (xy 373.465698 -269.912082) (xy 373.481814 -269.960356)
			(xy 373.489978 -270.01059) (xy 373.49049 -270.036036) (xy 373.798587 -270.036036) (xy 373.802682 -269.985308)
			(xy 373.814861 -269.935894) (xy 373.834809 -269.889074) (xy 373.86201 -269.84606) (xy 373.895758 -269.807966)
			(xy 373.93518 -269.775779) (xy 373.979254 -269.750333) (xy 374.02684 -269.732286) (xy 374.076704 -269.722106)
			(xy 374.127556 -269.720057) (xy 374.178077 -269.726191) (xy 374.226961 -269.740351) (xy 374.27294 -269.762168)
			(xy 374.314824 -269.791078) (xy 374.351528 -269.826333) (xy 374.382101 -269.867019) (xy 374.405752 -269.912082)
			(xy 374.421868 -269.960356) (xy 374.430032 -270.01059) (xy 374.430544 -270.036036) (xy 374.430032 -270.061482)
			(xy 374.421868 -270.111716) (xy 374.405752 -270.15999) (xy 374.382101 -270.205053) (xy 374.351528 -270.245739)
			(xy 374.314824 -270.280994) (xy 374.27294 -270.309904) (xy 374.226961 -270.331721) (xy 374.178077 -270.345881)
			(xy 374.127556 -270.352015) (xy 374.076704 -270.349966) (xy 374.02684 -270.339786) (xy 373.979254 -270.321739)
			(xy 373.93518 -270.296293) (xy 373.895758 -270.264106) (xy 373.86201 -270.226012) (xy 373.834809 -270.182998)
			(xy 373.814861 -270.136178) (xy 373.802682 -270.086764) (xy 373.798587 -270.036036) (xy 373.49049 -270.036036)
			(xy 373.489978 -270.061482) (xy 373.481814 -270.111716) (xy 373.465698 -270.15999) (xy 373.442047 -270.205053)
			(xy 373.411474 -270.245739) (xy 373.37477 -270.280994) (xy 373.332886 -270.309904) (xy 373.286907 -270.331721)
			(xy 373.238023 -270.345881) (xy 373.187502 -270.352015) (xy 373.13665 -270.349966) (xy 373.086786 -270.339786)
			(xy 373.0392 -270.321739) (xy 372.995126 -270.296293) (xy 372.955704 -270.264106) (xy 372.921956 -270.226012)
			(xy 372.894755 -270.182998) (xy 372.874807 -270.136178) (xy 372.862628 -270.086764) (xy 372.858533 -270.036036)
			(xy 372.540022 -270.036036) (xy 372.539527 -270.060643) (xy 372.531632 -270.10922) (xy 372.516048 -270.155901)
			(xy 372.493177 -270.199478) (xy 372.463612 -270.238822) (xy 372.428119 -270.272914) (xy 372.387616 -270.30087)
			(xy 372.343154 -270.321968) (xy 372.295883 -270.33566) (xy 372.247028 -270.341592) (xy 372.197853 -270.339611)
			(xy 372.149634 -270.329767) (xy 372.103618 -270.312315) (xy 372.060997 -270.287708) (xy 372.022876 -270.256583)
			(xy 371.990241 -270.219746) (xy 371.963938 -270.17815) (xy 371.944647 -270.132874) (xy 371.93287 -270.08509)
			(xy 371.92891 -270.036036) (xy 371.610636 -270.036036) (xy 371.610124 -270.061482) (xy 371.60196 -270.111716)
			(xy 371.585844 -270.15999) (xy 371.562193 -270.205053) (xy 371.53162 -270.245739) (xy 371.494916 -270.280994)
			(xy 371.453032 -270.309904) (xy 371.407053 -270.331721) (xy 371.358169 -270.345881) (xy 371.307648 -270.352015)
			(xy 371.256796 -270.349966) (xy 371.206932 -270.339786) (xy 371.159346 -270.321739) (xy 371.115272 -270.296293)
			(xy 371.07585 -270.264106) (xy 371.042102 -270.226012) (xy 371.014901 -270.182998) (xy 370.994953 -270.136178)
			(xy 370.982774 -270.086764) (xy 370.978679 -270.036036) (xy 370.670582 -270.036036) (xy 370.67007 -270.061482)
			(xy 370.661906 -270.111716) (xy 370.64579 -270.15999) (xy 370.622139 -270.205053) (xy 370.591566 -270.245739)
			(xy 370.554862 -270.280994) (xy 370.512978 -270.309904) (xy 370.466999 -270.331721) (xy 370.418115 -270.345881)
			(xy 370.367594 -270.352015) (xy 370.316742 -270.349966) (xy 370.266878 -270.339786) (xy 370.219292 -270.321739)
			(xy 370.175218 -270.296293) (xy 370.135796 -270.264106) (xy 370.102048 -270.226012) (xy 370.074847 -270.182998)
			(xy 370.054899 -270.136178) (xy 370.04272 -270.086764) (xy 370.038625 -270.036036) (xy 369.720114 -270.036036)
			(xy 369.719619 -270.060643) (xy 369.711724 -270.10922) (xy 369.69614 -270.155901) (xy 369.673269 -270.199478)
			(xy 369.643704 -270.238822) (xy 369.608211 -270.272914) (xy 369.567708 -270.30087) (xy 369.523246 -270.321968)
			(xy 369.475975 -270.33566) (xy 369.42712 -270.341592) (xy 369.377945 -270.339611) (xy 369.329726 -270.329767)
			(xy 369.28371 -270.312315) (xy 369.241089 -270.287708) (xy 369.202968 -270.256583) (xy 369.170333 -270.219746)
			(xy 369.14403 -270.17815) (xy 369.124739 -270.132874) (xy 369.112962 -270.08509) (xy 369.109002 -270.036036)
			(xy 368.790474 -270.036036) (xy 368.789962 -270.061482) (xy 368.781798 -270.111716) (xy 368.765682 -270.15999)
			(xy 368.742031 -270.205053) (xy 368.711458 -270.245739) (xy 368.674754 -270.280994) (xy 368.63287 -270.309904)
			(xy 368.586891 -270.331721) (xy 368.538007 -270.345881) (xy 368.487486 -270.352015) (xy 368.436634 -270.349966)
			(xy 368.38677 -270.339786) (xy 368.339184 -270.321739) (xy 368.29511 -270.296293) (xy 368.255688 -270.264106)
			(xy 368.22194 -270.226012) (xy 368.194739 -270.182998) (xy 368.174791 -270.136178) (xy 368.162612 -270.086764)
			(xy 368.158517 -270.036036) (xy 367.85042 -270.036036) (xy 367.849908 -270.061482) (xy 367.841744 -270.111716)
			(xy 367.825628 -270.15999) (xy 367.801977 -270.205053) (xy 367.771404 -270.245739) (xy 367.7347 -270.280994)
			(xy 367.692816 -270.309904) (xy 367.646837 -270.331721) (xy 367.597953 -270.345881) (xy 367.547432 -270.352015)
			(xy 367.49658 -270.349966) (xy 367.446716 -270.339786) (xy 367.39913 -270.321739) (xy 367.355056 -270.296293)
			(xy 367.315634 -270.264106) (xy 367.281886 -270.226012) (xy 367.254685 -270.182998) (xy 367.234737 -270.136178)
			(xy 367.222558 -270.086764) (xy 367.218463 -270.036036) (xy 366.900206 -270.036036) (xy 366.899711 -270.060643)
			(xy 366.891816 -270.10922) (xy 366.876232 -270.155901) (xy 366.853361 -270.199478) (xy 366.823796 -270.238822)
			(xy 366.788303 -270.272914) (xy 366.7478 -270.30087) (xy 366.703338 -270.321968) (xy 366.656067 -270.33566)
			(xy 366.607212 -270.341592) (xy 366.558037 -270.339611) (xy 366.509818 -270.329767) (xy 366.463802 -270.312315)
			(xy 366.421181 -270.287708) (xy 366.38306 -270.256583) (xy 366.350425 -270.219746) (xy 366.324122 -270.17815)
			(xy 366.304831 -270.132874) (xy 366.293054 -270.08509) (xy 366.289094 -270.036036) (xy 365.970566 -270.036036)
			(xy 365.970054 -270.061482) (xy 365.96189 -270.111716) (xy 365.945774 -270.15999) (xy 365.922123 -270.205053)
			(xy 365.89155 -270.245739) (xy 365.854846 -270.280994) (xy 365.812962 -270.309904) (xy 365.766983 -270.331721)
			(xy 365.718099 -270.345881) (xy 365.667578 -270.352015) (xy 365.616726 -270.349966) (xy 365.566862 -270.339786)
			(xy 365.519276 -270.321739) (xy 365.475202 -270.296293) (xy 365.43578 -270.264106) (xy 365.402032 -270.226012)
			(xy 365.374831 -270.182998) (xy 365.354883 -270.136178) (xy 365.342704 -270.086764) (xy 365.338609 -270.036036)
			(xy 365.030512 -270.036036) (xy 365.03 -270.061482) (xy 365.021836 -270.111716) (xy 365.00572 -270.15999)
			(xy 364.982069 -270.205053) (xy 364.951496 -270.245739) (xy 364.914792 -270.280994) (xy 364.872908 -270.309904)
			(xy 364.826929 -270.331721) (xy 364.778045 -270.345881) (xy 364.727524 -270.352015) (xy 364.676672 -270.349966)
			(xy 364.626808 -270.339786) (xy 364.579222 -270.321739) (xy 364.535148 -270.296293) (xy 364.495726 -270.264106)
			(xy 364.461978 -270.226012) (xy 364.434777 -270.182998) (xy 364.414829 -270.136178) (xy 364.40265 -270.086764)
			(xy 364.398555 -270.036036) (xy 364.080044 -270.036036) (xy 364.079549 -270.060643) (xy 364.071654 -270.10922)
			(xy 364.05607 -270.155901) (xy 364.033199 -270.199478) (xy 364.003634 -270.238822) (xy 363.968141 -270.272914)
			(xy 363.927638 -270.30087) (xy 363.883176 -270.321968) (xy 363.835905 -270.33566) (xy 363.78705 -270.341592)
			(xy 363.737875 -270.339611) (xy 363.689656 -270.329767) (xy 363.64364 -270.312315) (xy 363.601019 -270.287708)
			(xy 363.562898 -270.256583) (xy 363.530263 -270.219746) (xy 363.50396 -270.17815) (xy 363.484669 -270.132874)
			(xy 363.472892 -270.08509) (xy 363.468932 -270.036036) (xy 363.13999 -270.036036) (xy 363.139495 -270.060643)
			(xy 363.1316 -270.10922) (xy 363.116016 -270.155901) (xy 363.093145 -270.199478) (xy 363.06358 -270.238822)
			(xy 363.028087 -270.272914) (xy 362.987584 -270.30087) (xy 362.943122 -270.321968) (xy 362.895851 -270.33566)
			(xy 362.846996 -270.341592) (xy 362.797821 -270.339611) (xy 362.749602 -270.329767) (xy 362.703586 -270.312315)
			(xy 362.660965 -270.287708) (xy 362.622844 -270.256583) (xy 362.590209 -270.219746) (xy 362.563906 -270.17815)
			(xy 362.544615 -270.132874) (xy 362.532838 -270.08509) (xy 362.528878 -270.036036) (xy 362.20019 -270.036036)
			(xy 362.199695 -270.060643) (xy 362.1918 -270.10922) (xy 362.176216 -270.155901) (xy 362.153345 -270.199478)
			(xy 362.12378 -270.238822) (xy 362.088287 -270.272914) (xy 362.047784 -270.30087) (xy 362.003322 -270.321968)
			(xy 361.956051 -270.33566) (xy 361.907196 -270.341592) (xy 361.858021 -270.339611) (xy 361.809802 -270.329767)
			(xy 361.763786 -270.312315) (xy 361.721165 -270.287708) (xy 361.683044 -270.256583) (xy 361.650409 -270.219746)
			(xy 361.624106 -270.17815) (xy 361.604815 -270.132874) (xy 361.593038 -270.08509) (xy 361.589078 -270.036036)
			(xy 359.275454 -270.036036) (xy 359.836874 -270.846042) (xy 361.118924 -270.846042) (xy 361.122884 -270.796988)
			(xy 361.134661 -270.749204) (xy 361.153952 -270.703928) (xy 361.180255 -270.662332) (xy 361.21289 -270.625495)
			(xy 361.251011 -270.59437) (xy 361.293632 -270.569763) (xy 361.339648 -270.552311) (xy 361.387867 -270.542467)
			(xy 361.437042 -270.540486) (xy 361.485897 -270.546418) (xy 361.533168 -270.56011) (xy 361.57763 -270.581208)
			(xy 361.618133 -270.609164) (xy 361.653626 -270.643256) (xy 361.683191 -270.6826) (xy 361.706062 -270.726177)
			(xy 361.721646 -270.772858) (xy 361.729541 -270.821435) (xy 361.730036 -270.846042) (xy 362.048547 -270.846042)
			(xy 362.052642 -270.795314) (xy 362.064821 -270.7459) (xy 362.084769 -270.69908) (xy 362.11197 -270.656066)
			(xy 362.145718 -270.617972) (xy 362.18514 -270.585785) (xy 362.229214 -270.560339) (xy 362.2768 -270.542292)
			(xy 362.326664 -270.532112) (xy 362.377516 -270.530063) (xy 362.428037 -270.536197) (xy 362.476921 -270.550357)
			(xy 362.5229 -270.572174) (xy 362.564784 -270.601084) (xy 362.601488 -270.636339) (xy 362.632061 -270.677025)
			(xy 362.655712 -270.722088) (xy 362.671828 -270.770362) (xy 362.679992 -270.820596) (xy 362.680504 -270.846042)
			(xy 362.988601 -270.846042) (xy 362.992696 -270.795314) (xy 363.004875 -270.7459) (xy 363.024823 -270.69908)
			(xy 363.052024 -270.656066) (xy 363.085772 -270.617972) (xy 363.125194 -270.585785) (xy 363.169268 -270.560339)
			(xy 363.216854 -270.542292) (xy 363.266718 -270.532112) (xy 363.31757 -270.530063) (xy 363.368091 -270.536197)
			(xy 363.416975 -270.550357) (xy 363.462954 -270.572174) (xy 363.504838 -270.601084) (xy 363.541542 -270.636339)
			(xy 363.572115 -270.677025) (xy 363.595766 -270.722088) (xy 363.611882 -270.770362) (xy 363.620046 -270.820596)
			(xy 363.620558 -270.846042) (xy 363.939086 -270.846042) (xy 363.943046 -270.796988) (xy 363.954823 -270.749204)
			(xy 363.974114 -270.703928) (xy 364.000417 -270.662332) (xy 364.033052 -270.625495) (xy 364.071173 -270.59437)
			(xy 364.113794 -270.569763) (xy 364.15981 -270.552311) (xy 364.208029 -270.542467) (xy 364.257204 -270.540486)
			(xy 364.306059 -270.546418) (xy 364.35333 -270.56011) (xy 364.397792 -270.581208) (xy 364.438295 -270.609164)
			(xy 364.473788 -270.643256) (xy 364.503353 -270.6826) (xy 364.526224 -270.726177) (xy 364.541808 -270.772858)
			(xy 364.549703 -270.821435) (xy 364.550198 -270.846042) (xy 364.878886 -270.846042) (xy 364.882846 -270.796988)
			(xy 364.894623 -270.749204) (xy 364.913914 -270.703928) (xy 364.940217 -270.662332) (xy 364.972852 -270.625495)
			(xy 365.010973 -270.59437) (xy 365.053594 -270.569763) (xy 365.09961 -270.552311) (xy 365.147829 -270.542467)
			(xy 365.197004 -270.540486) (xy 365.245859 -270.546418) (xy 365.29313 -270.56011) (xy 365.337592 -270.581208)
			(xy 365.378095 -270.609164) (xy 365.413588 -270.643256) (xy 365.443153 -270.6826) (xy 365.466024 -270.726177)
			(xy 365.481608 -270.772858) (xy 365.489503 -270.821435) (xy 365.489998 -270.846042) (xy 365.81894 -270.846042)
			(xy 365.8229 -270.796988) (xy 365.834677 -270.749204) (xy 365.853968 -270.703928) (xy 365.880271 -270.662332)
			(xy 365.912906 -270.625495) (xy 365.951027 -270.59437) (xy 365.993648 -270.569763) (xy 366.039664 -270.552311)
			(xy 366.087883 -270.542467) (xy 366.137058 -270.540486) (xy 366.185913 -270.546418) (xy 366.233184 -270.56011)
			(xy 366.277646 -270.581208) (xy 366.318149 -270.609164) (xy 366.353642 -270.643256) (xy 366.383207 -270.6826)
			(xy 366.406078 -270.726177) (xy 366.421662 -270.772858) (xy 366.429557 -270.821435) (xy 366.430052 -270.846042)
			(xy 366.758994 -270.846042) (xy 366.762954 -270.796988) (xy 366.774731 -270.749204) (xy 366.794022 -270.703928)
			(xy 366.820325 -270.662332) (xy 366.85296 -270.625495) (xy 366.891081 -270.59437) (xy 366.933702 -270.569763)
			(xy 366.979718 -270.552311) (xy 367.027937 -270.542467) (xy 367.077112 -270.540486) (xy 367.125967 -270.546418)
			(xy 367.173238 -270.56011) (xy 367.2177 -270.581208) (xy 367.258203 -270.609164) (xy 367.293696 -270.643256)
			(xy 367.323261 -270.6826) (xy 367.346132 -270.726177) (xy 367.361716 -270.772858) (xy 367.369611 -270.821435)
			(xy 367.370106 -270.846042) (xy 367.699048 -270.846042) (xy 367.703008 -270.796988) (xy 367.714785 -270.749204)
			(xy 367.734076 -270.703928) (xy 367.760379 -270.662332) (xy 367.793014 -270.625495) (xy 367.831135 -270.59437)
			(xy 367.873756 -270.569763) (xy 367.919772 -270.552311) (xy 367.967991 -270.542467) (xy 368.017166 -270.540486)
			(xy 368.066021 -270.546418) (xy 368.113292 -270.56011) (xy 368.157754 -270.581208) (xy 368.198257 -270.609164)
			(xy 368.23375 -270.643256) (xy 368.263315 -270.6826) (xy 368.286186 -270.726177) (xy 368.30177 -270.772858)
			(xy 368.309665 -270.821435) (xy 368.31016 -270.846042) (xy 368.639102 -270.846042) (xy 368.643062 -270.796988)
			(xy 368.654839 -270.749204) (xy 368.67413 -270.703928) (xy 368.700433 -270.662332) (xy 368.733068 -270.625495)
			(xy 368.771189 -270.59437) (xy 368.81381 -270.569763) (xy 368.859826 -270.552311) (xy 368.908045 -270.542467)
			(xy 368.95722 -270.540486) (xy 369.006075 -270.546418) (xy 369.053346 -270.56011) (xy 369.097808 -270.581208)
			(xy 369.138311 -270.609164) (xy 369.173804 -270.643256) (xy 369.203369 -270.6826) (xy 369.22624 -270.726177)
			(xy 369.241824 -270.772858) (xy 369.249719 -270.821435) (xy 369.250214 -270.846042) (xy 369.578902 -270.846042)
			(xy 369.582862 -270.796988) (xy 369.594639 -270.749204) (xy 369.61393 -270.703928) (xy 369.640233 -270.662332)
			(xy 369.672868 -270.625495) (xy 369.710989 -270.59437) (xy 369.75361 -270.569763) (xy 369.799626 -270.552311)
			(xy 369.847845 -270.542467) (xy 369.89702 -270.540486) (xy 369.945875 -270.546418) (xy 369.993146 -270.56011)
			(xy 370.037608 -270.581208) (xy 370.078111 -270.609164) (xy 370.113604 -270.643256) (xy 370.143169 -270.6826)
			(xy 370.16604 -270.726177) (xy 370.181624 -270.772858) (xy 370.189519 -270.821435) (xy 370.190014 -270.846042)
			(xy 370.518956 -270.846042) (xy 370.522916 -270.796988) (xy 370.534693 -270.749204) (xy 370.553984 -270.703928)
			(xy 370.580287 -270.662332) (xy 370.612922 -270.625495) (xy 370.651043 -270.59437) (xy 370.693664 -270.569763)
			(xy 370.73968 -270.552311) (xy 370.787899 -270.542467) (xy 370.837074 -270.540486) (xy 370.885929 -270.546418)
			(xy 370.9332 -270.56011) (xy 370.977662 -270.581208) (xy 371.018165 -270.609164) (xy 371.053658 -270.643256)
			(xy 371.083223 -270.6826) (xy 371.106094 -270.726177) (xy 371.121678 -270.772858) (xy 371.129573 -270.821435)
			(xy 371.130068 -270.846042) (xy 371.45901 -270.846042) (xy 371.46297 -270.796988) (xy 371.474747 -270.749204)
			(xy 371.494038 -270.703928) (xy 371.520341 -270.662332) (xy 371.552976 -270.625495) (xy 371.591097 -270.59437)
			(xy 371.633718 -270.569763) (xy 371.679734 -270.552311) (xy 371.727953 -270.542467) (xy 371.777128 -270.540486)
			(xy 371.825983 -270.546418) (xy 371.873254 -270.56011) (xy 371.917716 -270.581208) (xy 371.958219 -270.609164)
			(xy 371.993712 -270.643256) (xy 372.023277 -270.6826) (xy 372.046148 -270.726177) (xy 372.061732 -270.772858)
			(xy 372.069627 -270.821435) (xy 372.070122 -270.846042) (xy 372.399064 -270.846042) (xy 372.403024 -270.796988)
			(xy 372.414801 -270.749204) (xy 372.434092 -270.703928) (xy 372.460395 -270.662332) (xy 372.49303 -270.625495)
			(xy 372.531151 -270.59437) (xy 372.573772 -270.569763) (xy 372.619788 -270.552311) (xy 372.668007 -270.542467)
			(xy 372.717182 -270.540486) (xy 372.766037 -270.546418) (xy 372.813308 -270.56011) (xy 372.85777 -270.581208)
			(xy 372.898273 -270.609164) (xy 372.933766 -270.643256) (xy 372.963331 -270.6826) (xy 372.986202 -270.726177)
			(xy 373.001786 -270.772858) (xy 373.009681 -270.821435) (xy 373.010176 -270.846042) (xy 373.339118 -270.846042)
			(xy 373.343078 -270.796988) (xy 373.354855 -270.749204) (xy 373.374146 -270.703928) (xy 373.400449 -270.662332)
			(xy 373.433084 -270.625495) (xy 373.471205 -270.59437) (xy 373.513826 -270.569763) (xy 373.559842 -270.552311)
			(xy 373.608061 -270.542467) (xy 373.657236 -270.540486) (xy 373.706091 -270.546418) (xy 373.753362 -270.56011)
			(xy 373.797824 -270.581208) (xy 373.838327 -270.609164) (xy 373.87382 -270.643256) (xy 373.903385 -270.6826)
			(xy 373.926256 -270.726177) (xy 373.94184 -270.772858) (xy 373.949735 -270.821435) (xy 373.95023 -270.846042)
			(xy 373.949735 -270.870649) (xy 373.94184 -270.919226) (xy 373.926256 -270.965907) (xy 373.903385 -271.009484)
			(xy 373.87382 -271.048828) (xy 373.838327 -271.08292) (xy 373.797824 -271.110876) (xy 373.753362 -271.131974)
			(xy 373.706091 -271.145666) (xy 373.657236 -271.151598) (xy 373.608061 -271.149617) (xy 373.559842 -271.139773)
			(xy 373.513826 -271.122321) (xy 373.471205 -271.097714) (xy 373.433084 -271.066589) (xy 373.400449 -271.029752)
			(xy 373.374146 -270.988156) (xy 373.354855 -270.94288) (xy 373.343078 -270.895096) (xy 373.339118 -270.846042)
			(xy 373.010176 -270.846042) (xy 373.009681 -270.870649) (xy 373.001786 -270.919226) (xy 372.986202 -270.965907)
			(xy 372.963331 -271.009484) (xy 372.933766 -271.048828) (xy 372.898273 -271.08292) (xy 372.85777 -271.110876)
			(xy 372.813308 -271.131974) (xy 372.766037 -271.145666) (xy 372.717182 -271.151598) (xy 372.668007 -271.149617)
			(xy 372.619788 -271.139773) (xy 372.573772 -271.122321) (xy 372.531151 -271.097714) (xy 372.49303 -271.066589)
			(xy 372.460395 -271.029752) (xy 372.434092 -270.988156) (xy 372.414801 -270.94288) (xy 372.403024 -270.895096)
			(xy 372.399064 -270.846042) (xy 372.070122 -270.846042) (xy 372.069627 -270.870649) (xy 372.061732 -270.919226)
			(xy 372.046148 -270.965907) (xy 372.023277 -271.009484) (xy 371.993712 -271.048828) (xy 371.958219 -271.08292)
			(xy 371.917716 -271.110876) (xy 371.873254 -271.131974) (xy 371.825983 -271.145666) (xy 371.777128 -271.151598)
			(xy 371.727953 -271.149617) (xy 371.679734 -271.139773) (xy 371.633718 -271.122321) (xy 371.591097 -271.097714)
			(xy 371.552976 -271.066589) (xy 371.520341 -271.029752) (xy 371.494038 -270.988156) (xy 371.474747 -270.94288)
			(xy 371.46297 -270.895096) (xy 371.45901 -270.846042) (xy 371.130068 -270.846042) (xy 371.129573 -270.870649)
			(xy 371.121678 -270.919226) (xy 371.106094 -270.965907) (xy 371.083223 -271.009484) (xy 371.053658 -271.048828)
			(xy 371.018165 -271.08292) (xy 370.977662 -271.110876) (xy 370.9332 -271.131974) (xy 370.885929 -271.145666)
			(xy 370.837074 -271.151598) (xy 370.787899 -271.149617) (xy 370.73968 -271.139773) (xy 370.693664 -271.122321)
			(xy 370.651043 -271.097714) (xy 370.612922 -271.066589) (xy 370.580287 -271.029752) (xy 370.553984 -270.988156)
			(xy 370.534693 -270.94288) (xy 370.522916 -270.895096) (xy 370.518956 -270.846042) (xy 370.190014 -270.846042)
			(xy 370.189519 -270.870649) (xy 370.181624 -270.919226) (xy 370.16604 -270.965907) (xy 370.143169 -271.009484)
			(xy 370.113604 -271.048828) (xy 370.078111 -271.08292) (xy 370.037608 -271.110876) (xy 369.993146 -271.131974)
			(xy 369.945875 -271.145666) (xy 369.89702 -271.151598) (xy 369.847845 -271.149617) (xy 369.799626 -271.139773)
			(xy 369.75361 -271.122321) (xy 369.710989 -271.097714) (xy 369.672868 -271.066589) (xy 369.640233 -271.029752)
			(xy 369.61393 -270.988156) (xy 369.594639 -270.94288) (xy 369.582862 -270.895096) (xy 369.578902 -270.846042)
			(xy 369.250214 -270.846042) (xy 369.249719 -270.870649) (xy 369.241824 -270.919226) (xy 369.22624 -270.965907)
			(xy 369.203369 -271.009484) (xy 369.173804 -271.048828) (xy 369.138311 -271.08292) (xy 369.097808 -271.110876)
			(xy 369.053346 -271.131974) (xy 369.006075 -271.145666) (xy 368.95722 -271.151598) (xy 368.908045 -271.149617)
			(xy 368.859826 -271.139773) (xy 368.81381 -271.122321) (xy 368.771189 -271.097714) (xy 368.733068 -271.066589)
			(xy 368.700433 -271.029752) (xy 368.67413 -270.988156) (xy 368.654839 -270.94288) (xy 368.643062 -270.895096)
			(xy 368.639102 -270.846042) (xy 368.31016 -270.846042) (xy 368.309665 -270.870649) (xy 368.30177 -270.919226)
			(xy 368.286186 -270.965907) (xy 368.263315 -271.009484) (xy 368.23375 -271.048828) (xy 368.198257 -271.08292)
			(xy 368.157754 -271.110876) (xy 368.113292 -271.131974) (xy 368.066021 -271.145666) (xy 368.017166 -271.151598)
			(xy 367.967991 -271.149617) (xy 367.919772 -271.139773) (xy 367.873756 -271.122321) (xy 367.831135 -271.097714)
			(xy 367.793014 -271.066589) (xy 367.760379 -271.029752) (xy 367.734076 -270.988156) (xy 367.714785 -270.94288)
			(xy 367.703008 -270.895096) (xy 367.699048 -270.846042) (xy 367.370106 -270.846042) (xy 367.369611 -270.870649)
			(xy 367.361716 -270.919226) (xy 367.346132 -270.965907) (xy 367.323261 -271.009484) (xy 367.293696 -271.048828)
			(xy 367.258203 -271.08292) (xy 367.2177 -271.110876) (xy 367.173238 -271.131974) (xy 367.125967 -271.145666)
			(xy 367.077112 -271.151598) (xy 367.027937 -271.149617) (xy 366.979718 -271.139773) (xy 366.933702 -271.122321)
			(xy 366.891081 -271.097714) (xy 366.85296 -271.066589) (xy 366.820325 -271.029752) (xy 366.794022 -270.988156)
			(xy 366.774731 -270.94288) (xy 366.762954 -270.895096) (xy 366.758994 -270.846042) (xy 366.430052 -270.846042)
			(xy 366.429557 -270.870649) (xy 366.421662 -270.919226) (xy 366.406078 -270.965907) (xy 366.383207 -271.009484)
			(xy 366.353642 -271.048828) (xy 366.318149 -271.08292) (xy 366.277646 -271.110876) (xy 366.233184 -271.131974)
			(xy 366.185913 -271.145666) (xy 366.137058 -271.151598) (xy 366.087883 -271.149617) (xy 366.039664 -271.139773)
			(xy 365.993648 -271.122321) (xy 365.951027 -271.097714) (xy 365.912906 -271.066589) (xy 365.880271 -271.029752)
			(xy 365.853968 -270.988156) (xy 365.834677 -270.94288) (xy 365.8229 -270.895096) (xy 365.81894 -270.846042)
			(xy 365.489998 -270.846042) (xy 365.489503 -270.870649) (xy 365.481608 -270.919226) (xy 365.466024 -270.965907)
			(xy 365.443153 -271.009484) (xy 365.413588 -271.048828) (xy 365.378095 -271.08292) (xy 365.337592 -271.110876)
			(xy 365.29313 -271.131974) (xy 365.245859 -271.145666) (xy 365.197004 -271.151598) (xy 365.147829 -271.149617)
			(xy 365.09961 -271.139773) (xy 365.053594 -271.122321) (xy 365.010973 -271.097714) (xy 364.972852 -271.066589)
			(xy 364.940217 -271.029752) (xy 364.913914 -270.988156) (xy 364.894623 -270.94288) (xy 364.882846 -270.895096)
			(xy 364.878886 -270.846042) (xy 364.550198 -270.846042) (xy 364.549703 -270.870649) (xy 364.541808 -270.919226)
			(xy 364.526224 -270.965907) (xy 364.503353 -271.009484) (xy 364.473788 -271.048828) (xy 364.438295 -271.08292)
			(xy 364.397792 -271.110876) (xy 364.35333 -271.131974) (xy 364.306059 -271.145666) (xy 364.257204 -271.151598)
			(xy 364.208029 -271.149617) (xy 364.15981 -271.139773) (xy 364.113794 -271.122321) (xy 364.071173 -271.097714)
			(xy 364.033052 -271.066589) (xy 364.000417 -271.029752) (xy 363.974114 -270.988156) (xy 363.954823 -270.94288)
			(xy 363.943046 -270.895096) (xy 363.939086 -270.846042) (xy 363.620558 -270.846042) (xy 363.620046 -270.871488)
			(xy 363.611882 -270.921722) (xy 363.595766 -270.969996) (xy 363.572115 -271.015059) (xy 363.541542 -271.055745)
			(xy 363.504838 -271.091) (xy 363.462954 -271.11991) (xy 363.416975 -271.141727) (xy 363.368091 -271.155887)
			(xy 363.31757 -271.162021) (xy 363.266718 -271.159972) (xy 363.216854 -271.149792) (xy 363.169268 -271.131745)
			(xy 363.125194 -271.106299) (xy 363.085772 -271.074112) (xy 363.052024 -271.036018) (xy 363.024823 -270.993004)
			(xy 363.004875 -270.946184) (xy 362.992696 -270.89677) (xy 362.988601 -270.846042) (xy 362.680504 -270.846042)
			(xy 362.679992 -270.871488) (xy 362.671828 -270.921722) (xy 362.655712 -270.969996) (xy 362.632061 -271.015059)
			(xy 362.601488 -271.055745) (xy 362.564784 -271.091) (xy 362.5229 -271.11991) (xy 362.476921 -271.141727)
			(xy 362.428037 -271.155887) (xy 362.377516 -271.162021) (xy 362.326664 -271.159972) (xy 362.2768 -271.149792)
			(xy 362.229214 -271.131745) (xy 362.18514 -271.106299) (xy 362.145718 -271.074112) (xy 362.11197 -271.036018)
			(xy 362.084769 -270.993004) (xy 362.064821 -270.946184) (xy 362.052642 -270.89677) (xy 362.048547 -270.846042)
			(xy 361.730036 -270.846042) (xy 361.729541 -270.870649) (xy 361.721646 -270.919226) (xy 361.706062 -270.965907)
			(xy 361.683191 -271.009484) (xy 361.653626 -271.048828) (xy 361.618133 -271.08292) (xy 361.57763 -271.110876)
			(xy 361.533168 -271.131974) (xy 361.485897 -271.145666) (xy 361.437042 -271.151598) (xy 361.387867 -271.149617)
			(xy 361.339648 -271.139773) (xy 361.293632 -271.122321) (xy 361.251011 -271.097714) (xy 361.21289 -271.066589)
			(xy 361.180255 -271.029752) (xy 361.153952 -270.988156) (xy 361.134661 -270.94288) (xy 361.122884 -270.895096)
			(xy 361.118924 -270.846042) (xy 359.836874 -270.846042) (xy 360.398294 -271.656048) (xy 363.468932 -271.656048)
			(xy 363.472892 -271.606994) (xy 363.484669 -271.55921) (xy 363.50396 -271.513934) (xy 363.530263 -271.472338)
			(xy 363.562898 -271.435501) (xy 363.601019 -271.404376) (xy 363.64364 -271.379769) (xy 363.689656 -271.362317)
			(xy 363.737875 -271.352473) (xy 363.78705 -271.350492) (xy 363.835905 -271.356424) (xy 363.883176 -271.370116)
			(xy 363.927638 -271.391214) (xy 363.968141 -271.41917) (xy 364.003634 -271.453262) (xy 364.033199 -271.492606)
			(xy 364.05607 -271.536183) (xy 364.071654 -271.582864) (xy 364.079549 -271.631441) (xy 364.080044 -271.656048)
			(xy 364.398555 -271.656048) (xy 364.40265 -271.60532) (xy 364.414829 -271.555906) (xy 364.434777 -271.509086)
			(xy 364.461978 -271.466072) (xy 364.495726 -271.427978) (xy 364.535148 -271.395791) (xy 364.579222 -271.370345)
			(xy 364.626808 -271.352298) (xy 364.676672 -271.342118) (xy 364.727524 -271.340069) (xy 364.778045 -271.346203)
			(xy 364.826929 -271.360363) (xy 364.872908 -271.38218) (xy 364.914792 -271.41109) (xy 364.951496 -271.446345)
			(xy 364.982069 -271.487031) (xy 365.00572 -271.532094) (xy 365.021836 -271.580368) (xy 365.03 -271.630602)
			(xy 365.030512 -271.656048) (xy 365.338609 -271.656048) (xy 365.342704 -271.60532) (xy 365.354883 -271.555906)
			(xy 365.374831 -271.509086) (xy 365.402032 -271.466072) (xy 365.43578 -271.427978) (xy 365.475202 -271.395791)
			(xy 365.519276 -271.370345) (xy 365.566862 -271.352298) (xy 365.616726 -271.342118) (xy 365.667578 -271.340069)
			(xy 365.718099 -271.346203) (xy 365.766983 -271.360363) (xy 365.812962 -271.38218) (xy 365.854846 -271.41109)
			(xy 365.89155 -271.446345) (xy 365.922123 -271.487031) (xy 365.945774 -271.532094) (xy 365.96189 -271.580368)
			(xy 365.970054 -271.630602) (xy 365.970566 -271.656048) (xy 366.289094 -271.656048) (xy 366.293054 -271.606994)
			(xy 366.304831 -271.55921) (xy 366.324122 -271.513934) (xy 366.350425 -271.472338) (xy 366.38306 -271.435501)
			(xy 366.421181 -271.404376) (xy 366.463802 -271.379769) (xy 366.509818 -271.362317) (xy 366.558037 -271.352473)
			(xy 366.607212 -271.350492) (xy 366.656067 -271.356424) (xy 366.703338 -271.370116) (xy 366.7478 -271.391214)
			(xy 366.788303 -271.41917) (xy 366.823796 -271.453262) (xy 366.853361 -271.492606) (xy 366.876232 -271.536183)
			(xy 366.891816 -271.582864) (xy 366.899711 -271.631441) (xy 366.900206 -271.656048) (xy 367.218463 -271.656048)
			(xy 367.222558 -271.60532) (xy 367.234737 -271.555906) (xy 367.254685 -271.509086) (xy 367.281886 -271.466072)
			(xy 367.315634 -271.427978) (xy 367.355056 -271.395791) (xy 367.39913 -271.370345) (xy 367.446716 -271.352298)
			(xy 367.49658 -271.342118) (xy 367.547432 -271.340069) (xy 367.597953 -271.346203) (xy 367.646837 -271.360363)
			(xy 367.692816 -271.38218) (xy 367.7347 -271.41109) (xy 367.771404 -271.446345) (xy 367.801977 -271.487031)
			(xy 367.825628 -271.532094) (xy 367.841744 -271.580368) (xy 367.849908 -271.630602) (xy 367.85042 -271.656048)
			(xy 368.158517 -271.656048) (xy 368.162612 -271.60532) (xy 368.174791 -271.555906) (xy 368.194739 -271.509086)
			(xy 368.22194 -271.466072) (xy 368.255688 -271.427978) (xy 368.29511 -271.395791) (xy 368.339184 -271.370345)
			(xy 368.38677 -271.352298) (xy 368.436634 -271.342118) (xy 368.487486 -271.340069) (xy 368.538007 -271.346203)
			(xy 368.586891 -271.360363) (xy 368.63287 -271.38218) (xy 368.674754 -271.41109) (xy 368.711458 -271.446345)
			(xy 368.742031 -271.487031) (xy 368.765682 -271.532094) (xy 368.781798 -271.580368) (xy 368.789962 -271.630602)
			(xy 368.790474 -271.656048) (xy 369.109002 -271.656048) (xy 369.112962 -271.606994) (xy 369.124739 -271.55921)
			(xy 369.14403 -271.513934) (xy 369.170333 -271.472338) (xy 369.202968 -271.435501) (xy 369.241089 -271.404376)
			(xy 369.28371 -271.379769) (xy 369.329726 -271.362317) (xy 369.377945 -271.352473) (xy 369.42712 -271.350492)
			(xy 369.475975 -271.356424) (xy 369.523246 -271.370116) (xy 369.567708 -271.391214) (xy 369.608211 -271.41917)
			(xy 369.643704 -271.453262) (xy 369.673269 -271.492606) (xy 369.69614 -271.536183) (xy 369.711724 -271.582864)
			(xy 369.719619 -271.631441) (xy 369.720114 -271.656048) (xy 370.038625 -271.656048) (xy 370.04272 -271.60532)
			(xy 370.054899 -271.555906) (xy 370.074847 -271.509086) (xy 370.102048 -271.466072) (xy 370.135796 -271.427978)
			(xy 370.175218 -271.395791) (xy 370.219292 -271.370345) (xy 370.266878 -271.352298) (xy 370.316742 -271.342118)
			(xy 370.367594 -271.340069) (xy 370.418115 -271.346203) (xy 370.466999 -271.360363) (xy 370.512978 -271.38218)
			(xy 370.554862 -271.41109) (xy 370.591566 -271.446345) (xy 370.622139 -271.487031) (xy 370.64579 -271.532094)
			(xy 370.661906 -271.580368) (xy 370.67007 -271.630602) (xy 370.670582 -271.656048) (xy 370.978679 -271.656048)
			(xy 370.982774 -271.60532) (xy 370.994953 -271.555906) (xy 371.014901 -271.509086) (xy 371.042102 -271.466072)
			(xy 371.07585 -271.427978) (xy 371.115272 -271.395791) (xy 371.159346 -271.370345) (xy 371.206932 -271.352298)
			(xy 371.256796 -271.342118) (xy 371.307648 -271.340069) (xy 371.358169 -271.346203) (xy 371.407053 -271.360363)
			(xy 371.453032 -271.38218) (xy 371.494916 -271.41109) (xy 371.53162 -271.446345) (xy 371.562193 -271.487031)
			(xy 371.585844 -271.532094) (xy 371.60196 -271.580368) (xy 371.610124 -271.630602) (xy 371.610636 -271.656048)
			(xy 371.92891 -271.656048) (xy 371.93287 -271.606994) (xy 371.944647 -271.55921) (xy 371.963938 -271.513934)
			(xy 371.990241 -271.472338) (xy 372.022876 -271.435501) (xy 372.060997 -271.404376) (xy 372.103618 -271.379769)
			(xy 372.149634 -271.362317) (xy 372.197853 -271.352473) (xy 372.247028 -271.350492) (xy 372.295883 -271.356424)
			(xy 372.343154 -271.370116) (xy 372.387616 -271.391214) (xy 372.428119 -271.41917) (xy 372.463612 -271.453262)
			(xy 372.493177 -271.492606) (xy 372.516048 -271.536183) (xy 372.531632 -271.582864) (xy 372.539527 -271.631441)
			(xy 372.540022 -271.656048) (xy 372.858533 -271.656048) (xy 372.862628 -271.60532) (xy 372.874807 -271.555906)
			(xy 372.894755 -271.509086) (xy 372.921956 -271.466072) (xy 372.955704 -271.427978) (xy 372.995126 -271.395791)
			(xy 373.0392 -271.370345) (xy 373.086786 -271.352298) (xy 373.13665 -271.342118) (xy 373.187502 -271.340069)
			(xy 373.238023 -271.346203) (xy 373.286907 -271.360363) (xy 373.332886 -271.38218) (xy 373.37477 -271.41109)
			(xy 373.411474 -271.446345) (xy 373.442047 -271.487031) (xy 373.465698 -271.532094) (xy 373.481814 -271.580368)
			(xy 373.489978 -271.630602) (xy 373.49049 -271.656048) (xy 373.798587 -271.656048) (xy 373.802682 -271.60532)
			(xy 373.814861 -271.555906) (xy 373.834809 -271.509086) (xy 373.86201 -271.466072) (xy 373.895758 -271.427978)
			(xy 373.93518 -271.395791) (xy 373.979254 -271.370345) (xy 374.02684 -271.352298) (xy 374.076704 -271.342118)
			(xy 374.127556 -271.340069) (xy 374.178077 -271.346203) (xy 374.226961 -271.360363) (xy 374.27294 -271.38218)
			(xy 374.314824 -271.41109) (xy 374.351528 -271.446345) (xy 374.382101 -271.487031) (xy 374.405752 -271.532094)
			(xy 374.421868 -271.580368) (xy 374.430032 -271.630602) (xy 374.430544 -271.656048) (xy 374.430032 -271.681494)
			(xy 374.421868 -271.731728) (xy 374.405752 -271.780002) (xy 374.382101 -271.825065) (xy 374.351528 -271.865751)
			(xy 374.314824 -271.901006) (xy 374.27294 -271.929916) (xy 374.226961 -271.951733) (xy 374.178077 -271.965893)
			(xy 374.127556 -271.972027) (xy 374.076704 -271.969978) (xy 374.02684 -271.959798) (xy 373.979254 -271.941751)
			(xy 373.93518 -271.916305) (xy 373.895758 -271.884118) (xy 373.86201 -271.846024) (xy 373.834809 -271.80301)
			(xy 373.814861 -271.75619) (xy 373.802682 -271.706776) (xy 373.798587 -271.656048) (xy 373.49049 -271.656048)
			(xy 373.489978 -271.681494) (xy 373.481814 -271.731728) (xy 373.465698 -271.780002) (xy 373.442047 -271.825065)
			(xy 373.411474 -271.865751) (xy 373.37477 -271.901006) (xy 373.332886 -271.929916) (xy 373.286907 -271.951733)
			(xy 373.238023 -271.965893) (xy 373.187502 -271.972027) (xy 373.13665 -271.969978) (xy 373.086786 -271.959798)
			(xy 373.0392 -271.941751) (xy 372.995126 -271.916305) (xy 372.955704 -271.884118) (xy 372.921956 -271.846024)
			(xy 372.894755 -271.80301) (xy 372.874807 -271.75619) (xy 372.862628 -271.706776) (xy 372.858533 -271.656048)
			(xy 372.540022 -271.656048) (xy 372.539527 -271.680655) (xy 372.531632 -271.729232) (xy 372.516048 -271.775913)
			(xy 372.493177 -271.81949) (xy 372.463612 -271.858834) (xy 372.428119 -271.892926) (xy 372.387616 -271.920882)
			(xy 372.343154 -271.94198) (xy 372.295883 -271.955672) (xy 372.247028 -271.961604) (xy 372.197853 -271.959623)
			(xy 372.149634 -271.949779) (xy 372.103618 -271.932327) (xy 372.060997 -271.90772) (xy 372.022876 -271.876595)
			(xy 371.990241 -271.839758) (xy 371.963938 -271.798162) (xy 371.944647 -271.752886) (xy 371.93287 -271.705102)
			(xy 371.92891 -271.656048) (xy 371.610636 -271.656048) (xy 371.610124 -271.681494) (xy 371.60196 -271.731728)
			(xy 371.585844 -271.780002) (xy 371.562193 -271.825065) (xy 371.53162 -271.865751) (xy 371.494916 -271.901006)
			(xy 371.453032 -271.929916) (xy 371.407053 -271.951733) (xy 371.358169 -271.965893) (xy 371.307648 -271.972027)
			(xy 371.256796 -271.969978) (xy 371.206932 -271.959798) (xy 371.159346 -271.941751) (xy 371.115272 -271.916305)
			(xy 371.07585 -271.884118) (xy 371.042102 -271.846024) (xy 371.014901 -271.80301) (xy 370.994953 -271.75619)
			(xy 370.982774 -271.706776) (xy 370.978679 -271.656048) (xy 370.670582 -271.656048) (xy 370.67007 -271.681494)
			(xy 370.661906 -271.731728) (xy 370.64579 -271.780002) (xy 370.622139 -271.825065) (xy 370.591566 -271.865751)
			(xy 370.554862 -271.901006) (xy 370.512978 -271.929916) (xy 370.466999 -271.951733) (xy 370.418115 -271.965893)
			(xy 370.367594 -271.972027) (xy 370.316742 -271.969978) (xy 370.266878 -271.959798) (xy 370.219292 -271.941751)
			(xy 370.175218 -271.916305) (xy 370.135796 -271.884118) (xy 370.102048 -271.846024) (xy 370.074847 -271.80301)
			(xy 370.054899 -271.75619) (xy 370.04272 -271.706776) (xy 370.038625 -271.656048) (xy 369.720114 -271.656048)
			(xy 369.719619 -271.680655) (xy 369.711724 -271.729232) (xy 369.69614 -271.775913) (xy 369.673269 -271.81949)
			(xy 369.643704 -271.858834) (xy 369.608211 -271.892926) (xy 369.567708 -271.920882) (xy 369.523246 -271.94198)
			(xy 369.475975 -271.955672) (xy 369.42712 -271.961604) (xy 369.377945 -271.959623) (xy 369.329726 -271.949779)
			(xy 369.28371 -271.932327) (xy 369.241089 -271.90772) (xy 369.202968 -271.876595) (xy 369.170333 -271.839758)
			(xy 369.14403 -271.798162) (xy 369.124739 -271.752886) (xy 369.112962 -271.705102) (xy 369.109002 -271.656048)
			(xy 368.790474 -271.656048) (xy 368.789962 -271.681494) (xy 368.781798 -271.731728) (xy 368.765682 -271.780002)
			(xy 368.742031 -271.825065) (xy 368.711458 -271.865751) (xy 368.674754 -271.901006) (xy 368.63287 -271.929916)
			(xy 368.586891 -271.951733) (xy 368.538007 -271.965893) (xy 368.487486 -271.972027) (xy 368.436634 -271.969978)
			(xy 368.38677 -271.959798) (xy 368.339184 -271.941751) (xy 368.29511 -271.916305) (xy 368.255688 -271.884118)
			(xy 368.22194 -271.846024) (xy 368.194739 -271.80301) (xy 368.174791 -271.75619) (xy 368.162612 -271.706776)
			(xy 368.158517 -271.656048) (xy 367.85042 -271.656048) (xy 367.849908 -271.681494) (xy 367.841744 -271.731728)
			(xy 367.825628 -271.780002) (xy 367.801977 -271.825065) (xy 367.771404 -271.865751) (xy 367.7347 -271.901006)
			(xy 367.692816 -271.929916) (xy 367.646837 -271.951733) (xy 367.597953 -271.965893) (xy 367.547432 -271.972027)
			(xy 367.49658 -271.969978) (xy 367.446716 -271.959798) (xy 367.39913 -271.941751) (xy 367.355056 -271.916305)
			(xy 367.315634 -271.884118) (xy 367.281886 -271.846024) (xy 367.254685 -271.80301) (xy 367.234737 -271.75619)
			(xy 367.222558 -271.706776) (xy 367.218463 -271.656048) (xy 366.900206 -271.656048) (xy 366.899711 -271.680655)
			(xy 366.891816 -271.729232) (xy 366.876232 -271.775913) (xy 366.853361 -271.81949) (xy 366.823796 -271.858834)
			(xy 366.788303 -271.892926) (xy 366.7478 -271.920882) (xy 366.703338 -271.94198) (xy 366.656067 -271.955672)
			(xy 366.607212 -271.961604) (xy 366.558037 -271.959623) (xy 366.509818 -271.949779) (xy 366.463802 -271.932327)
			(xy 366.421181 -271.90772) (xy 366.38306 -271.876595) (xy 366.350425 -271.839758) (xy 366.324122 -271.798162)
			(xy 366.304831 -271.752886) (xy 366.293054 -271.705102) (xy 366.289094 -271.656048) (xy 365.970566 -271.656048)
			(xy 365.970054 -271.681494) (xy 365.96189 -271.731728) (xy 365.945774 -271.780002) (xy 365.922123 -271.825065)
			(xy 365.89155 -271.865751) (xy 365.854846 -271.901006) (xy 365.812962 -271.929916) (xy 365.766983 -271.951733)
			(xy 365.718099 -271.965893) (xy 365.667578 -271.972027) (xy 365.616726 -271.969978) (xy 365.566862 -271.959798)
			(xy 365.519276 -271.941751) (xy 365.475202 -271.916305) (xy 365.43578 -271.884118) (xy 365.402032 -271.846024)
			(xy 365.374831 -271.80301) (xy 365.354883 -271.75619) (xy 365.342704 -271.706776) (xy 365.338609 -271.656048)
			(xy 365.030512 -271.656048) (xy 365.03 -271.681494) (xy 365.021836 -271.731728) (xy 365.00572 -271.780002)
			(xy 364.982069 -271.825065) (xy 364.951496 -271.865751) (xy 364.914792 -271.901006) (xy 364.872908 -271.929916)
			(xy 364.826929 -271.951733) (xy 364.778045 -271.965893) (xy 364.727524 -271.972027) (xy 364.676672 -271.969978)
			(xy 364.626808 -271.959798) (xy 364.579222 -271.941751) (xy 364.535148 -271.916305) (xy 364.495726 -271.884118)
			(xy 364.461978 -271.846024) (xy 364.434777 -271.80301) (xy 364.414829 -271.75619) (xy 364.40265 -271.706776)
			(xy 364.398555 -271.656048) (xy 364.080044 -271.656048) (xy 364.079549 -271.680655) (xy 364.071654 -271.729232)
			(xy 364.05607 -271.775913) (xy 364.033199 -271.81949) (xy 364.003634 -271.858834) (xy 363.968141 -271.892926)
			(xy 363.927638 -271.920882) (xy 363.883176 -271.94198) (xy 363.835905 -271.955672) (xy 363.78705 -271.961604)
			(xy 363.737875 -271.959623) (xy 363.689656 -271.949779) (xy 363.64364 -271.932327) (xy 363.601019 -271.90772)
			(xy 363.562898 -271.876595) (xy 363.530263 -271.839758) (xy 363.50396 -271.798162) (xy 363.484669 -271.752886)
			(xy 363.472892 -271.705102) (xy 363.468932 -271.656048) (xy 360.398294 -271.656048) (xy 360.924856 -272.415762)
			(xy 360.928853 -272.421859) (xy 360.933507 -272.435667) (xy 360.934 -272.44294) (xy 360.93479 -272.466054)
			(xy 361.118924 -272.466054) (xy 361.122884 -272.417) (xy 361.134661 -272.369216) (xy 361.153952 -272.32394)
			(xy 361.180255 -272.282344) (xy 361.21289 -272.245507) (xy 361.251011 -272.214382) (xy 361.293632 -272.189775)
			(xy 361.339648 -272.172323) (xy 361.387867 -272.162479) (xy 361.437042 -272.160498) (xy 361.485897 -272.16643)
			(xy 361.533168 -272.180122) (xy 361.57763 -272.20122) (xy 361.618133 -272.229176) (xy 361.653626 -272.263268)
			(xy 361.683191 -272.302612) (xy 361.706062 -272.346189) (xy 361.721646 -272.39287) (xy 361.729541 -272.441447)
			(xy 361.730036 -272.466054) (xy 362.048547 -272.466054) (xy 362.052642 -272.415326) (xy 362.064821 -272.365912)
			(xy 362.084769 -272.319092) (xy 362.11197 -272.276078) (xy 362.145718 -272.237984) (xy 362.18514 -272.205797)
			(xy 362.229214 -272.180351) (xy 362.2768 -272.162304) (xy 362.326664 -272.152124) (xy 362.377516 -272.150075)
			(xy 362.428037 -272.156209) (xy 362.476921 -272.170369) (xy 362.5229 -272.192186) (xy 362.564784 -272.221096)
			(xy 362.601488 -272.256351) (xy 362.632061 -272.297037) (xy 362.655712 -272.3421) (xy 362.671828 -272.390374)
			(xy 362.679992 -272.440608) (xy 362.680504 -272.466054) (xy 362.988601 -272.466054) (xy 362.992696 -272.415326)
			(xy 363.004875 -272.365912) (xy 363.024823 -272.319092) (xy 363.052024 -272.276078) (xy 363.085772 -272.237984)
			(xy 363.125194 -272.205797) (xy 363.169268 -272.180351) (xy 363.216854 -272.162304) (xy 363.266718 -272.152124)
			(xy 363.31757 -272.150075) (xy 363.368091 -272.156209) (xy 363.416975 -272.170369) (xy 363.462954 -272.192186)
			(xy 363.504838 -272.221096) (xy 363.541542 -272.256351) (xy 363.572115 -272.297037) (xy 363.595766 -272.3421)
			(xy 363.611882 -272.390374) (xy 363.620046 -272.440608) (xy 363.620558 -272.466054) (xy 363.939086 -272.466054)
			(xy 363.943046 -272.417) (xy 363.954823 -272.369216) (xy 363.974114 -272.32394) (xy 364.000417 -272.282344)
			(xy 364.033052 -272.245507) (xy 364.071173 -272.214382) (xy 364.113794 -272.189775) (xy 364.15981 -272.172323)
			(xy 364.208029 -272.162479) (xy 364.257204 -272.160498) (xy 364.306059 -272.16643) (xy 364.35333 -272.180122)
			(xy 364.397792 -272.20122) (xy 364.438295 -272.229176) (xy 364.473788 -272.263268) (xy 364.503353 -272.302612)
			(xy 364.526224 -272.346189) (xy 364.541808 -272.39287) (xy 364.549703 -272.441447) (xy 364.550198 -272.466054)
			(xy 366.758994 -272.466054) (xy 366.762954 -272.417) (xy 366.774731 -272.369216) (xy 366.794022 -272.32394)
			(xy 366.820325 -272.282344) (xy 366.85296 -272.245507) (xy 366.891081 -272.214382) (xy 366.933702 -272.189775)
			(xy 366.979718 -272.172323) (xy 367.027937 -272.162479) (xy 367.077112 -272.160498) (xy 367.125967 -272.16643)
			(xy 367.173238 -272.180122) (xy 367.2177 -272.20122) (xy 367.258203 -272.229176) (xy 367.293696 -272.263268)
			(xy 367.323261 -272.302612) (xy 367.346132 -272.346189) (xy 367.361716 -272.39287) (xy 367.369611 -272.441447)
			(xy 367.370106 -272.466054) (xy 369.578902 -272.466054) (xy 369.582862 -272.417) (xy 369.594639 -272.369216)
			(xy 369.61393 -272.32394) (xy 369.640233 -272.282344) (xy 369.672868 -272.245507) (xy 369.710989 -272.214382)
			(xy 369.75361 -272.189775) (xy 369.799626 -272.172323) (xy 369.847845 -272.162479) (xy 369.89702 -272.160498)
			(xy 369.945875 -272.16643) (xy 369.993146 -272.180122) (xy 370.037608 -272.20122) (xy 370.078111 -272.229176)
			(xy 370.113604 -272.263268) (xy 370.143169 -272.302612) (xy 370.16604 -272.346189) (xy 370.181624 -272.39287)
			(xy 370.189519 -272.441447) (xy 370.190014 -272.466054) (xy 372.399064 -272.466054) (xy 372.403024 -272.417)
			(xy 372.414801 -272.369216) (xy 372.434092 -272.32394) (xy 372.460395 -272.282344) (xy 372.49303 -272.245507)
			(xy 372.531151 -272.214382) (xy 372.573772 -272.189775) (xy 372.619788 -272.172323) (xy 372.668007 -272.162479)
			(xy 372.717182 -272.160498) (xy 372.766037 -272.16643) (xy 372.813308 -272.180122) (xy 372.85777 -272.20122)
			(xy 372.898273 -272.229176) (xy 372.933766 -272.263268) (xy 372.963331 -272.302612) (xy 372.986202 -272.346189)
			(xy 373.001786 -272.39287) (xy 373.009681 -272.441447) (xy 373.010176 -272.466054) (xy 373.009681 -272.490661)
			(xy 373.001786 -272.539238) (xy 372.986202 -272.585919) (xy 372.963331 -272.629496) (xy 372.933766 -272.66884)
			(xy 372.898273 -272.702932) (xy 372.85777 -272.730888) (xy 372.813308 -272.751986) (xy 372.766037 -272.765678)
			(xy 372.717182 -272.77161) (xy 372.668007 -272.769629) (xy 372.619788 -272.759785) (xy 372.573772 -272.742333)
			(xy 372.531151 -272.717726) (xy 372.49303 -272.686601) (xy 372.460395 -272.649764) (xy 372.434092 -272.608168)
			(xy 372.414801 -272.562892) (xy 372.403024 -272.515108) (xy 372.399064 -272.466054) (xy 370.190014 -272.466054)
			(xy 370.189519 -272.490661) (xy 370.181624 -272.539238) (xy 370.16604 -272.585919) (xy 370.143169 -272.629496)
			(xy 370.113604 -272.66884) (xy 370.078111 -272.702932) (xy 370.037608 -272.730888) (xy 369.993146 -272.751986)
			(xy 369.945875 -272.765678) (xy 369.89702 -272.77161) (xy 369.847845 -272.769629) (xy 369.799626 -272.759785)
			(xy 369.75361 -272.742333) (xy 369.710989 -272.717726) (xy 369.672868 -272.686601) (xy 369.640233 -272.649764)
			(xy 369.61393 -272.608168) (xy 369.594639 -272.562892) (xy 369.582862 -272.515108) (xy 369.578902 -272.466054)
			(xy 367.370106 -272.466054) (xy 367.369611 -272.490661) (xy 367.361716 -272.539238) (xy 367.346132 -272.585919)
			(xy 367.323261 -272.629496) (xy 367.293696 -272.66884) (xy 367.258203 -272.702932) (xy 367.2177 -272.730888)
			(xy 367.173238 -272.751986) (xy 367.125967 -272.765678) (xy 367.077112 -272.77161) (xy 367.027937 -272.769629)
			(xy 366.979718 -272.759785) (xy 366.933702 -272.742333) (xy 366.891081 -272.717726) (xy 366.85296 -272.686601)
			(xy 366.820325 -272.649764) (xy 366.794022 -272.608168) (xy 366.774731 -272.562892) (xy 366.762954 -272.515108)
			(xy 366.758994 -272.466054) (xy 364.550198 -272.466054) (xy 364.549703 -272.490661) (xy 364.541808 -272.539238)
			(xy 364.526224 -272.585919) (xy 364.503353 -272.629496) (xy 364.473788 -272.66884) (xy 364.438295 -272.702932)
			(xy 364.397792 -272.730888) (xy 364.35333 -272.751986) (xy 364.306059 -272.765678) (xy 364.257204 -272.77161)
			(xy 364.208029 -272.769629) (xy 364.15981 -272.759785) (xy 364.113794 -272.742333) (xy 364.071173 -272.717726)
			(xy 364.033052 -272.686601) (xy 364.000417 -272.649764) (xy 363.974114 -272.608168) (xy 363.954823 -272.562892)
			(xy 363.943046 -272.515108) (xy 363.939086 -272.466054) (xy 363.620558 -272.466054) (xy 363.620046 -272.4915)
			(xy 363.611882 -272.541734) (xy 363.595766 -272.590008) (xy 363.572115 -272.635071) (xy 363.541542 -272.675757)
			(xy 363.504838 -272.711012) (xy 363.462954 -272.739922) (xy 363.416975 -272.761739) (xy 363.368091 -272.775899)
			(xy 363.31757 -272.782033) (xy 363.266718 -272.779984) (xy 363.216854 -272.769804) (xy 363.169268 -272.751757)
			(xy 363.125194 -272.726311) (xy 363.085772 -272.694124) (xy 363.052024 -272.65603) (xy 363.024823 -272.613016)
			(xy 363.004875 -272.566196) (xy 362.992696 -272.516782) (xy 362.988601 -272.466054) (xy 362.680504 -272.466054)
			(xy 362.679992 -272.4915) (xy 362.671828 -272.541734) (xy 362.655712 -272.590008) (xy 362.632061 -272.635071)
			(xy 362.601488 -272.675757) (xy 362.564784 -272.711012) (xy 362.5229 -272.739922) (xy 362.476921 -272.761739)
			(xy 362.428037 -272.775899) (xy 362.377516 -272.782033) (xy 362.326664 -272.779984) (xy 362.2768 -272.769804)
			(xy 362.229214 -272.751757) (xy 362.18514 -272.726311) (xy 362.145718 -272.694124) (xy 362.11197 -272.65603)
			(xy 362.084769 -272.613016) (xy 362.064821 -272.566196) (xy 362.052642 -272.516782) (xy 362.048547 -272.466054)
			(xy 361.730036 -272.466054) (xy 361.729541 -272.490661) (xy 361.721646 -272.539238) (xy 361.706062 -272.585919)
			(xy 361.683191 -272.629496) (xy 361.653626 -272.66884) (xy 361.618133 -272.702932) (xy 361.57763 -272.730888)
			(xy 361.533168 -272.751986) (xy 361.485897 -272.765678) (xy 361.437042 -272.77161) (xy 361.387867 -272.769629)
			(xy 361.339648 -272.759785) (xy 361.293632 -272.742333) (xy 361.251011 -272.717726) (xy 361.21289 -272.686601)
			(xy 361.180255 -272.649764) (xy 361.153952 -272.608168) (xy 361.134661 -272.562892) (xy 361.122884 -272.515108)
			(xy 361.118924 -272.466054) (xy 360.93479 -272.466054) (xy 360.962488 -273.27606) (xy 361.589078 -273.27606)
			(xy 361.593038 -273.227006) (xy 361.604815 -273.179222) (xy 361.624106 -273.133946) (xy 361.650409 -273.09235)
			(xy 361.683044 -273.055513) (xy 361.721165 -273.024388) (xy 361.763786 -272.999781) (xy 361.809802 -272.982329)
			(xy 361.858021 -272.972485) (xy 361.907196 -272.970504) (xy 361.956051 -272.976436) (xy 362.003322 -272.990128)
			(xy 362.047784 -273.011226) (xy 362.088287 -273.039182) (xy 362.12378 -273.073274) (xy 362.153345 -273.112618)
			(xy 362.176216 -273.156195) (xy 362.1918 -273.202876) (xy 362.199695 -273.251453) (xy 362.20019 -273.27606)
			(xy 362.528878 -273.27606) (xy 362.532838 -273.227006) (xy 362.544615 -273.179222) (xy 362.563906 -273.133946)
			(xy 362.590209 -273.09235) (xy 362.622844 -273.055513) (xy 362.660965 -273.024388) (xy 362.703586 -272.999781)
			(xy 362.749602 -272.982329) (xy 362.797821 -272.972485) (xy 362.846996 -272.970504) (xy 362.895851 -272.976436)
			(xy 362.943122 -272.990128) (xy 362.987584 -273.011226) (xy 363.028087 -273.039182) (xy 363.06358 -273.073274)
			(xy 363.093145 -273.112618) (xy 363.116016 -273.156195) (xy 363.1316 -273.202876) (xy 363.139495 -273.251453)
			(xy 363.13999 -273.27606) (xy 363.468932 -273.27606) (xy 363.472892 -273.227006) (xy 363.484669 -273.179222)
			(xy 363.50396 -273.133946) (xy 363.530263 -273.09235) (xy 363.562898 -273.055513) (xy 363.601019 -273.024388)
			(xy 363.64364 -272.999781) (xy 363.689656 -272.982329) (xy 363.737875 -272.972485) (xy 363.78705 -272.970504)
			(xy 363.835905 -272.976436) (xy 363.883176 -272.990128) (xy 363.927638 -273.011226) (xy 363.968141 -273.039182)
			(xy 364.003634 -273.073274) (xy 364.033199 -273.112618) (xy 364.05607 -273.156195) (xy 364.071654 -273.202876)
			(xy 364.079549 -273.251453) (xy 364.080044 -273.27606) (xy 364.398555 -273.27606) (xy 364.40265 -273.225332)
			(xy 364.414829 -273.175918) (xy 364.434777 -273.129098) (xy 364.461978 -273.086084) (xy 364.495726 -273.04799)
			(xy 364.535148 -273.015803) (xy 364.579222 -272.990357) (xy 364.626808 -272.97231) (xy 364.676672 -272.96213)
			(xy 364.727524 -272.960081) (xy 364.778045 -272.966215) (xy 364.826929 -272.980375) (xy 364.872908 -273.002192)
			(xy 364.914792 -273.031102) (xy 364.951496 -273.066357) (xy 364.982069 -273.107043) (xy 365.00572 -273.152106)
			(xy 365.021836 -273.20038) (xy 365.03 -273.250614) (xy 365.030512 -273.27606) (xy 365.338609 -273.27606)
			(xy 365.342704 -273.225332) (xy 365.354883 -273.175918) (xy 365.374831 -273.129098) (xy 365.402032 -273.086084)
			(xy 365.43578 -273.04799) (xy 365.475202 -273.015803) (xy 365.519276 -272.990357) (xy 365.566862 -272.97231)
			(xy 365.616726 -272.96213) (xy 365.667578 -272.960081) (xy 365.718099 -272.966215) (xy 365.766983 -272.980375)
			(xy 365.812962 -273.002192) (xy 365.854846 -273.031102) (xy 365.89155 -273.066357) (xy 365.922123 -273.107043)
			(xy 365.945774 -273.152106) (xy 365.96189 -273.20038) (xy 365.970054 -273.250614) (xy 365.970566 -273.27606)
			(xy 366.289094 -273.27606) (xy 366.293054 -273.227006) (xy 366.304831 -273.179222) (xy 366.324122 -273.133946)
			(xy 366.350425 -273.09235) (xy 366.38306 -273.055513) (xy 366.421181 -273.024388) (xy 366.463802 -272.999781)
			(xy 366.509818 -272.982329) (xy 366.558037 -272.972485) (xy 366.607212 -272.970504) (xy 366.656067 -272.976436)
			(xy 366.703338 -272.990128) (xy 366.7478 -273.011226) (xy 366.788303 -273.039182) (xy 366.823796 -273.073274)
			(xy 366.853361 -273.112618) (xy 366.876232 -273.156195) (xy 366.891816 -273.202876) (xy 366.899711 -273.251453)
			(xy 366.900206 -273.27606) (xy 367.218463 -273.27606) (xy 367.222558 -273.225332) (xy 367.234737 -273.175918)
			(xy 367.254685 -273.129098) (xy 367.281886 -273.086084) (xy 367.315634 -273.04799) (xy 367.355056 -273.015803)
			(xy 367.39913 -272.990357) (xy 367.446716 -272.97231) (xy 367.49658 -272.96213) (xy 367.547432 -272.960081)
			(xy 367.597953 -272.966215) (xy 367.646837 -272.980375) (xy 367.692816 -273.002192) (xy 367.7347 -273.031102)
			(xy 367.771404 -273.066357) (xy 367.801977 -273.107043) (xy 367.825628 -273.152106) (xy 367.841744 -273.20038)
			(xy 367.849908 -273.250614) (xy 367.85042 -273.27606) (xy 368.158517 -273.27606) (xy 368.162612 -273.225332)
			(xy 368.174791 -273.175918) (xy 368.194739 -273.129098) (xy 368.22194 -273.086084) (xy 368.255688 -273.04799)
			(xy 368.29511 -273.015803) (xy 368.339184 -272.990357) (xy 368.38677 -272.97231) (xy 368.436634 -272.96213)
			(xy 368.487486 -272.960081) (xy 368.538007 -272.966215) (xy 368.586891 -272.980375) (xy 368.63287 -273.002192)
			(xy 368.674754 -273.031102) (xy 368.711458 -273.066357) (xy 368.742031 -273.107043) (xy 368.765682 -273.152106)
			(xy 368.781798 -273.20038) (xy 368.789962 -273.250614) (xy 368.790474 -273.27606) (xy 369.109002 -273.27606)
			(xy 369.112962 -273.227006) (xy 369.124739 -273.179222) (xy 369.14403 -273.133946) (xy 369.170333 -273.09235)
			(xy 369.202968 -273.055513) (xy 369.241089 -273.024388) (xy 369.28371 -272.999781) (xy 369.329726 -272.982329)
			(xy 369.377945 -272.972485) (xy 369.42712 -272.970504) (xy 369.475975 -272.976436) (xy 369.523246 -272.990128)
			(xy 369.567708 -273.011226) (xy 369.608211 -273.039182) (xy 369.643704 -273.073274) (xy 369.673269 -273.112618)
			(xy 369.69614 -273.156195) (xy 369.711724 -273.202876) (xy 369.719619 -273.251453) (xy 369.720114 -273.27606)
			(xy 370.038625 -273.27606) (xy 370.04272 -273.225332) (xy 370.054899 -273.175918) (xy 370.074847 -273.129098)
			(xy 370.102048 -273.086084) (xy 370.135796 -273.04799) (xy 370.175218 -273.015803) (xy 370.219292 -272.990357)
			(xy 370.266878 -272.97231) (xy 370.316742 -272.96213) (xy 370.367594 -272.960081) (xy 370.418115 -272.966215)
			(xy 370.466999 -272.980375) (xy 370.512978 -273.002192) (xy 370.554862 -273.031102) (xy 370.591566 -273.066357)
			(xy 370.622139 -273.107043) (xy 370.64579 -273.152106) (xy 370.661906 -273.20038) (xy 370.67007 -273.250614)
			(xy 370.670582 -273.27606) (xy 370.978679 -273.27606) (xy 370.982774 -273.225332) (xy 370.994953 -273.175918)
			(xy 371.014901 -273.129098) (xy 371.042102 -273.086084) (xy 371.07585 -273.04799) (xy 371.115272 -273.015803)
			(xy 371.159346 -272.990357) (xy 371.206932 -272.97231) (xy 371.256796 -272.96213) (xy 371.307648 -272.960081)
			(xy 371.358169 -272.966215) (xy 371.407053 -272.980375) (xy 371.453032 -273.002192) (xy 371.494916 -273.031102)
			(xy 371.53162 -273.066357) (xy 371.562193 -273.107043) (xy 371.585844 -273.152106) (xy 371.60196 -273.20038)
			(xy 371.610124 -273.250614) (xy 371.610636 -273.27606) (xy 371.92891 -273.27606) (xy 371.93287 -273.227006)
			(xy 371.944647 -273.179222) (xy 371.963938 -273.133946) (xy 371.990241 -273.09235) (xy 372.022876 -273.055513)
			(xy 372.060997 -273.024388) (xy 372.103618 -272.999781) (xy 372.149634 -272.982329) (xy 372.197853 -272.972485)
			(xy 372.247028 -272.970504) (xy 372.295883 -272.976436) (xy 372.343154 -272.990128) (xy 372.387616 -273.011226)
			(xy 372.428119 -273.039182) (xy 372.463612 -273.073274) (xy 372.493177 -273.112618) (xy 372.516048 -273.156195)
			(xy 372.531632 -273.202876) (xy 372.539527 -273.251453) (xy 372.540022 -273.27606) (xy 372.858533 -273.27606)
			(xy 372.862628 -273.225332) (xy 372.874807 -273.175918) (xy 372.894755 -273.129098) (xy 372.921956 -273.086084)
			(xy 372.955704 -273.04799) (xy 372.995126 -273.015803) (xy 373.0392 -272.990357) (xy 373.086786 -272.97231)
			(xy 373.13665 -272.96213) (xy 373.187502 -272.960081) (xy 373.238023 -272.966215) (xy 373.286907 -272.980375)
			(xy 373.332886 -273.002192) (xy 373.37477 -273.031102) (xy 373.411474 -273.066357) (xy 373.442047 -273.107043)
			(xy 373.465698 -273.152106) (xy 373.481814 -273.20038) (xy 373.489978 -273.250614) (xy 373.49049 -273.27606)
			(xy 373.798587 -273.27606) (xy 373.802682 -273.225332) (xy 373.814861 -273.175918) (xy 373.834809 -273.129098)
			(xy 373.86201 -273.086084) (xy 373.895758 -273.04799) (xy 373.93518 -273.015803) (xy 373.979254 -272.990357)
			(xy 374.02684 -272.97231) (xy 374.076704 -272.96213) (xy 374.127556 -272.960081) (xy 374.178077 -272.966215)
			(xy 374.226961 -272.980375) (xy 374.27294 -273.002192) (xy 374.314824 -273.031102) (xy 374.351528 -273.066357)
			(xy 374.382101 -273.107043) (xy 374.405752 -273.152106) (xy 374.421868 -273.20038) (xy 374.430032 -273.250614)
			(xy 374.430544 -273.27606) (xy 374.430032 -273.301506) (xy 374.421868 -273.35174) (xy 374.405752 -273.400014)
			(xy 374.382101 -273.445077) (xy 374.351528 -273.485763) (xy 374.314824 -273.521018) (xy 374.27294 -273.549928)
			(xy 374.226961 -273.571745) (xy 374.178077 -273.585905) (xy 374.127556 -273.592039) (xy 374.076704 -273.58999)
			(xy 374.02684 -273.57981) (xy 373.979254 -273.561763) (xy 373.93518 -273.536317) (xy 373.895758 -273.50413)
			(xy 373.86201 -273.466036) (xy 373.834809 -273.423022) (xy 373.814861 -273.376202) (xy 373.802682 -273.326788)
			(xy 373.798587 -273.27606) (xy 373.49049 -273.27606) (xy 373.489978 -273.301506) (xy 373.481814 -273.35174)
			(xy 373.465698 -273.400014) (xy 373.442047 -273.445077) (xy 373.411474 -273.485763) (xy 373.37477 -273.521018)
			(xy 373.332886 -273.549928) (xy 373.286907 -273.571745) (xy 373.238023 -273.585905) (xy 373.187502 -273.592039)
			(xy 373.13665 -273.58999) (xy 373.086786 -273.57981) (xy 373.0392 -273.561763) (xy 372.995126 -273.536317)
			(xy 372.955704 -273.50413) (xy 372.921956 -273.466036) (xy 372.894755 -273.423022) (xy 372.874807 -273.376202)
			(xy 372.862628 -273.326788) (xy 372.858533 -273.27606) (xy 372.540022 -273.27606) (xy 372.539527 -273.300667)
			(xy 372.531632 -273.349244) (xy 372.516048 -273.395925) (xy 372.493177 -273.439502) (xy 372.463612 -273.478846)
			(xy 372.428119 -273.512938) (xy 372.387616 -273.540894) (xy 372.343154 -273.561992) (xy 372.295883 -273.575684)
			(xy 372.247028 -273.581616) (xy 372.197853 -273.579635) (xy 372.149634 -273.569791) (xy 372.103618 -273.552339)
			(xy 372.060997 -273.527732) (xy 372.022876 -273.496607) (xy 371.990241 -273.45977) (xy 371.963938 -273.418174)
			(xy 371.944647 -273.372898) (xy 371.93287 -273.325114) (xy 371.92891 -273.27606) (xy 371.610636 -273.27606)
			(xy 371.610124 -273.301506) (xy 371.60196 -273.35174) (xy 371.585844 -273.400014) (xy 371.562193 -273.445077)
			(xy 371.53162 -273.485763) (xy 371.494916 -273.521018) (xy 371.453032 -273.549928) (xy 371.407053 -273.571745)
			(xy 371.358169 -273.585905) (xy 371.307648 -273.592039) (xy 371.256796 -273.58999) (xy 371.206932 -273.57981)
			(xy 371.159346 -273.561763) (xy 371.115272 -273.536317) (xy 371.07585 -273.50413) (xy 371.042102 -273.466036)
			(xy 371.014901 -273.423022) (xy 370.994953 -273.376202) (xy 370.982774 -273.326788) (xy 370.978679 -273.27606)
			(xy 370.670582 -273.27606) (xy 370.67007 -273.301506) (xy 370.661906 -273.35174) (xy 370.64579 -273.400014)
			(xy 370.622139 -273.445077) (xy 370.591566 -273.485763) (xy 370.554862 -273.521018) (xy 370.512978 -273.549928)
			(xy 370.466999 -273.571745) (xy 370.418115 -273.585905) (xy 370.367594 -273.592039) (xy 370.316742 -273.58999)
			(xy 370.266878 -273.57981) (xy 370.219292 -273.561763) (xy 370.175218 -273.536317) (xy 370.135796 -273.50413)
			(xy 370.102048 -273.466036) (xy 370.074847 -273.423022) (xy 370.054899 -273.376202) (xy 370.04272 -273.326788)
			(xy 370.038625 -273.27606) (xy 369.720114 -273.27606) (xy 369.719619 -273.300667) (xy 369.711724 -273.349244)
			(xy 369.69614 -273.395925) (xy 369.673269 -273.439502) (xy 369.643704 -273.478846) (xy 369.608211 -273.512938)
			(xy 369.567708 -273.540894) (xy 369.523246 -273.561992) (xy 369.475975 -273.575684) (xy 369.42712 -273.581616)
			(xy 369.377945 -273.579635) (xy 369.329726 -273.569791) (xy 369.28371 -273.552339) (xy 369.241089 -273.527732)
			(xy 369.202968 -273.496607) (xy 369.170333 -273.45977) (xy 369.14403 -273.418174) (xy 369.124739 -273.372898)
			(xy 369.112962 -273.325114) (xy 369.109002 -273.27606) (xy 368.790474 -273.27606) (xy 368.789962 -273.301506)
			(xy 368.781798 -273.35174) (xy 368.765682 -273.400014) (xy 368.742031 -273.445077) (xy 368.711458 -273.485763)
			(xy 368.674754 -273.521018) (xy 368.63287 -273.549928) (xy 368.586891 -273.571745) (xy 368.538007 -273.585905)
			(xy 368.487486 -273.592039) (xy 368.436634 -273.58999) (xy 368.38677 -273.57981) (xy 368.339184 -273.561763)
			(xy 368.29511 -273.536317) (xy 368.255688 -273.50413) (xy 368.22194 -273.466036) (xy 368.194739 -273.423022)
			(xy 368.174791 -273.376202) (xy 368.162612 -273.326788) (xy 368.158517 -273.27606) (xy 367.85042 -273.27606)
			(xy 367.849908 -273.301506) (xy 367.841744 -273.35174) (xy 367.825628 -273.400014) (xy 367.801977 -273.445077)
			(xy 367.771404 -273.485763) (xy 367.7347 -273.521018) (xy 367.692816 -273.549928) (xy 367.646837 -273.571745)
			(xy 367.597953 -273.585905) (xy 367.547432 -273.592039) (xy 367.49658 -273.58999) (xy 367.446716 -273.57981)
			(xy 367.39913 -273.561763) (xy 367.355056 -273.536317) (xy 367.315634 -273.50413) (xy 367.281886 -273.466036)
			(xy 367.254685 -273.423022) (xy 367.234737 -273.376202) (xy 367.222558 -273.326788) (xy 367.218463 -273.27606)
			(xy 366.900206 -273.27606) (xy 366.899711 -273.300667) (xy 366.891816 -273.349244) (xy 366.876232 -273.395925)
			(xy 366.853361 -273.439502) (xy 366.823796 -273.478846) (xy 366.788303 -273.512938) (xy 366.7478 -273.540894)
			(xy 366.703338 -273.561992) (xy 366.656067 -273.575684) (xy 366.607212 -273.581616) (xy 366.558037 -273.579635)
			(xy 366.509818 -273.569791) (xy 366.463802 -273.552339) (xy 366.421181 -273.527732) (xy 366.38306 -273.496607)
			(xy 366.350425 -273.45977) (xy 366.324122 -273.418174) (xy 366.304831 -273.372898) (xy 366.293054 -273.325114)
			(xy 366.289094 -273.27606) (xy 365.970566 -273.27606) (xy 365.970054 -273.301506) (xy 365.96189 -273.35174)
			(xy 365.945774 -273.400014) (xy 365.922123 -273.445077) (xy 365.89155 -273.485763) (xy 365.854846 -273.521018)
			(xy 365.812962 -273.549928) (xy 365.766983 -273.571745) (xy 365.718099 -273.585905) (xy 365.667578 -273.592039)
			(xy 365.616726 -273.58999) (xy 365.566862 -273.57981) (xy 365.519276 -273.561763) (xy 365.475202 -273.536317)
			(xy 365.43578 -273.50413) (xy 365.402032 -273.466036) (xy 365.374831 -273.423022) (xy 365.354883 -273.376202)
			(xy 365.342704 -273.326788) (xy 365.338609 -273.27606) (xy 365.030512 -273.27606) (xy 365.03 -273.301506)
			(xy 365.021836 -273.35174) (xy 365.00572 -273.400014) (xy 364.982069 -273.445077) (xy 364.951496 -273.485763)
			(xy 364.914792 -273.521018) (xy 364.872908 -273.549928) (xy 364.826929 -273.571745) (xy 364.778045 -273.585905)
			(xy 364.727524 -273.592039) (xy 364.676672 -273.58999) (xy 364.626808 -273.57981) (xy 364.579222 -273.561763)
			(xy 364.535148 -273.536317) (xy 364.495726 -273.50413) (xy 364.461978 -273.466036) (xy 364.434777 -273.423022)
			(xy 364.414829 -273.376202) (xy 364.40265 -273.326788) (xy 364.398555 -273.27606) (xy 364.080044 -273.27606)
			(xy 364.079549 -273.300667) (xy 364.071654 -273.349244) (xy 364.05607 -273.395925) (xy 364.033199 -273.439502)
			(xy 364.003634 -273.478846) (xy 363.968141 -273.512938) (xy 363.927638 -273.540894) (xy 363.883176 -273.561992)
			(xy 363.835905 -273.575684) (xy 363.78705 -273.581616) (xy 363.737875 -273.579635) (xy 363.689656 -273.569791)
			(xy 363.64364 -273.552339) (xy 363.601019 -273.527732) (xy 363.562898 -273.496607) (xy 363.530263 -273.45977)
			(xy 363.50396 -273.418174) (xy 363.484669 -273.372898) (xy 363.472892 -273.325114) (xy 363.468932 -273.27606)
			(xy 363.13999 -273.27606) (xy 363.139495 -273.300667) (xy 363.1316 -273.349244) (xy 363.116016 -273.395925)
			(xy 363.093145 -273.439502) (xy 363.06358 -273.478846) (xy 363.028087 -273.512938) (xy 362.987584 -273.540894)
			(xy 362.943122 -273.561992) (xy 362.895851 -273.575684) (xy 362.846996 -273.581616) (xy 362.797821 -273.579635)
			(xy 362.749602 -273.569791) (xy 362.703586 -273.552339) (xy 362.660965 -273.527732) (xy 362.622844 -273.496607)
			(xy 362.590209 -273.45977) (xy 362.563906 -273.418174) (xy 362.544615 -273.372898) (xy 362.532838 -273.325114)
			(xy 362.528878 -273.27606) (xy 362.20019 -273.27606) (xy 362.199695 -273.300667) (xy 362.1918 -273.349244)
			(xy 362.176216 -273.395925) (xy 362.153345 -273.439502) (xy 362.12378 -273.478846) (xy 362.088287 -273.512938)
			(xy 362.047784 -273.540894) (xy 362.003322 -273.561992) (xy 361.956051 -273.575684) (xy 361.907196 -273.581616)
			(xy 361.858021 -273.579635) (xy 361.809802 -273.569791) (xy 361.763786 -273.552339) (xy 361.721165 -273.527732)
			(xy 361.683044 -273.496607) (xy 361.650409 -273.45977) (xy 361.624106 -273.418174) (xy 361.604815 -273.372898)
			(xy 361.593038 -273.325114) (xy 361.589078 -273.27606) (xy 360.962488 -273.27606) (xy 360.990186 -274.086066)
			(xy 361.118924 -274.086066) (xy 361.122884 -274.037012) (xy 361.134661 -273.989228) (xy 361.153952 -273.943952)
			(xy 361.180255 -273.902356) (xy 361.21289 -273.865519) (xy 361.251011 -273.834394) (xy 361.293632 -273.809787)
			(xy 361.339648 -273.792335) (xy 361.387867 -273.782491) (xy 361.437042 -273.78051) (xy 361.485897 -273.786442)
			(xy 361.533168 -273.800134) (xy 361.57763 -273.821232) (xy 361.618133 -273.849188) (xy 361.653626 -273.88328)
			(xy 361.683191 -273.922624) (xy 361.706062 -273.966201) (xy 361.721646 -274.012882) (xy 361.729541 -274.061459)
			(xy 361.730036 -274.086066) (xy 362.048547 -274.086066) (xy 362.052642 -274.035338) (xy 362.064821 -273.985924)
			(xy 362.084769 -273.939104) (xy 362.11197 -273.89609) (xy 362.145718 -273.857996) (xy 362.18514 -273.825809)
			(xy 362.229214 -273.800363) (xy 362.2768 -273.782316) (xy 362.326664 -273.772136) (xy 362.377516 -273.770087)
			(xy 362.428037 -273.776221) (xy 362.476921 -273.790381) (xy 362.5229 -273.812198) (xy 362.564784 -273.841108)
			(xy 362.601488 -273.876363) (xy 362.632061 -273.917049) (xy 362.655712 -273.962112) (xy 362.671828 -274.010386)
			(xy 362.679992 -274.06062) (xy 362.680504 -274.086066) (xy 362.988601 -274.086066) (xy 362.992696 -274.035338)
			(xy 363.004875 -273.985924) (xy 363.024823 -273.939104) (xy 363.052024 -273.89609) (xy 363.085772 -273.857996)
			(xy 363.125194 -273.825809) (xy 363.169268 -273.800363) (xy 363.216854 -273.782316) (xy 363.266718 -273.772136)
			(xy 363.31757 -273.770087) (xy 363.368091 -273.776221) (xy 363.416975 -273.790381) (xy 363.462954 -273.812198)
			(xy 363.504838 -273.841108) (xy 363.541542 -273.876363) (xy 363.572115 -273.917049) (xy 363.595766 -273.962112)
			(xy 363.611882 -274.010386) (xy 363.620046 -274.06062) (xy 363.620558 -274.086066) (xy 363.939086 -274.086066)
			(xy 363.943046 -274.037012) (xy 363.954823 -273.989228) (xy 363.974114 -273.943952) (xy 364.000417 -273.902356)
			(xy 364.033052 -273.865519) (xy 364.071173 -273.834394) (xy 364.113794 -273.809787) (xy 364.15981 -273.792335)
			(xy 364.208029 -273.782491) (xy 364.257204 -273.78051) (xy 364.306059 -273.786442) (xy 364.35333 -273.800134)
			(xy 364.397792 -273.821232) (xy 364.438295 -273.849188) (xy 364.473788 -273.88328) (xy 364.503353 -273.922624)
			(xy 364.526224 -273.966201) (xy 364.541808 -274.012882) (xy 364.549703 -274.061459) (xy 364.550198 -274.086066)
			(xy 364.878886 -274.086066) (xy 364.882846 -274.037012) (xy 364.894623 -273.989228) (xy 364.913914 -273.943952)
			(xy 364.940217 -273.902356) (xy 364.972852 -273.865519) (xy 365.010973 -273.834394) (xy 365.053594 -273.809787)
			(xy 365.09961 -273.792335) (xy 365.147829 -273.782491) (xy 365.197004 -273.78051) (xy 365.245859 -273.786442)
			(xy 365.29313 -273.800134) (xy 365.337592 -273.821232) (xy 365.378095 -273.849188) (xy 365.413588 -273.88328)
			(xy 365.443153 -273.922624) (xy 365.466024 -273.966201) (xy 365.481608 -274.012882) (xy 365.489503 -274.061459)
			(xy 365.489998 -274.086066) (xy 365.81894 -274.086066) (xy 365.8229 -274.037012) (xy 365.834677 -273.989228)
			(xy 365.853968 -273.943952) (xy 365.880271 -273.902356) (xy 365.912906 -273.865519) (xy 365.951027 -273.834394)
			(xy 365.993648 -273.809787) (xy 366.039664 -273.792335) (xy 366.087883 -273.782491) (xy 366.137058 -273.78051)
			(xy 366.185913 -273.786442) (xy 366.233184 -273.800134) (xy 366.277646 -273.821232) (xy 366.318149 -273.849188)
			(xy 366.353642 -273.88328) (xy 366.383207 -273.922624) (xy 366.406078 -273.966201) (xy 366.421662 -274.012882)
			(xy 366.429557 -274.061459) (xy 366.430052 -274.086066) (xy 366.758994 -274.086066) (xy 366.762954 -274.037012)
			(xy 366.774731 -273.989228) (xy 366.794022 -273.943952) (xy 366.820325 -273.902356) (xy 366.85296 -273.865519)
			(xy 366.891081 -273.834394) (xy 366.933702 -273.809787) (xy 366.979718 -273.792335) (xy 367.027937 -273.782491)
			(xy 367.077112 -273.78051) (xy 367.125967 -273.786442) (xy 367.173238 -273.800134) (xy 367.2177 -273.821232)
			(xy 367.258203 -273.849188) (xy 367.293696 -273.88328) (xy 367.323261 -273.922624) (xy 367.346132 -273.966201)
			(xy 367.361716 -274.012882) (xy 367.369611 -274.061459) (xy 367.370106 -274.086066) (xy 367.699048 -274.086066)
			(xy 367.703008 -274.037012) (xy 367.714785 -273.989228) (xy 367.734076 -273.943952) (xy 367.760379 -273.902356)
			(xy 367.793014 -273.865519) (xy 367.831135 -273.834394) (xy 367.873756 -273.809787) (xy 367.919772 -273.792335)
			(xy 367.967991 -273.782491) (xy 368.017166 -273.78051) (xy 368.066021 -273.786442) (xy 368.113292 -273.800134)
			(xy 368.157754 -273.821232) (xy 368.198257 -273.849188) (xy 368.23375 -273.88328) (xy 368.263315 -273.922624)
			(xy 368.286186 -273.966201) (xy 368.30177 -274.012882) (xy 368.309665 -274.061459) (xy 368.31016 -274.086066)
			(xy 368.639102 -274.086066) (xy 368.643062 -274.037012) (xy 368.654839 -273.989228) (xy 368.67413 -273.943952)
			(xy 368.700433 -273.902356) (xy 368.733068 -273.865519) (xy 368.771189 -273.834394) (xy 368.81381 -273.809787)
			(xy 368.859826 -273.792335) (xy 368.908045 -273.782491) (xy 368.95722 -273.78051) (xy 369.006075 -273.786442)
			(xy 369.053346 -273.800134) (xy 369.097808 -273.821232) (xy 369.138311 -273.849188) (xy 369.173804 -273.88328)
			(xy 369.203369 -273.922624) (xy 369.22624 -273.966201) (xy 369.241824 -274.012882) (xy 369.249719 -274.061459)
			(xy 369.250214 -274.086066) (xy 369.578902 -274.086066) (xy 369.582862 -274.037012) (xy 369.594639 -273.989228)
			(xy 369.61393 -273.943952) (xy 369.640233 -273.902356) (xy 369.672868 -273.865519) (xy 369.710989 -273.834394)
			(xy 369.75361 -273.809787) (xy 369.799626 -273.792335) (xy 369.847845 -273.782491) (xy 369.89702 -273.78051)
			(xy 369.945875 -273.786442) (xy 369.993146 -273.800134) (xy 370.037608 -273.821232) (xy 370.078111 -273.849188)
			(xy 370.113604 -273.88328) (xy 370.143169 -273.922624) (xy 370.16604 -273.966201) (xy 370.181624 -274.012882)
			(xy 370.189519 -274.061459) (xy 370.190014 -274.086066) (xy 370.518956 -274.086066) (xy 370.522916 -274.037012)
			(xy 370.534693 -273.989228) (xy 370.553984 -273.943952) (xy 370.580287 -273.902356) (xy 370.612922 -273.865519)
			(xy 370.651043 -273.834394) (xy 370.693664 -273.809787) (xy 370.73968 -273.792335) (xy 370.787899 -273.782491)
			(xy 370.837074 -273.78051) (xy 370.885929 -273.786442) (xy 370.9332 -273.800134) (xy 370.977662 -273.821232)
			(xy 371.018165 -273.849188) (xy 371.053658 -273.88328) (xy 371.083223 -273.922624) (xy 371.106094 -273.966201)
			(xy 371.121678 -274.012882) (xy 371.129573 -274.061459) (xy 371.130068 -274.086066) (xy 371.45901 -274.086066)
			(xy 371.46297 -274.037012) (xy 371.474747 -273.989228) (xy 371.494038 -273.943952) (xy 371.520341 -273.902356)
			(xy 371.552976 -273.865519) (xy 371.591097 -273.834394) (xy 371.633718 -273.809787) (xy 371.679734 -273.792335)
			(xy 371.727953 -273.782491) (xy 371.777128 -273.78051) (xy 371.825983 -273.786442) (xy 371.873254 -273.800134)
			(xy 371.917716 -273.821232) (xy 371.958219 -273.849188) (xy 371.993712 -273.88328) (xy 372.023277 -273.922624)
			(xy 372.046148 -273.966201) (xy 372.061732 -274.012882) (xy 372.069627 -274.061459) (xy 372.070122 -274.086066)
			(xy 372.399064 -274.086066) (xy 372.403024 -274.037012) (xy 372.414801 -273.989228) (xy 372.434092 -273.943952)
			(xy 372.460395 -273.902356) (xy 372.49303 -273.865519) (xy 372.531151 -273.834394) (xy 372.573772 -273.809787)
			(xy 372.619788 -273.792335) (xy 372.668007 -273.782491) (xy 372.717182 -273.78051) (xy 372.766037 -273.786442)
			(xy 372.813308 -273.800134) (xy 372.85777 -273.821232) (xy 372.898273 -273.849188) (xy 372.933766 -273.88328)
			(xy 372.963331 -273.922624) (xy 372.986202 -273.966201) (xy 373.001786 -274.012882) (xy 373.009681 -274.061459)
			(xy 373.010176 -274.086066) (xy 373.339118 -274.086066) (xy 373.343078 -274.037012) (xy 373.354855 -273.989228)
			(xy 373.374146 -273.943952) (xy 373.400449 -273.902356) (xy 373.433084 -273.865519) (xy 373.471205 -273.834394)
			(xy 373.513826 -273.809787) (xy 373.559842 -273.792335) (xy 373.608061 -273.782491) (xy 373.657236 -273.78051)
			(xy 373.706091 -273.786442) (xy 373.753362 -273.800134) (xy 373.797824 -273.821232) (xy 373.838327 -273.849188)
			(xy 373.87382 -273.88328) (xy 373.903385 -273.922624) (xy 373.926256 -273.966201) (xy 373.94184 -274.012882)
			(xy 373.949735 -274.061459) (xy 373.95023 -274.086066) (xy 373.949735 -274.110673) (xy 373.94184 -274.15925)
			(xy 373.926256 -274.205931) (xy 373.903385 -274.249508) (xy 373.87382 -274.288852) (xy 373.838327 -274.322944)
			(xy 373.797824 -274.3509) (xy 373.753362 -274.371998) (xy 373.706091 -274.38569) (xy 373.657236 -274.391622)
			(xy 373.608061 -274.389641) (xy 373.559842 -274.379797) (xy 373.513826 -274.362345) (xy 373.471205 -274.337738)
			(xy 373.433084 -274.306613) (xy 373.400449 -274.269776) (xy 373.374146 -274.22818) (xy 373.354855 -274.182904)
			(xy 373.343078 -274.13512) (xy 373.339118 -274.086066) (xy 373.010176 -274.086066) (xy 373.009681 -274.110673)
			(xy 373.001786 -274.15925) (xy 372.986202 -274.205931) (xy 372.963331 -274.249508) (xy 372.933766 -274.288852)
			(xy 372.898273 -274.322944) (xy 372.85777 -274.3509) (xy 372.813308 -274.371998) (xy 372.766037 -274.38569)
			(xy 372.717182 -274.391622) (xy 372.668007 -274.389641) (xy 372.619788 -274.379797) (xy 372.573772 -274.362345)
			(xy 372.531151 -274.337738) (xy 372.49303 -274.306613) (xy 372.460395 -274.269776) (xy 372.434092 -274.22818)
			(xy 372.414801 -274.182904) (xy 372.403024 -274.13512) (xy 372.399064 -274.086066) (xy 372.070122 -274.086066)
			(xy 372.069627 -274.110673) (xy 372.061732 -274.15925) (xy 372.046148 -274.205931) (xy 372.023277 -274.249508)
			(xy 371.993712 -274.288852) (xy 371.958219 -274.322944) (xy 371.917716 -274.3509) (xy 371.873254 -274.371998)
			(xy 371.825983 -274.38569) (xy 371.777128 -274.391622) (xy 371.727953 -274.389641) (xy 371.679734 -274.379797)
			(xy 371.633718 -274.362345) (xy 371.591097 -274.337738) (xy 371.552976 -274.306613) (xy 371.520341 -274.269776)
			(xy 371.494038 -274.22818) (xy 371.474747 -274.182904) (xy 371.46297 -274.13512) (xy 371.45901 -274.086066)
			(xy 371.130068 -274.086066) (xy 371.129573 -274.110673) (xy 371.121678 -274.15925) (xy 371.106094 -274.205931)
			(xy 371.083223 -274.249508) (xy 371.053658 -274.288852) (xy 371.018165 -274.322944) (xy 370.977662 -274.3509)
			(xy 370.9332 -274.371998) (xy 370.885929 -274.38569) (xy 370.837074 -274.391622) (xy 370.787899 -274.389641)
			(xy 370.73968 -274.379797) (xy 370.693664 -274.362345) (xy 370.651043 -274.337738) (xy 370.612922 -274.306613)
			(xy 370.580287 -274.269776) (xy 370.553984 -274.22818) (xy 370.534693 -274.182904) (xy 370.522916 -274.13512)
			(xy 370.518956 -274.086066) (xy 370.190014 -274.086066) (xy 370.189519 -274.110673) (xy 370.181624 -274.15925)
			(xy 370.16604 -274.205931) (xy 370.143169 -274.249508) (xy 370.113604 -274.288852) (xy 370.078111 -274.322944)
			(xy 370.037608 -274.3509) (xy 369.993146 -274.371998) (xy 369.945875 -274.38569) (xy 369.89702 -274.391622)
			(xy 369.847845 -274.389641) (xy 369.799626 -274.379797) (xy 369.75361 -274.362345) (xy 369.710989 -274.337738)
			(xy 369.672868 -274.306613) (xy 369.640233 -274.269776) (xy 369.61393 -274.22818) (xy 369.594639 -274.182904)
			(xy 369.582862 -274.13512) (xy 369.578902 -274.086066) (xy 369.250214 -274.086066) (xy 369.249719 -274.110673)
			(xy 369.241824 -274.15925) (xy 369.22624 -274.205931) (xy 369.203369 -274.249508) (xy 369.173804 -274.288852)
			(xy 369.138311 -274.322944) (xy 369.097808 -274.3509) (xy 369.053346 -274.371998) (xy 369.006075 -274.38569)
			(xy 368.95722 -274.391622) (xy 368.908045 -274.389641) (xy 368.859826 -274.379797) (xy 368.81381 -274.362345)
			(xy 368.771189 -274.337738) (xy 368.733068 -274.306613) (xy 368.700433 -274.269776) (xy 368.67413 -274.22818)
			(xy 368.654839 -274.182904) (xy 368.643062 -274.13512) (xy 368.639102 -274.086066) (xy 368.31016 -274.086066)
			(xy 368.309665 -274.110673) (xy 368.30177 -274.15925) (xy 368.286186 -274.205931) (xy 368.263315 -274.249508)
			(xy 368.23375 -274.288852) (xy 368.198257 -274.322944) (xy 368.157754 -274.3509) (xy 368.113292 -274.371998)
			(xy 368.066021 -274.38569) (xy 368.017166 -274.391622) (xy 367.967991 -274.389641) (xy 367.919772 -274.379797)
			(xy 367.873756 -274.362345) (xy 367.831135 -274.337738) (xy 367.793014 -274.306613) (xy 367.760379 -274.269776)
			(xy 367.734076 -274.22818) (xy 367.714785 -274.182904) (xy 367.703008 -274.13512) (xy 367.699048 -274.086066)
			(xy 367.370106 -274.086066) (xy 367.369611 -274.110673) (xy 367.361716 -274.15925) (xy 367.346132 -274.205931)
			(xy 367.323261 -274.249508) (xy 367.293696 -274.288852) (xy 367.258203 -274.322944) (xy 367.2177 -274.3509)
			(xy 367.173238 -274.371998) (xy 367.125967 -274.38569) (xy 367.077112 -274.391622) (xy 367.027937 -274.389641)
			(xy 366.979718 -274.379797) (xy 366.933702 -274.362345) (xy 366.891081 -274.337738) (xy 366.85296 -274.306613)
			(xy 366.820325 -274.269776) (xy 366.794022 -274.22818) (xy 366.774731 -274.182904) (xy 366.762954 -274.13512)
			(xy 366.758994 -274.086066) (xy 366.430052 -274.086066) (xy 366.429557 -274.110673) (xy 366.421662 -274.15925)
			(xy 366.406078 -274.205931) (xy 366.383207 -274.249508) (xy 366.353642 -274.288852) (xy 366.318149 -274.322944)
			(xy 366.277646 -274.3509) (xy 366.233184 -274.371998) (xy 366.185913 -274.38569) (xy 366.137058 -274.391622)
			(xy 366.087883 -274.389641) (xy 366.039664 -274.379797) (xy 365.993648 -274.362345) (xy 365.951027 -274.337738)
			(xy 365.912906 -274.306613) (xy 365.880271 -274.269776) (xy 365.853968 -274.22818) (xy 365.834677 -274.182904)
			(xy 365.8229 -274.13512) (xy 365.81894 -274.086066) (xy 365.489998 -274.086066) (xy 365.489503 -274.110673)
			(xy 365.481608 -274.15925) (xy 365.466024 -274.205931) (xy 365.443153 -274.249508) (xy 365.413588 -274.288852)
			(xy 365.378095 -274.322944) (xy 365.337592 -274.3509) (xy 365.29313 -274.371998) (xy 365.245859 -274.38569)
			(xy 365.197004 -274.391622) (xy 365.147829 -274.389641) (xy 365.09961 -274.379797) (xy 365.053594 -274.362345)
			(xy 365.010973 -274.337738) (xy 364.972852 -274.306613) (xy 364.940217 -274.269776) (xy 364.913914 -274.22818)
			(xy 364.894623 -274.182904) (xy 364.882846 -274.13512) (xy 364.878886 -274.086066) (xy 364.550198 -274.086066)
			(xy 364.549703 -274.110673) (xy 364.541808 -274.15925) (xy 364.526224 -274.205931) (xy 364.503353 -274.249508)
			(xy 364.473788 -274.288852) (xy 364.438295 -274.322944) (xy 364.397792 -274.3509) (xy 364.35333 -274.371998)
			(xy 364.306059 -274.38569) (xy 364.257204 -274.391622) (xy 364.208029 -274.389641) (xy 364.15981 -274.379797)
			(xy 364.113794 -274.362345) (xy 364.071173 -274.337738) (xy 364.033052 -274.306613) (xy 364.000417 -274.269776)
			(xy 363.974114 -274.22818) (xy 363.954823 -274.182904) (xy 363.943046 -274.13512) (xy 363.939086 -274.086066)
			(xy 363.620558 -274.086066) (xy 363.620046 -274.111512) (xy 363.611882 -274.161746) (xy 363.595766 -274.21002)
			(xy 363.572115 -274.255083) (xy 363.541542 -274.295769) (xy 363.504838 -274.331024) (xy 363.462954 -274.359934)
			(xy 363.416975 -274.381751) (xy 363.368091 -274.395911) (xy 363.31757 -274.402045) (xy 363.266718 -274.399996)
			(xy 363.216854 -274.389816) (xy 363.169268 -274.371769) (xy 363.125194 -274.346323) (xy 363.085772 -274.314136)
			(xy 363.052024 -274.276042) (xy 363.024823 -274.233028) (xy 363.004875 -274.186208) (xy 362.992696 -274.136794)
			(xy 362.988601 -274.086066) (xy 362.680504 -274.086066) (xy 362.679992 -274.111512) (xy 362.671828 -274.161746)
			(xy 362.655712 -274.21002) (xy 362.632061 -274.255083) (xy 362.601488 -274.295769) (xy 362.564784 -274.331024)
			(xy 362.5229 -274.359934) (xy 362.476921 -274.381751) (xy 362.428037 -274.395911) (xy 362.377516 -274.402045)
			(xy 362.326664 -274.399996) (xy 362.2768 -274.389816) (xy 362.229214 -274.371769) (xy 362.18514 -274.346323)
			(xy 362.145718 -274.314136) (xy 362.11197 -274.276042) (xy 362.084769 -274.233028) (xy 362.064821 -274.186208)
			(xy 362.052642 -274.136794) (xy 362.048547 -274.086066) (xy 361.730036 -274.086066) (xy 361.729541 -274.110673)
			(xy 361.721646 -274.15925) (xy 361.706062 -274.205931) (xy 361.683191 -274.249508) (xy 361.653626 -274.288852)
			(xy 361.618133 -274.322944) (xy 361.57763 -274.3509) (xy 361.533168 -274.371998) (xy 361.485897 -274.38569)
			(xy 361.437042 -274.391622) (xy 361.387867 -274.389641) (xy 361.339648 -274.379797) (xy 361.293632 -274.362345)
			(xy 361.251011 -274.337738) (xy 361.21289 -274.306613) (xy 361.180255 -274.269776) (xy 361.153952 -274.22818)
			(xy 361.134661 -274.182904) (xy 361.122884 -274.13512) (xy 361.118924 -274.086066) (xy 360.990186 -274.086066)
			(xy 361.017884 -274.896072) (xy 363.468932 -274.896072) (xy 363.472892 -274.847018) (xy 363.484669 -274.799234)
			(xy 363.50396 -274.753958) (xy 363.530263 -274.712362) (xy 363.562898 -274.675525) (xy 363.601019 -274.6444)
			(xy 363.64364 -274.619793) (xy 363.689656 -274.602341) (xy 363.737875 -274.592497) (xy 363.78705 -274.590516)
			(xy 363.835905 -274.596448) (xy 363.883176 -274.61014) (xy 363.927638 -274.631238) (xy 363.968141 -274.659194)
			(xy 364.003634 -274.693286) (xy 364.033199 -274.73263) (xy 364.05607 -274.776207) (xy 364.071654 -274.822888)
			(xy 364.079549 -274.871465) (xy 364.080044 -274.896072) (xy 364.398555 -274.896072) (xy 364.40265 -274.845344)
			(xy 364.414829 -274.79593) (xy 364.434777 -274.74911) (xy 364.461978 -274.706096) (xy 364.495726 -274.668002)
			(xy 364.535148 -274.635815) (xy 364.579222 -274.610369) (xy 364.626808 -274.592322) (xy 364.676672 -274.582142)
			(xy 364.727524 -274.580093) (xy 364.778045 -274.586227) (xy 364.826929 -274.600387) (xy 364.872908 -274.622204)
			(xy 364.914792 -274.651114) (xy 364.951496 -274.686369) (xy 364.982069 -274.727055) (xy 365.00572 -274.772118)
			(xy 365.021836 -274.820392) (xy 365.03 -274.870626) (xy 365.030512 -274.896072) (xy 365.338609 -274.896072)
			(xy 365.342704 -274.845344) (xy 365.354883 -274.79593) (xy 365.374831 -274.74911) (xy 365.402032 -274.706096)
			(xy 365.43578 -274.668002) (xy 365.475202 -274.635815) (xy 365.519276 -274.610369) (xy 365.566862 -274.592322)
			(xy 365.616726 -274.582142) (xy 365.667578 -274.580093) (xy 365.718099 -274.586227) (xy 365.766983 -274.600387)
			(xy 365.812962 -274.622204) (xy 365.854846 -274.651114) (xy 365.89155 -274.686369) (xy 365.922123 -274.727055)
			(xy 365.945774 -274.772118) (xy 365.96189 -274.820392) (xy 365.970054 -274.870626) (xy 365.970566 -274.896072)
			(xy 366.289094 -274.896072) (xy 366.293054 -274.847018) (xy 366.304831 -274.799234) (xy 366.324122 -274.753958)
			(xy 366.350425 -274.712362) (xy 366.38306 -274.675525) (xy 366.421181 -274.6444) (xy 366.463802 -274.619793)
			(xy 366.509818 -274.602341) (xy 366.558037 -274.592497) (xy 366.607212 -274.590516) (xy 366.656067 -274.596448)
			(xy 366.703338 -274.61014) (xy 366.7478 -274.631238) (xy 366.788303 -274.659194) (xy 366.823796 -274.693286)
			(xy 366.853361 -274.73263) (xy 366.876232 -274.776207) (xy 366.891816 -274.822888) (xy 366.899711 -274.871465)
			(xy 366.900206 -274.896072) (xy 367.218463 -274.896072) (xy 367.222558 -274.845344) (xy 367.234737 -274.79593)
			(xy 367.254685 -274.74911) (xy 367.281886 -274.706096) (xy 367.315634 -274.668002) (xy 367.355056 -274.635815)
			(xy 367.39913 -274.610369) (xy 367.446716 -274.592322) (xy 367.49658 -274.582142) (xy 367.547432 -274.580093)
			(xy 367.597953 -274.586227) (xy 367.646837 -274.600387) (xy 367.692816 -274.622204) (xy 367.7347 -274.651114)
			(xy 367.771404 -274.686369) (xy 367.801977 -274.727055) (xy 367.825628 -274.772118) (xy 367.841744 -274.820392)
			(xy 367.849908 -274.870626) (xy 367.85042 -274.896072) (xy 368.158517 -274.896072) (xy 368.162612 -274.845344)
			(xy 368.174791 -274.79593) (xy 368.194739 -274.74911) (xy 368.22194 -274.706096) (xy 368.255688 -274.668002)
			(xy 368.29511 -274.635815) (xy 368.339184 -274.610369) (xy 368.38677 -274.592322) (xy 368.436634 -274.582142)
			(xy 368.487486 -274.580093) (xy 368.538007 -274.586227) (xy 368.586891 -274.600387) (xy 368.63287 -274.622204)
			(xy 368.674754 -274.651114) (xy 368.711458 -274.686369) (xy 368.742031 -274.727055) (xy 368.765682 -274.772118)
			(xy 368.781798 -274.820392) (xy 368.789962 -274.870626) (xy 368.790474 -274.896072) (xy 369.109002 -274.896072)
			(xy 369.112962 -274.847018) (xy 369.124739 -274.799234) (xy 369.14403 -274.753958) (xy 369.170333 -274.712362)
			(xy 369.202968 -274.675525) (xy 369.241089 -274.6444) (xy 369.28371 -274.619793) (xy 369.329726 -274.602341)
			(xy 369.377945 -274.592497) (xy 369.42712 -274.590516) (xy 369.475975 -274.596448) (xy 369.523246 -274.61014)
			(xy 369.567708 -274.631238) (xy 369.608211 -274.659194) (xy 369.643704 -274.693286) (xy 369.673269 -274.73263)
			(xy 369.69614 -274.776207) (xy 369.711724 -274.822888) (xy 369.719619 -274.871465) (xy 369.720114 -274.896072)
			(xy 370.038625 -274.896072) (xy 370.04272 -274.845344) (xy 370.054899 -274.79593) (xy 370.074847 -274.74911)
			(xy 370.102048 -274.706096) (xy 370.135796 -274.668002) (xy 370.175218 -274.635815) (xy 370.219292 -274.610369)
			(xy 370.266878 -274.592322) (xy 370.316742 -274.582142) (xy 370.367594 -274.580093) (xy 370.418115 -274.586227)
			(xy 370.466999 -274.600387) (xy 370.512978 -274.622204) (xy 370.554862 -274.651114) (xy 370.591566 -274.686369)
			(xy 370.622139 -274.727055) (xy 370.64579 -274.772118) (xy 370.661906 -274.820392) (xy 370.67007 -274.870626)
			(xy 370.670582 -274.896072) (xy 370.978679 -274.896072) (xy 370.982774 -274.845344) (xy 370.994953 -274.79593)
			(xy 371.014901 -274.74911) (xy 371.042102 -274.706096) (xy 371.07585 -274.668002) (xy 371.115272 -274.635815)
			(xy 371.159346 -274.610369) (xy 371.206932 -274.592322) (xy 371.256796 -274.582142) (xy 371.307648 -274.580093)
			(xy 371.358169 -274.586227) (xy 371.407053 -274.600387) (xy 371.453032 -274.622204) (xy 371.494916 -274.651114)
			(xy 371.53162 -274.686369) (xy 371.562193 -274.727055) (xy 371.585844 -274.772118) (xy 371.60196 -274.820392)
			(xy 371.610124 -274.870626) (xy 371.610636 -274.896072) (xy 371.92891 -274.896072) (xy 371.93287 -274.847018)
			(xy 371.944647 -274.799234) (xy 371.963938 -274.753958) (xy 371.990241 -274.712362) (xy 372.022876 -274.675525)
			(xy 372.060997 -274.6444) (xy 372.103618 -274.619793) (xy 372.149634 -274.602341) (xy 372.197853 -274.592497)
			(xy 372.247028 -274.590516) (xy 372.295883 -274.596448) (xy 372.343154 -274.61014) (xy 372.387616 -274.631238)
			(xy 372.428119 -274.659194) (xy 372.463612 -274.693286) (xy 372.493177 -274.73263) (xy 372.516048 -274.776207)
			(xy 372.531632 -274.822888) (xy 372.539527 -274.871465) (xy 372.540022 -274.896072) (xy 372.858533 -274.896072)
			(xy 372.862628 -274.845344) (xy 372.874807 -274.79593) (xy 372.894755 -274.74911) (xy 372.921956 -274.706096)
			(xy 372.955704 -274.668002) (xy 372.995126 -274.635815) (xy 373.0392 -274.610369) (xy 373.086786 -274.592322)
			(xy 373.13665 -274.582142) (xy 373.187502 -274.580093) (xy 373.238023 -274.586227) (xy 373.286907 -274.600387)
			(xy 373.332886 -274.622204) (xy 373.37477 -274.651114) (xy 373.411474 -274.686369) (xy 373.442047 -274.727055)
			(xy 373.465698 -274.772118) (xy 373.481814 -274.820392) (xy 373.489978 -274.870626) (xy 373.49049 -274.896072)
			(xy 373.798587 -274.896072) (xy 373.802682 -274.845344) (xy 373.814861 -274.79593) (xy 373.834809 -274.74911)
			(xy 373.86201 -274.706096) (xy 373.895758 -274.668002) (xy 373.93518 -274.635815) (xy 373.979254 -274.610369)
			(xy 374.02684 -274.592322) (xy 374.076704 -274.582142) (xy 374.127556 -274.580093) (xy 374.178077 -274.586227)
			(xy 374.226961 -274.600387) (xy 374.27294 -274.622204) (xy 374.314824 -274.651114) (xy 374.351528 -274.686369)
			(xy 374.382101 -274.727055) (xy 374.405752 -274.772118) (xy 374.421868 -274.820392) (xy 374.430032 -274.870626)
			(xy 374.430544 -274.896072) (xy 374.430032 -274.921518) (xy 374.421868 -274.971752) (xy 374.405752 -275.020026)
			(xy 374.382101 -275.065089) (xy 374.351528 -275.105775) (xy 374.314824 -275.14103) (xy 374.27294 -275.16994)
			(xy 374.226961 -275.191757) (xy 374.178077 -275.205917) (xy 374.127556 -275.212051) (xy 374.076704 -275.210002)
			(xy 374.02684 -275.199822) (xy 373.979254 -275.181775) (xy 373.93518 -275.156329) (xy 373.895758 -275.124142)
			(xy 373.86201 -275.086048) (xy 373.834809 -275.043034) (xy 373.814861 -274.996214) (xy 373.802682 -274.9468)
			(xy 373.798587 -274.896072) (xy 373.49049 -274.896072) (xy 373.489978 -274.921518) (xy 373.481814 -274.971752)
			(xy 373.465698 -275.020026) (xy 373.442047 -275.065089) (xy 373.411474 -275.105775) (xy 373.37477 -275.14103)
			(xy 373.332886 -275.16994) (xy 373.286907 -275.191757) (xy 373.238023 -275.205917) (xy 373.187502 -275.212051)
			(xy 373.13665 -275.210002) (xy 373.086786 -275.199822) (xy 373.0392 -275.181775) (xy 372.995126 -275.156329)
			(xy 372.955704 -275.124142) (xy 372.921956 -275.086048) (xy 372.894755 -275.043034) (xy 372.874807 -274.996214)
			(xy 372.862628 -274.9468) (xy 372.858533 -274.896072) (xy 372.540022 -274.896072) (xy 372.539527 -274.920679)
			(xy 372.531632 -274.969256) (xy 372.516048 -275.015937) (xy 372.493177 -275.059514) (xy 372.463612 -275.098858)
			(xy 372.428119 -275.13295) (xy 372.387616 -275.160906) (xy 372.343154 -275.182004) (xy 372.295883 -275.195696)
			(xy 372.247028 -275.201628) (xy 372.197853 -275.199647) (xy 372.149634 -275.189803) (xy 372.103618 -275.172351)
			(xy 372.060997 -275.147744) (xy 372.022876 -275.116619) (xy 371.990241 -275.079782) (xy 371.963938 -275.038186)
			(xy 371.944647 -274.99291) (xy 371.93287 -274.945126) (xy 371.92891 -274.896072) (xy 371.610636 -274.896072)
			(xy 371.610124 -274.921518) (xy 371.60196 -274.971752) (xy 371.585844 -275.020026) (xy 371.562193 -275.065089)
			(xy 371.53162 -275.105775) (xy 371.494916 -275.14103) (xy 371.453032 -275.16994) (xy 371.407053 -275.191757)
			(xy 371.358169 -275.205917) (xy 371.307648 -275.212051) (xy 371.256796 -275.210002) (xy 371.206932 -275.199822)
			(xy 371.159346 -275.181775) (xy 371.115272 -275.156329) (xy 371.07585 -275.124142) (xy 371.042102 -275.086048)
			(xy 371.014901 -275.043034) (xy 370.994953 -274.996214) (xy 370.982774 -274.9468) (xy 370.978679 -274.896072)
			(xy 370.670582 -274.896072) (xy 370.67007 -274.921518) (xy 370.661906 -274.971752) (xy 370.64579 -275.020026)
			(xy 370.622139 -275.065089) (xy 370.591566 -275.105775) (xy 370.554862 -275.14103) (xy 370.512978 -275.16994)
			(xy 370.466999 -275.191757) (xy 370.418115 -275.205917) (xy 370.367594 -275.212051) (xy 370.316742 -275.210002)
			(xy 370.266878 -275.199822) (xy 370.219292 -275.181775) (xy 370.175218 -275.156329) (xy 370.135796 -275.124142)
			(xy 370.102048 -275.086048) (xy 370.074847 -275.043034) (xy 370.054899 -274.996214) (xy 370.04272 -274.9468)
			(xy 370.038625 -274.896072) (xy 369.720114 -274.896072) (xy 369.719619 -274.920679) (xy 369.711724 -274.969256)
			(xy 369.69614 -275.015937) (xy 369.673269 -275.059514) (xy 369.643704 -275.098858) (xy 369.608211 -275.13295)
			(xy 369.567708 -275.160906) (xy 369.523246 -275.182004) (xy 369.475975 -275.195696) (xy 369.42712 -275.201628)
			(xy 369.377945 -275.199647) (xy 369.329726 -275.189803) (xy 369.28371 -275.172351) (xy 369.241089 -275.147744)
			(xy 369.202968 -275.116619) (xy 369.170333 -275.079782) (xy 369.14403 -275.038186) (xy 369.124739 -274.99291)
			(xy 369.112962 -274.945126) (xy 369.109002 -274.896072) (xy 368.790474 -274.896072) (xy 368.789962 -274.921518)
			(xy 368.781798 -274.971752) (xy 368.765682 -275.020026) (xy 368.742031 -275.065089) (xy 368.711458 -275.105775)
			(xy 368.674754 -275.14103) (xy 368.63287 -275.16994) (xy 368.586891 -275.191757) (xy 368.538007 -275.205917)
			(xy 368.487486 -275.212051) (xy 368.436634 -275.210002) (xy 368.38677 -275.199822) (xy 368.339184 -275.181775)
			(xy 368.29511 -275.156329) (xy 368.255688 -275.124142) (xy 368.22194 -275.086048) (xy 368.194739 -275.043034)
			(xy 368.174791 -274.996214) (xy 368.162612 -274.9468) (xy 368.158517 -274.896072) (xy 367.85042 -274.896072)
			(xy 367.849908 -274.921518) (xy 367.841744 -274.971752) (xy 367.825628 -275.020026) (xy 367.801977 -275.065089)
			(xy 367.771404 -275.105775) (xy 367.7347 -275.14103) (xy 367.692816 -275.16994) (xy 367.646837 -275.191757)
			(xy 367.597953 -275.205917) (xy 367.547432 -275.212051) (xy 367.49658 -275.210002) (xy 367.446716 -275.199822)
			(xy 367.39913 -275.181775) (xy 367.355056 -275.156329) (xy 367.315634 -275.124142) (xy 367.281886 -275.086048)
			(xy 367.254685 -275.043034) (xy 367.234737 -274.996214) (xy 367.222558 -274.9468) (xy 367.218463 -274.896072)
			(xy 366.900206 -274.896072) (xy 366.899711 -274.920679) (xy 366.891816 -274.969256) (xy 366.876232 -275.015937)
			(xy 366.853361 -275.059514) (xy 366.823796 -275.098858) (xy 366.788303 -275.13295) (xy 366.7478 -275.160906)
			(xy 366.703338 -275.182004) (xy 366.656067 -275.195696) (xy 366.607212 -275.201628) (xy 366.558037 -275.199647)
			(xy 366.509818 -275.189803) (xy 366.463802 -275.172351) (xy 366.421181 -275.147744) (xy 366.38306 -275.116619)
			(xy 366.350425 -275.079782) (xy 366.324122 -275.038186) (xy 366.304831 -274.99291) (xy 366.293054 -274.945126)
			(xy 366.289094 -274.896072) (xy 365.970566 -274.896072) (xy 365.970054 -274.921518) (xy 365.96189 -274.971752)
			(xy 365.945774 -275.020026) (xy 365.922123 -275.065089) (xy 365.89155 -275.105775) (xy 365.854846 -275.14103)
			(xy 365.812962 -275.16994) (xy 365.766983 -275.191757) (xy 365.718099 -275.205917) (xy 365.667578 -275.212051)
			(xy 365.616726 -275.210002) (xy 365.566862 -275.199822) (xy 365.519276 -275.181775) (xy 365.475202 -275.156329)
			(xy 365.43578 -275.124142) (xy 365.402032 -275.086048) (xy 365.374831 -275.043034) (xy 365.354883 -274.996214)
			(xy 365.342704 -274.9468) (xy 365.338609 -274.896072) (xy 365.030512 -274.896072) (xy 365.03 -274.921518)
			(xy 365.021836 -274.971752) (xy 365.00572 -275.020026) (xy 364.982069 -275.065089) (xy 364.951496 -275.105775)
			(xy 364.914792 -275.14103) (xy 364.872908 -275.16994) (xy 364.826929 -275.191757) (xy 364.778045 -275.205917)
			(xy 364.727524 -275.212051) (xy 364.676672 -275.210002) (xy 364.626808 -275.199822) (xy 364.579222 -275.181775)
			(xy 364.535148 -275.156329) (xy 364.495726 -275.124142) (xy 364.461978 -275.086048) (xy 364.434777 -275.043034)
			(xy 364.414829 -274.996214) (xy 364.40265 -274.9468) (xy 364.398555 -274.896072) (xy 364.080044 -274.896072)
			(xy 364.079549 -274.920679) (xy 364.071654 -274.969256) (xy 364.05607 -275.015937) (xy 364.033199 -275.059514)
			(xy 364.003634 -275.098858) (xy 363.968141 -275.13295) (xy 363.927638 -275.160906) (xy 363.883176 -275.182004)
			(xy 363.835905 -275.195696) (xy 363.78705 -275.201628) (xy 363.737875 -275.199647) (xy 363.689656 -275.189803)
			(xy 363.64364 -275.172351) (xy 363.601019 -275.147744) (xy 363.562898 -275.116619) (xy 363.530263 -275.079782)
			(xy 363.50396 -275.038186) (xy 363.484669 -274.99291) (xy 363.472892 -274.945126) (xy 363.468932 -274.896072)
			(xy 361.017884 -274.896072) (xy 361.035854 -275.421598) (xy 361.036654 -275.431414) (xy 361.04469 -275.449375)
			(xy 361.058888 -275.462997) (xy 361.067858 -275.467064) (xy 361.142026 -275.496528) (xy 361.142534 -275.496528)
			(xy 361.154726 -275.501354) (xy 361.164046 -275.504523) (xy 361.183711 -275.504256) (xy 361.20181 -275.496562)
			(xy 361.209082 -275.489924) (xy 361.226373 -275.473339) (xy 361.265164 -275.445222) (xy 361.307873 -275.423511)
			(xy 361.353449 -275.408741) (xy 361.400773 -275.401275) (xy 361.424728 -275.40077) (xy 361.449984 -275.401294)
			(xy 361.499805 -275.409612) (xy 361.547579 -275.426016) (xy 361.592001 -275.45006) (xy 361.631859 -275.481087)
			(xy 361.666068 -275.518251) (xy 361.693694 -275.560538) (xy 361.713983 -275.606795) (xy 361.726382 -275.655761)
			(xy 361.730551 -275.706078) (xy 362.048547 -275.706078) (xy 362.052642 -275.65535) (xy 362.064821 -275.605936)
			(xy 362.084769 -275.559116) (xy 362.11197 -275.516102) (xy 362.145718 -275.478008) (xy 362.18514 -275.445821)
			(xy 362.229214 -275.420375) (xy 362.2768 -275.402328) (xy 362.326664 -275.392148) (xy 362.377516 -275.390099)
			(xy 362.428037 -275.396233) (xy 362.476921 -275.410393) (xy 362.5229 -275.43221) (xy 362.564784 -275.46112)
			(xy 362.601488 -275.496375) (xy 362.632061 -275.537061) (xy 362.655712 -275.582124) (xy 362.671828 -275.630398)
			(xy 362.679992 -275.680632) (xy 362.680504 -275.706078) (xy 362.988601 -275.706078) (xy 362.992696 -275.65535)
			(xy 363.004875 -275.605936) (xy 363.024823 -275.559116) (xy 363.052024 -275.516102) (xy 363.085772 -275.478008)
			(xy 363.125194 -275.445821) (xy 363.169268 -275.420375) (xy 363.216854 -275.402328) (xy 363.266718 -275.392148)
			(xy 363.31757 -275.390099) (xy 363.368091 -275.396233) (xy 363.416975 -275.410393) (xy 363.462954 -275.43221)
			(xy 363.504838 -275.46112) (xy 363.541542 -275.496375) (xy 363.572115 -275.537061) (xy 363.595766 -275.582124)
			(xy 363.611882 -275.630398) (xy 363.620046 -275.680632) (xy 363.620558 -275.706078) (xy 363.939086 -275.706078)
			(xy 363.943046 -275.657024) (xy 363.954823 -275.60924) (xy 363.974114 -275.563964) (xy 364.000417 -275.522368)
			(xy 364.033052 -275.485531) (xy 364.071173 -275.454406) (xy 364.113794 -275.429799) (xy 364.15981 -275.412347)
			(xy 364.208029 -275.402503) (xy 364.257204 -275.400522) (xy 364.306059 -275.406454) (xy 364.35333 -275.420146)
			(xy 364.397792 -275.441244) (xy 364.438295 -275.4692) (xy 364.473788 -275.503292) (xy 364.503353 -275.542636)
			(xy 364.526224 -275.586213) (xy 364.541808 -275.632894) (xy 364.549703 -275.681471) (xy 364.550198 -275.706078)
			(xy 366.758994 -275.706078) (xy 366.762954 -275.657024) (xy 366.774731 -275.60924) (xy 366.794022 -275.563964)
			(xy 366.820325 -275.522368) (xy 366.85296 -275.485531) (xy 366.891081 -275.454406) (xy 366.933702 -275.429799)
			(xy 366.979718 -275.412347) (xy 367.027937 -275.402503) (xy 367.077112 -275.400522) (xy 367.125967 -275.406454)
			(xy 367.173238 -275.420146) (xy 367.2177 -275.441244) (xy 367.258203 -275.4692) (xy 367.293696 -275.503292)
			(xy 367.323261 -275.542636) (xy 367.346132 -275.586213) (xy 367.361716 -275.632894) (xy 367.369611 -275.681471)
			(xy 367.370106 -275.706078) (xy 369.578902 -275.706078) (xy 369.582862 -275.657024) (xy 369.594639 -275.60924)
			(xy 369.61393 -275.563964) (xy 369.640233 -275.522368) (xy 369.672868 -275.485531) (xy 369.710989 -275.454406)
			(xy 369.75361 -275.429799) (xy 369.799626 -275.412347) (xy 369.847845 -275.402503) (xy 369.89702 -275.400522)
			(xy 369.945875 -275.406454) (xy 369.993146 -275.420146) (xy 370.037608 -275.441244) (xy 370.078111 -275.4692)
			(xy 370.113604 -275.503292) (xy 370.143169 -275.542636) (xy 370.16604 -275.586213) (xy 370.181624 -275.632894)
			(xy 370.189519 -275.681471) (xy 370.190014 -275.706078) (xy 372.399064 -275.706078) (xy 372.403024 -275.657024)
			(xy 372.414801 -275.60924) (xy 372.434092 -275.563964) (xy 372.460395 -275.522368) (xy 372.49303 -275.485531)
			(xy 372.531151 -275.454406) (xy 372.573772 -275.429799) (xy 372.619788 -275.412347) (xy 372.668007 -275.402503)
			(xy 372.717182 -275.400522) (xy 372.766037 -275.406454) (xy 372.813308 -275.420146) (xy 372.85777 -275.441244)
			(xy 372.898273 -275.4692) (xy 372.933766 -275.503292) (xy 372.963331 -275.542636) (xy 372.986202 -275.586213)
			(xy 373.001786 -275.632894) (xy 373.009681 -275.681471) (xy 373.010176 -275.706078) (xy 373.009681 -275.730685)
			(xy 373.001786 -275.779262) (xy 372.986202 -275.825943) (xy 372.963331 -275.86952) (xy 372.933766 -275.908864)
			(xy 372.898273 -275.942956) (xy 372.85777 -275.970912) (xy 372.813308 -275.99201) (xy 372.766037 -276.005702)
			(xy 372.717182 -276.011634) (xy 372.668007 -276.009653) (xy 372.619788 -275.999809) (xy 372.573772 -275.982357)
			(xy 372.531151 -275.95775) (xy 372.49303 -275.926625) (xy 372.460395 -275.889788) (xy 372.434092 -275.848192)
			(xy 372.414801 -275.802916) (xy 372.403024 -275.755132) (xy 372.399064 -275.706078) (xy 370.190014 -275.706078)
			(xy 370.189519 -275.730685) (xy 370.181624 -275.779262) (xy 370.16604 -275.825943) (xy 370.143169 -275.86952)
			(xy 370.113604 -275.908864) (xy 370.078111 -275.942956) (xy 370.037608 -275.970912) (xy 369.993146 -275.99201)
			(xy 369.945875 -276.005702) (xy 369.89702 -276.011634) (xy 369.847845 -276.009653) (xy 369.799626 -275.999809)
			(xy 369.75361 -275.982357) (xy 369.710989 -275.95775) (xy 369.672868 -275.926625) (xy 369.640233 -275.889788)
			(xy 369.61393 -275.848192) (xy 369.594639 -275.802916) (xy 369.582862 -275.755132) (xy 369.578902 -275.706078)
			(xy 367.370106 -275.706078) (xy 367.369611 -275.730685) (xy 367.361716 -275.779262) (xy 367.346132 -275.825943)
			(xy 367.323261 -275.86952) (xy 367.293696 -275.908864) (xy 367.258203 -275.942956) (xy 367.2177 -275.970912)
			(xy 367.173238 -275.99201) (xy 367.125967 -276.005702) (xy 367.077112 -276.011634) (xy 367.027937 -276.009653)
			(xy 366.979718 -275.999809) (xy 366.933702 -275.982357) (xy 366.891081 -275.95775) (xy 366.85296 -275.926625)
			(xy 366.820325 -275.889788) (xy 366.794022 -275.848192) (xy 366.774731 -275.802916) (xy 366.762954 -275.755132)
			(xy 366.758994 -275.706078) (xy 364.550198 -275.706078) (xy 364.549703 -275.730685) (xy 364.541808 -275.779262)
			(xy 364.526224 -275.825943) (xy 364.503353 -275.86952) (xy 364.473788 -275.908864) (xy 364.438295 -275.942956)
			(xy 364.397792 -275.970912) (xy 364.35333 -275.99201) (xy 364.306059 -276.005702) (xy 364.257204 -276.011634)
			(xy 364.208029 -276.009653) (xy 364.15981 -275.999809) (xy 364.113794 -275.982357) (xy 364.071173 -275.95775)
			(xy 364.033052 -275.926625) (xy 364.000417 -275.889788) (xy 363.974114 -275.848192) (xy 363.954823 -275.802916)
			(xy 363.943046 -275.755132) (xy 363.939086 -275.706078) (xy 363.620558 -275.706078) (xy 363.620046 -275.731524)
			(xy 363.611882 -275.781758) (xy 363.595766 -275.830032) (xy 363.572115 -275.875095) (xy 363.541542 -275.915781)
			(xy 363.504838 -275.951036) (xy 363.462954 -275.979946) (xy 363.416975 -276.001763) (xy 363.368091 -276.015923)
			(xy 363.31757 -276.022057) (xy 363.266718 -276.020008) (xy 363.216854 -276.009828) (xy 363.169268 -275.991781)
			(xy 363.125194 -275.966335) (xy 363.085772 -275.934148) (xy 363.052024 -275.896054) (xy 363.024823 -275.85304)
			(xy 363.004875 -275.80622) (xy 362.992696 -275.756806) (xy 362.988601 -275.706078) (xy 362.680504 -275.706078)
			(xy 362.679992 -275.731524) (xy 362.671828 -275.781758) (xy 362.655712 -275.830032) (xy 362.632061 -275.875095)
			(xy 362.601488 -275.915781) (xy 362.564784 -275.951036) (xy 362.5229 -275.979946) (xy 362.476921 -276.001763)
			(xy 362.428037 -276.015923) (xy 362.377516 -276.022057) (xy 362.326664 -276.020008) (xy 362.2768 -276.009828)
			(xy 362.229214 -275.991781) (xy 362.18514 -275.966335) (xy 362.145718 -275.934148) (xy 362.11197 -275.896054)
			(xy 362.084769 -275.85304) (xy 362.064821 -275.80622) (xy 362.052642 -275.756806) (xy 362.048547 -275.706078)
			(xy 361.730551 -275.706078) (xy 361.730553 -275.7061) (xy 361.726382 -275.756439) (xy 361.713983 -275.805405)
			(xy 361.693694 -275.851662) (xy 361.666068 -275.893949) (xy 361.631859 -275.931113) (xy 361.592001 -275.96214)
			(xy 361.547579 -275.986184) (xy 361.499805 -276.002588) (xy 361.449984 -276.010906) (xy 361.424728 -276.011386)
			(xy 361.411965 -276.011246) (xy 361.386532 -276.009081) (xy 361.373928 -276.007068) (xy 361.373928 -276.007322)
			(xy 361.346465 -276.002035) (xy 361.293951 -275.982813) (xy 361.245814 -275.954352) (xy 361.224322 -275.936456)
			(xy 361.212638 -275.92655) (xy 361.18292 -275.922486) (xy 361.08513 -275.968968) (xy 361.076385 -275.973621)
			(xy 361.06304 -275.988234) (xy 361.056233 -276.006816) (xy 361.056174 -276.01672) (xy 361.073308 -276.516084)
			(xy 361.589078 -276.516084) (xy 361.593038 -276.46703) (xy 361.604815 -276.419246) (xy 361.624106 -276.37397)
			(xy 361.650409 -276.332374) (xy 361.683044 -276.295537) (xy 361.721165 -276.264412) (xy 361.763786 -276.239805)
			(xy 361.809802 -276.222353) (xy 361.858021 -276.212509) (xy 361.907196 -276.210528) (xy 361.956051 -276.21646)
			(xy 362.003322 -276.230152) (xy 362.047784 -276.25125) (xy 362.088287 -276.279206) (xy 362.12378 -276.313298)
			(xy 362.153345 -276.352642) (xy 362.176216 -276.396219) (xy 362.1918 -276.4429) (xy 362.199695 -276.491477)
			(xy 362.20019 -276.516084) (xy 362.528878 -276.516084) (xy 362.532838 -276.46703) (xy 362.544615 -276.419246)
			(xy 362.563906 -276.37397) (xy 362.590209 -276.332374) (xy 362.622844 -276.295537) (xy 362.660965 -276.264412)
			(xy 362.703586 -276.239805) (xy 362.749602 -276.222353) (xy 362.797821 -276.212509) (xy 362.846996 -276.210528)
			(xy 362.895851 -276.21646) (xy 362.943122 -276.230152) (xy 362.987584 -276.25125) (xy 363.028087 -276.279206)
			(xy 363.06358 -276.313298) (xy 363.093145 -276.352642) (xy 363.116016 -276.396219) (xy 363.1316 -276.4429)
			(xy 363.139495 -276.491477) (xy 363.13999 -276.516084) (xy 363.468932 -276.516084) (xy 363.472892 -276.46703)
			(xy 363.484669 -276.419246) (xy 363.50396 -276.37397) (xy 363.530263 -276.332374) (xy 363.562898 -276.295537)
			(xy 363.601019 -276.264412) (xy 363.64364 -276.239805) (xy 363.689656 -276.222353) (xy 363.737875 -276.212509)
			(xy 363.78705 -276.210528) (xy 363.835905 -276.21646) (xy 363.883176 -276.230152) (xy 363.927638 -276.25125)
			(xy 363.968141 -276.279206) (xy 364.003634 -276.313298) (xy 364.033199 -276.352642) (xy 364.05607 -276.396219)
			(xy 364.071654 -276.4429) (xy 364.079549 -276.491477) (xy 364.080044 -276.516084) (xy 364.398555 -276.516084)
			(xy 364.40265 -276.465356) (xy 364.414829 -276.415942) (xy 364.434777 -276.369122) (xy 364.461978 -276.326108)
			(xy 364.495726 -276.288014) (xy 364.535148 -276.255827) (xy 364.579222 -276.230381) (xy 364.626808 -276.212334)
			(xy 364.676672 -276.202154) (xy 364.727524 -276.200105) (xy 364.778045 -276.206239) (xy 364.826929 -276.220399)
			(xy 364.872908 -276.242216) (xy 364.914792 -276.271126) (xy 364.951496 -276.306381) (xy 364.982069 -276.347067)
			(xy 365.00572 -276.39213) (xy 365.021836 -276.440404) (xy 365.03 -276.490638) (xy 365.030512 -276.516084)
			(xy 365.338609 -276.516084) (xy 365.342704 -276.465356) (xy 365.354883 -276.415942) (xy 365.374831 -276.369122)
			(xy 365.402032 -276.326108) (xy 365.43578 -276.288014) (xy 365.475202 -276.255827) (xy 365.519276 -276.230381)
			(xy 365.566862 -276.212334) (xy 365.616726 -276.202154) (xy 365.667578 -276.200105) (xy 365.718099 -276.206239)
			(xy 365.766983 -276.220399) (xy 365.812962 -276.242216) (xy 365.854846 -276.271126) (xy 365.89155 -276.306381)
			(xy 365.922123 -276.347067) (xy 365.945774 -276.39213) (xy 365.96189 -276.440404) (xy 365.970054 -276.490638)
			(xy 365.970566 -276.516084) (xy 366.289094 -276.516084) (xy 366.293054 -276.46703) (xy 366.304831 -276.419246)
			(xy 366.324122 -276.37397) (xy 366.350425 -276.332374) (xy 366.38306 -276.295537) (xy 366.421181 -276.264412)
			(xy 366.463802 -276.239805) (xy 366.509818 -276.222353) (xy 366.558037 -276.212509) (xy 366.607212 -276.210528)
			(xy 366.656067 -276.21646) (xy 366.703338 -276.230152) (xy 366.7478 -276.25125) (xy 366.788303 -276.279206)
			(xy 366.823796 -276.313298) (xy 366.853361 -276.352642) (xy 366.876232 -276.396219) (xy 366.891816 -276.4429)
			(xy 366.899711 -276.491477) (xy 366.900206 -276.516084) (xy 367.218463 -276.516084) (xy 367.222558 -276.465356)
			(xy 367.234737 -276.415942) (xy 367.254685 -276.369122) (xy 367.281886 -276.326108) (xy 367.315634 -276.288014)
			(xy 367.355056 -276.255827) (xy 367.39913 -276.230381) (xy 367.446716 -276.212334) (xy 367.49658 -276.202154)
			(xy 367.547432 -276.200105) (xy 367.597953 -276.206239) (xy 367.646837 -276.220399) (xy 367.692816 -276.242216)
			(xy 367.7347 -276.271126) (xy 367.771404 -276.306381) (xy 367.801977 -276.347067) (xy 367.825628 -276.39213)
			(xy 367.841744 -276.440404) (xy 367.849908 -276.490638) (xy 367.85042 -276.516084) (xy 368.158517 -276.516084)
			(xy 368.162612 -276.465356) (xy 368.174791 -276.415942) (xy 368.194739 -276.369122) (xy 368.22194 -276.326108)
			(xy 368.255688 -276.288014) (xy 368.29511 -276.255827) (xy 368.339184 -276.230381) (xy 368.38677 -276.212334)
			(xy 368.436634 -276.202154) (xy 368.487486 -276.200105) (xy 368.538007 -276.206239) (xy 368.586891 -276.220399)
			(xy 368.63287 -276.242216) (xy 368.674754 -276.271126) (xy 368.711458 -276.306381) (xy 368.742031 -276.347067)
			(xy 368.765682 -276.39213) (xy 368.781798 -276.440404) (xy 368.789962 -276.490638) (xy 368.790474 -276.516084)
			(xy 369.109002 -276.516084) (xy 369.112962 -276.46703) (xy 369.124739 -276.419246) (xy 369.14403 -276.37397)
			(xy 369.170333 -276.332374) (xy 369.202968 -276.295537) (xy 369.241089 -276.264412) (xy 369.28371 -276.239805)
			(xy 369.329726 -276.222353) (xy 369.377945 -276.212509) (xy 369.42712 -276.210528) (xy 369.475975 -276.21646)
			(xy 369.523246 -276.230152) (xy 369.567708 -276.25125) (xy 369.608211 -276.279206) (xy 369.643704 -276.313298)
			(xy 369.673269 -276.352642) (xy 369.69614 -276.396219) (xy 369.711724 -276.4429) (xy 369.719619 -276.491477)
			(xy 369.720114 -276.516084) (xy 370.038625 -276.516084) (xy 370.04272 -276.465356) (xy 370.054899 -276.415942)
			(xy 370.074847 -276.369122) (xy 370.102048 -276.326108) (xy 370.135796 -276.288014) (xy 370.175218 -276.255827)
			(xy 370.219292 -276.230381) (xy 370.266878 -276.212334) (xy 370.316742 -276.202154) (xy 370.367594 -276.200105)
			(xy 370.418115 -276.206239) (xy 370.466999 -276.220399) (xy 370.512978 -276.242216) (xy 370.554862 -276.271126)
			(xy 370.591566 -276.306381) (xy 370.622139 -276.347067) (xy 370.64579 -276.39213) (xy 370.661906 -276.440404)
			(xy 370.67007 -276.490638) (xy 370.670582 -276.516084) (xy 370.978679 -276.516084) (xy 370.982774 -276.465356)
			(xy 370.994953 -276.415942) (xy 371.014901 -276.369122) (xy 371.042102 -276.326108) (xy 371.07585 -276.288014)
			(xy 371.115272 -276.255827) (xy 371.159346 -276.230381) (xy 371.206932 -276.212334) (xy 371.256796 -276.202154)
			(xy 371.307648 -276.200105) (xy 371.358169 -276.206239) (xy 371.407053 -276.220399) (xy 371.453032 -276.242216)
			(xy 371.494916 -276.271126) (xy 371.53162 -276.306381) (xy 371.562193 -276.347067) (xy 371.585844 -276.39213)
			(xy 371.60196 -276.440404) (xy 371.610124 -276.490638) (xy 371.610636 -276.516084) (xy 371.92891 -276.516084)
			(xy 371.93287 -276.46703) (xy 371.944647 -276.419246) (xy 371.963938 -276.37397) (xy 371.990241 -276.332374)
			(xy 372.022876 -276.295537) (xy 372.060997 -276.264412) (xy 372.103618 -276.239805) (xy 372.149634 -276.222353)
			(xy 372.197853 -276.212509) (xy 372.247028 -276.210528) (xy 372.295883 -276.21646) (xy 372.343154 -276.230152)
			(xy 372.387616 -276.25125) (xy 372.428119 -276.279206) (xy 372.463612 -276.313298) (xy 372.493177 -276.352642)
			(xy 372.516048 -276.396219) (xy 372.531632 -276.4429) (xy 372.539527 -276.491477) (xy 372.540022 -276.516084)
			(xy 372.858533 -276.516084) (xy 372.862628 -276.465356) (xy 372.874807 -276.415942) (xy 372.894755 -276.369122)
			(xy 372.921956 -276.326108) (xy 372.955704 -276.288014) (xy 372.995126 -276.255827) (xy 373.0392 -276.230381)
			(xy 373.086786 -276.212334) (xy 373.13665 -276.202154) (xy 373.187502 -276.200105) (xy 373.238023 -276.206239)
			(xy 373.286907 -276.220399) (xy 373.332886 -276.242216) (xy 373.37477 -276.271126) (xy 373.411474 -276.306381)
			(xy 373.442047 -276.347067) (xy 373.465698 -276.39213) (xy 373.481814 -276.440404) (xy 373.489978 -276.490638)
			(xy 373.49049 -276.516084) (xy 373.798587 -276.516084) (xy 373.802682 -276.465356) (xy 373.814861 -276.415942)
			(xy 373.834809 -276.369122) (xy 373.86201 -276.326108) (xy 373.895758 -276.288014) (xy 373.93518 -276.255827)
			(xy 373.979254 -276.230381) (xy 374.02684 -276.212334) (xy 374.076704 -276.202154) (xy 374.127556 -276.200105)
			(xy 374.178077 -276.206239) (xy 374.226961 -276.220399) (xy 374.27294 -276.242216) (xy 374.314824 -276.271126)
			(xy 374.351528 -276.306381) (xy 374.382101 -276.347067) (xy 374.405752 -276.39213) (xy 374.421868 -276.440404)
			(xy 374.430032 -276.490638) (xy 374.430544 -276.516084) (xy 374.430032 -276.54153) (xy 374.421868 -276.591764)
			(xy 374.405752 -276.640038) (xy 374.382101 -276.685101) (xy 374.351528 -276.725787) (xy 374.314824 -276.761042)
			(xy 374.27294 -276.789952) (xy 374.226961 -276.811769) (xy 374.178077 -276.825929) (xy 374.127556 -276.832063)
			(xy 374.076704 -276.830014) (xy 374.02684 -276.819834) (xy 373.979254 -276.801787) (xy 373.93518 -276.776341)
			(xy 373.895758 -276.744154) (xy 373.86201 -276.70606) (xy 373.834809 -276.663046) (xy 373.814861 -276.616226)
			(xy 373.802682 -276.566812) (xy 373.798587 -276.516084) (xy 373.49049 -276.516084) (xy 373.489978 -276.54153)
			(xy 373.481814 -276.591764) (xy 373.465698 -276.640038) (xy 373.442047 -276.685101) (xy 373.411474 -276.725787)
			(xy 373.37477 -276.761042) (xy 373.332886 -276.789952) (xy 373.286907 -276.811769) (xy 373.238023 -276.825929)
			(xy 373.187502 -276.832063) (xy 373.13665 -276.830014) (xy 373.086786 -276.819834) (xy 373.0392 -276.801787)
			(xy 372.995126 -276.776341) (xy 372.955704 -276.744154) (xy 372.921956 -276.70606) (xy 372.894755 -276.663046)
			(xy 372.874807 -276.616226) (xy 372.862628 -276.566812) (xy 372.858533 -276.516084) (xy 372.540022 -276.516084)
			(xy 372.539527 -276.540691) (xy 372.531632 -276.589268) (xy 372.516048 -276.635949) (xy 372.493177 -276.679526)
			(xy 372.463612 -276.71887) (xy 372.428119 -276.752962) (xy 372.387616 -276.780918) (xy 372.343154 -276.802016)
			(xy 372.295883 -276.815708) (xy 372.247028 -276.82164) (xy 372.197853 -276.819659) (xy 372.149634 -276.809815)
			(xy 372.103618 -276.792363) (xy 372.060997 -276.767756) (xy 372.022876 -276.736631) (xy 371.990241 -276.699794)
			(xy 371.963938 -276.658198) (xy 371.944647 -276.612922) (xy 371.93287 -276.565138) (xy 371.92891 -276.516084)
			(xy 371.610636 -276.516084) (xy 371.610124 -276.54153) (xy 371.60196 -276.591764) (xy 371.585844 -276.640038)
			(xy 371.562193 -276.685101) (xy 371.53162 -276.725787) (xy 371.494916 -276.761042) (xy 371.453032 -276.789952)
			(xy 371.407053 -276.811769) (xy 371.358169 -276.825929) (xy 371.307648 -276.832063) (xy 371.256796 -276.830014)
			(xy 371.206932 -276.819834) (xy 371.159346 -276.801787) (xy 371.115272 -276.776341) (xy 371.07585 -276.744154)
			(xy 371.042102 -276.70606) (xy 371.014901 -276.663046) (xy 370.994953 -276.616226) (xy 370.982774 -276.566812)
			(xy 370.978679 -276.516084) (xy 370.670582 -276.516084) (xy 370.67007 -276.54153) (xy 370.661906 -276.591764)
			(xy 370.64579 -276.640038) (xy 370.622139 -276.685101) (xy 370.591566 -276.725787) (xy 370.554862 -276.761042)
			(xy 370.512978 -276.789952) (xy 370.466999 -276.811769) (xy 370.418115 -276.825929) (xy 370.367594 -276.832063)
			(xy 370.316742 -276.830014) (xy 370.266878 -276.819834) (xy 370.219292 -276.801787) (xy 370.175218 -276.776341)
			(xy 370.135796 -276.744154) (xy 370.102048 -276.70606) (xy 370.074847 -276.663046) (xy 370.054899 -276.616226)
			(xy 370.04272 -276.566812) (xy 370.038625 -276.516084) (xy 369.720114 -276.516084) (xy 369.719619 -276.540691)
			(xy 369.711724 -276.589268) (xy 369.69614 -276.635949) (xy 369.673269 -276.679526) (xy 369.643704 -276.71887)
			(xy 369.608211 -276.752962) (xy 369.567708 -276.780918) (xy 369.523246 -276.802016) (xy 369.475975 -276.815708)
			(xy 369.42712 -276.82164) (xy 369.377945 -276.819659) (xy 369.329726 -276.809815) (xy 369.28371 -276.792363)
			(xy 369.241089 -276.767756) (xy 369.202968 -276.736631) (xy 369.170333 -276.699794) (xy 369.14403 -276.658198)
			(xy 369.124739 -276.612922) (xy 369.112962 -276.565138) (xy 369.109002 -276.516084) (xy 368.790474 -276.516084)
			(xy 368.789962 -276.54153) (xy 368.781798 -276.591764) (xy 368.765682 -276.640038) (xy 368.742031 -276.685101)
			(xy 368.711458 -276.725787) (xy 368.674754 -276.761042) (xy 368.63287 -276.789952) (xy 368.586891 -276.811769)
			(xy 368.538007 -276.825929) (xy 368.487486 -276.832063) (xy 368.436634 -276.830014) (xy 368.38677 -276.819834)
			(xy 368.339184 -276.801787) (xy 368.29511 -276.776341) (xy 368.255688 -276.744154) (xy 368.22194 -276.70606)
			(xy 368.194739 -276.663046) (xy 368.174791 -276.616226) (xy 368.162612 -276.566812) (xy 368.158517 -276.516084)
			(xy 367.85042 -276.516084) (xy 367.849908 -276.54153) (xy 367.841744 -276.591764) (xy 367.825628 -276.640038)
			(xy 367.801977 -276.685101) (xy 367.771404 -276.725787) (xy 367.7347 -276.761042) (xy 367.692816 -276.789952)
			(xy 367.646837 -276.811769) (xy 367.597953 -276.825929) (xy 367.547432 -276.832063) (xy 367.49658 -276.830014)
			(xy 367.446716 -276.819834) (xy 367.39913 -276.801787) (xy 367.355056 -276.776341) (xy 367.315634 -276.744154)
			(xy 367.281886 -276.70606) (xy 367.254685 -276.663046) (xy 367.234737 -276.616226) (xy 367.222558 -276.566812)
			(xy 367.218463 -276.516084) (xy 366.900206 -276.516084) (xy 366.899711 -276.540691) (xy 366.891816 -276.589268)
			(xy 366.876232 -276.635949) (xy 366.853361 -276.679526) (xy 366.823796 -276.71887) (xy 366.788303 -276.752962)
			(xy 366.7478 -276.780918) (xy 366.703338 -276.802016) (xy 366.656067 -276.815708) (xy 366.607212 -276.82164)
			(xy 366.558037 -276.819659) (xy 366.509818 -276.809815) (xy 366.463802 -276.792363) (xy 366.421181 -276.767756)
			(xy 366.38306 -276.736631) (xy 366.350425 -276.699794) (xy 366.324122 -276.658198) (xy 366.304831 -276.612922)
			(xy 366.293054 -276.565138) (xy 366.289094 -276.516084) (xy 365.970566 -276.516084) (xy 365.970054 -276.54153)
			(xy 365.96189 -276.591764) (xy 365.945774 -276.640038) (xy 365.922123 -276.685101) (xy 365.89155 -276.725787)
			(xy 365.854846 -276.761042) (xy 365.812962 -276.789952) (xy 365.766983 -276.811769) (xy 365.718099 -276.825929)
			(xy 365.667578 -276.832063) (xy 365.616726 -276.830014) (xy 365.566862 -276.819834) (xy 365.519276 -276.801787)
			(xy 365.475202 -276.776341) (xy 365.43578 -276.744154) (xy 365.402032 -276.70606) (xy 365.374831 -276.663046)
			(xy 365.354883 -276.616226) (xy 365.342704 -276.566812) (xy 365.338609 -276.516084) (xy 365.030512 -276.516084)
			(xy 365.03 -276.54153) (xy 365.021836 -276.591764) (xy 365.00572 -276.640038) (xy 364.982069 -276.685101)
			(xy 364.951496 -276.725787) (xy 364.914792 -276.761042) (xy 364.872908 -276.789952) (xy 364.826929 -276.811769)
			(xy 364.778045 -276.825929) (xy 364.727524 -276.832063) (xy 364.676672 -276.830014) (xy 364.626808 -276.819834)
			(xy 364.579222 -276.801787) (xy 364.535148 -276.776341) (xy 364.495726 -276.744154) (xy 364.461978 -276.70606)
			(xy 364.434777 -276.663046) (xy 364.414829 -276.616226) (xy 364.40265 -276.566812) (xy 364.398555 -276.516084)
			(xy 364.080044 -276.516084) (xy 364.079549 -276.540691) (xy 364.071654 -276.589268) (xy 364.05607 -276.635949)
			(xy 364.033199 -276.679526) (xy 364.003634 -276.71887) (xy 363.968141 -276.752962) (xy 363.927638 -276.780918)
			(xy 363.883176 -276.802016) (xy 363.835905 -276.815708) (xy 363.78705 -276.82164) (xy 363.737875 -276.819659)
			(xy 363.689656 -276.809815) (xy 363.64364 -276.792363) (xy 363.601019 -276.767756) (xy 363.562898 -276.736631)
			(xy 363.530263 -276.699794) (xy 363.50396 -276.658198) (xy 363.484669 -276.612922) (xy 363.472892 -276.565138)
			(xy 363.468932 -276.516084) (xy 363.13999 -276.516084) (xy 363.139495 -276.540691) (xy 363.1316 -276.589268)
			(xy 363.116016 -276.635949) (xy 363.093145 -276.679526) (xy 363.06358 -276.71887) (xy 363.028087 -276.752962)
			(xy 362.987584 -276.780918) (xy 362.943122 -276.802016) (xy 362.895851 -276.815708) (xy 362.846996 -276.82164)
			(xy 362.797821 -276.819659) (xy 362.749602 -276.809815) (xy 362.703586 -276.792363) (xy 362.660965 -276.767756)
			(xy 362.622844 -276.736631) (xy 362.590209 -276.699794) (xy 362.563906 -276.658198) (xy 362.544615 -276.612922)
			(xy 362.532838 -276.565138) (xy 362.528878 -276.516084) (xy 362.20019 -276.516084) (xy 362.199695 -276.540691)
			(xy 362.1918 -276.589268) (xy 362.176216 -276.635949) (xy 362.153345 -276.679526) (xy 362.12378 -276.71887)
			(xy 362.088287 -276.752962) (xy 362.047784 -276.780918) (xy 362.003322 -276.802016) (xy 361.956051 -276.815708)
			(xy 361.907196 -276.82164) (xy 361.858021 -276.819659) (xy 361.809802 -276.809815) (xy 361.763786 -276.792363)
			(xy 361.721165 -276.767756) (xy 361.683044 -276.736631) (xy 361.650409 -276.699794) (xy 361.624106 -276.658198)
			(xy 361.604815 -276.612922) (xy 361.593038 -276.565138) (xy 361.589078 -276.516084) (xy 361.073308 -276.516084)
			(xy 361.085892 -276.88286) (xy 361.089702 -276.996398) (xy 361.090391 -277.005479) (xy 361.097322 -277.022308)
			(xy 361.109677 -277.035672) (xy 361.117642 -277.040086) (xy 361.197144 -277.079964) (xy 361.203359 -277.082771)
			(xy 361.216747 -277.085346) (xy 361.22356 -277.085044) (xy 361.224068 -277.085044) (xy 361.230874 -277.084305)
			(xy 361.243748 -277.079664) (xy 361.249468 -277.0759) (xy 361.253278 -277.07336) (xy 361.261152 -277.06828)
			(xy 361.28582 -277.053416) (xy 361.339366 -277.032229) (xy 361.395935 -277.021457) (xy 361.424728 -277.020782)
			(xy 361.449983 -277.021306) (xy 361.499802 -277.029623) (xy 361.547574 -277.046027) (xy 361.591994 -277.07007)
			(xy 361.631851 -277.101095) (xy 361.666059 -277.138258) (xy 361.693683 -277.180544) (xy 361.713972 -277.226799)
			(xy 361.72637 -277.275763) (xy 361.73054 -277.32609) (xy 362.048547 -277.32609) (xy 362.052642 -277.275362)
			(xy 362.064821 -277.225948) (xy 362.084769 -277.179128) (xy 362.11197 -277.136114) (xy 362.145718 -277.09802)
			(xy 362.18514 -277.065833) (xy 362.229214 -277.040387) (xy 362.2768 -277.02234) (xy 362.326664 -277.01216)
			(xy 362.377516 -277.010111) (xy 362.428037 -277.016245) (xy 362.476921 -277.030405) (xy 362.5229 -277.052222)
			(xy 362.564784 -277.081132) (xy 362.601488 -277.116387) (xy 362.632061 -277.157073) (xy 362.655712 -277.202136)
			(xy 362.671828 -277.25041) (xy 362.679992 -277.300644) (xy 362.680504 -277.32609) (xy 362.988601 -277.32609)
			(xy 362.992696 -277.275362) (xy 363.004875 -277.225948) (xy 363.024823 -277.179128) (xy 363.052024 -277.136114)
			(xy 363.085772 -277.09802) (xy 363.125194 -277.065833) (xy 363.169268 -277.040387) (xy 363.216854 -277.02234)
			(xy 363.266718 -277.01216) (xy 363.31757 -277.010111) (xy 363.368091 -277.016245) (xy 363.416975 -277.030405)
			(xy 363.462954 -277.052222) (xy 363.504838 -277.081132) (xy 363.541542 -277.116387) (xy 363.572115 -277.157073)
			(xy 363.595766 -277.202136) (xy 363.611882 -277.25041) (xy 363.620046 -277.300644) (xy 363.620558 -277.32609)
			(xy 363.939086 -277.32609) (xy 363.943046 -277.277036) (xy 363.954823 -277.229252) (xy 363.974114 -277.183976)
			(xy 364.000417 -277.14238) (xy 364.033052 -277.105543) (xy 364.071173 -277.074418) (xy 364.113794 -277.049811)
			(xy 364.15981 -277.032359) (xy 364.208029 -277.022515) (xy 364.257204 -277.020534) (xy 364.306059 -277.026466)
			(xy 364.35333 -277.040158) (xy 364.397792 -277.061256) (xy 364.438295 -277.089212) (xy 364.473788 -277.123304)
			(xy 364.503353 -277.162648) (xy 364.526224 -277.206225) (xy 364.541808 -277.252906) (xy 364.549703 -277.301483)
			(xy 364.550198 -277.32609) (xy 364.878886 -277.32609) (xy 364.882846 -277.277036) (xy 364.894623 -277.229252)
			(xy 364.913914 -277.183976) (xy 364.940217 -277.14238) (xy 364.972852 -277.105543) (xy 365.010973 -277.074418)
			(xy 365.053594 -277.049811) (xy 365.09961 -277.032359) (xy 365.147829 -277.022515) (xy 365.197004 -277.020534)
			(xy 365.245859 -277.026466) (xy 365.29313 -277.040158) (xy 365.337592 -277.061256) (xy 365.378095 -277.089212)
			(xy 365.413588 -277.123304) (xy 365.443153 -277.162648) (xy 365.466024 -277.206225) (xy 365.481608 -277.252906)
			(xy 365.489503 -277.301483) (xy 365.489998 -277.32609) (xy 365.81894 -277.32609) (xy 365.8229 -277.277036)
			(xy 365.834677 -277.229252) (xy 365.853968 -277.183976) (xy 365.880271 -277.14238) (xy 365.912906 -277.105543)
			(xy 365.951027 -277.074418) (xy 365.993648 -277.049811) (xy 366.039664 -277.032359) (xy 366.087883 -277.022515)
			(xy 366.137058 -277.020534) (xy 366.185913 -277.026466) (xy 366.233184 -277.040158) (xy 366.277646 -277.061256)
			(xy 366.318149 -277.089212) (xy 366.353642 -277.123304) (xy 366.383207 -277.162648) (xy 366.406078 -277.206225)
			(xy 366.421662 -277.252906) (xy 366.429557 -277.301483) (xy 366.430052 -277.32609) (xy 366.758994 -277.32609)
			(xy 366.762954 -277.277036) (xy 366.774731 -277.229252) (xy 366.794022 -277.183976) (xy 366.820325 -277.14238)
			(xy 366.85296 -277.105543) (xy 366.891081 -277.074418) (xy 366.933702 -277.049811) (xy 366.979718 -277.032359)
			(xy 367.027937 -277.022515) (xy 367.077112 -277.020534) (xy 367.125967 -277.026466) (xy 367.173238 -277.040158)
			(xy 367.2177 -277.061256) (xy 367.258203 -277.089212) (xy 367.293696 -277.123304) (xy 367.323261 -277.162648)
			(xy 367.346132 -277.206225) (xy 367.361716 -277.252906) (xy 367.369611 -277.301483) (xy 367.370106 -277.32609)
			(xy 367.699048 -277.32609) (xy 367.703008 -277.277036) (xy 367.714785 -277.229252) (xy 367.734076 -277.183976)
			(xy 367.760379 -277.14238) (xy 367.793014 -277.105543) (xy 367.831135 -277.074418) (xy 367.873756 -277.049811)
			(xy 367.919772 -277.032359) (xy 367.967991 -277.022515) (xy 368.017166 -277.020534) (xy 368.066021 -277.026466)
			(xy 368.113292 -277.040158) (xy 368.157754 -277.061256) (xy 368.198257 -277.089212) (xy 368.23375 -277.123304)
			(xy 368.263315 -277.162648) (xy 368.286186 -277.206225) (xy 368.30177 -277.252906) (xy 368.309665 -277.301483)
			(xy 368.31016 -277.32609) (xy 368.639102 -277.32609) (xy 368.643062 -277.277036) (xy 368.654839 -277.229252)
			(xy 368.67413 -277.183976) (xy 368.700433 -277.14238) (xy 368.733068 -277.105543) (xy 368.771189 -277.074418)
			(xy 368.81381 -277.049811) (xy 368.859826 -277.032359) (xy 368.908045 -277.022515) (xy 368.95722 -277.020534)
			(xy 369.006075 -277.026466) (xy 369.053346 -277.040158) (xy 369.097808 -277.061256) (xy 369.138311 -277.089212)
			(xy 369.173804 -277.123304) (xy 369.203369 -277.162648) (xy 369.22624 -277.206225) (xy 369.241824 -277.252906)
			(xy 369.249719 -277.301483) (xy 369.250214 -277.32609) (xy 369.578902 -277.32609) (xy 369.582862 -277.277036)
			(xy 369.594639 -277.229252) (xy 369.61393 -277.183976) (xy 369.640233 -277.14238) (xy 369.672868 -277.105543)
			(xy 369.710989 -277.074418) (xy 369.75361 -277.049811) (xy 369.799626 -277.032359) (xy 369.847845 -277.022515)
			(xy 369.89702 -277.020534) (xy 369.945875 -277.026466) (xy 369.993146 -277.040158) (xy 370.037608 -277.061256)
			(xy 370.078111 -277.089212) (xy 370.113604 -277.123304) (xy 370.143169 -277.162648) (xy 370.16604 -277.206225)
			(xy 370.181624 -277.252906) (xy 370.189519 -277.301483) (xy 370.190014 -277.32609) (xy 370.518956 -277.32609)
			(xy 370.522916 -277.277036) (xy 370.534693 -277.229252) (xy 370.553984 -277.183976) (xy 370.580287 -277.14238)
			(xy 370.612922 -277.105543) (xy 370.651043 -277.074418) (xy 370.693664 -277.049811) (xy 370.73968 -277.032359)
			(xy 370.787899 -277.022515) (xy 370.837074 -277.020534) (xy 370.885929 -277.026466) (xy 370.9332 -277.040158)
			(xy 370.977662 -277.061256) (xy 371.018165 -277.089212) (xy 371.053658 -277.123304) (xy 371.083223 -277.162648)
			(xy 371.106094 -277.206225) (xy 371.121678 -277.252906) (xy 371.129573 -277.301483) (xy 371.130068 -277.32609)
			(xy 371.45901 -277.32609) (xy 371.46297 -277.277036) (xy 371.474747 -277.229252) (xy 371.494038 -277.183976)
			(xy 371.520341 -277.14238) (xy 371.552976 -277.105543) (xy 371.591097 -277.074418) (xy 371.633718 -277.049811)
			(xy 371.679734 -277.032359) (xy 371.727953 -277.022515) (xy 371.777128 -277.020534) (xy 371.825983 -277.026466)
			(xy 371.873254 -277.040158) (xy 371.917716 -277.061256) (xy 371.958219 -277.089212) (xy 371.993712 -277.123304)
			(xy 372.023277 -277.162648) (xy 372.046148 -277.206225) (xy 372.061732 -277.252906) (xy 372.069627 -277.301483)
			(xy 372.070122 -277.32609) (xy 372.399064 -277.32609) (xy 372.403024 -277.277036) (xy 372.414801 -277.229252)
			(xy 372.434092 -277.183976) (xy 372.460395 -277.14238) (xy 372.49303 -277.105543) (xy 372.531151 -277.074418)
			(xy 372.573772 -277.049811) (xy 372.619788 -277.032359) (xy 372.668007 -277.022515) (xy 372.717182 -277.020534)
			(xy 372.766037 -277.026466) (xy 372.813308 -277.040158) (xy 372.85777 -277.061256) (xy 372.898273 -277.089212)
			(xy 372.933766 -277.123304) (xy 372.963331 -277.162648) (xy 372.986202 -277.206225) (xy 373.001786 -277.252906)
			(xy 373.009681 -277.301483) (xy 373.010176 -277.32609) (xy 373.339118 -277.32609) (xy 373.343078 -277.277036)
			(xy 373.354855 -277.229252) (xy 373.374146 -277.183976) (xy 373.400449 -277.14238) (xy 373.433084 -277.105543)
			(xy 373.471205 -277.074418) (xy 373.513826 -277.049811) (xy 373.559842 -277.032359) (xy 373.608061 -277.022515)
			(xy 373.657236 -277.020534) (xy 373.706091 -277.026466) (xy 373.753362 -277.040158) (xy 373.797824 -277.061256)
			(xy 373.838327 -277.089212) (xy 373.87382 -277.123304) (xy 373.903385 -277.162648) (xy 373.926256 -277.206225)
			(xy 373.94184 -277.252906) (xy 373.949735 -277.301483) (xy 373.95023 -277.32609) (xy 373.949735 -277.350697)
			(xy 373.94184 -277.399274) (xy 373.926256 -277.445955) (xy 373.903385 -277.489532) (xy 373.87382 -277.528876)
			(xy 373.838327 -277.562968) (xy 373.797824 -277.590924) (xy 373.753362 -277.612022) (xy 373.706091 -277.625714)
			(xy 373.657236 -277.631646) (xy 373.608061 -277.629665) (xy 373.559842 -277.619821) (xy 373.513826 -277.602369)
			(xy 373.471205 -277.577762) (xy 373.433084 -277.546637) (xy 373.400449 -277.5098) (xy 373.374146 -277.468204)
			(xy 373.354855 -277.422928) (xy 373.343078 -277.375144) (xy 373.339118 -277.32609) (xy 373.010176 -277.32609)
			(xy 373.009681 -277.350697) (xy 373.001786 -277.399274) (xy 372.986202 -277.445955) (xy 372.963331 -277.489532)
			(xy 372.933766 -277.528876) (xy 372.898273 -277.562968) (xy 372.85777 -277.590924) (xy 372.813308 -277.612022)
			(xy 372.766037 -277.625714) (xy 372.717182 -277.631646) (xy 372.668007 -277.629665) (xy 372.619788 -277.619821)
			(xy 372.573772 -277.602369) (xy 372.531151 -277.577762) (xy 372.49303 -277.546637) (xy 372.460395 -277.5098)
			(xy 372.434092 -277.468204) (xy 372.414801 -277.422928) (xy 372.403024 -277.375144) (xy 372.399064 -277.32609)
			(xy 372.070122 -277.32609) (xy 372.069627 -277.350697) (xy 372.061732 -277.399274) (xy 372.046148 -277.445955)
			(xy 372.023277 -277.489532) (xy 371.993712 -277.528876) (xy 371.958219 -277.562968) (xy 371.917716 -277.590924)
			(xy 371.873254 -277.612022) (xy 371.825983 -277.625714) (xy 371.777128 -277.631646) (xy 371.727953 -277.629665)
			(xy 371.679734 -277.619821) (xy 371.633718 -277.602369) (xy 371.591097 -277.577762) (xy 371.552976 -277.546637)
			(xy 371.520341 -277.5098) (xy 371.494038 -277.468204) (xy 371.474747 -277.422928) (xy 371.46297 -277.375144)
			(xy 371.45901 -277.32609) (xy 371.130068 -277.32609) (xy 371.129573 -277.350697) (xy 371.121678 -277.399274)
			(xy 371.106094 -277.445955) (xy 371.083223 -277.489532) (xy 371.053658 -277.528876) (xy 371.018165 -277.562968)
			(xy 370.977662 -277.590924) (xy 370.9332 -277.612022) (xy 370.885929 -277.625714) (xy 370.837074 -277.631646)
			(xy 370.787899 -277.629665) (xy 370.73968 -277.619821) (xy 370.693664 -277.602369) (xy 370.651043 -277.577762)
			(xy 370.612922 -277.546637) (xy 370.580287 -277.5098) (xy 370.553984 -277.468204) (xy 370.534693 -277.422928)
			(xy 370.522916 -277.375144) (xy 370.518956 -277.32609) (xy 370.190014 -277.32609) (xy 370.189519 -277.350697)
			(xy 370.181624 -277.399274) (xy 370.16604 -277.445955) (xy 370.143169 -277.489532) (xy 370.113604 -277.528876)
			(xy 370.078111 -277.562968) (xy 370.037608 -277.590924) (xy 369.993146 -277.612022) (xy 369.945875 -277.625714)
			(xy 369.89702 -277.631646) (xy 369.847845 -277.629665) (xy 369.799626 -277.619821) (xy 369.75361 -277.602369)
			(xy 369.710989 -277.577762) (xy 369.672868 -277.546637) (xy 369.640233 -277.5098) (xy 369.61393 -277.468204)
			(xy 369.594639 -277.422928) (xy 369.582862 -277.375144) (xy 369.578902 -277.32609) (xy 369.250214 -277.32609)
			(xy 369.249719 -277.350697) (xy 369.241824 -277.399274) (xy 369.22624 -277.445955) (xy 369.203369 -277.489532)
			(xy 369.173804 -277.528876) (xy 369.138311 -277.562968) (xy 369.097808 -277.590924) (xy 369.053346 -277.612022)
			(xy 369.006075 -277.625714) (xy 368.95722 -277.631646) (xy 368.908045 -277.629665) (xy 368.859826 -277.619821)
			(xy 368.81381 -277.602369) (xy 368.771189 -277.577762) (xy 368.733068 -277.546637) (xy 368.700433 -277.5098)
			(xy 368.67413 -277.468204) (xy 368.654839 -277.422928) (xy 368.643062 -277.375144) (xy 368.639102 -277.32609)
			(xy 368.31016 -277.32609) (xy 368.309665 -277.350697) (xy 368.30177 -277.399274) (xy 368.286186 -277.445955)
			(xy 368.263315 -277.489532) (xy 368.23375 -277.528876) (xy 368.198257 -277.562968) (xy 368.157754 -277.590924)
			(xy 368.113292 -277.612022) (xy 368.066021 -277.625714) (xy 368.017166 -277.631646) (xy 367.967991 -277.629665)
			(xy 367.919772 -277.619821) (xy 367.873756 -277.602369) (xy 367.831135 -277.577762) (xy 367.793014 -277.546637)
			(xy 367.760379 -277.5098) (xy 367.734076 -277.468204) (xy 367.714785 -277.422928) (xy 367.703008 -277.375144)
			(xy 367.699048 -277.32609) (xy 367.370106 -277.32609) (xy 367.369611 -277.350697) (xy 367.361716 -277.399274)
			(xy 367.346132 -277.445955) (xy 367.323261 -277.489532) (xy 367.293696 -277.528876) (xy 367.258203 -277.562968)
			(xy 367.2177 -277.590924) (xy 367.173238 -277.612022) (xy 367.125967 -277.625714) (xy 367.077112 -277.631646)
			(xy 367.027937 -277.629665) (xy 366.979718 -277.619821) (xy 366.933702 -277.602369) (xy 366.891081 -277.577762)
			(xy 366.85296 -277.546637) (xy 366.820325 -277.5098) (xy 366.794022 -277.468204) (xy 366.774731 -277.422928)
			(xy 366.762954 -277.375144) (xy 366.758994 -277.32609) (xy 366.430052 -277.32609) (xy 366.429557 -277.350697)
			(xy 366.421662 -277.399274) (xy 366.406078 -277.445955) (xy 366.383207 -277.489532) (xy 366.353642 -277.528876)
			(xy 366.318149 -277.562968) (xy 366.277646 -277.590924) (xy 366.233184 -277.612022) (xy 366.185913 -277.625714)
			(xy 366.137058 -277.631646) (xy 366.087883 -277.629665) (xy 366.039664 -277.619821) (xy 365.993648 -277.602369)
			(xy 365.951027 -277.577762) (xy 365.912906 -277.546637) (xy 365.880271 -277.5098) (xy 365.853968 -277.468204)
			(xy 365.834677 -277.422928) (xy 365.8229 -277.375144) (xy 365.81894 -277.32609) (xy 365.489998 -277.32609)
			(xy 365.489503 -277.350697) (xy 365.481608 -277.399274) (xy 365.466024 -277.445955) (xy 365.443153 -277.489532)
			(xy 365.413588 -277.528876) (xy 365.378095 -277.562968) (xy 365.337592 -277.590924) (xy 365.29313 -277.612022)
			(xy 365.245859 -277.625714) (xy 365.197004 -277.631646) (xy 365.147829 -277.629665) (xy 365.09961 -277.619821)
			(xy 365.053594 -277.602369) (xy 365.010973 -277.577762) (xy 364.972852 -277.546637) (xy 364.940217 -277.5098)
			(xy 364.913914 -277.468204) (xy 364.894623 -277.422928) (xy 364.882846 -277.375144) (xy 364.878886 -277.32609)
			(xy 364.550198 -277.32609) (xy 364.549703 -277.350697) (xy 364.541808 -277.399274) (xy 364.526224 -277.445955)
			(xy 364.503353 -277.489532) (xy 364.473788 -277.528876) (xy 364.438295 -277.562968) (xy 364.397792 -277.590924)
			(xy 364.35333 -277.612022) (xy 364.306059 -277.625714) (xy 364.257204 -277.631646) (xy 364.208029 -277.629665)
			(xy 364.15981 -277.619821) (xy 364.113794 -277.602369) (xy 364.071173 -277.577762) (xy 364.033052 -277.546637)
			(xy 364.000417 -277.5098) (xy 363.974114 -277.468204) (xy 363.954823 -277.422928) (xy 363.943046 -277.375144)
			(xy 363.939086 -277.32609) (xy 363.620558 -277.32609) (xy 363.620046 -277.351536) (xy 363.611882 -277.40177)
			(xy 363.595766 -277.450044) (xy 363.572115 -277.495107) (xy 363.541542 -277.535793) (xy 363.504838 -277.571048)
			(xy 363.462954 -277.599958) (xy 363.416975 -277.621775) (xy 363.368091 -277.635935) (xy 363.31757 -277.642069)
			(xy 363.266718 -277.64002) (xy 363.216854 -277.62984) (xy 363.169268 -277.611793) (xy 363.125194 -277.586347)
			(xy 363.085772 -277.55416) (xy 363.052024 -277.516066) (xy 363.024823 -277.473052) (xy 363.004875 -277.426232)
			(xy 362.992696 -277.376818) (xy 362.988601 -277.32609) (xy 362.680504 -277.32609) (xy 362.679992 -277.351536)
			(xy 362.671828 -277.40177) (xy 362.655712 -277.450044) (xy 362.632061 -277.495107) (xy 362.601488 -277.535793)
			(xy 362.564784 -277.571048) (xy 362.5229 -277.599958) (xy 362.476921 -277.621775) (xy 362.428037 -277.635935)
			(xy 362.377516 -277.642069) (xy 362.326664 -277.64002) (xy 362.2768 -277.62984) (xy 362.229214 -277.611793)
			(xy 362.18514 -277.586347) (xy 362.145718 -277.55416) (xy 362.11197 -277.516066) (xy 362.084769 -277.473052)
			(xy 362.064821 -277.426232) (xy 362.052642 -277.376818) (xy 362.048547 -277.32609) (xy 361.73054 -277.32609)
			(xy 361.730541 -277.3261) (xy 361.72637 -277.376437) (xy 361.713972 -277.425401) (xy 361.693683 -277.471656)
			(xy 361.666059 -277.513942) (xy 361.631851 -277.551105) (xy 361.591994 -277.58213) (xy 361.547574 -277.606173)
			(xy 361.499802 -277.622577) (xy 361.449983 -277.630894) (xy 361.424728 -277.631398) (xy 361.397134 -277.630803)
			(xy 361.34284 -277.620898) (xy 361.291202 -277.601422) (xy 361.267248 -277.58771) (xy 361.261406 -277.584154)
			(xy 361.248706 -277.580598) (xy 361.24134 -277.580344) (xy 361.234356 -277.580444) (xy 361.220832 -277.583914)
			(xy 361.21467 -277.587202) (xy 361.137962 -277.632414) (xy 361.130277 -277.637337) (xy 361.11875 -277.651472)
			(xy 361.112917 -277.668752) (xy 361.112816 -277.67788) (xy 361.128608 -278.136096) (xy 363.468932 -278.136096)
			(xy 363.472892 -278.087042) (xy 363.484669 -278.039258) (xy 363.50396 -277.993982) (xy 363.530263 -277.952386)
			(xy 363.562898 -277.915549) (xy 363.601019 -277.884424) (xy 363.64364 -277.859817) (xy 363.689656 -277.842365)
			(xy 363.737875 -277.832521) (xy 363.78705 -277.83054) (xy 363.835905 -277.836472) (xy 363.883176 -277.850164)
			(xy 363.927638 -277.871262) (xy 363.968141 -277.899218) (xy 364.003634 -277.93331) (xy 364.033199 -277.972654)
			(xy 364.05607 -278.016231) (xy 364.071654 -278.062912) (xy 364.079549 -278.111489) (xy 364.080044 -278.136096)
			(xy 364.398555 -278.136096) (xy 364.40265 -278.085368) (xy 364.414829 -278.035954) (xy 364.434777 -277.989134)
			(xy 364.461978 -277.94612) (xy 364.495726 -277.908026) (xy 364.535148 -277.875839) (xy 364.579222 -277.850393)
			(xy 364.626808 -277.832346) (xy 364.676672 -277.822166) (xy 364.727524 -277.820117) (xy 364.778045 -277.826251)
			(xy 364.826929 -277.840411) (xy 364.872908 -277.862228) (xy 364.914792 -277.891138) (xy 364.951496 -277.926393)
			(xy 364.982069 -277.967079) (xy 365.00572 -278.012142) (xy 365.021836 -278.060416) (xy 365.03 -278.11065)
			(xy 365.030512 -278.136096) (xy 365.338609 -278.136096) (xy 365.342704 -278.085368) (xy 365.354883 -278.035954)
			(xy 365.374831 -277.989134) (xy 365.402032 -277.94612) (xy 365.43578 -277.908026) (xy 365.475202 -277.875839)
			(xy 365.519276 -277.850393) (xy 365.566862 -277.832346) (xy 365.616726 -277.822166) (xy 365.667578 -277.820117)
			(xy 365.718099 -277.826251) (xy 365.766983 -277.840411) (xy 365.812962 -277.862228) (xy 365.854846 -277.891138)
			(xy 365.89155 -277.926393) (xy 365.922123 -277.967079) (xy 365.945774 -278.012142) (xy 365.96189 -278.060416)
			(xy 365.970054 -278.11065) (xy 365.970566 -278.136096) (xy 366.289094 -278.136096) (xy 366.293054 -278.087042)
			(xy 366.304831 -278.039258) (xy 366.324122 -277.993982) (xy 366.350425 -277.952386) (xy 366.38306 -277.915549)
			(xy 366.421181 -277.884424) (xy 366.463802 -277.859817) (xy 366.509818 -277.842365) (xy 366.558037 -277.832521)
			(xy 366.607212 -277.83054) (xy 366.656067 -277.836472) (xy 366.703338 -277.850164) (xy 366.7478 -277.871262)
			(xy 366.788303 -277.899218) (xy 366.823796 -277.93331) (xy 366.853361 -277.972654) (xy 366.876232 -278.016231)
			(xy 366.891816 -278.062912) (xy 366.899711 -278.111489) (xy 366.900206 -278.136096) (xy 367.218463 -278.136096)
			(xy 367.222558 -278.085368) (xy 367.234737 -278.035954) (xy 367.254685 -277.989134) (xy 367.281886 -277.94612)
			(xy 367.315634 -277.908026) (xy 367.355056 -277.875839) (xy 367.39913 -277.850393) (xy 367.446716 -277.832346)
			(xy 367.49658 -277.822166) (xy 367.547432 -277.820117) (xy 367.597953 -277.826251) (xy 367.646837 -277.840411)
			(xy 367.692816 -277.862228) (xy 367.7347 -277.891138) (xy 367.771404 -277.926393) (xy 367.801977 -277.967079)
			(xy 367.825628 -278.012142) (xy 367.841744 -278.060416) (xy 367.849908 -278.11065) (xy 367.85042 -278.136096)
			(xy 368.158517 -278.136096) (xy 368.162612 -278.085368) (xy 368.174791 -278.035954) (xy 368.194739 -277.989134)
			(xy 368.22194 -277.94612) (xy 368.255688 -277.908026) (xy 368.29511 -277.875839) (xy 368.339184 -277.850393)
			(xy 368.38677 -277.832346) (xy 368.436634 -277.822166) (xy 368.487486 -277.820117) (xy 368.538007 -277.826251)
			(xy 368.586891 -277.840411) (xy 368.63287 -277.862228) (xy 368.674754 -277.891138) (xy 368.711458 -277.926393)
			(xy 368.742031 -277.967079) (xy 368.765682 -278.012142) (xy 368.781798 -278.060416) (xy 368.789962 -278.11065)
			(xy 368.790474 -278.136096) (xy 369.109002 -278.136096) (xy 369.112962 -278.087042) (xy 369.124739 -278.039258)
			(xy 369.14403 -277.993982) (xy 369.170333 -277.952386) (xy 369.202968 -277.915549) (xy 369.241089 -277.884424)
			(xy 369.28371 -277.859817) (xy 369.329726 -277.842365) (xy 369.377945 -277.832521) (xy 369.42712 -277.83054)
			(xy 369.475975 -277.836472) (xy 369.523246 -277.850164) (xy 369.567708 -277.871262) (xy 369.608211 -277.899218)
			(xy 369.643704 -277.93331) (xy 369.673269 -277.972654) (xy 369.69614 -278.016231) (xy 369.711724 -278.062912)
			(xy 369.719619 -278.111489) (xy 369.720114 -278.136096) (xy 370.038625 -278.136096) (xy 370.04272 -278.085368)
			(xy 370.054899 -278.035954) (xy 370.074847 -277.989134) (xy 370.102048 -277.94612) (xy 370.135796 -277.908026)
			(xy 370.175218 -277.875839) (xy 370.219292 -277.850393) (xy 370.266878 -277.832346) (xy 370.316742 -277.822166)
			(xy 370.367594 -277.820117) (xy 370.418115 -277.826251) (xy 370.466999 -277.840411) (xy 370.512978 -277.862228)
			(xy 370.554862 -277.891138) (xy 370.591566 -277.926393) (xy 370.622139 -277.967079) (xy 370.64579 -278.012142)
			(xy 370.661906 -278.060416) (xy 370.67007 -278.11065) (xy 370.670582 -278.136096) (xy 370.978679 -278.136096)
			(xy 370.982774 -278.085368) (xy 370.994953 -278.035954) (xy 371.014901 -277.989134) (xy 371.042102 -277.94612)
			(xy 371.07585 -277.908026) (xy 371.115272 -277.875839) (xy 371.159346 -277.850393) (xy 371.206932 -277.832346)
			(xy 371.256796 -277.822166) (xy 371.307648 -277.820117) (xy 371.358169 -277.826251) (xy 371.407053 -277.840411)
			(xy 371.453032 -277.862228) (xy 371.494916 -277.891138) (xy 371.53162 -277.926393) (xy 371.562193 -277.967079)
			(xy 371.585844 -278.012142) (xy 371.60196 -278.060416) (xy 371.610124 -278.11065) (xy 371.610636 -278.136096)
			(xy 371.92891 -278.136096) (xy 371.93287 -278.087042) (xy 371.944647 -278.039258) (xy 371.963938 -277.993982)
			(xy 371.990241 -277.952386) (xy 372.022876 -277.915549) (xy 372.060997 -277.884424) (xy 372.103618 -277.859817)
			(xy 372.149634 -277.842365) (xy 372.197853 -277.832521) (xy 372.247028 -277.83054) (xy 372.295883 -277.836472)
			(xy 372.343154 -277.850164) (xy 372.387616 -277.871262) (xy 372.428119 -277.899218) (xy 372.463612 -277.93331)
			(xy 372.493177 -277.972654) (xy 372.516048 -278.016231) (xy 372.531632 -278.062912) (xy 372.539527 -278.111489)
			(xy 372.540022 -278.136096) (xy 372.858533 -278.136096) (xy 372.862628 -278.085368) (xy 372.874807 -278.035954)
			(xy 372.894755 -277.989134) (xy 372.921956 -277.94612) (xy 372.955704 -277.908026) (xy 372.995126 -277.875839)
			(xy 373.0392 -277.850393) (xy 373.086786 -277.832346) (xy 373.13665 -277.822166) (xy 373.187502 -277.820117)
			(xy 373.238023 -277.826251) (xy 373.286907 -277.840411) (xy 373.332886 -277.862228) (xy 373.37477 -277.891138)
			(xy 373.411474 -277.926393) (xy 373.442047 -277.967079) (xy 373.465698 -278.012142) (xy 373.481814 -278.060416)
			(xy 373.489978 -278.11065) (xy 373.49049 -278.136096) (xy 373.798587 -278.136096) (xy 373.802682 -278.085368)
			(xy 373.814861 -278.035954) (xy 373.834809 -277.989134) (xy 373.86201 -277.94612) (xy 373.895758 -277.908026)
			(xy 373.93518 -277.875839) (xy 373.979254 -277.850393) (xy 374.02684 -277.832346) (xy 374.076704 -277.822166)
			(xy 374.127556 -277.820117) (xy 374.178077 -277.826251) (xy 374.226961 -277.840411) (xy 374.27294 -277.862228)
			(xy 374.314824 -277.891138) (xy 374.351528 -277.926393) (xy 374.382101 -277.967079) (xy 374.405752 -278.012142)
			(xy 374.421868 -278.060416) (xy 374.430032 -278.11065) (xy 374.430544 -278.136096) (xy 374.430032 -278.161542)
			(xy 374.421868 -278.211776) (xy 374.405752 -278.26005) (xy 374.382101 -278.305113) (xy 374.351528 -278.345799)
			(xy 374.314824 -278.381054) (xy 374.27294 -278.409964) (xy 374.226961 -278.431781) (xy 374.178077 -278.445941)
			(xy 374.127556 -278.452075) (xy 374.076704 -278.450026) (xy 374.02684 -278.439846) (xy 373.979254 -278.421799)
			(xy 373.93518 -278.396353) (xy 373.895758 -278.364166) (xy 373.86201 -278.326072) (xy 373.834809 -278.283058)
			(xy 373.814861 -278.236238) (xy 373.802682 -278.186824) (xy 373.798587 -278.136096) (xy 373.49049 -278.136096)
			(xy 373.489978 -278.161542) (xy 373.481814 -278.211776) (xy 373.465698 -278.26005) (xy 373.442047 -278.305113)
			(xy 373.411474 -278.345799) (xy 373.37477 -278.381054) (xy 373.332886 -278.409964) (xy 373.286907 -278.431781)
			(xy 373.238023 -278.445941) (xy 373.187502 -278.452075) (xy 373.13665 -278.450026) (xy 373.086786 -278.439846)
			(xy 373.0392 -278.421799) (xy 372.995126 -278.396353) (xy 372.955704 -278.364166) (xy 372.921956 -278.326072)
			(xy 372.894755 -278.283058) (xy 372.874807 -278.236238) (xy 372.862628 -278.186824) (xy 372.858533 -278.136096)
			(xy 372.540022 -278.136096) (xy 372.539527 -278.160703) (xy 372.531632 -278.20928) (xy 372.516048 -278.255961)
			(xy 372.493177 -278.299538) (xy 372.463612 -278.338882) (xy 372.428119 -278.372974) (xy 372.387616 -278.40093)
			(xy 372.343154 -278.422028) (xy 372.295883 -278.43572) (xy 372.247028 -278.441652) (xy 372.197853 -278.439671)
			(xy 372.149634 -278.429827) (xy 372.103618 -278.412375) (xy 372.060997 -278.387768) (xy 372.022876 -278.356643)
			(xy 371.990241 -278.319806) (xy 371.963938 -278.27821) (xy 371.944647 -278.232934) (xy 371.93287 -278.18515)
			(xy 371.92891 -278.136096) (xy 371.610636 -278.136096) (xy 371.610124 -278.161542) (xy 371.60196 -278.211776)
			(xy 371.585844 -278.26005) (xy 371.562193 -278.305113) (xy 371.53162 -278.345799) (xy 371.494916 -278.381054)
			(xy 371.453032 -278.409964) (xy 371.407053 -278.431781) (xy 371.358169 -278.445941) (xy 371.307648 -278.452075)
			(xy 371.256796 -278.450026) (xy 371.206932 -278.439846) (xy 371.159346 -278.421799) (xy 371.115272 -278.396353)
			(xy 371.07585 -278.364166) (xy 371.042102 -278.326072) (xy 371.014901 -278.283058) (xy 370.994953 -278.236238)
			(xy 370.982774 -278.186824) (xy 370.978679 -278.136096) (xy 370.670582 -278.136096) (xy 370.67007 -278.161542)
			(xy 370.661906 -278.211776) (xy 370.64579 -278.26005) (xy 370.622139 -278.305113) (xy 370.591566 -278.345799)
			(xy 370.554862 -278.381054) (xy 370.512978 -278.409964) (xy 370.466999 -278.431781) (xy 370.418115 -278.445941)
			(xy 370.367594 -278.452075) (xy 370.316742 -278.450026) (xy 370.266878 -278.439846) (xy 370.219292 -278.421799)
			(xy 370.175218 -278.396353) (xy 370.135796 -278.364166) (xy 370.102048 -278.326072) (xy 370.074847 -278.283058)
			(xy 370.054899 -278.236238) (xy 370.04272 -278.186824) (xy 370.038625 -278.136096) (xy 369.720114 -278.136096)
			(xy 369.719619 -278.160703) (xy 369.711724 -278.20928) (xy 369.69614 -278.255961) (xy 369.673269 -278.299538)
			(xy 369.643704 -278.338882) (xy 369.608211 -278.372974) (xy 369.567708 -278.40093) (xy 369.523246 -278.422028)
			(xy 369.475975 -278.43572) (xy 369.42712 -278.441652) (xy 369.377945 -278.439671) (xy 369.329726 -278.429827)
			(xy 369.28371 -278.412375) (xy 369.241089 -278.387768) (xy 369.202968 -278.356643) (xy 369.170333 -278.319806)
			(xy 369.14403 -278.27821) (xy 369.124739 -278.232934) (xy 369.112962 -278.18515) (xy 369.109002 -278.136096)
			(xy 368.790474 -278.136096) (xy 368.789962 -278.161542) (xy 368.781798 -278.211776) (xy 368.765682 -278.26005)
			(xy 368.742031 -278.305113) (xy 368.711458 -278.345799) (xy 368.674754 -278.381054) (xy 368.63287 -278.409964)
			(xy 368.586891 -278.431781) (xy 368.538007 -278.445941) (xy 368.487486 -278.452075) (xy 368.436634 -278.450026)
			(xy 368.38677 -278.439846) (xy 368.339184 -278.421799) (xy 368.29511 -278.396353) (xy 368.255688 -278.364166)
			(xy 368.22194 -278.326072) (xy 368.194739 -278.283058) (xy 368.174791 -278.236238) (xy 368.162612 -278.186824)
			(xy 368.158517 -278.136096) (xy 367.85042 -278.136096) (xy 367.849908 -278.161542) (xy 367.841744 -278.211776)
			(xy 367.825628 -278.26005) (xy 367.801977 -278.305113) (xy 367.771404 -278.345799) (xy 367.7347 -278.381054)
			(xy 367.692816 -278.409964) (xy 367.646837 -278.431781) (xy 367.597953 -278.445941) (xy 367.547432 -278.452075)
			(xy 367.49658 -278.450026) (xy 367.446716 -278.439846) (xy 367.39913 -278.421799) (xy 367.355056 -278.396353)
			(xy 367.315634 -278.364166) (xy 367.281886 -278.326072) (xy 367.254685 -278.283058) (xy 367.234737 -278.236238)
			(xy 367.222558 -278.186824) (xy 367.218463 -278.136096) (xy 366.900206 -278.136096) (xy 366.899711 -278.160703)
			(xy 366.891816 -278.20928) (xy 366.876232 -278.255961) (xy 366.853361 -278.299538) (xy 366.823796 -278.338882)
			(xy 366.788303 -278.372974) (xy 366.7478 -278.40093) (xy 366.703338 -278.422028) (xy 366.656067 -278.43572)
			(xy 366.607212 -278.441652) (xy 366.558037 -278.439671) (xy 366.509818 -278.429827) (xy 366.463802 -278.412375)
			(xy 366.421181 -278.387768) (xy 366.38306 -278.356643) (xy 366.350425 -278.319806) (xy 366.324122 -278.27821)
			(xy 366.304831 -278.232934) (xy 366.293054 -278.18515) (xy 366.289094 -278.136096) (xy 365.970566 -278.136096)
			(xy 365.970054 -278.161542) (xy 365.96189 -278.211776) (xy 365.945774 -278.26005) (xy 365.922123 -278.305113)
			(xy 365.89155 -278.345799) (xy 365.854846 -278.381054) (xy 365.812962 -278.409964) (xy 365.766983 -278.431781)
			(xy 365.718099 -278.445941) (xy 365.667578 -278.452075) (xy 365.616726 -278.450026) (xy 365.566862 -278.439846)
			(xy 365.519276 -278.421799) (xy 365.475202 -278.396353) (xy 365.43578 -278.364166) (xy 365.402032 -278.326072)
			(xy 365.374831 -278.283058) (xy 365.354883 -278.236238) (xy 365.342704 -278.186824) (xy 365.338609 -278.136096)
			(xy 365.030512 -278.136096) (xy 365.03 -278.161542) (xy 365.021836 -278.211776) (xy 365.00572 -278.26005)
			(xy 364.982069 -278.305113) (xy 364.951496 -278.345799) (xy 364.914792 -278.381054) (xy 364.872908 -278.409964)
			(xy 364.826929 -278.431781) (xy 364.778045 -278.445941) (xy 364.727524 -278.452075) (xy 364.676672 -278.450026)
			(xy 364.626808 -278.439846) (xy 364.579222 -278.421799) (xy 364.535148 -278.396353) (xy 364.495726 -278.364166)
			(xy 364.461978 -278.326072) (xy 364.434777 -278.283058) (xy 364.414829 -278.236238) (xy 364.40265 -278.186824)
			(xy 364.398555 -278.136096) (xy 364.080044 -278.136096) (xy 364.079549 -278.160703) (xy 364.071654 -278.20928)
			(xy 364.05607 -278.255961) (xy 364.033199 -278.299538) (xy 364.003634 -278.338882) (xy 363.968141 -278.372974)
			(xy 363.927638 -278.40093) (xy 363.883176 -278.422028) (xy 363.835905 -278.43572) (xy 363.78705 -278.441652)
			(xy 363.737875 -278.439671) (xy 363.689656 -278.429827) (xy 363.64364 -278.412375) (xy 363.601019 -278.387768)
			(xy 363.562898 -278.356643) (xy 363.530263 -278.319806) (xy 363.50396 -278.27821) (xy 363.484669 -278.232934)
			(xy 363.472892 -278.18515) (xy 363.468932 -278.136096) (xy 361.128608 -278.136096) (xy 361.144058 -278.584406)
			(xy 361.145215 -278.597124) (xy 361.158154 -278.619105) (xy 361.168696 -278.626316) (xy 361.199684 -278.644858)
			(xy 361.200192 -278.644858) (xy 361.24134 -278.670004) (xy 361.248755 -278.674111) (xy 361.265325 -278.677636)
			(xy 361.282136 -278.675536) (xy 361.289854 -278.672036) (xy 361.290108 -278.672036) (xy 361.311167 -278.662182)
			(xy 361.355525 -278.648256) (xy 361.401482 -278.641214) (xy 361.424728 -278.640794) (xy 361.448718 -278.641267)
			(xy 361.496106 -278.648776) (xy 361.541736 -278.663606) (xy 361.584485 -278.685391) (xy 361.623299 -278.713595)
			(xy 361.657224 -278.747524) (xy 361.685424 -278.786341) (xy 361.707205 -278.829092) (xy 361.722031 -278.874723)
			(xy 361.729536 -278.922112) (xy 361.730036 -278.946102) (xy 362.048547 -278.946102) (xy 362.052642 -278.895374)
			(xy 362.064821 -278.84596) (xy 362.084769 -278.79914) (xy 362.11197 -278.756126) (xy 362.145718 -278.718032)
			(xy 362.18514 -278.685845) (xy 362.229214 -278.660399) (xy 362.2768 -278.642352) (xy 362.326664 -278.632172)
			(xy 362.377516 -278.630123) (xy 362.428037 -278.636257) (xy 362.476921 -278.650417) (xy 362.5229 -278.672234)
			(xy 362.564784 -278.701144) (xy 362.601488 -278.736399) (xy 362.632061 -278.777085) (xy 362.655712 -278.822148)
			(xy 362.671828 -278.870422) (xy 362.679992 -278.920656) (xy 362.680504 -278.946102) (xy 362.988601 -278.946102)
			(xy 362.992696 -278.895374) (xy 363.004875 -278.84596) (xy 363.024823 -278.79914) (xy 363.052024 -278.756126)
			(xy 363.085772 -278.718032) (xy 363.125194 -278.685845) (xy 363.169268 -278.660399) (xy 363.216854 -278.642352)
			(xy 363.266718 -278.632172) (xy 363.31757 -278.630123) (xy 363.368091 -278.636257) (xy 363.416975 -278.650417)
			(xy 363.462954 -278.672234) (xy 363.504838 -278.701144) (xy 363.541542 -278.736399) (xy 363.572115 -278.777085)
			(xy 363.595766 -278.822148) (xy 363.611882 -278.870422) (xy 363.620046 -278.920656) (xy 363.620558 -278.946102)
			(xy 363.939086 -278.946102) (xy 363.943046 -278.897048) (xy 363.954823 -278.849264) (xy 363.974114 -278.803988)
			(xy 364.000417 -278.762392) (xy 364.033052 -278.725555) (xy 364.071173 -278.69443) (xy 364.113794 -278.669823)
			(xy 364.15981 -278.652371) (xy 364.208029 -278.642527) (xy 364.257204 -278.640546) (xy 364.306059 -278.646478)
			(xy 364.35333 -278.66017) (xy 364.397792 -278.681268) (xy 364.438295 -278.709224) (xy 364.473788 -278.743316)
			(xy 364.503353 -278.78266) (xy 364.526224 -278.826237) (xy 364.541808 -278.872918) (xy 364.549703 -278.921495)
			(xy 364.550198 -278.946102) (xy 366.758994 -278.946102) (xy 366.762954 -278.897048) (xy 366.774731 -278.849264)
			(xy 366.794022 -278.803988) (xy 366.820325 -278.762392) (xy 366.85296 -278.725555) (xy 366.891081 -278.69443)
			(xy 366.933702 -278.669823) (xy 366.979718 -278.652371) (xy 367.027937 -278.642527) (xy 367.077112 -278.640546)
			(xy 367.125967 -278.646478) (xy 367.173238 -278.66017) (xy 367.2177 -278.681268) (xy 367.258203 -278.709224)
			(xy 367.293696 -278.743316) (xy 367.323261 -278.78266) (xy 367.346132 -278.826237) (xy 367.361716 -278.872918)
			(xy 367.369611 -278.921495) (xy 367.370106 -278.946102) (xy 369.578902 -278.946102) (xy 369.582862 -278.897048)
			(xy 369.594639 -278.849264) (xy 369.61393 -278.803988) (xy 369.640233 -278.762392) (xy 369.672868 -278.725555)
			(xy 369.710989 -278.69443) (xy 369.75361 -278.669823) (xy 369.799626 -278.652371) (xy 369.847845 -278.642527)
			(xy 369.89702 -278.640546) (xy 369.945875 -278.646478) (xy 369.993146 -278.66017) (xy 370.037608 -278.681268)
			(xy 370.078111 -278.709224) (xy 370.113604 -278.743316) (xy 370.143169 -278.78266) (xy 370.16604 -278.826237)
			(xy 370.181624 -278.872918) (xy 370.189519 -278.921495) (xy 370.190014 -278.946102) (xy 372.399064 -278.946102)
			(xy 372.403024 -278.897048) (xy 372.414801 -278.849264) (xy 372.434092 -278.803988) (xy 372.460395 -278.762392)
			(xy 372.49303 -278.725555) (xy 372.531151 -278.69443) (xy 372.573772 -278.669823) (xy 372.619788 -278.652371)
			(xy 372.668007 -278.642527) (xy 372.717182 -278.640546) (xy 372.766037 -278.646478) (xy 372.813308 -278.66017)
			(xy 372.85777 -278.681268) (xy 372.898273 -278.709224) (xy 372.933766 -278.743316) (xy 372.963331 -278.78266)
			(xy 372.986202 -278.826237) (xy 373.001786 -278.872918) (xy 373.009681 -278.921495) (xy 373.010176 -278.946102)
			(xy 373.009681 -278.970709) (xy 373.001786 -279.019286) (xy 372.986202 -279.065967) (xy 372.963331 -279.109544)
			(xy 372.933766 -279.148888) (xy 372.898273 -279.18298) (xy 372.85777 -279.210936) (xy 372.813308 -279.232034)
			(xy 372.766037 -279.245726) (xy 372.717182 -279.251658) (xy 372.668007 -279.249677) (xy 372.619788 -279.239833)
			(xy 372.573772 -279.222381) (xy 372.531151 -279.197774) (xy 372.49303 -279.166649) (xy 372.460395 -279.129812)
			(xy 372.434092 -279.088216) (xy 372.414801 -279.04294) (xy 372.403024 -278.995156) (xy 372.399064 -278.946102)
			(xy 370.190014 -278.946102) (xy 370.189519 -278.970709) (xy 370.181624 -279.019286) (xy 370.16604 -279.065967)
			(xy 370.143169 -279.109544) (xy 370.113604 -279.148888) (xy 370.078111 -279.18298) (xy 370.037608 -279.210936)
			(xy 369.993146 -279.232034) (xy 369.945875 -279.245726) (xy 369.89702 -279.251658) (xy 369.847845 -279.249677)
			(xy 369.799626 -279.239833) (xy 369.75361 -279.222381) (xy 369.710989 -279.197774) (xy 369.672868 -279.166649)
			(xy 369.640233 -279.129812) (xy 369.61393 -279.088216) (xy 369.594639 -279.04294) (xy 369.582862 -278.995156)
			(xy 369.578902 -278.946102) (xy 367.370106 -278.946102) (xy 367.369611 -278.970709) (xy 367.361716 -279.019286)
			(xy 367.346132 -279.065967) (xy 367.323261 -279.109544) (xy 367.293696 -279.148888) (xy 367.258203 -279.18298)
			(xy 367.2177 -279.210936) (xy 367.173238 -279.232034) (xy 367.125967 -279.245726) (xy 367.077112 -279.251658)
			(xy 367.027937 -279.249677) (xy 366.979718 -279.239833) (xy 366.933702 -279.222381) (xy 366.891081 -279.197774)
			(xy 366.85296 -279.166649) (xy 366.820325 -279.129812) (xy 366.794022 -279.088216) (xy 366.774731 -279.04294)
			(xy 366.762954 -278.995156) (xy 366.758994 -278.946102) (xy 364.550198 -278.946102) (xy 364.549703 -278.970709)
			(xy 364.541808 -279.019286) (xy 364.526224 -279.065967) (xy 364.503353 -279.109544) (xy 364.473788 -279.148888)
			(xy 364.438295 -279.18298) (xy 364.397792 -279.210936) (xy 364.35333 -279.232034) (xy 364.306059 -279.245726)
			(xy 364.257204 -279.251658) (xy 364.208029 -279.249677) (xy 364.15981 -279.239833) (xy 364.113794 -279.222381)
			(xy 364.071173 -279.197774) (xy 364.033052 -279.166649) (xy 364.000417 -279.129812) (xy 363.974114 -279.088216)
			(xy 363.954823 -279.04294) (xy 363.943046 -278.995156) (xy 363.939086 -278.946102) (xy 363.620558 -278.946102)
			(xy 363.620046 -278.971548) (xy 363.611882 -279.021782) (xy 363.595766 -279.070056) (xy 363.572115 -279.115119)
			(xy 363.541542 -279.155805) (xy 363.504838 -279.19106) (xy 363.462954 -279.21997) (xy 363.416975 -279.241787)
			(xy 363.368091 -279.255947) (xy 363.31757 -279.262081) (xy 363.266718 -279.260032) (xy 363.216854 -279.249852)
			(xy 363.169268 -279.231805) (xy 363.125194 -279.206359) (xy 363.085772 -279.174172) (xy 363.052024 -279.136078)
			(xy 363.024823 -279.093064) (xy 363.004875 -279.046244) (xy 362.992696 -278.99683) (xy 362.988601 -278.946102)
			(xy 362.680504 -278.946102) (xy 362.679992 -278.971548) (xy 362.671828 -279.021782) (xy 362.655712 -279.070056)
			(xy 362.632061 -279.115119) (xy 362.601488 -279.155805) (xy 362.564784 -279.19106) (xy 362.5229 -279.21997)
			(xy 362.476921 -279.241787) (xy 362.428037 -279.255947) (xy 362.377516 -279.262081) (xy 362.326664 -279.260032)
			(xy 362.2768 -279.249852) (xy 362.229214 -279.231805) (xy 362.18514 -279.206359) (xy 362.145718 -279.174172)
			(xy 362.11197 -279.136078) (xy 362.084769 -279.093064) (xy 362.064821 -279.046244) (xy 362.052642 -278.99683)
			(xy 362.048547 -278.946102) (xy 361.730036 -278.946102) (xy 361.729582 -278.969878) (xy 361.72221 -279.016856)
			(xy 361.707644 -279.062123) (xy 361.686236 -279.104584) (xy 361.658505 -279.143214) (xy 361.62512 -279.177077)
			(xy 361.586889 -279.205355) (xy 361.544737 -279.227365) (xy 361.499682 -279.242573) (xy 361.452813 -279.250613)
			(xy 361.429046 -279.25141) (xy 361.424474 -279.25141) (xy 361.396051 -279.250811) (xy 361.34018 -279.240334)
			(xy 361.313476 -279.230582) (xy 361.309158 -279.228804) (xy 361.298744 -279.226772) (xy 361.288604 -279.22522)
			(xy 361.26854 -279.229401) (xy 361.259882 -279.2349) (xy 361.223052 -279.260554) (xy 361.190794 -279.28316)
			(xy 361.18405 -279.288267) (xy 361.174126 -279.301956) (xy 361.16921 -279.318134) (xy 361.169204 -279.326594)
			(xy 361.183865 -279.756108) (xy 361.589078 -279.756108) (xy 361.593038 -279.707054) (xy 361.604815 -279.65927)
			(xy 361.624106 -279.613994) (xy 361.650409 -279.572398) (xy 361.683044 -279.535561) (xy 361.721165 -279.504436)
			(xy 361.763786 -279.479829) (xy 361.809802 -279.462377) (xy 361.858021 -279.452533) (xy 361.907196 -279.450552)
			(xy 361.956051 -279.456484) (xy 362.003322 -279.470176) (xy 362.047784 -279.491274) (xy 362.088287 -279.51923)
			(xy 362.12378 -279.553322) (xy 362.153345 -279.592666) (xy 362.176216 -279.636243) (xy 362.1918 -279.682924)
			(xy 362.199695 -279.731501) (xy 362.20019 -279.756108) (xy 362.528878 -279.756108) (xy 362.532838 -279.707054)
			(xy 362.544615 -279.65927) (xy 362.563906 -279.613994) (xy 362.590209 -279.572398) (xy 362.622844 -279.535561)
			(xy 362.660965 -279.504436) (xy 362.703586 -279.479829) (xy 362.749602 -279.462377) (xy 362.797821 -279.452533)
			(xy 362.846996 -279.450552) (xy 362.895851 -279.456484) (xy 362.943122 -279.470176) (xy 362.987584 -279.491274)
			(xy 363.028087 -279.51923) (xy 363.06358 -279.553322) (xy 363.093145 -279.592666) (xy 363.116016 -279.636243)
			(xy 363.1316 -279.682924) (xy 363.139495 -279.731501) (xy 363.13999 -279.756108) (xy 363.468932 -279.756108)
			(xy 363.472892 -279.707054) (xy 363.484669 -279.65927) (xy 363.50396 -279.613994) (xy 363.530263 -279.572398)
			(xy 363.562898 -279.535561) (xy 363.601019 -279.504436) (xy 363.64364 -279.479829) (xy 363.689656 -279.462377)
			(xy 363.737875 -279.452533) (xy 363.78705 -279.450552) (xy 363.835905 -279.456484) (xy 363.883176 -279.470176)
			(xy 363.927638 -279.491274) (xy 363.968141 -279.51923) (xy 364.003634 -279.553322) (xy 364.033199 -279.592666)
			(xy 364.05607 -279.636243) (xy 364.071654 -279.682924) (xy 364.079549 -279.731501) (xy 364.080044 -279.756108)
			(xy 364.398555 -279.756108) (xy 364.40265 -279.70538) (xy 364.414829 -279.655966) (xy 364.434777 -279.609146)
			(xy 364.461978 -279.566132) (xy 364.495726 -279.528038) (xy 364.535148 -279.495851) (xy 364.579222 -279.470405)
			(xy 364.626808 -279.452358) (xy 364.676672 -279.442178) (xy 364.727524 -279.440129) (xy 364.778045 -279.446263)
			(xy 364.826929 -279.460423) (xy 364.872908 -279.48224) (xy 364.914792 -279.51115) (xy 364.951496 -279.546405)
			(xy 364.982069 -279.587091) (xy 365.00572 -279.632154) (xy 365.021836 -279.680428) (xy 365.03 -279.730662)
			(xy 365.030512 -279.756108) (xy 365.338609 -279.756108) (xy 365.342704 -279.70538) (xy 365.354883 -279.655966)
			(xy 365.374831 -279.609146) (xy 365.402032 -279.566132) (xy 365.43578 -279.528038) (xy 365.475202 -279.495851)
			(xy 365.519276 -279.470405) (xy 365.566862 -279.452358) (xy 365.616726 -279.442178) (xy 365.667578 -279.440129)
			(xy 365.718099 -279.446263) (xy 365.766983 -279.460423) (xy 365.812962 -279.48224) (xy 365.854846 -279.51115)
			(xy 365.89155 -279.546405) (xy 365.922123 -279.587091) (xy 365.945774 -279.632154) (xy 365.96189 -279.680428)
			(xy 365.970054 -279.730662) (xy 365.970566 -279.756108) (xy 366.289094 -279.756108) (xy 366.293054 -279.707054)
			(xy 366.304831 -279.65927) (xy 366.324122 -279.613994) (xy 366.350425 -279.572398) (xy 366.38306 -279.535561)
			(xy 366.421181 -279.504436) (xy 366.463802 -279.479829) (xy 366.509818 -279.462377) (xy 366.558037 -279.452533)
			(xy 366.607212 -279.450552) (xy 366.656067 -279.456484) (xy 366.703338 -279.470176) (xy 366.7478 -279.491274)
			(xy 366.788303 -279.51923) (xy 366.823796 -279.553322) (xy 366.853361 -279.592666) (xy 366.876232 -279.636243)
			(xy 366.891816 -279.682924) (xy 366.899711 -279.731501) (xy 366.900206 -279.756108) (xy 367.228894 -279.756108)
			(xy 367.232854 -279.707054) (xy 367.244631 -279.65927) (xy 367.263922 -279.613994) (xy 367.290225 -279.572398)
			(xy 367.32286 -279.535561) (xy 367.360981 -279.504436) (xy 367.403602 -279.479829) (xy 367.449618 -279.462377)
			(xy 367.497837 -279.452533) (xy 367.547012 -279.450552) (xy 367.595867 -279.456484) (xy 367.643138 -279.470176)
			(xy 367.6876 -279.491274) (xy 367.728103 -279.51923) (xy 367.763596 -279.553322) (xy 367.793161 -279.592666)
			(xy 367.816032 -279.636243) (xy 367.831616 -279.682924) (xy 367.839511 -279.731501) (xy 367.840006 -279.756108)
			(xy 368.168948 -279.756108) (xy 368.172908 -279.707054) (xy 368.184685 -279.65927) (xy 368.203976 -279.613994)
			(xy 368.230279 -279.572398) (xy 368.262914 -279.535561) (xy 368.301035 -279.504436) (xy 368.343656 -279.479829)
			(xy 368.389672 -279.462377) (xy 368.437891 -279.452533) (xy 368.487066 -279.450552) (xy 368.535921 -279.456484)
			(xy 368.583192 -279.470176) (xy 368.627654 -279.491274) (xy 368.668157 -279.51923) (xy 368.70365 -279.553322)
			(xy 368.733215 -279.592666) (xy 368.756086 -279.636243) (xy 368.77167 -279.682924) (xy 368.779565 -279.731501)
			(xy 368.78006 -279.756108) (xy 369.109002 -279.756108) (xy 369.112962 -279.707054) (xy 369.124739 -279.65927)
			(xy 369.14403 -279.613994) (xy 369.170333 -279.572398) (xy 369.202968 -279.535561) (xy 369.241089 -279.504436)
			(xy 369.28371 -279.479829) (xy 369.329726 -279.462377) (xy 369.377945 -279.452533) (xy 369.42712 -279.450552)
			(xy 369.475975 -279.456484) (xy 369.523246 -279.470176) (xy 369.567708 -279.491274) (xy 369.608211 -279.51923)
			(xy 369.643704 -279.553322) (xy 369.673269 -279.592666) (xy 369.69614 -279.636243) (xy 369.711724 -279.682924)
			(xy 369.719619 -279.731501) (xy 369.720114 -279.756108) (xy 370.049056 -279.756108) (xy 370.053016 -279.707054)
			(xy 370.064793 -279.65927) (xy 370.084084 -279.613994) (xy 370.110387 -279.572398) (xy 370.143022 -279.535561)
			(xy 370.181143 -279.504436) (xy 370.223764 -279.479829) (xy 370.26978 -279.462377) (xy 370.317999 -279.452533)
			(xy 370.367174 -279.450552) (xy 370.416029 -279.456484) (xy 370.4633 -279.470176) (xy 370.507762 -279.491274)
			(xy 370.548265 -279.51923) (xy 370.583758 -279.553322) (xy 370.613323 -279.592666) (xy 370.636194 -279.636243)
			(xy 370.651778 -279.682924) (xy 370.659673 -279.731501) (xy 370.660168 -279.756108) (xy 370.98911 -279.756108)
			(xy 370.99307 -279.707054) (xy 371.004847 -279.65927) (xy 371.024138 -279.613994) (xy 371.050441 -279.572398)
			(xy 371.083076 -279.535561) (xy 371.121197 -279.504436) (xy 371.163818 -279.479829) (xy 371.209834 -279.462377)
			(xy 371.258053 -279.452533) (xy 371.307228 -279.450552) (xy 371.356083 -279.456484) (xy 371.403354 -279.470176)
			(xy 371.447816 -279.491274) (xy 371.488319 -279.51923) (xy 371.523812 -279.553322) (xy 371.553377 -279.592666)
			(xy 371.576248 -279.636243) (xy 371.591832 -279.682924) (xy 371.599727 -279.731501) (xy 371.600222 -279.756108)
			(xy 371.92891 -279.756108) (xy 371.93287 -279.707054) (xy 371.944647 -279.65927) (xy 371.963938 -279.613994)
			(xy 371.990241 -279.572398) (xy 372.022876 -279.535561) (xy 372.060997 -279.504436) (xy 372.103618 -279.479829)
			(xy 372.149634 -279.462377) (xy 372.197853 -279.452533) (xy 372.247028 -279.450552) (xy 372.295883 -279.456484)
			(xy 372.343154 -279.470176) (xy 372.387616 -279.491274) (xy 372.428119 -279.51923) (xy 372.463612 -279.553322)
			(xy 372.493177 -279.592666) (xy 372.516048 -279.636243) (xy 372.531632 -279.682924) (xy 372.539527 -279.731501)
			(xy 372.540022 -279.756108) (xy 372.868964 -279.756108) (xy 372.872924 -279.707054) (xy 372.884701 -279.65927)
			(xy 372.903992 -279.613994) (xy 372.930295 -279.572398) (xy 372.96293 -279.535561) (xy 373.001051 -279.504436)
			(xy 373.043672 -279.479829) (xy 373.089688 -279.462377) (xy 373.137907 -279.452533) (xy 373.187082 -279.450552)
			(xy 373.235937 -279.456484) (xy 373.283208 -279.470176) (xy 373.32767 -279.491274) (xy 373.368173 -279.51923)
			(xy 373.403666 -279.553322) (xy 373.433231 -279.592666) (xy 373.456102 -279.636243) (xy 373.471686 -279.682924)
			(xy 373.479581 -279.731501) (xy 373.480076 -279.756108) (xy 373.809018 -279.756108) (xy 373.812978 -279.707054)
			(xy 373.824755 -279.65927) (xy 373.844046 -279.613994) (xy 373.870349 -279.572398) (xy 373.902984 -279.535561)
			(xy 373.941105 -279.504436) (xy 373.983726 -279.479829) (xy 374.029742 -279.462377) (xy 374.077961 -279.452533)
			(xy 374.127136 -279.450552) (xy 374.175991 -279.456484) (xy 374.223262 -279.470176) (xy 374.267724 -279.491274)
			(xy 374.308227 -279.51923) (xy 374.34372 -279.553322) (xy 374.373285 -279.592666) (xy 374.396156 -279.636243)
			(xy 374.41174 -279.682924) (xy 374.419635 -279.731501) (xy 374.42013 -279.756108) (xy 374.419635 -279.780715)
			(xy 374.41174 -279.829292) (xy 374.396156 -279.875973) (xy 374.373285 -279.91955) (xy 374.34372 -279.958894)
			(xy 374.308227 -279.992986) (xy 374.267724 -280.020942) (xy 374.223262 -280.04204) (xy 374.175991 -280.055732)
			(xy 374.127136 -280.061664) (xy 374.077961 -280.059683) (xy 374.029742 -280.049839) (xy 373.983726 -280.032387)
			(xy 373.941105 -280.00778) (xy 373.902984 -279.976655) (xy 373.870349 -279.939818) (xy 373.844046 -279.898222)
			(xy 373.824755 -279.852946) (xy 373.812978 -279.805162) (xy 373.809018 -279.756108) (xy 373.480076 -279.756108)
			(xy 373.479581 -279.780715) (xy 373.471686 -279.829292) (xy 373.456102 -279.875973) (xy 373.433231 -279.91955)
			(xy 373.403666 -279.958894) (xy 373.368173 -279.992986) (xy 373.32767 -280.020942) (xy 373.283208 -280.04204)
			(xy 373.235937 -280.055732) (xy 373.187082 -280.061664) (xy 373.137907 -280.059683) (xy 373.089688 -280.049839)
			(xy 373.043672 -280.032387) (xy 373.001051 -280.00778) (xy 372.96293 -279.976655) (xy 372.930295 -279.939818)
			(xy 372.903992 -279.898222) (xy 372.884701 -279.852946) (xy 372.872924 -279.805162) (xy 372.868964 -279.756108)
			(xy 372.540022 -279.756108) (xy 372.539527 -279.780715) (xy 372.531632 -279.829292) (xy 372.516048 -279.875973)
			(xy 372.493177 -279.91955) (xy 372.463612 -279.958894) (xy 372.428119 -279.992986) (xy 372.387616 -280.020942)
			(xy 372.343154 -280.04204) (xy 372.295883 -280.055732) (xy 372.247028 -280.061664) (xy 372.197853 -280.059683)
			(xy 372.149634 -280.049839) (xy 372.103618 -280.032387) (xy 372.060997 -280.00778) (xy 372.022876 -279.976655)
			(xy 371.990241 -279.939818) (xy 371.963938 -279.898222) (xy 371.944647 -279.852946) (xy 371.93287 -279.805162)
			(xy 371.92891 -279.756108) (xy 371.600222 -279.756108) (xy 371.599727 -279.780715) (xy 371.591832 -279.829292)
			(xy 371.576248 -279.875973) (xy 371.553377 -279.91955) (xy 371.523812 -279.958894) (xy 371.488319 -279.992986)
			(xy 371.447816 -280.020942) (xy 371.403354 -280.04204) (xy 371.356083 -280.055732) (xy 371.307228 -280.061664)
			(xy 371.258053 -280.059683) (xy 371.209834 -280.049839) (xy 371.163818 -280.032387) (xy 371.121197 -280.00778)
			(xy 371.083076 -279.976655) (xy 371.050441 -279.939818) (xy 371.024138 -279.898222) (xy 371.004847 -279.852946)
			(xy 370.99307 -279.805162) (xy 370.98911 -279.756108) (xy 370.660168 -279.756108) (xy 370.659673 -279.780715)
			(xy 370.651778 -279.829292) (xy 370.636194 -279.875973) (xy 370.613323 -279.91955) (xy 370.583758 -279.958894)
			(xy 370.548265 -279.992986) (xy 370.507762 -280.020942) (xy 370.4633 -280.04204) (xy 370.416029 -280.055732)
			(xy 370.367174 -280.061664) (xy 370.317999 -280.059683) (xy 370.26978 -280.049839) (xy 370.223764 -280.032387)
			(xy 370.181143 -280.00778) (xy 370.143022 -279.976655) (xy 370.110387 -279.939818) (xy 370.084084 -279.898222)
			(xy 370.064793 -279.852946) (xy 370.053016 -279.805162) (xy 370.049056 -279.756108) (xy 369.720114 -279.756108)
			(xy 369.719619 -279.780715) (xy 369.711724 -279.829292) (xy 369.69614 -279.875973) (xy 369.673269 -279.91955)
			(xy 369.643704 -279.958894) (xy 369.608211 -279.992986) (xy 369.567708 -280.020942) (xy 369.523246 -280.04204)
			(xy 369.475975 -280.055732) (xy 369.42712 -280.061664) (xy 369.377945 -280.059683) (xy 369.329726 -280.049839)
			(xy 369.28371 -280.032387) (xy 369.241089 -280.00778) (xy 369.202968 -279.976655) (xy 369.170333 -279.939818)
			(xy 369.14403 -279.898222) (xy 369.124739 -279.852946) (xy 369.112962 -279.805162) (xy 369.109002 -279.756108)
			(xy 368.78006 -279.756108) (xy 368.779565 -279.780715) (xy 368.77167 -279.829292) (xy 368.756086 -279.875973)
			(xy 368.733215 -279.91955) (xy 368.70365 -279.958894) (xy 368.668157 -279.992986) (xy 368.627654 -280.020942)
			(xy 368.583192 -280.04204) (xy 368.535921 -280.055732) (xy 368.487066 -280.061664) (xy 368.437891 -280.059683)
			(xy 368.389672 -280.049839) (xy 368.343656 -280.032387) (xy 368.301035 -280.00778) (xy 368.262914 -279.976655)
			(xy 368.230279 -279.939818) (xy 368.203976 -279.898222) (xy 368.184685 -279.852946) (xy 368.172908 -279.805162)
			(xy 368.168948 -279.756108) (xy 367.840006 -279.756108) (xy 367.839511 -279.780715) (xy 367.831616 -279.829292)
			(xy 367.816032 -279.875973) (xy 367.793161 -279.91955) (xy 367.763596 -279.958894) (xy 367.728103 -279.992986)
			(xy 367.6876 -280.020942) (xy 367.643138 -280.04204) (xy 367.595867 -280.055732) (xy 367.547012 -280.061664)
			(xy 367.497837 -280.059683) (xy 367.449618 -280.049839) (xy 367.403602 -280.032387) (xy 367.360981 -280.00778)
			(xy 367.32286 -279.976655) (xy 367.290225 -279.939818) (xy 367.263922 -279.898222) (xy 367.244631 -279.852946)
			(xy 367.232854 -279.805162) (xy 367.228894 -279.756108) (xy 366.900206 -279.756108) (xy 366.899711 -279.780715)
			(xy 366.891816 -279.829292) (xy 366.876232 -279.875973) (xy 366.853361 -279.91955) (xy 366.823796 -279.958894)
			(xy 366.788303 -279.992986) (xy 366.7478 -280.020942) (xy 366.703338 -280.04204) (xy 366.656067 -280.055732)
			(xy 366.607212 -280.061664) (xy 366.558037 -280.059683) (xy 366.509818 -280.049839) (xy 366.463802 -280.032387)
			(xy 366.421181 -280.00778) (xy 366.38306 -279.976655) (xy 366.350425 -279.939818) (xy 366.324122 -279.898222)
			(xy 366.304831 -279.852946) (xy 366.293054 -279.805162) (xy 366.289094 -279.756108) (xy 365.970566 -279.756108)
			(xy 365.970054 -279.781554) (xy 365.96189 -279.831788) (xy 365.945774 -279.880062) (xy 365.922123 -279.925125)
			(xy 365.89155 -279.965811) (xy 365.854846 -280.001066) (xy 365.812962 -280.029976) (xy 365.766983 -280.051793)
			(xy 365.718099 -280.065953) (xy 365.667578 -280.072087) (xy 365.616726 -280.070038) (xy 365.566862 -280.059858)
			(xy 365.519276 -280.041811) (xy 365.475202 -280.016365) (xy 365.43578 -279.984178) (xy 365.402032 -279.946084)
			(xy 365.374831 -279.90307) (xy 365.354883 -279.85625) (xy 365.342704 -279.806836) (xy 365.338609 -279.756108)
			(xy 365.030512 -279.756108) (xy 365.03 -279.781554) (xy 365.021836 -279.831788) (xy 365.00572 -279.880062)
			(xy 364.982069 -279.925125) (xy 364.951496 -279.965811) (xy 364.914792 -280.001066) (xy 364.872908 -280.029976)
			(xy 364.826929 -280.051793) (xy 364.778045 -280.065953) (xy 364.727524 -280.072087) (xy 364.676672 -280.070038)
			(xy 364.626808 -280.059858) (xy 364.579222 -280.041811) (xy 364.535148 -280.016365) (xy 364.495726 -279.984178)
			(xy 364.461978 -279.946084) (xy 364.434777 -279.90307) (xy 364.414829 -279.85625) (xy 364.40265 -279.806836)
			(xy 364.398555 -279.756108) (xy 364.080044 -279.756108) (xy 364.079549 -279.780715) (xy 364.071654 -279.829292)
			(xy 364.05607 -279.875973) (xy 364.033199 -279.91955) (xy 364.003634 -279.958894) (xy 363.968141 -279.992986)
			(xy 363.927638 -280.020942) (xy 363.883176 -280.04204) (xy 363.835905 -280.055732) (xy 363.78705 -280.061664)
			(xy 363.737875 -280.059683) (xy 363.689656 -280.049839) (xy 363.64364 -280.032387) (xy 363.601019 -280.00778)
			(xy 363.562898 -279.976655) (xy 363.530263 -279.939818) (xy 363.50396 -279.898222) (xy 363.484669 -279.852946)
			(xy 363.472892 -279.805162) (xy 363.468932 -279.756108) (xy 363.13999 -279.756108) (xy 363.139495 -279.780715)
			(xy 363.1316 -279.829292) (xy 363.116016 -279.875973) (xy 363.093145 -279.91955) (xy 363.06358 -279.958894)
			(xy 363.028087 -279.992986) (xy 362.987584 -280.020942) (xy 362.943122 -280.04204) (xy 362.895851 -280.055732)
			(xy 362.846996 -280.061664) (xy 362.797821 -280.059683) (xy 362.749602 -280.049839) (xy 362.703586 -280.032387)
			(xy 362.660965 -280.00778) (xy 362.622844 -279.976655) (xy 362.590209 -279.939818) (xy 362.563906 -279.898222)
			(xy 362.544615 -279.852946) (xy 362.532838 -279.805162) (xy 362.528878 -279.756108) (xy 362.20019 -279.756108)
			(xy 362.199695 -279.780715) (xy 362.1918 -279.829292) (xy 362.176216 -279.875973) (xy 362.153345 -279.91955)
			(xy 362.12378 -279.958894) (xy 362.088287 -279.992986) (xy 362.047784 -280.020942) (xy 362.003322 -280.04204)
			(xy 361.956051 -280.055732) (xy 361.907196 -280.061664) (xy 361.858021 -280.059683) (xy 361.809802 -280.049839)
			(xy 361.763786 -280.032387) (xy 361.721165 -280.00778) (xy 361.683044 -279.976655) (xy 361.650409 -279.939818)
			(xy 361.624106 -279.898222) (xy 361.604815 -279.852946) (xy 361.593038 -279.805162) (xy 361.589078 -279.756108)
			(xy 361.183865 -279.756108) (xy 361.198414 -280.18232) (xy 361.198693 -280.187516) (xy 361.201124 -280.197632)
			(xy 361.20324 -280.202386) (xy 361.206247 -280.208231) (xy 361.214743 -280.218256) (xy 361.220004 -280.222198)
			(xy 361.286298 -280.26868) (xy 361.29623 -280.274935) (xy 361.319398 -280.278523) (xy 361.330748 -280.275538)
			(xy 361.331002 -280.275538) (xy 361.353822 -280.268666) (xy 361.4009 -280.261273) (xy 361.424728 -280.260806)
			(xy 361.449981 -280.26133) (xy 361.499797 -280.269647) (xy 361.547564 -280.286049) (xy 361.591981 -280.31009)
			(xy 361.631835 -280.341113) (xy 361.66604 -280.378273) (xy 361.693662 -280.420555) (xy 361.713949 -280.466807)
			(xy 361.726347 -280.515767) (xy 361.730517 -280.5661) (xy 361.730516 -280.566114) (xy 363.939086 -280.566114)
			(xy 363.943046 -280.51706) (xy 363.954823 -280.469276) (xy 363.974114 -280.424) (xy 364.000417 -280.382404)
			(xy 364.033052 -280.345567) (xy 364.071173 -280.314442) (xy 364.113794 -280.289835) (xy 364.15981 -280.272383)
			(xy 364.208029 -280.262539) (xy 364.257204 -280.260558) (xy 364.306059 -280.26649) (xy 364.35333 -280.280182)
			(xy 364.397792 -280.30128) (xy 364.438295 -280.329236) (xy 364.473788 -280.363328) (xy 364.503353 -280.402672)
			(xy 364.526224 -280.446249) (xy 364.541808 -280.49293) (xy 364.549703 -280.541507) (xy 364.550198 -280.566114)
			(xy 364.878886 -280.566114) (xy 364.882846 -280.51706) (xy 364.894623 -280.469276) (xy 364.913914 -280.424)
			(xy 364.940217 -280.382404) (xy 364.972852 -280.345567) (xy 365.010973 -280.314442) (xy 365.053594 -280.289835)
			(xy 365.09961 -280.272383) (xy 365.147829 -280.262539) (xy 365.197004 -280.260558) (xy 365.245859 -280.26649)
			(xy 365.29313 -280.280182) (xy 365.337592 -280.30128) (xy 365.378095 -280.329236) (xy 365.413588 -280.363328)
			(xy 365.443153 -280.402672) (xy 365.466024 -280.446249) (xy 365.481608 -280.49293) (xy 365.489503 -280.541507)
			(xy 365.489998 -280.566114) (xy 365.81894 -280.566114) (xy 365.8229 -280.51706) (xy 365.834677 -280.469276)
			(xy 365.853968 -280.424) (xy 365.880271 -280.382404) (xy 365.912906 -280.345567) (xy 365.951027 -280.314442)
			(xy 365.993648 -280.289835) (xy 366.039664 -280.272383) (xy 366.087883 -280.262539) (xy 366.137058 -280.260558)
			(xy 366.185913 -280.26649) (xy 366.233184 -280.280182) (xy 366.277646 -280.30128) (xy 366.318149 -280.329236)
			(xy 366.353642 -280.363328) (xy 366.383207 -280.402672) (xy 366.406078 -280.446249) (xy 366.421662 -280.49293)
			(xy 366.429557 -280.541507) (xy 366.430052 -280.566114) (xy 366.758994 -280.566114) (xy 366.762954 -280.51706)
			(xy 366.774731 -280.469276) (xy 366.794022 -280.424) (xy 366.820325 -280.382404) (xy 366.85296 -280.345567)
			(xy 366.891081 -280.314442) (xy 366.933702 -280.289835) (xy 366.979718 -280.272383) (xy 367.027937 -280.262539)
			(xy 367.077112 -280.260558) (xy 367.125967 -280.26649) (xy 367.173238 -280.280182) (xy 367.2177 -280.30128)
			(xy 367.258203 -280.329236) (xy 367.293696 -280.363328) (xy 367.323261 -280.402672) (xy 367.346132 -280.446249)
			(xy 367.361716 -280.49293) (xy 367.369611 -280.541507) (xy 367.370106 -280.566114) (xy 367.699048 -280.566114)
			(xy 367.703008 -280.51706) (xy 367.714785 -280.469276) (xy 367.734076 -280.424) (xy 367.760379 -280.382404)
			(xy 367.793014 -280.345567) (xy 367.831135 -280.314442) (xy 367.873756 -280.289835) (xy 367.919772 -280.272383)
			(xy 367.967991 -280.262539) (xy 368.017166 -280.260558) (xy 368.066021 -280.26649) (xy 368.113292 -280.280182)
			(xy 368.157754 -280.30128) (xy 368.198257 -280.329236) (xy 368.23375 -280.363328) (xy 368.263315 -280.402672)
			(xy 368.286186 -280.446249) (xy 368.30177 -280.49293) (xy 368.309665 -280.541507) (xy 368.31016 -280.566114)
			(xy 368.639102 -280.566114) (xy 368.643062 -280.51706) (xy 368.654839 -280.469276) (xy 368.67413 -280.424)
			(xy 368.700433 -280.382404) (xy 368.733068 -280.345567) (xy 368.771189 -280.314442) (xy 368.81381 -280.289835)
			(xy 368.859826 -280.272383) (xy 368.908045 -280.262539) (xy 368.95722 -280.260558) (xy 369.006075 -280.26649)
			(xy 369.053346 -280.280182) (xy 369.097808 -280.30128) (xy 369.138311 -280.329236) (xy 369.173804 -280.363328)
			(xy 369.203369 -280.402672) (xy 369.22624 -280.446249) (xy 369.241824 -280.49293) (xy 369.249719 -280.541507)
			(xy 369.250214 -280.566114) (xy 369.578902 -280.566114) (xy 369.582862 -280.51706) (xy 369.594639 -280.469276)
			(xy 369.61393 -280.424) (xy 369.640233 -280.382404) (xy 369.672868 -280.345567) (xy 369.710989 -280.314442)
			(xy 369.75361 -280.289835) (xy 369.799626 -280.272383) (xy 369.847845 -280.262539) (xy 369.89702 -280.260558)
			(xy 369.945875 -280.26649) (xy 369.993146 -280.280182) (xy 370.037608 -280.30128) (xy 370.078111 -280.329236)
			(xy 370.113604 -280.363328) (xy 370.143169 -280.402672) (xy 370.16604 -280.446249) (xy 370.181624 -280.49293)
			(xy 370.189519 -280.541507) (xy 370.190014 -280.566114) (xy 370.518956 -280.566114) (xy 370.522916 -280.51706)
			(xy 370.534693 -280.469276) (xy 370.553984 -280.424) (xy 370.580287 -280.382404) (xy 370.612922 -280.345567)
			(xy 370.651043 -280.314442) (xy 370.693664 -280.289835) (xy 370.73968 -280.272383) (xy 370.787899 -280.262539)
			(xy 370.837074 -280.260558) (xy 370.885929 -280.26649) (xy 370.9332 -280.280182) (xy 370.977662 -280.30128)
			(xy 371.018165 -280.329236) (xy 371.053658 -280.363328) (xy 371.083223 -280.402672) (xy 371.106094 -280.446249)
			(xy 371.121678 -280.49293) (xy 371.129573 -280.541507) (xy 371.130068 -280.566114) (xy 371.45901 -280.566114)
			(xy 371.46297 -280.51706) (xy 371.474747 -280.469276) (xy 371.494038 -280.424) (xy 371.520341 -280.382404)
			(xy 371.552976 -280.345567) (xy 371.591097 -280.314442) (xy 371.633718 -280.289835) (xy 371.679734 -280.272383)
			(xy 371.727953 -280.262539) (xy 371.777128 -280.260558) (xy 371.825983 -280.26649) (xy 371.873254 -280.280182)
			(xy 371.917716 -280.30128) (xy 371.958219 -280.329236) (xy 371.993712 -280.363328) (xy 372.023277 -280.402672)
			(xy 372.046148 -280.446249) (xy 372.061732 -280.49293) (xy 372.069627 -280.541507) (xy 372.070122 -280.566114)
			(xy 372.399064 -280.566114) (xy 372.403024 -280.51706) (xy 372.414801 -280.469276) (xy 372.434092 -280.424)
			(xy 372.460395 -280.382404) (xy 372.49303 -280.345567) (xy 372.531151 -280.314442) (xy 372.573772 -280.289835)
			(xy 372.619788 -280.272383) (xy 372.668007 -280.262539) (xy 372.717182 -280.260558) (xy 372.766037 -280.26649)
			(xy 372.813308 -280.280182) (xy 372.85777 -280.30128) (xy 372.898273 -280.329236) (xy 372.933766 -280.363328)
			(xy 372.963331 -280.402672) (xy 372.986202 -280.446249) (xy 373.001786 -280.49293) (xy 373.009681 -280.541507)
			(xy 373.010176 -280.566114) (xy 373.339118 -280.566114) (xy 373.343078 -280.51706) (xy 373.354855 -280.469276)
			(xy 373.374146 -280.424) (xy 373.400449 -280.382404) (xy 373.433084 -280.345567) (xy 373.471205 -280.314442)
			(xy 373.513826 -280.289835) (xy 373.559842 -280.272383) (xy 373.608061 -280.262539) (xy 373.657236 -280.260558)
			(xy 373.706091 -280.26649) (xy 373.753362 -280.280182) (xy 373.797824 -280.30128) (xy 373.838327 -280.329236)
			(xy 373.87382 -280.363328) (xy 373.903385 -280.402672) (xy 373.926256 -280.446249) (xy 373.94184 -280.49293)
			(xy 373.949735 -280.541507) (xy 373.95023 -280.566114) (xy 373.949735 -280.590721) (xy 373.94184 -280.639298)
			(xy 373.926256 -280.685979) (xy 373.903385 -280.729556) (xy 373.87382 -280.7689) (xy 373.838327 -280.802992)
			(xy 373.797824 -280.830948) (xy 373.753362 -280.852046) (xy 373.706091 -280.865738) (xy 373.657236 -280.87167)
			(xy 373.608061 -280.869689) (xy 373.559842 -280.859845) (xy 373.513826 -280.842393) (xy 373.471205 -280.817786)
			(xy 373.433084 -280.786661) (xy 373.400449 -280.749824) (xy 373.374146 -280.708228) (xy 373.354855 -280.662952)
			(xy 373.343078 -280.615168) (xy 373.339118 -280.566114) (xy 373.010176 -280.566114) (xy 373.009681 -280.590721)
			(xy 373.001786 -280.639298) (xy 372.986202 -280.685979) (xy 372.963331 -280.729556) (xy 372.933766 -280.7689)
			(xy 372.898273 -280.802992) (xy 372.85777 -280.830948) (xy 372.813308 -280.852046) (xy 372.766037 -280.865738)
			(xy 372.717182 -280.87167) (xy 372.668007 -280.869689) (xy 372.619788 -280.859845) (xy 372.573772 -280.842393)
			(xy 372.531151 -280.817786) (xy 372.49303 -280.786661) (xy 372.460395 -280.749824) (xy 372.434092 -280.708228)
			(xy 372.414801 -280.662952) (xy 372.403024 -280.615168) (xy 372.399064 -280.566114) (xy 372.070122 -280.566114)
			(xy 372.069627 -280.590721) (xy 372.061732 -280.639298) (xy 372.046148 -280.685979) (xy 372.023277 -280.729556)
			(xy 371.993712 -280.7689) (xy 371.958219 -280.802992) (xy 371.917716 -280.830948) (xy 371.873254 -280.852046)
			(xy 371.825983 -280.865738) (xy 371.777128 -280.87167) (xy 371.727953 -280.869689) (xy 371.679734 -280.859845)
			(xy 371.633718 -280.842393) (xy 371.591097 -280.817786) (xy 371.552976 -280.786661) (xy 371.520341 -280.749824)
			(xy 371.494038 -280.708228) (xy 371.474747 -280.662952) (xy 371.46297 -280.615168) (xy 371.45901 -280.566114)
			(xy 371.130068 -280.566114) (xy 371.129573 -280.590721) (xy 371.121678 -280.639298) (xy 371.106094 -280.685979)
			(xy 371.083223 -280.729556) (xy 371.053658 -280.7689) (xy 371.018165 -280.802992) (xy 370.977662 -280.830948)
			(xy 370.9332 -280.852046) (xy 370.885929 -280.865738) (xy 370.837074 -280.87167) (xy 370.787899 -280.869689)
			(xy 370.73968 -280.859845) (xy 370.693664 -280.842393) (xy 370.651043 -280.817786) (xy 370.612922 -280.786661)
			(xy 370.580287 -280.749824) (xy 370.553984 -280.708228) (xy 370.534693 -280.662952) (xy 370.522916 -280.615168)
			(xy 370.518956 -280.566114) (xy 370.190014 -280.566114) (xy 370.189519 -280.590721) (xy 370.181624 -280.639298)
			(xy 370.16604 -280.685979) (xy 370.143169 -280.729556) (xy 370.113604 -280.7689) (xy 370.078111 -280.802992)
			(xy 370.037608 -280.830948) (xy 369.993146 -280.852046) (xy 369.945875 -280.865738) (xy 369.89702 -280.87167)
			(xy 369.847845 -280.869689) (xy 369.799626 -280.859845) (xy 369.75361 -280.842393) (xy 369.710989 -280.817786)
			(xy 369.672868 -280.786661) (xy 369.640233 -280.749824) (xy 369.61393 -280.708228) (xy 369.594639 -280.662952)
			(xy 369.582862 -280.615168) (xy 369.578902 -280.566114) (xy 369.250214 -280.566114) (xy 369.249719 -280.590721)
			(xy 369.241824 -280.639298) (xy 369.22624 -280.685979) (xy 369.203369 -280.729556) (xy 369.173804 -280.7689)
			(xy 369.138311 -280.802992) (xy 369.097808 -280.830948) (xy 369.053346 -280.852046) (xy 369.006075 -280.865738)
			(xy 368.95722 -280.87167) (xy 368.908045 -280.869689) (xy 368.859826 -280.859845) (xy 368.81381 -280.842393)
			(xy 368.771189 -280.817786) (xy 368.733068 -280.786661) (xy 368.700433 -280.749824) (xy 368.67413 -280.708228)
			(xy 368.654839 -280.662952) (xy 368.643062 -280.615168) (xy 368.639102 -280.566114) (xy 368.31016 -280.566114)
			(xy 368.309665 -280.590721) (xy 368.30177 -280.639298) (xy 368.286186 -280.685979) (xy 368.263315 -280.729556)
			(xy 368.23375 -280.7689) (xy 368.198257 -280.802992) (xy 368.157754 -280.830948) (xy 368.113292 -280.852046)
			(xy 368.066021 -280.865738) (xy 368.017166 -280.87167) (xy 367.967991 -280.869689) (xy 367.919772 -280.859845)
			(xy 367.873756 -280.842393) (xy 367.831135 -280.817786) (xy 367.793014 -280.786661) (xy 367.760379 -280.749824)
			(xy 367.734076 -280.708228) (xy 367.714785 -280.662952) (xy 367.703008 -280.615168) (xy 367.699048 -280.566114)
			(xy 367.370106 -280.566114) (xy 367.369611 -280.590721) (xy 367.361716 -280.639298) (xy 367.346132 -280.685979)
			(xy 367.323261 -280.729556) (xy 367.293696 -280.7689) (xy 367.258203 -280.802992) (xy 367.2177 -280.830948)
			(xy 367.173238 -280.852046) (xy 367.125967 -280.865738) (xy 367.077112 -280.87167) (xy 367.027937 -280.869689)
			(xy 366.979718 -280.859845) (xy 366.933702 -280.842393) (xy 366.891081 -280.817786) (xy 366.85296 -280.786661)
			(xy 366.820325 -280.749824) (xy 366.794022 -280.708228) (xy 366.774731 -280.662952) (xy 366.762954 -280.615168)
			(xy 366.758994 -280.566114) (xy 366.430052 -280.566114) (xy 366.429557 -280.590721) (xy 366.421662 -280.639298)
			(xy 366.406078 -280.685979) (xy 366.383207 -280.729556) (xy 366.353642 -280.7689) (xy 366.318149 -280.802992)
			(xy 366.277646 -280.830948) (xy 366.233184 -280.852046) (xy 366.185913 -280.865738) (xy 366.137058 -280.87167)
			(xy 366.087883 -280.869689) (xy 366.039664 -280.859845) (xy 365.993648 -280.842393) (xy 365.951027 -280.817786)
			(xy 365.912906 -280.786661) (xy 365.880271 -280.749824) (xy 365.853968 -280.708228) (xy 365.834677 -280.662952)
			(xy 365.8229 -280.615168) (xy 365.81894 -280.566114) (xy 365.489998 -280.566114) (xy 365.489503 -280.590721)
			(xy 365.481608 -280.639298) (xy 365.466024 -280.685979) (xy 365.443153 -280.729556) (xy 365.413588 -280.7689)
			(xy 365.378095 -280.802992) (xy 365.337592 -280.830948) (xy 365.29313 -280.852046) (xy 365.245859 -280.865738)
			(xy 365.197004 -280.87167) (xy 365.147829 -280.869689) (xy 365.09961 -280.859845) (xy 365.053594 -280.842393)
			(xy 365.010973 -280.817786) (xy 364.972852 -280.786661) (xy 364.940217 -280.749824) (xy 364.913914 -280.708228)
			(xy 364.894623 -280.662952) (xy 364.882846 -280.615168) (xy 364.878886 -280.566114) (xy 364.550198 -280.566114)
			(xy 364.549703 -280.590721) (xy 364.541808 -280.639298) (xy 364.526224 -280.685979) (xy 364.503353 -280.729556)
			(xy 364.473788 -280.7689) (xy 364.438295 -280.802992) (xy 364.397792 -280.830948) (xy 364.35333 -280.852046)
			(xy 364.306059 -280.865738) (xy 364.257204 -280.87167) (xy 364.208029 -280.869689) (xy 364.15981 -280.859845)
			(xy 364.113794 -280.842393) (xy 364.071173 -280.817786) (xy 364.033052 -280.786661) (xy 364.000417 -280.749824)
			(xy 363.974114 -280.708228) (xy 363.954823 -280.662952) (xy 363.943046 -280.615168) (xy 363.939086 -280.566114)
			(xy 361.730516 -280.566114) (xy 361.726347 -280.616433) (xy 361.713949 -280.665393) (xy 361.693662 -280.711645)
			(xy 361.66604 -280.753927) (xy 361.631835 -280.791087) (xy 361.591981 -280.82211) (xy 361.547564 -280.846151)
			(xy 361.499797 -280.862553) (xy 361.449981 -280.87087) (xy 361.424728 -280.871422) (xy 361.406063 -280.871187)
			(xy 361.369003 -280.866727) (xy 361.350814 -280.862532) (xy 361.339384 -280.859738) (xy 361.31627 -280.864818)
			(xy 361.24388 -280.923238) (xy 361.235479 -280.930853) (xy 361.22572 -280.951288) (xy 361.225084 -280.962608)
			(xy 361.225084 -280.964386) (xy 361.239168 -281.37612) (xy 361.589078 -281.37612) (xy 361.593038 -281.327066)
			(xy 361.604815 -281.279282) (xy 361.624106 -281.234006) (xy 361.650409 -281.19241) (xy 361.683044 -281.155573)
			(xy 361.721165 -281.124448) (xy 361.763786 -281.099841) (xy 361.809802 -281.082389) (xy 361.858021 -281.072545)
			(xy 361.907196 -281.070564) (xy 361.956051 -281.076496) (xy 362.003322 -281.090188) (xy 362.047784 -281.111286)
			(xy 362.088287 -281.139242) (xy 362.12378 -281.173334) (xy 362.153345 -281.212678) (xy 362.176216 -281.256255)
			(xy 362.1918 -281.302936) (xy 362.199695 -281.351513) (xy 362.20019 -281.37612) (xy 362.528878 -281.37612)
			(xy 362.532838 -281.327066) (xy 362.544615 -281.279282) (xy 362.563906 -281.234006) (xy 362.590209 -281.19241)
			(xy 362.622844 -281.155573) (xy 362.660965 -281.124448) (xy 362.703586 -281.099841) (xy 362.749602 -281.082389)
			(xy 362.797821 -281.072545) (xy 362.846996 -281.070564) (xy 362.895851 -281.076496) (xy 362.943122 -281.090188)
			(xy 362.987584 -281.111286) (xy 363.028087 -281.139242) (xy 363.06358 -281.173334) (xy 363.093145 -281.212678)
			(xy 363.116016 -281.256255) (xy 363.1316 -281.302936) (xy 363.139495 -281.351513) (xy 363.13999 -281.37612)
			(xy 363.468932 -281.37612) (xy 363.472892 -281.327066) (xy 363.484669 -281.279282) (xy 363.50396 -281.234006)
			(xy 363.530263 -281.19241) (xy 363.562898 -281.155573) (xy 363.601019 -281.124448) (xy 363.64364 -281.099841)
			(xy 363.689656 -281.082389) (xy 363.737875 -281.072545) (xy 363.78705 -281.070564) (xy 363.835905 -281.076496)
			(xy 363.883176 -281.090188) (xy 363.927638 -281.111286) (xy 363.968141 -281.139242) (xy 364.003634 -281.173334)
			(xy 364.033199 -281.212678) (xy 364.05607 -281.256255) (xy 364.071654 -281.302936) (xy 364.079549 -281.351513)
			(xy 364.080044 -281.37612) (xy 366.289094 -281.37612) (xy 366.293054 -281.327066) (xy 366.304831 -281.279282)
			(xy 366.324122 -281.234006) (xy 366.350425 -281.19241) (xy 366.38306 -281.155573) (xy 366.421181 -281.124448)
			(xy 366.463802 -281.099841) (xy 366.509818 -281.082389) (xy 366.558037 -281.072545) (xy 366.607212 -281.070564)
			(xy 366.656067 -281.076496) (xy 366.703338 -281.090188) (xy 366.7478 -281.111286) (xy 366.788303 -281.139242)
			(xy 366.823796 -281.173334) (xy 366.853361 -281.212678) (xy 366.876232 -281.256255) (xy 366.891816 -281.302936)
			(xy 366.899711 -281.351513) (xy 366.900206 -281.37612) (xy 369.109002 -281.37612) (xy 369.112962 -281.327066)
			(xy 369.124739 -281.279282) (xy 369.14403 -281.234006) (xy 369.170333 -281.19241) (xy 369.202968 -281.155573)
			(xy 369.241089 -281.124448) (xy 369.28371 -281.099841) (xy 369.329726 -281.082389) (xy 369.377945 -281.072545)
			(xy 369.42712 -281.070564) (xy 369.475975 -281.076496) (xy 369.523246 -281.090188) (xy 369.567708 -281.111286)
			(xy 369.608211 -281.139242) (xy 369.643704 -281.173334) (xy 369.673269 -281.212678) (xy 369.69614 -281.256255)
			(xy 369.711724 -281.302936) (xy 369.719619 -281.351513) (xy 369.720114 -281.37612) (xy 370.038625 -281.37612)
			(xy 370.04272 -281.325392) (xy 370.054899 -281.275978) (xy 370.074847 -281.229158) (xy 370.102048 -281.186144)
			(xy 370.135796 -281.14805) (xy 370.175218 -281.115863) (xy 370.219292 -281.090417) (xy 370.266878 -281.07237)
			(xy 370.316742 -281.06219) (xy 370.367594 -281.060141) (xy 370.418115 -281.066275) (xy 370.466999 -281.080435)
			(xy 370.512978 -281.102252) (xy 370.554862 -281.131162) (xy 370.591566 -281.166417) (xy 370.622139 -281.207103)
			(xy 370.64579 -281.252166) (xy 370.661906 -281.30044) (xy 370.67007 -281.350674) (xy 370.670582 -281.37612)
			(xy 370.978679 -281.37612) (xy 370.982774 -281.325392) (xy 370.994953 -281.275978) (xy 371.014901 -281.229158)
			(xy 371.042102 -281.186144) (xy 371.07585 -281.14805) (xy 371.115272 -281.115863) (xy 371.159346 -281.090417)
			(xy 371.206932 -281.07237) (xy 371.256796 -281.06219) (xy 371.307648 -281.060141) (xy 371.358169 -281.066275)
			(xy 371.407053 -281.080435) (xy 371.453032 -281.102252) (xy 371.494916 -281.131162) (xy 371.53162 -281.166417)
			(xy 371.562193 -281.207103) (xy 371.585844 -281.252166) (xy 371.60196 -281.30044) (xy 371.610124 -281.350674)
			(xy 371.610636 -281.37612) (xy 371.92891 -281.37612) (xy 371.93287 -281.327066) (xy 371.944647 -281.279282)
			(xy 371.963938 -281.234006) (xy 371.990241 -281.19241) (xy 372.022876 -281.155573) (xy 372.060997 -281.124448)
			(xy 372.103618 -281.099841) (xy 372.149634 -281.082389) (xy 372.197853 -281.072545) (xy 372.247028 -281.070564)
			(xy 372.295883 -281.076496) (xy 372.343154 -281.090188) (xy 372.387616 -281.111286) (xy 372.428119 -281.139242)
			(xy 372.463612 -281.173334) (xy 372.493177 -281.212678) (xy 372.516048 -281.256255) (xy 372.531632 -281.302936)
			(xy 372.539527 -281.351513) (xy 372.540022 -281.37612) (xy 372.858533 -281.37612) (xy 372.862628 -281.325392)
			(xy 372.874807 -281.275978) (xy 372.894755 -281.229158) (xy 372.921956 -281.186144) (xy 372.955704 -281.14805)
			(xy 372.995126 -281.115863) (xy 373.0392 -281.090417) (xy 373.086786 -281.07237) (xy 373.13665 -281.06219)
			(xy 373.187502 -281.060141) (xy 373.238023 -281.066275) (xy 373.286907 -281.080435) (xy 373.332886 -281.102252)
			(xy 373.37477 -281.131162) (xy 373.411474 -281.166417) (xy 373.442047 -281.207103) (xy 373.465698 -281.252166)
			(xy 373.481814 -281.30044) (xy 373.489978 -281.350674) (xy 373.49049 -281.37612) (xy 373.798587 -281.37612)
			(xy 373.802682 -281.325392) (xy 373.814861 -281.275978) (xy 373.834809 -281.229158) (xy 373.86201 -281.186144)
			(xy 373.895758 -281.14805) (xy 373.93518 -281.115863) (xy 373.979254 -281.090417) (xy 374.02684 -281.07237)
			(xy 374.076704 -281.06219) (xy 374.127556 -281.060141) (xy 374.178077 -281.066275) (xy 374.226961 -281.080435)
			(xy 374.27294 -281.102252) (xy 374.314824 -281.131162) (xy 374.351528 -281.166417) (xy 374.382101 -281.207103)
			(xy 374.405752 -281.252166) (xy 374.421868 -281.30044) (xy 374.430032 -281.350674) (xy 374.430544 -281.37612)
			(xy 374.430032 -281.401566) (xy 374.421868 -281.4518) (xy 374.405752 -281.500074) (xy 374.382101 -281.545137)
			(xy 374.351528 -281.585823) (xy 374.314824 -281.621078) (xy 374.27294 -281.649988) (xy 374.226961 -281.671805)
			(xy 374.178077 -281.685965) (xy 374.127556 -281.692099) (xy 374.076704 -281.69005) (xy 374.02684 -281.67987)
			(xy 373.979254 -281.661823) (xy 373.93518 -281.636377) (xy 373.895758 -281.60419) (xy 373.86201 -281.566096)
			(xy 373.834809 -281.523082) (xy 373.814861 -281.476262) (xy 373.802682 -281.426848) (xy 373.798587 -281.37612)
			(xy 373.49049 -281.37612) (xy 373.489978 -281.401566) (xy 373.481814 -281.4518) (xy 373.465698 -281.500074)
			(xy 373.442047 -281.545137) (xy 373.411474 -281.585823) (xy 373.37477 -281.621078) (xy 373.332886 -281.649988)
			(xy 373.286907 -281.671805) (xy 373.238023 -281.685965) (xy 373.187502 -281.692099) (xy 373.13665 -281.69005)
			(xy 373.086786 -281.67987) (xy 373.0392 -281.661823) (xy 372.995126 -281.636377) (xy 372.955704 -281.60419)
			(xy 372.921956 -281.566096) (xy 372.894755 -281.523082) (xy 372.874807 -281.476262) (xy 372.862628 -281.426848)
			(xy 372.858533 -281.37612) (xy 372.540022 -281.37612) (xy 372.539527 -281.400727) (xy 372.531632 -281.449304)
			(xy 372.516048 -281.495985) (xy 372.493177 -281.539562) (xy 372.463612 -281.578906) (xy 372.428119 -281.612998)
			(xy 372.387616 -281.640954) (xy 372.343154 -281.662052) (xy 372.295883 -281.675744) (xy 372.247028 -281.681676)
			(xy 372.197853 -281.679695) (xy 372.149634 -281.669851) (xy 372.103618 -281.652399) (xy 372.060997 -281.627792)
			(xy 372.022876 -281.596667) (xy 371.990241 -281.55983) (xy 371.963938 -281.518234) (xy 371.944647 -281.472958)
			(xy 371.93287 -281.425174) (xy 371.92891 -281.37612) (xy 371.610636 -281.37612) (xy 371.610124 -281.401566)
			(xy 371.60196 -281.4518) (xy 371.585844 -281.500074) (xy 371.562193 -281.545137) (xy 371.53162 -281.585823)
			(xy 371.494916 -281.621078) (xy 371.453032 -281.649988) (xy 371.407053 -281.671805) (xy 371.358169 -281.685965)
			(xy 371.307648 -281.692099) (xy 371.256796 -281.69005) (xy 371.206932 -281.67987) (xy 371.159346 -281.661823)
			(xy 371.115272 -281.636377) (xy 371.07585 -281.60419) (xy 371.042102 -281.566096) (xy 371.014901 -281.523082)
			(xy 370.994953 -281.476262) (xy 370.982774 -281.426848) (xy 370.978679 -281.37612) (xy 370.670582 -281.37612)
			(xy 370.67007 -281.401566) (xy 370.661906 -281.4518) (xy 370.64579 -281.500074) (xy 370.622139 -281.545137)
			(xy 370.591566 -281.585823) (xy 370.554862 -281.621078) (xy 370.512978 -281.649988) (xy 370.466999 -281.671805)
			(xy 370.418115 -281.685965) (xy 370.367594 -281.692099) (xy 370.316742 -281.69005) (xy 370.266878 -281.67987)
			(xy 370.219292 -281.661823) (xy 370.175218 -281.636377) (xy 370.135796 -281.60419) (xy 370.102048 -281.566096)
			(xy 370.074847 -281.523082) (xy 370.054899 -281.476262) (xy 370.04272 -281.426848) (xy 370.038625 -281.37612)
			(xy 369.720114 -281.37612) (xy 369.719619 -281.400727) (xy 369.711724 -281.449304) (xy 369.69614 -281.495985)
			(xy 369.673269 -281.539562) (xy 369.643704 -281.578906) (xy 369.608211 -281.612998) (xy 369.567708 -281.640954)
			(xy 369.523246 -281.662052) (xy 369.475975 -281.675744) (xy 369.42712 -281.681676) (xy 369.377945 -281.679695)
			(xy 369.329726 -281.669851) (xy 369.28371 -281.652399) (xy 369.241089 -281.627792) (xy 369.202968 -281.596667)
			(xy 369.170333 -281.55983) (xy 369.14403 -281.518234) (xy 369.124739 -281.472958) (xy 369.112962 -281.425174)
			(xy 369.109002 -281.37612) (xy 366.900206 -281.37612) (xy 366.899711 -281.400727) (xy 366.891816 -281.449304)
			(xy 366.876232 -281.495985) (xy 366.853361 -281.539562) (xy 366.823796 -281.578906) (xy 366.788303 -281.612998)
			(xy 366.7478 -281.640954) (xy 366.703338 -281.662052) (xy 366.656067 -281.675744) (xy 366.607212 -281.681676)
			(xy 366.558037 -281.679695) (xy 366.509818 -281.669851) (xy 366.463802 -281.652399) (xy 366.421181 -281.627792)
			(xy 366.38306 -281.596667) (xy 366.350425 -281.55983) (xy 366.324122 -281.518234) (xy 366.304831 -281.472958)
			(xy 366.293054 -281.425174) (xy 366.289094 -281.37612) (xy 364.080044 -281.37612) (xy 364.079549 -281.400727)
			(xy 364.071654 -281.449304) (xy 364.05607 -281.495985) (xy 364.033199 -281.539562) (xy 364.003634 -281.578906)
			(xy 363.968141 -281.612998) (xy 363.927638 -281.640954) (xy 363.883176 -281.662052) (xy 363.835905 -281.675744)
			(xy 363.78705 -281.681676) (xy 363.737875 -281.679695) (xy 363.689656 -281.669851) (xy 363.64364 -281.652399)
			(xy 363.601019 -281.627792) (xy 363.562898 -281.596667) (xy 363.530263 -281.55983) (xy 363.50396 -281.518234)
			(xy 363.484669 -281.472958) (xy 363.472892 -281.425174) (xy 363.468932 -281.37612) (xy 363.13999 -281.37612)
			(xy 363.139495 -281.400727) (xy 363.1316 -281.449304) (xy 363.116016 -281.495985) (xy 363.093145 -281.539562)
			(xy 363.06358 -281.578906) (xy 363.028087 -281.612998) (xy 362.987584 -281.640954) (xy 362.943122 -281.662052)
			(xy 362.895851 -281.675744) (xy 362.846996 -281.681676) (xy 362.797821 -281.679695) (xy 362.749602 -281.669851)
			(xy 362.703586 -281.652399) (xy 362.660965 -281.627792) (xy 362.622844 -281.596667) (xy 362.590209 -281.55983)
			(xy 362.563906 -281.518234) (xy 362.544615 -281.472958) (xy 362.532838 -281.425174) (xy 362.528878 -281.37612)
			(xy 362.20019 -281.37612) (xy 362.199695 -281.400727) (xy 362.1918 -281.449304) (xy 362.176216 -281.495985)
			(xy 362.153345 -281.539562) (xy 362.12378 -281.578906) (xy 362.088287 -281.612998) (xy 362.047784 -281.640954)
			(xy 362.003322 -281.662052) (xy 361.956051 -281.675744) (xy 361.907196 -281.681676) (xy 361.858021 -281.679695)
			(xy 361.809802 -281.669851) (xy 361.763786 -281.652399) (xy 361.721165 -281.627792) (xy 361.683044 -281.596667)
			(xy 361.650409 -281.55983) (xy 361.624106 -281.518234) (xy 361.604815 -281.472958) (xy 361.593038 -281.425174)
			(xy 361.589078 -281.37612) (xy 361.239168 -281.37612) (xy 361.253278 -281.788616) (xy 361.2538 -281.796414)
			(xy 361.258985 -281.811148) (xy 361.263438 -281.817572) (xy 361.267248 -281.822398) (xy 361.340146 -281.881834)
			(xy 361.361228 -281.887168) (xy 361.372404 -281.88539) (xy 361.385381 -281.883265) (xy 361.411579 -281.880973)
			(xy 361.424728 -281.880818) (xy 361.44998 -281.881342) (xy 361.499794 -281.889658) (xy 361.547559 -281.90606)
			(xy 361.591974 -281.9301) (xy 361.631827 -281.961122) (xy 361.66603 -281.99828) (xy 361.693652 -282.040561)
			(xy 361.713938 -282.086811) (xy 361.726335 -282.135769) (xy 361.730505 -282.1861) (xy 361.730503 -282.186126)
			(xy 362.048547 -282.186126) (xy 362.052642 -282.135398) (xy 362.064821 -282.085984) (xy 362.084769 -282.039164)
			(xy 362.11197 -281.99615) (xy 362.145718 -281.958056) (xy 362.18514 -281.925869) (xy 362.229214 -281.900423)
			(xy 362.2768 -281.882376) (xy 362.326664 -281.872196) (xy 362.377516 -281.870147) (xy 362.428037 -281.876281)
			(xy 362.476921 -281.890441) (xy 362.5229 -281.912258) (xy 362.564784 -281.941168) (xy 362.601488 -281.976423)
			(xy 362.632061 -282.017109) (xy 362.655712 -282.062172) (xy 362.671828 -282.110446) (xy 362.679992 -282.16068)
			(xy 362.680504 -282.186126) (xy 362.988601 -282.186126) (xy 362.992696 -282.135398) (xy 363.004875 -282.085984)
			(xy 363.024823 -282.039164) (xy 363.052024 -281.99615) (xy 363.085772 -281.958056) (xy 363.125194 -281.925869)
			(xy 363.169268 -281.900423) (xy 363.216854 -281.882376) (xy 363.266718 -281.872196) (xy 363.31757 -281.870147)
			(xy 363.368091 -281.876281) (xy 363.416975 -281.890441) (xy 363.462954 -281.912258) (xy 363.504838 -281.941168)
			(xy 363.541542 -281.976423) (xy 363.572115 -282.017109) (xy 363.595766 -282.062172) (xy 363.611882 -282.110446)
			(xy 363.620046 -282.16068) (xy 363.620558 -282.186126) (xy 363.939086 -282.186126) (xy 363.943046 -282.137072)
			(xy 363.954823 -282.089288) (xy 363.974114 -282.044012) (xy 364.000417 -282.002416) (xy 364.033052 -281.965579)
			(xy 364.071173 -281.934454) (xy 364.113794 -281.909847) (xy 364.15981 -281.892395) (xy 364.208029 -281.882551)
			(xy 364.257204 -281.88057) (xy 364.306059 -281.886502) (xy 364.35333 -281.900194) (xy 364.397792 -281.921292)
			(xy 364.438295 -281.949248) (xy 364.473788 -281.98334) (xy 364.503353 -282.022684) (xy 364.526224 -282.066261)
			(xy 364.541808 -282.112942) (xy 364.549703 -282.161519) (xy 364.550198 -282.186126) (xy 364.878886 -282.186126)
			(xy 364.882846 -282.137072) (xy 364.894623 -282.089288) (xy 364.913914 -282.044012) (xy 364.940217 -282.002416)
			(xy 364.972852 -281.965579) (xy 365.010973 -281.934454) (xy 365.053594 -281.909847) (xy 365.09961 -281.892395)
			(xy 365.147829 -281.882551) (xy 365.197004 -281.88057) (xy 365.245859 -281.886502) (xy 365.29313 -281.900194)
			(xy 365.337592 -281.921292) (xy 365.378095 -281.949248) (xy 365.413588 -281.98334) (xy 365.443153 -282.022684)
			(xy 365.466024 -282.066261) (xy 365.481608 -282.112942) (xy 365.489503 -282.161519) (xy 365.489998 -282.186126)
			(xy 365.81894 -282.186126) (xy 365.8229 -282.137072) (xy 365.834677 -282.089288) (xy 365.853968 -282.044012)
			(xy 365.880271 -282.002416) (xy 365.912906 -281.965579) (xy 365.951027 -281.934454) (xy 365.993648 -281.909847)
			(xy 366.039664 -281.892395) (xy 366.087883 -281.882551) (xy 366.137058 -281.88057) (xy 366.185913 -281.886502)
			(xy 366.233184 -281.900194) (xy 366.277646 -281.921292) (xy 366.318149 -281.949248) (xy 366.353642 -281.98334)
			(xy 366.383207 -282.022684) (xy 366.406078 -282.066261) (xy 366.421662 -282.112942) (xy 366.429557 -282.161519)
			(xy 366.430052 -282.186126) (xy 366.758994 -282.186126) (xy 366.762954 -282.137072) (xy 366.774731 -282.089288)
			(xy 366.794022 -282.044012) (xy 366.820325 -282.002416) (xy 366.85296 -281.965579) (xy 366.891081 -281.934454)
			(xy 366.933702 -281.909847) (xy 366.979718 -281.892395) (xy 367.027937 -281.882551) (xy 367.077112 -281.88057)
			(xy 367.125967 -281.886502) (xy 367.173238 -281.900194) (xy 367.2177 -281.921292) (xy 367.258203 -281.949248)
			(xy 367.293696 -281.98334) (xy 367.323261 -282.022684) (xy 367.346132 -282.066261) (xy 367.361716 -282.112942)
			(xy 367.369611 -282.161519) (xy 367.370106 -282.186126) (xy 367.699048 -282.186126) (xy 367.703008 -282.137072)
			(xy 367.714785 -282.089288) (xy 367.734076 -282.044012) (xy 367.760379 -282.002416) (xy 367.793014 -281.965579)
			(xy 367.831135 -281.934454) (xy 367.873756 -281.909847) (xy 367.919772 -281.892395) (xy 367.967991 -281.882551)
			(xy 368.017166 -281.88057) (xy 368.066021 -281.886502) (xy 368.113292 -281.900194) (xy 368.157754 -281.921292)
			(xy 368.198257 -281.949248) (xy 368.23375 -281.98334) (xy 368.263315 -282.022684) (xy 368.286186 -282.066261)
			(xy 368.30177 -282.112942) (xy 368.309665 -282.161519) (xy 368.31016 -282.186126) (xy 368.639102 -282.186126)
			(xy 368.643062 -282.137072) (xy 368.654839 -282.089288) (xy 368.67413 -282.044012) (xy 368.700433 -282.002416)
			(xy 368.733068 -281.965579) (xy 368.771189 -281.934454) (xy 368.81381 -281.909847) (xy 368.859826 -281.892395)
			(xy 368.908045 -281.882551) (xy 368.95722 -281.88057) (xy 369.006075 -281.886502) (xy 369.053346 -281.900194)
			(xy 369.097808 -281.921292) (xy 369.138311 -281.949248) (xy 369.173804 -281.98334) (xy 369.203369 -282.022684)
			(xy 369.22624 -282.066261) (xy 369.241824 -282.112942) (xy 369.249719 -282.161519) (xy 369.250214 -282.186126)
			(xy 369.578902 -282.186126) (xy 369.582862 -282.137072) (xy 369.594639 -282.089288) (xy 369.61393 -282.044012)
			(xy 369.640233 -282.002416) (xy 369.672868 -281.965579) (xy 369.710989 -281.934454) (xy 369.75361 -281.909847)
			(xy 369.799626 -281.892395) (xy 369.847845 -281.882551) (xy 369.89702 -281.88057) (xy 369.945875 -281.886502)
			(xy 369.993146 -281.900194) (xy 370.037608 -281.921292) (xy 370.078111 -281.949248) (xy 370.113604 -281.98334)
			(xy 370.143169 -282.022684) (xy 370.16604 -282.066261) (xy 370.181624 -282.112942) (xy 370.189519 -282.161519)
			(xy 370.190014 -282.186126) (xy 370.518956 -282.186126) (xy 370.522916 -282.137072) (xy 370.534693 -282.089288)
			(xy 370.553984 -282.044012) (xy 370.580287 -282.002416) (xy 370.612922 -281.965579) (xy 370.651043 -281.934454)
			(xy 370.693664 -281.909847) (xy 370.73968 -281.892395) (xy 370.787899 -281.882551) (xy 370.837074 -281.88057)
			(xy 370.885929 -281.886502) (xy 370.9332 -281.900194) (xy 370.977662 -281.921292) (xy 371.018165 -281.949248)
			(xy 371.053658 -281.98334) (xy 371.083223 -282.022684) (xy 371.106094 -282.066261) (xy 371.121678 -282.112942)
			(xy 371.129573 -282.161519) (xy 371.130068 -282.186126) (xy 371.45901 -282.186126) (xy 371.46297 -282.137072)
			(xy 371.474747 -282.089288) (xy 371.494038 -282.044012) (xy 371.520341 -282.002416) (xy 371.552976 -281.965579)
			(xy 371.591097 -281.934454) (xy 371.633718 -281.909847) (xy 371.679734 -281.892395) (xy 371.727953 -281.882551)
			(xy 371.777128 -281.88057) (xy 371.825983 -281.886502) (xy 371.873254 -281.900194) (xy 371.917716 -281.921292)
			(xy 371.958219 -281.949248) (xy 371.993712 -281.98334) (xy 372.023277 -282.022684) (xy 372.046148 -282.066261)
			(xy 372.061732 -282.112942) (xy 372.069627 -282.161519) (xy 372.070122 -282.186126) (xy 372.399064 -282.186126)
			(xy 372.403024 -282.137072) (xy 372.414801 -282.089288) (xy 372.434092 -282.044012) (xy 372.460395 -282.002416)
			(xy 372.49303 -281.965579) (xy 372.531151 -281.934454) (xy 372.573772 -281.909847) (xy 372.619788 -281.892395)
			(xy 372.668007 -281.882551) (xy 372.717182 -281.88057) (xy 372.766037 -281.886502) (xy 372.813308 -281.900194)
			(xy 372.85777 -281.921292) (xy 372.898273 -281.949248) (xy 372.933766 -281.98334) (xy 372.963331 -282.022684)
			(xy 372.986202 -282.066261) (xy 373.001786 -282.112942) (xy 373.009681 -282.161519) (xy 373.010176 -282.186126)
			(xy 373.339118 -282.186126) (xy 373.343078 -282.137072) (xy 373.354855 -282.089288) (xy 373.374146 -282.044012)
			(xy 373.400449 -282.002416) (xy 373.433084 -281.965579) (xy 373.471205 -281.934454) (xy 373.513826 -281.909847)
			(xy 373.559842 -281.892395) (xy 373.608061 -281.882551) (xy 373.657236 -281.88057) (xy 373.706091 -281.886502)
			(xy 373.753362 -281.900194) (xy 373.797824 -281.921292) (xy 373.838327 -281.949248) (xy 373.87382 -281.98334)
			(xy 373.903385 -282.022684) (xy 373.926256 -282.066261) (xy 373.94184 -282.112942) (xy 373.949735 -282.161519)
			(xy 373.95023 -282.186126) (xy 373.949735 -282.210733) (xy 373.94184 -282.25931) (xy 373.926256 -282.305991)
			(xy 373.903385 -282.349568) (xy 373.87382 -282.388912) (xy 373.838327 -282.423004) (xy 373.797824 -282.45096)
			(xy 373.753362 -282.472058) (xy 373.706091 -282.48575) (xy 373.657236 -282.491682) (xy 373.608061 -282.489701)
			(xy 373.559842 -282.479857) (xy 373.513826 -282.462405) (xy 373.471205 -282.437798) (xy 373.433084 -282.406673)
			(xy 373.400449 -282.369836) (xy 373.374146 -282.32824) (xy 373.354855 -282.282964) (xy 373.343078 -282.23518)
			(xy 373.339118 -282.186126) (xy 373.010176 -282.186126) (xy 373.009681 -282.210733) (xy 373.001786 -282.25931)
			(xy 372.986202 -282.305991) (xy 372.963331 -282.349568) (xy 372.933766 -282.388912) (xy 372.898273 -282.423004)
			(xy 372.85777 -282.45096) (xy 372.813308 -282.472058) (xy 372.766037 -282.48575) (xy 372.717182 -282.491682)
			(xy 372.668007 -282.489701) (xy 372.619788 -282.479857) (xy 372.573772 -282.462405) (xy 372.531151 -282.437798)
			(xy 372.49303 -282.406673) (xy 372.460395 -282.369836) (xy 372.434092 -282.32824) (xy 372.414801 -282.282964)
			(xy 372.403024 -282.23518) (xy 372.399064 -282.186126) (xy 372.070122 -282.186126) (xy 372.069627 -282.210733)
			(xy 372.061732 -282.25931) (xy 372.046148 -282.305991) (xy 372.023277 -282.349568) (xy 371.993712 -282.388912)
			(xy 371.958219 -282.423004) (xy 371.917716 -282.45096) (xy 371.873254 -282.472058) (xy 371.825983 -282.48575)
			(xy 371.777128 -282.491682) (xy 371.727953 -282.489701) (xy 371.679734 -282.479857) (xy 371.633718 -282.462405)
			(xy 371.591097 -282.437798) (xy 371.552976 -282.406673) (xy 371.520341 -282.369836) (xy 371.494038 -282.32824)
			(xy 371.474747 -282.282964) (xy 371.46297 -282.23518) (xy 371.45901 -282.186126) (xy 371.130068 -282.186126)
			(xy 371.129573 -282.210733) (xy 371.121678 -282.25931) (xy 371.106094 -282.305991) (xy 371.083223 -282.349568)
			(xy 371.053658 -282.388912) (xy 371.018165 -282.423004) (xy 370.977662 -282.45096) (xy 370.9332 -282.472058)
			(xy 370.885929 -282.48575) (xy 370.837074 -282.491682) (xy 370.787899 -282.489701) (xy 370.73968 -282.479857)
			(xy 370.693664 -282.462405) (xy 370.651043 -282.437798) (xy 370.612922 -282.406673) (xy 370.580287 -282.369836)
			(xy 370.553984 -282.32824) (xy 370.534693 -282.282964) (xy 370.522916 -282.23518) (xy 370.518956 -282.186126)
			(xy 370.190014 -282.186126) (xy 370.189519 -282.210733) (xy 370.181624 -282.25931) (xy 370.16604 -282.305991)
			(xy 370.143169 -282.349568) (xy 370.113604 -282.388912) (xy 370.078111 -282.423004) (xy 370.037608 -282.45096)
			(xy 369.993146 -282.472058) (xy 369.945875 -282.48575) (xy 369.89702 -282.491682) (xy 369.847845 -282.489701)
			(xy 369.799626 -282.479857) (xy 369.75361 -282.462405) (xy 369.710989 -282.437798) (xy 369.672868 -282.406673)
			(xy 369.640233 -282.369836) (xy 369.61393 -282.32824) (xy 369.594639 -282.282964) (xy 369.582862 -282.23518)
			(xy 369.578902 -282.186126) (xy 369.250214 -282.186126) (xy 369.249719 -282.210733) (xy 369.241824 -282.25931)
			(xy 369.22624 -282.305991) (xy 369.203369 -282.349568) (xy 369.173804 -282.388912) (xy 369.138311 -282.423004)
			(xy 369.097808 -282.45096) (xy 369.053346 -282.472058) (xy 369.006075 -282.48575) (xy 368.95722 -282.491682)
			(xy 368.908045 -282.489701) (xy 368.859826 -282.479857) (xy 368.81381 -282.462405) (xy 368.771189 -282.437798)
			(xy 368.733068 -282.406673) (xy 368.700433 -282.369836) (xy 368.67413 -282.32824) (xy 368.654839 -282.282964)
			(xy 368.643062 -282.23518) (xy 368.639102 -282.186126) (xy 368.31016 -282.186126) (xy 368.309665 -282.210733)
			(xy 368.30177 -282.25931) (xy 368.286186 -282.305991) (xy 368.263315 -282.349568) (xy 368.23375 -282.388912)
			(xy 368.198257 -282.423004) (xy 368.157754 -282.45096) (xy 368.113292 -282.472058) (xy 368.066021 -282.48575)
			(xy 368.017166 -282.491682) (xy 367.967991 -282.489701) (xy 367.919772 -282.479857) (xy 367.873756 -282.462405)
			(xy 367.831135 -282.437798) (xy 367.793014 -282.406673) (xy 367.760379 -282.369836) (xy 367.734076 -282.32824)
			(xy 367.714785 -282.282964) (xy 367.703008 -282.23518) (xy 367.699048 -282.186126) (xy 367.370106 -282.186126)
			(xy 367.369611 -282.210733) (xy 367.361716 -282.25931) (xy 367.346132 -282.305991) (xy 367.323261 -282.349568)
			(xy 367.293696 -282.388912) (xy 367.258203 -282.423004) (xy 367.2177 -282.45096) (xy 367.173238 -282.472058)
			(xy 367.125967 -282.48575) (xy 367.077112 -282.491682) (xy 367.027937 -282.489701) (xy 366.979718 -282.479857)
			(xy 366.933702 -282.462405) (xy 366.891081 -282.437798) (xy 366.85296 -282.406673) (xy 366.820325 -282.369836)
			(xy 366.794022 -282.32824) (xy 366.774731 -282.282964) (xy 366.762954 -282.23518) (xy 366.758994 -282.186126)
			(xy 366.430052 -282.186126) (xy 366.429557 -282.210733) (xy 366.421662 -282.25931) (xy 366.406078 -282.305991)
			(xy 366.383207 -282.349568) (xy 366.353642 -282.388912) (xy 366.318149 -282.423004) (xy 366.277646 -282.45096)
			(xy 366.233184 -282.472058) (xy 366.185913 -282.48575) (xy 366.137058 -282.491682) (xy 366.087883 -282.489701)
			(xy 366.039664 -282.479857) (xy 365.993648 -282.462405) (xy 365.951027 -282.437798) (xy 365.912906 -282.406673)
			(xy 365.880271 -282.369836) (xy 365.853968 -282.32824) (xy 365.834677 -282.282964) (xy 365.8229 -282.23518)
			(xy 365.81894 -282.186126) (xy 365.489998 -282.186126) (xy 365.489503 -282.210733) (xy 365.481608 -282.25931)
			(xy 365.466024 -282.305991) (xy 365.443153 -282.349568) (xy 365.413588 -282.388912) (xy 365.378095 -282.423004)
			(xy 365.337592 -282.45096) (xy 365.29313 -282.472058) (xy 365.245859 -282.48575) (xy 365.197004 -282.491682)
			(xy 365.147829 -282.489701) (xy 365.09961 -282.479857) (xy 365.053594 -282.462405) (xy 365.010973 -282.437798)
			(xy 364.972852 -282.406673) (xy 364.940217 -282.369836) (xy 364.913914 -282.32824) (xy 364.894623 -282.282964)
			(xy 364.882846 -282.23518) (xy 364.878886 -282.186126) (xy 364.550198 -282.186126) (xy 364.549703 -282.210733)
			(xy 364.541808 -282.25931) (xy 364.526224 -282.305991) (xy 364.503353 -282.349568) (xy 364.473788 -282.388912)
			(xy 364.438295 -282.423004) (xy 364.397792 -282.45096) (xy 364.35333 -282.472058) (xy 364.306059 -282.48575)
			(xy 364.257204 -282.491682) (xy 364.208029 -282.489701) (xy 364.15981 -282.479857) (xy 364.113794 -282.462405)
			(xy 364.071173 -282.437798) (xy 364.033052 -282.406673) (xy 364.000417 -282.369836) (xy 363.974114 -282.32824)
			(xy 363.954823 -282.282964) (xy 363.943046 -282.23518) (xy 363.939086 -282.186126) (xy 363.620558 -282.186126)
			(xy 363.620046 -282.211572) (xy 363.611882 -282.261806) (xy 363.595766 -282.31008) (xy 363.572115 -282.355143)
			(xy 363.541542 -282.395829) (xy 363.504838 -282.431084) (xy 363.462954 -282.459994) (xy 363.416975 -282.481811)
			(xy 363.368091 -282.495971) (xy 363.31757 -282.502105) (xy 363.266718 -282.500056) (xy 363.216854 -282.489876)
			(xy 363.169268 -282.471829) (xy 363.125194 -282.446383) (xy 363.085772 -282.414196) (xy 363.052024 -282.376102)
			(xy 363.024823 -282.333088) (xy 363.004875 -282.286268) (xy 362.992696 -282.236854) (xy 362.988601 -282.186126)
			(xy 362.680504 -282.186126) (xy 362.679992 -282.211572) (xy 362.671828 -282.261806) (xy 362.655712 -282.31008)
			(xy 362.632061 -282.355143) (xy 362.601488 -282.395829) (xy 362.564784 -282.431084) (xy 362.5229 -282.459994)
			(xy 362.476921 -282.481811) (xy 362.428037 -282.495971) (xy 362.377516 -282.502105) (xy 362.326664 -282.500056)
			(xy 362.2768 -282.489876) (xy 362.229214 -282.471829) (xy 362.18514 -282.446383) (xy 362.145718 -282.414196)
			(xy 362.11197 -282.376102) (xy 362.084769 -282.333088) (xy 362.064821 -282.286268) (xy 362.052642 -282.236854)
			(xy 362.048547 -282.186126) (xy 361.730503 -282.186126) (xy 361.726335 -282.236431) (xy 361.713938 -282.285389)
			(xy 361.693652 -282.331639) (xy 361.66603 -282.37392) (xy 361.631827 -282.411078) (xy 361.591974 -282.4421)
			(xy 361.547559 -282.46614) (xy 361.499794 -282.482542) (xy 361.44998 -282.490858) (xy 361.424728 -282.491434)
			(xy 361.392978 -282.489656) (xy 361.381802 -282.48864) (xy 361.361228 -282.495498) (xy 361.334304 -282.520644)
			(xy 361.29722 -282.555442) (xy 361.289566 -282.563237) (xy 361.281162 -282.583379) (xy 361.280964 -282.594304)
			(xy 361.294554 -282.996132) (xy 363.468932 -282.996132) (xy 363.472892 -282.947078) (xy 363.484669 -282.899294)
			(xy 363.50396 -282.854018) (xy 363.530263 -282.812422) (xy 363.562898 -282.775585) (xy 363.601019 -282.74446)
			(xy 363.64364 -282.719853) (xy 363.689656 -282.702401) (xy 363.737875 -282.692557) (xy 363.78705 -282.690576)
			(xy 363.835905 -282.696508) (xy 363.883176 -282.7102) (xy 363.927638 -282.731298) (xy 363.968141 -282.759254)
			(xy 364.003634 -282.793346) (xy 364.033199 -282.83269) (xy 364.05607 -282.876267) (xy 364.071654 -282.922948)
			(xy 364.079549 -282.971525) (xy 364.080044 -282.996132) (xy 364.398555 -282.996132) (xy 364.40265 -282.945404)
			(xy 364.414829 -282.89599) (xy 364.434777 -282.84917) (xy 364.461978 -282.806156) (xy 364.495726 -282.768062)
			(xy 364.535148 -282.735875) (xy 364.579222 -282.710429) (xy 364.626808 -282.692382) (xy 364.676672 -282.682202)
			(xy 364.727524 -282.680153) (xy 364.778045 -282.686287) (xy 364.826929 -282.700447) (xy 364.872908 -282.722264)
			(xy 364.914792 -282.751174) (xy 364.951496 -282.786429) (xy 364.982069 -282.827115) (xy 365.00572 -282.872178)
			(xy 365.021836 -282.920452) (xy 365.03 -282.970686) (xy 365.030512 -282.996132) (xy 365.338609 -282.996132)
			(xy 365.342704 -282.945404) (xy 365.354883 -282.89599) (xy 365.374831 -282.84917) (xy 365.402032 -282.806156)
			(xy 365.43578 -282.768062) (xy 365.475202 -282.735875) (xy 365.519276 -282.710429) (xy 365.566862 -282.692382)
			(xy 365.616726 -282.682202) (xy 365.667578 -282.680153) (xy 365.718099 -282.686287) (xy 365.766983 -282.700447)
			(xy 365.812962 -282.722264) (xy 365.854846 -282.751174) (xy 365.89155 -282.786429) (xy 365.922123 -282.827115)
			(xy 365.945774 -282.872178) (xy 365.96189 -282.920452) (xy 365.970054 -282.970686) (xy 365.970566 -282.996132)
			(xy 366.289094 -282.996132) (xy 366.293054 -282.947078) (xy 366.304831 -282.899294) (xy 366.324122 -282.854018)
			(xy 366.350425 -282.812422) (xy 366.38306 -282.775585) (xy 366.421181 -282.74446) (xy 366.463802 -282.719853)
			(xy 366.509818 -282.702401) (xy 366.558037 -282.692557) (xy 366.607212 -282.690576) (xy 366.656067 -282.696508)
			(xy 366.703338 -282.7102) (xy 366.7478 -282.731298) (xy 366.788303 -282.759254) (xy 366.823796 -282.793346)
			(xy 366.853361 -282.83269) (xy 366.876232 -282.876267) (xy 366.891816 -282.922948) (xy 366.899711 -282.971525)
			(xy 366.900206 -282.996132) (xy 367.218463 -282.996132) (xy 367.222558 -282.945404) (xy 367.234737 -282.89599)
			(xy 367.254685 -282.84917) (xy 367.281886 -282.806156) (xy 367.315634 -282.768062) (xy 367.355056 -282.735875)
			(xy 367.39913 -282.710429) (xy 367.446716 -282.692382) (xy 367.49658 -282.682202) (xy 367.547432 -282.680153)
			(xy 367.597953 -282.686287) (xy 367.646837 -282.700447) (xy 367.692816 -282.722264) (xy 367.7347 -282.751174)
			(xy 367.771404 -282.786429) (xy 367.801977 -282.827115) (xy 367.825628 -282.872178) (xy 367.841744 -282.920452)
			(xy 367.849908 -282.970686) (xy 367.85042 -282.996132) (xy 368.158517 -282.996132) (xy 368.162612 -282.945404)
			(xy 368.174791 -282.89599) (xy 368.194739 -282.84917) (xy 368.22194 -282.806156) (xy 368.255688 -282.768062)
			(xy 368.29511 -282.735875) (xy 368.339184 -282.710429) (xy 368.38677 -282.692382) (xy 368.436634 -282.682202)
			(xy 368.487486 -282.680153) (xy 368.538007 -282.686287) (xy 368.586891 -282.700447) (xy 368.63287 -282.722264)
			(xy 368.674754 -282.751174) (xy 368.711458 -282.786429) (xy 368.742031 -282.827115) (xy 368.765682 -282.872178)
			(xy 368.781798 -282.920452) (xy 368.789962 -282.970686) (xy 368.790474 -282.996132) (xy 369.109002 -282.996132)
			(xy 369.112962 -282.947078) (xy 369.124739 -282.899294) (xy 369.14403 -282.854018) (xy 369.170333 -282.812422)
			(xy 369.202968 -282.775585) (xy 369.241089 -282.74446) (xy 369.28371 -282.719853) (xy 369.329726 -282.702401)
			(xy 369.377945 -282.692557) (xy 369.42712 -282.690576) (xy 369.475975 -282.696508) (xy 369.523246 -282.7102)
			(xy 369.567708 -282.731298) (xy 369.608211 -282.759254) (xy 369.643704 -282.793346) (xy 369.673269 -282.83269)
			(xy 369.69614 -282.876267) (xy 369.711724 -282.922948) (xy 369.719619 -282.971525) (xy 369.720114 -282.996132)
			(xy 370.038625 -282.996132) (xy 370.04272 -282.945404) (xy 370.054899 -282.89599) (xy 370.074847 -282.84917)
			(xy 370.102048 -282.806156) (xy 370.135796 -282.768062) (xy 370.175218 -282.735875) (xy 370.219292 -282.710429)
			(xy 370.266878 -282.692382) (xy 370.316742 -282.682202) (xy 370.367594 -282.680153) (xy 370.418115 -282.686287)
			(xy 370.466999 -282.700447) (xy 370.512978 -282.722264) (xy 370.554862 -282.751174) (xy 370.591566 -282.786429)
			(xy 370.622139 -282.827115) (xy 370.64579 -282.872178) (xy 370.661906 -282.920452) (xy 370.67007 -282.970686)
			(xy 370.670582 -282.996132) (xy 370.978679 -282.996132) (xy 370.982774 -282.945404) (xy 370.994953 -282.89599)
			(xy 371.014901 -282.84917) (xy 371.042102 -282.806156) (xy 371.07585 -282.768062) (xy 371.115272 -282.735875)
			(xy 371.159346 -282.710429) (xy 371.206932 -282.692382) (xy 371.256796 -282.682202) (xy 371.307648 -282.680153)
			(xy 371.358169 -282.686287) (xy 371.407053 -282.700447) (xy 371.453032 -282.722264) (xy 371.494916 -282.751174)
			(xy 371.53162 -282.786429) (xy 371.562193 -282.827115) (xy 371.585844 -282.872178) (xy 371.60196 -282.920452)
			(xy 371.610124 -282.970686) (xy 371.610636 -282.996132) (xy 371.92891 -282.996132) (xy 371.93287 -282.947078)
			(xy 371.944647 -282.899294) (xy 371.963938 -282.854018) (xy 371.990241 -282.812422) (xy 372.022876 -282.775585)
			(xy 372.060997 -282.74446) (xy 372.103618 -282.719853) (xy 372.149634 -282.702401) (xy 372.197853 -282.692557)
			(xy 372.247028 -282.690576) (xy 372.295883 -282.696508) (xy 372.343154 -282.7102) (xy 372.387616 -282.731298)
			(xy 372.428119 -282.759254) (xy 372.463612 -282.793346) (xy 372.493177 -282.83269) (xy 372.516048 -282.876267)
			(xy 372.531632 -282.922948) (xy 372.539527 -282.971525) (xy 372.540022 -282.996132) (xy 372.858533 -282.996132)
			(xy 372.862628 -282.945404) (xy 372.874807 -282.89599) (xy 372.894755 -282.84917) (xy 372.921956 -282.806156)
			(xy 372.955704 -282.768062) (xy 372.995126 -282.735875) (xy 373.0392 -282.710429) (xy 373.086786 -282.692382)
			(xy 373.13665 -282.682202) (xy 373.187502 -282.680153) (xy 373.238023 -282.686287) (xy 373.286907 -282.700447)
			(xy 373.332886 -282.722264) (xy 373.37477 -282.751174) (xy 373.411474 -282.786429) (xy 373.442047 -282.827115)
			(xy 373.465698 -282.872178) (xy 373.481814 -282.920452) (xy 373.489978 -282.970686) (xy 373.49049 -282.996132)
			(xy 373.798587 -282.996132) (xy 373.802682 -282.945404) (xy 373.814861 -282.89599) (xy 373.834809 -282.84917)
			(xy 373.86201 -282.806156) (xy 373.895758 -282.768062) (xy 373.93518 -282.735875) (xy 373.979254 -282.710429)
			(xy 374.02684 -282.692382) (xy 374.076704 -282.682202) (xy 374.127556 -282.680153) (xy 374.178077 -282.686287)
			(xy 374.226961 -282.700447) (xy 374.27294 -282.722264) (xy 374.314824 -282.751174) (xy 374.351528 -282.786429)
			(xy 374.382101 -282.827115) (xy 374.405752 -282.872178) (xy 374.421868 -282.920452) (xy 374.430032 -282.970686)
			(xy 374.430544 -282.996132) (xy 374.430032 -283.021578) (xy 374.421868 -283.071812) (xy 374.405752 -283.120086)
			(xy 374.382101 -283.165149) (xy 374.351528 -283.205835) (xy 374.314824 -283.24109) (xy 374.27294 -283.27)
			(xy 374.226961 -283.291817) (xy 374.178077 -283.305977) (xy 374.127556 -283.312111) (xy 374.076704 -283.310062)
			(xy 374.02684 -283.299882) (xy 373.979254 -283.281835) (xy 373.93518 -283.256389) (xy 373.895758 -283.224202)
			(xy 373.86201 -283.186108) (xy 373.834809 -283.143094) (xy 373.814861 -283.096274) (xy 373.802682 -283.04686)
			(xy 373.798587 -282.996132) (xy 373.49049 -282.996132) (xy 373.489978 -283.021578) (xy 373.481814 -283.071812)
			(xy 373.465698 -283.120086) (xy 373.442047 -283.165149) (xy 373.411474 -283.205835) (xy 373.37477 -283.24109)
			(xy 373.332886 -283.27) (xy 373.286907 -283.291817) (xy 373.238023 -283.305977) (xy 373.187502 -283.312111)
			(xy 373.13665 -283.310062) (xy 373.086786 -283.299882) (xy 373.0392 -283.281835) (xy 372.995126 -283.256389)
			(xy 372.955704 -283.224202) (xy 372.921956 -283.186108) (xy 372.894755 -283.143094) (xy 372.874807 -283.096274)
			(xy 372.862628 -283.04686) (xy 372.858533 -282.996132) (xy 372.540022 -282.996132) (xy 372.539527 -283.020739)
			(xy 372.531632 -283.069316) (xy 372.516048 -283.115997) (xy 372.493177 -283.159574) (xy 372.463612 -283.198918)
			(xy 372.428119 -283.23301) (xy 372.387616 -283.260966) (xy 372.343154 -283.282064) (xy 372.295883 -283.295756)
			(xy 372.247028 -283.301688) (xy 372.197853 -283.299707) (xy 372.149634 -283.289863) (xy 372.103618 -283.272411)
			(xy 372.060997 -283.247804) (xy 372.022876 -283.216679) (xy 371.990241 -283.179842) (xy 371.963938 -283.138246)
			(xy 371.944647 -283.09297) (xy 371.93287 -283.045186) (xy 371.92891 -282.996132) (xy 371.610636 -282.996132)
			(xy 371.610124 -283.021578) (xy 371.60196 -283.071812) (xy 371.585844 -283.120086) (xy 371.562193 -283.165149)
			(xy 371.53162 -283.205835) (xy 371.494916 -283.24109) (xy 371.453032 -283.27) (xy 371.407053 -283.291817)
			(xy 371.358169 -283.305977) (xy 371.307648 -283.312111) (xy 371.256796 -283.310062) (xy 371.206932 -283.299882)
			(xy 371.159346 -283.281835) (xy 371.115272 -283.256389) (xy 371.07585 -283.224202) (xy 371.042102 -283.186108)
			(xy 371.014901 -283.143094) (xy 370.994953 -283.096274) (xy 370.982774 -283.04686) (xy 370.978679 -282.996132)
			(xy 370.670582 -282.996132) (xy 370.67007 -283.021578) (xy 370.661906 -283.071812) (xy 370.64579 -283.120086)
			(xy 370.622139 -283.165149) (xy 370.591566 -283.205835) (xy 370.554862 -283.24109) (xy 370.512978 -283.27)
			(xy 370.466999 -283.291817) (xy 370.418115 -283.305977) (xy 370.367594 -283.312111) (xy 370.316742 -283.310062)
			(xy 370.266878 -283.299882) (xy 370.219292 -283.281835) (xy 370.175218 -283.256389) (xy 370.135796 -283.224202)
			(xy 370.102048 -283.186108) (xy 370.074847 -283.143094) (xy 370.054899 -283.096274) (xy 370.04272 -283.04686)
			(xy 370.038625 -282.996132) (xy 369.720114 -282.996132) (xy 369.719619 -283.020739) (xy 369.711724 -283.069316)
			(xy 369.69614 -283.115997) (xy 369.673269 -283.159574) (xy 369.643704 -283.198918) (xy 369.608211 -283.23301)
			(xy 369.567708 -283.260966) (xy 369.523246 -283.282064) (xy 369.475975 -283.295756) (xy 369.42712 -283.301688)
			(xy 369.377945 -283.299707) (xy 369.329726 -283.289863) (xy 369.28371 -283.272411) (xy 369.241089 -283.247804)
			(xy 369.202968 -283.216679) (xy 369.170333 -283.179842) (xy 369.14403 -283.138246) (xy 369.124739 -283.09297)
			(xy 369.112962 -283.045186) (xy 369.109002 -282.996132) (xy 368.790474 -282.996132) (xy 368.789962 -283.021578)
			(xy 368.781798 -283.071812) (xy 368.765682 -283.120086) (xy 368.742031 -283.165149) (xy 368.711458 -283.205835)
			(xy 368.674754 -283.24109) (xy 368.63287 -283.27) (xy 368.586891 -283.291817) (xy 368.538007 -283.305977)
			(xy 368.487486 -283.312111) (xy 368.436634 -283.310062) (xy 368.38677 -283.299882) (xy 368.339184 -283.281835)
			(xy 368.29511 -283.256389) (xy 368.255688 -283.224202) (xy 368.22194 -283.186108) (xy 368.194739 -283.143094)
			(xy 368.174791 -283.096274) (xy 368.162612 -283.04686) (xy 368.158517 -282.996132) (xy 367.85042 -282.996132)
			(xy 367.849908 -283.021578) (xy 367.841744 -283.071812) (xy 367.825628 -283.120086) (xy 367.801977 -283.165149)
			(xy 367.771404 -283.205835) (xy 367.7347 -283.24109) (xy 367.692816 -283.27) (xy 367.646837 -283.291817)
			(xy 367.597953 -283.305977) (xy 367.547432 -283.312111) (xy 367.49658 -283.310062) (xy 367.446716 -283.299882)
			(xy 367.39913 -283.281835) (xy 367.355056 -283.256389) (xy 367.315634 -283.224202) (xy 367.281886 -283.186108)
			(xy 367.254685 -283.143094) (xy 367.234737 -283.096274) (xy 367.222558 -283.04686) (xy 367.218463 -282.996132)
			(xy 366.900206 -282.996132) (xy 366.899711 -283.020739) (xy 366.891816 -283.069316) (xy 366.876232 -283.115997)
			(xy 366.853361 -283.159574) (xy 366.823796 -283.198918) (xy 366.788303 -283.23301) (xy 366.7478 -283.260966)
			(xy 366.703338 -283.282064) (xy 366.656067 -283.295756) (xy 366.607212 -283.301688) (xy 366.558037 -283.299707)
			(xy 366.509818 -283.289863) (xy 366.463802 -283.272411) (xy 366.421181 -283.247804) (xy 366.38306 -283.216679)
			(xy 366.350425 -283.179842) (xy 366.324122 -283.138246) (xy 366.304831 -283.09297) (xy 366.293054 -283.045186)
			(xy 366.289094 -282.996132) (xy 365.970566 -282.996132) (xy 365.970054 -283.021578) (xy 365.96189 -283.071812)
			(xy 365.945774 -283.120086) (xy 365.922123 -283.165149) (xy 365.89155 -283.205835) (xy 365.854846 -283.24109)
			(xy 365.812962 -283.27) (xy 365.766983 -283.291817) (xy 365.718099 -283.305977) (xy 365.667578 -283.312111)
			(xy 365.616726 -283.310062) (xy 365.566862 -283.299882) (xy 365.519276 -283.281835) (xy 365.475202 -283.256389)
			(xy 365.43578 -283.224202) (xy 365.402032 -283.186108) (xy 365.374831 -283.143094) (xy 365.354883 -283.096274)
			(xy 365.342704 -283.04686) (xy 365.338609 -282.996132) (xy 365.030512 -282.996132) (xy 365.03 -283.021578)
			(xy 365.021836 -283.071812) (xy 365.00572 -283.120086) (xy 364.982069 -283.165149) (xy 364.951496 -283.205835)
			(xy 364.914792 -283.24109) (xy 364.872908 -283.27) (xy 364.826929 -283.291817) (xy 364.778045 -283.305977)
			(xy 364.727524 -283.312111) (xy 364.676672 -283.310062) (xy 364.626808 -283.299882) (xy 364.579222 -283.281835)
			(xy 364.535148 -283.256389) (xy 364.495726 -283.224202) (xy 364.461978 -283.186108) (xy 364.434777 -283.143094)
			(xy 364.414829 -283.096274) (xy 364.40265 -283.04686) (xy 364.398555 -282.996132) (xy 364.080044 -282.996132)
			(xy 364.079549 -283.020739) (xy 364.071654 -283.069316) (xy 364.05607 -283.115997) (xy 364.033199 -283.159574)
			(xy 364.003634 -283.198918) (xy 363.968141 -283.23301) (xy 363.927638 -283.260966) (xy 363.883176 -283.282064)
			(xy 363.835905 -283.295756) (xy 363.78705 -283.301688) (xy 363.737875 -283.299707) (xy 363.689656 -283.289863)
			(xy 363.64364 -283.272411) (xy 363.601019 -283.247804) (xy 363.562898 -283.216679) (xy 363.530263 -283.179842)
			(xy 363.50396 -283.138246) (xy 363.484669 -283.09297) (xy 363.472892 -283.045186) (xy 363.468932 -282.996132)
			(xy 361.294554 -282.996132) (xy 361.30865 -283.412946) (xy 361.317032 -283.431234) (xy 361.324398 -283.438092)
			(xy 361.324652 -283.438346) (xy 361.384596 -283.494226) (xy 361.403138 -283.501338) (xy 361.413298 -283.501084)
			(xy 361.424474 -283.50083) (xy 361.424982 -283.50083) (xy 361.448958 -283.501322) (xy 361.496313 -283.508863)
			(xy 361.541907 -283.523716) (xy 361.584618 -283.545515) (xy 361.623395 -283.573724) (xy 361.657284 -283.607649)
			(xy 361.685453 -283.646456) (xy 361.707207 -283.689189) (xy 361.722012 -283.734799) (xy 361.729504 -283.782162)
			(xy 361.730036 -283.806138) (xy 362.048547 -283.806138) (xy 362.052642 -283.75541) (xy 362.064821 -283.705996)
			(xy 362.084769 -283.659176) (xy 362.11197 -283.616162) (xy 362.145718 -283.578068) (xy 362.18514 -283.545881)
			(xy 362.229214 -283.520435) (xy 362.2768 -283.502388) (xy 362.326664 -283.492208) (xy 362.377516 -283.490159)
			(xy 362.428037 -283.496293) (xy 362.476921 -283.510453) (xy 362.5229 -283.53227) (xy 362.564784 -283.56118)
			(xy 362.601488 -283.596435) (xy 362.632061 -283.637121) (xy 362.655712 -283.682184) (xy 362.671828 -283.730458)
			(xy 362.679992 -283.780692) (xy 362.680504 -283.806138) (xy 362.988601 -283.806138) (xy 362.992696 -283.75541)
			(xy 363.004875 -283.705996) (xy 363.024823 -283.659176) (xy 363.052024 -283.616162) (xy 363.085772 -283.578068)
			(xy 363.125194 -283.545881) (xy 363.169268 -283.520435) (xy 363.216854 -283.502388) (xy 363.266718 -283.492208)
			(xy 363.31757 -283.490159) (xy 363.368091 -283.496293) (xy 363.416975 -283.510453) (xy 363.462954 -283.53227)
			(xy 363.504838 -283.56118) (xy 363.541542 -283.596435) (xy 363.572115 -283.637121) (xy 363.595766 -283.682184)
			(xy 363.611882 -283.730458) (xy 363.620046 -283.780692) (xy 363.620558 -283.806138) (xy 363.939086 -283.806138)
			(xy 363.943046 -283.757084) (xy 363.954823 -283.7093) (xy 363.974114 -283.664024) (xy 364.000417 -283.622428)
			(xy 364.033052 -283.585591) (xy 364.071173 -283.554466) (xy 364.113794 -283.529859) (xy 364.15981 -283.512407)
			(xy 364.208029 -283.502563) (xy 364.257204 -283.500582) (xy 364.306059 -283.506514) (xy 364.35333 -283.520206)
			(xy 364.397792 -283.541304) (xy 364.438295 -283.56926) (xy 364.473788 -283.603352) (xy 364.503353 -283.642696)
			(xy 364.526224 -283.686273) (xy 364.541808 -283.732954) (xy 364.549703 -283.781531) (xy 364.550198 -283.806138)
			(xy 366.758994 -283.806138) (xy 366.762954 -283.757084) (xy 366.774731 -283.7093) (xy 366.794022 -283.664024)
			(xy 366.820325 -283.622428) (xy 366.85296 -283.585591) (xy 366.891081 -283.554466) (xy 366.933702 -283.529859)
			(xy 366.979718 -283.512407) (xy 367.027937 -283.502563) (xy 367.077112 -283.500582) (xy 367.125967 -283.506514)
			(xy 367.173238 -283.520206) (xy 367.2177 -283.541304) (xy 367.258203 -283.56926) (xy 367.293696 -283.603352)
			(xy 367.323261 -283.642696) (xy 367.346132 -283.686273) (xy 367.361716 -283.732954) (xy 367.369611 -283.781531)
			(xy 367.370106 -283.806138) (xy 369.578902 -283.806138) (xy 369.582862 -283.757084) (xy 369.594639 -283.7093)
			(xy 369.61393 -283.664024) (xy 369.640233 -283.622428) (xy 369.672868 -283.585591) (xy 369.710989 -283.554466)
			(xy 369.75361 -283.529859) (xy 369.799626 -283.512407) (xy 369.847845 -283.502563) (xy 369.89702 -283.500582)
			(xy 369.945875 -283.506514) (xy 369.993146 -283.520206) (xy 370.037608 -283.541304) (xy 370.078111 -283.56926)
			(xy 370.113604 -283.603352) (xy 370.143169 -283.642696) (xy 370.16604 -283.686273) (xy 370.181624 -283.732954)
			(xy 370.189519 -283.781531) (xy 370.190014 -283.806138) (xy 372.399064 -283.806138) (xy 372.403024 -283.757084)
			(xy 372.414801 -283.7093) (xy 372.434092 -283.664024) (xy 372.460395 -283.622428) (xy 372.49303 -283.585591)
			(xy 372.531151 -283.554466) (xy 372.573772 -283.529859) (xy 372.619788 -283.512407) (xy 372.668007 -283.502563)
			(xy 372.717182 -283.500582) (xy 372.766037 -283.506514) (xy 372.813308 -283.520206) (xy 372.85777 -283.541304)
			(xy 372.898273 -283.56926) (xy 372.933766 -283.603352) (xy 372.963331 -283.642696) (xy 372.986202 -283.686273)
			(xy 373.001786 -283.732954) (xy 373.009681 -283.781531) (xy 373.010176 -283.806138) (xy 373.009681 -283.830745)
			(xy 373.001786 -283.879322) (xy 372.986202 -283.926003) (xy 372.963331 -283.96958) (xy 372.933766 -284.008924)
			(xy 372.898273 -284.043016) (xy 372.85777 -284.070972) (xy 372.813308 -284.09207) (xy 372.766037 -284.105762)
			(xy 372.717182 -284.111694) (xy 372.668007 -284.109713) (xy 372.619788 -284.099869) (xy 372.573772 -284.082417)
			(xy 372.531151 -284.05781) (xy 372.49303 -284.026685) (xy 372.460395 -283.989848) (xy 372.434092 -283.948252)
			(xy 372.414801 -283.902976) (xy 372.403024 -283.855192) (xy 372.399064 -283.806138) (xy 370.190014 -283.806138)
			(xy 370.189519 -283.830745) (xy 370.181624 -283.879322) (xy 370.16604 -283.926003) (xy 370.143169 -283.96958)
			(xy 370.113604 -284.008924) (xy 370.078111 -284.043016) (xy 370.037608 -284.070972) (xy 369.993146 -284.09207)
			(xy 369.945875 -284.105762) (xy 369.89702 -284.111694) (xy 369.847845 -284.109713) (xy 369.799626 -284.099869)
			(xy 369.75361 -284.082417) (xy 369.710989 -284.05781) (xy 369.672868 -284.026685) (xy 369.640233 -283.989848)
			(xy 369.61393 -283.948252) (xy 369.594639 -283.902976) (xy 369.582862 -283.855192) (xy 369.578902 -283.806138)
			(xy 367.370106 -283.806138) (xy 367.369611 -283.830745) (xy 367.361716 -283.879322) (xy 367.346132 -283.926003)
			(xy 367.323261 -283.96958) (xy 367.293696 -284.008924) (xy 367.258203 -284.043016) (xy 367.2177 -284.070972)
			(xy 367.173238 -284.09207) (xy 367.125967 -284.105762) (xy 367.077112 -284.111694) (xy 367.027937 -284.109713)
			(xy 366.979718 -284.099869) (xy 366.933702 -284.082417) (xy 366.891081 -284.05781) (xy 366.85296 -284.026685)
			(xy 366.820325 -283.989848) (xy 366.794022 -283.948252) (xy 366.774731 -283.902976) (xy 366.762954 -283.855192)
			(xy 366.758994 -283.806138) (xy 364.550198 -283.806138) (xy 364.549703 -283.830745) (xy 364.541808 -283.879322)
			(xy 364.526224 -283.926003) (xy 364.503353 -283.96958) (xy 364.473788 -284.008924) (xy 364.438295 -284.043016)
			(xy 364.397792 -284.070972) (xy 364.35333 -284.09207) (xy 364.306059 -284.105762) (xy 364.257204 -284.111694)
			(xy 364.208029 -284.109713) (xy 364.15981 -284.099869) (xy 364.113794 -284.082417) (xy 364.071173 -284.05781)
			(xy 364.033052 -284.026685) (xy 364.000417 -283.989848) (xy 363.974114 -283.948252) (xy 363.954823 -283.902976)
			(xy 363.943046 -283.855192) (xy 363.939086 -283.806138) (xy 363.620558 -283.806138) (xy 363.620046 -283.831584)
			(xy 363.611882 -283.881818) (xy 363.595766 -283.930092) (xy 363.572115 -283.975155) (xy 363.541542 -284.015841)
			(xy 363.504838 -284.051096) (xy 363.462954 -284.080006) (xy 363.416975 -284.101823) (xy 363.368091 -284.115983)
			(xy 363.31757 -284.122117) (xy 363.266718 -284.120068) (xy 363.216854 -284.109888) (xy 363.169268 -284.091841)
			(xy 363.125194 -284.066395) (xy 363.085772 -284.034208) (xy 363.052024 -283.996114) (xy 363.024823 -283.9531)
			(xy 363.004875 -283.90628) (xy 362.992696 -283.856866) (xy 362.988601 -283.806138) (xy 362.680504 -283.806138)
			(xy 362.679992 -283.831584) (xy 362.671828 -283.881818) (xy 362.655712 -283.930092) (xy 362.632061 -283.975155)
			(xy 362.601488 -284.015841) (xy 362.564784 -284.051096) (xy 362.5229 -284.080006) (xy 362.476921 -284.101823)
			(xy 362.428037 -284.115983) (xy 362.377516 -284.122117) (xy 362.326664 -284.120068) (xy 362.2768 -284.109888)
			(xy 362.229214 -284.091841) (xy 362.18514 -284.066395) (xy 362.145718 -284.034208) (xy 362.11197 -283.996114)
			(xy 362.084769 -283.9531) (xy 362.064821 -283.90628) (xy 362.052642 -283.856866) (xy 362.048547 -283.806138)
			(xy 361.730036 -283.806138) (xy 361.729607 -283.829646) (xy 361.722405 -283.876106) (xy 361.708162 -283.920911)
			(xy 361.687216 -283.963002) (xy 361.66006 -284.001382) (xy 361.62734 -284.035142) (xy 361.589828 -284.063484)
			(xy 361.548413 -284.085737) (xy 361.504075 -284.101374) (xy 361.457863 -284.110025) (xy 361.43438 -284.111192)
			(xy 361.423966 -284.1117) (xy 361.405678 -284.120082) (xy 361.398566 -284.127702) (xy 361.350052 -284.179772)
			(xy 361.343469 -284.187407) (xy 361.336392 -284.206267) (xy 361.336336 -284.216348) (xy 361.349989 -284.616144)
			(xy 361.589078 -284.616144) (xy 361.593038 -284.56709) (xy 361.604815 -284.519306) (xy 361.624106 -284.47403)
			(xy 361.650409 -284.432434) (xy 361.683044 -284.395597) (xy 361.721165 -284.364472) (xy 361.763786 -284.339865)
			(xy 361.809802 -284.322413) (xy 361.858021 -284.312569) (xy 361.907196 -284.310588) (xy 361.956051 -284.31652)
			(xy 362.003322 -284.330212) (xy 362.047784 -284.35131) (xy 362.088287 -284.379266) (xy 362.12378 -284.413358)
			(xy 362.153345 -284.452702) (xy 362.176216 -284.496279) (xy 362.1918 -284.54296) (xy 362.199695 -284.591537)
			(xy 362.20019 -284.616144) (xy 362.528878 -284.616144) (xy 362.532838 -284.56709) (xy 362.544615 -284.519306)
			(xy 362.563906 -284.47403) (xy 362.590209 -284.432434) (xy 362.622844 -284.395597) (xy 362.660965 -284.364472)
			(xy 362.703586 -284.339865) (xy 362.749602 -284.322413) (xy 362.797821 -284.312569) (xy 362.846996 -284.310588)
			(xy 362.895851 -284.31652) (xy 362.943122 -284.330212) (xy 362.987584 -284.35131) (xy 363.028087 -284.379266)
			(xy 363.06358 -284.413358) (xy 363.093145 -284.452702) (xy 363.116016 -284.496279) (xy 363.1316 -284.54296)
			(xy 363.139495 -284.591537) (xy 363.13999 -284.616144) (xy 363.468932 -284.616144) (xy 363.472892 -284.56709)
			(xy 363.484669 -284.519306) (xy 363.50396 -284.47403) (xy 363.530263 -284.432434) (xy 363.562898 -284.395597)
			(xy 363.601019 -284.364472) (xy 363.64364 -284.339865) (xy 363.689656 -284.322413) (xy 363.737875 -284.312569)
			(xy 363.78705 -284.310588) (xy 363.835905 -284.31652) (xy 363.883176 -284.330212) (xy 363.927638 -284.35131)
			(xy 363.968141 -284.379266) (xy 364.003634 -284.413358) (xy 364.033199 -284.452702) (xy 364.05607 -284.496279)
			(xy 364.071654 -284.54296) (xy 364.079549 -284.591537) (xy 364.080044 -284.616144) (xy 364.398555 -284.616144)
			(xy 364.40265 -284.565416) (xy 364.414829 -284.516002) (xy 364.434777 -284.469182) (xy 364.461978 -284.426168)
			(xy 364.495726 -284.388074) (xy 364.535148 -284.355887) (xy 364.579222 -284.330441) (xy 364.626808 -284.312394)
			(xy 364.676672 -284.302214) (xy 364.727524 -284.300165) (xy 364.778045 -284.306299) (xy 364.826929 -284.320459)
			(xy 364.872908 -284.342276) (xy 364.914792 -284.371186) (xy 364.951496 -284.406441) (xy 364.982069 -284.447127)
			(xy 365.00572 -284.49219) (xy 365.021836 -284.540464) (xy 365.03 -284.590698) (xy 365.030512 -284.616144)
			(xy 365.338609 -284.616144) (xy 365.342704 -284.565416) (xy 365.354883 -284.516002) (xy 365.374831 -284.469182)
			(xy 365.402032 -284.426168) (xy 365.43578 -284.388074) (xy 365.475202 -284.355887) (xy 365.519276 -284.330441)
			(xy 365.566862 -284.312394) (xy 365.616726 -284.302214) (xy 365.667578 -284.300165) (xy 365.718099 -284.306299)
			(xy 365.766983 -284.320459) (xy 365.812962 -284.342276) (xy 365.854846 -284.371186) (xy 365.89155 -284.406441)
			(xy 365.922123 -284.447127) (xy 365.945774 -284.49219) (xy 365.96189 -284.540464) (xy 365.970054 -284.590698)
			(xy 365.970566 -284.616144) (xy 366.289094 -284.616144) (xy 366.293054 -284.56709) (xy 366.304831 -284.519306)
			(xy 366.324122 -284.47403) (xy 366.350425 -284.432434) (xy 366.38306 -284.395597) (xy 366.421181 -284.364472)
			(xy 366.463802 -284.339865) (xy 366.509818 -284.322413) (xy 366.558037 -284.312569) (xy 366.607212 -284.310588)
			(xy 366.656067 -284.31652) (xy 366.703338 -284.330212) (xy 366.7478 -284.35131) (xy 366.788303 -284.379266)
			(xy 366.823796 -284.413358) (xy 366.853361 -284.452702) (xy 366.876232 -284.496279) (xy 366.891816 -284.54296)
			(xy 366.899711 -284.591537) (xy 366.900206 -284.616144) (xy 367.218463 -284.616144) (xy 367.222558 -284.565416)
			(xy 367.234737 -284.516002) (xy 367.254685 -284.469182) (xy 367.281886 -284.426168) (xy 367.315634 -284.388074)
			(xy 367.355056 -284.355887) (xy 367.39913 -284.330441) (xy 367.446716 -284.312394) (xy 367.49658 -284.302214)
			(xy 367.547432 -284.300165) (xy 367.597953 -284.306299) (xy 367.646837 -284.320459) (xy 367.692816 -284.342276)
			(xy 367.7347 -284.371186) (xy 367.771404 -284.406441) (xy 367.801977 -284.447127) (xy 367.825628 -284.49219)
			(xy 367.841744 -284.540464) (xy 367.849908 -284.590698) (xy 367.85042 -284.616144) (xy 368.158517 -284.616144)
			(xy 368.162612 -284.565416) (xy 368.174791 -284.516002) (xy 368.194739 -284.469182) (xy 368.22194 -284.426168)
			(xy 368.255688 -284.388074) (xy 368.29511 -284.355887) (xy 368.339184 -284.330441) (xy 368.38677 -284.312394)
			(xy 368.436634 -284.302214) (xy 368.487486 -284.300165) (xy 368.538007 -284.306299) (xy 368.586891 -284.320459)
			(xy 368.63287 -284.342276) (xy 368.674754 -284.371186) (xy 368.711458 -284.406441) (xy 368.742031 -284.447127)
			(xy 368.765682 -284.49219) (xy 368.781798 -284.540464) (xy 368.789962 -284.590698) (xy 368.790474 -284.616144)
			(xy 369.109002 -284.616144) (xy 369.112962 -284.56709) (xy 369.124739 -284.519306) (xy 369.14403 -284.47403)
			(xy 369.170333 -284.432434) (xy 369.202968 -284.395597) (xy 369.241089 -284.364472) (xy 369.28371 -284.339865)
			(xy 369.329726 -284.322413) (xy 369.377945 -284.312569) (xy 369.42712 -284.310588) (xy 369.475975 -284.31652)
			(xy 369.523246 -284.330212) (xy 369.567708 -284.35131) (xy 369.608211 -284.379266) (xy 369.643704 -284.413358)
			(xy 369.673269 -284.452702) (xy 369.69614 -284.496279) (xy 369.711724 -284.54296) (xy 369.719619 -284.591537)
			(xy 369.720114 -284.616144) (xy 370.038625 -284.616144) (xy 370.04272 -284.565416) (xy 370.054899 -284.516002)
			(xy 370.074847 -284.469182) (xy 370.102048 -284.426168) (xy 370.135796 -284.388074) (xy 370.175218 -284.355887)
			(xy 370.219292 -284.330441) (xy 370.266878 -284.312394) (xy 370.316742 -284.302214) (xy 370.367594 -284.300165)
			(xy 370.418115 -284.306299) (xy 370.466999 -284.320459) (xy 370.512978 -284.342276) (xy 370.554862 -284.371186)
			(xy 370.591566 -284.406441) (xy 370.622139 -284.447127) (xy 370.64579 -284.49219) (xy 370.661906 -284.540464)
			(xy 370.67007 -284.590698) (xy 370.670582 -284.616144) (xy 370.978679 -284.616144) (xy 370.982774 -284.565416)
			(xy 370.994953 -284.516002) (xy 371.014901 -284.469182) (xy 371.042102 -284.426168) (xy 371.07585 -284.388074)
			(xy 371.115272 -284.355887) (xy 371.159346 -284.330441) (xy 371.206932 -284.312394) (xy 371.256796 -284.302214)
			(xy 371.307648 -284.300165) (xy 371.358169 -284.306299) (xy 371.407053 -284.320459) (xy 371.453032 -284.342276)
			(xy 371.494916 -284.371186) (xy 371.53162 -284.406441) (xy 371.562193 -284.447127) (xy 371.585844 -284.49219)
			(xy 371.60196 -284.540464) (xy 371.610124 -284.590698) (xy 371.610636 -284.616144) (xy 371.92891 -284.616144)
			(xy 371.93287 -284.56709) (xy 371.944647 -284.519306) (xy 371.963938 -284.47403) (xy 371.990241 -284.432434)
			(xy 372.022876 -284.395597) (xy 372.060997 -284.364472) (xy 372.103618 -284.339865) (xy 372.149634 -284.322413)
			(xy 372.197853 -284.312569) (xy 372.247028 -284.310588) (xy 372.295883 -284.31652) (xy 372.343154 -284.330212)
			(xy 372.387616 -284.35131) (xy 372.428119 -284.379266) (xy 372.463612 -284.413358) (xy 372.493177 -284.452702)
			(xy 372.516048 -284.496279) (xy 372.531632 -284.54296) (xy 372.539527 -284.591537) (xy 372.540022 -284.616144)
			(xy 372.858533 -284.616144) (xy 372.862628 -284.565416) (xy 372.874807 -284.516002) (xy 372.894755 -284.469182)
			(xy 372.921956 -284.426168) (xy 372.955704 -284.388074) (xy 372.995126 -284.355887) (xy 373.0392 -284.330441)
			(xy 373.086786 -284.312394) (xy 373.13665 -284.302214) (xy 373.187502 -284.300165) (xy 373.238023 -284.306299)
			(xy 373.286907 -284.320459) (xy 373.332886 -284.342276) (xy 373.37477 -284.371186) (xy 373.411474 -284.406441)
			(xy 373.442047 -284.447127) (xy 373.465698 -284.49219) (xy 373.481814 -284.540464) (xy 373.489978 -284.590698)
			(xy 373.49049 -284.616144) (xy 373.798587 -284.616144) (xy 373.802682 -284.565416) (xy 373.814861 -284.516002)
			(xy 373.834809 -284.469182) (xy 373.86201 -284.426168) (xy 373.895758 -284.388074) (xy 373.93518 -284.355887)
			(xy 373.979254 -284.330441) (xy 374.02684 -284.312394) (xy 374.076704 -284.302214) (xy 374.127556 -284.300165)
			(xy 374.178077 -284.306299) (xy 374.226961 -284.320459) (xy 374.27294 -284.342276) (xy 374.314824 -284.371186)
			(xy 374.351528 -284.406441) (xy 374.382101 -284.447127) (xy 374.405752 -284.49219) (xy 374.421868 -284.540464)
			(xy 374.430032 -284.590698) (xy 374.430544 -284.616144) (xy 374.430032 -284.64159) (xy 374.421868 -284.691824)
			(xy 374.405752 -284.740098) (xy 374.382101 -284.785161) (xy 374.351528 -284.825847) (xy 374.314824 -284.861102)
			(xy 374.27294 -284.890012) (xy 374.226961 -284.911829) (xy 374.178077 -284.925989) (xy 374.127556 -284.932123)
			(xy 374.076704 -284.930074) (xy 374.02684 -284.919894) (xy 373.979254 -284.901847) (xy 373.93518 -284.876401)
			(xy 373.895758 -284.844214) (xy 373.86201 -284.80612) (xy 373.834809 -284.763106) (xy 373.814861 -284.716286)
			(xy 373.802682 -284.666872) (xy 373.798587 -284.616144) (xy 373.49049 -284.616144) (xy 373.489978 -284.64159)
			(xy 373.481814 -284.691824) (xy 373.465698 -284.740098) (xy 373.442047 -284.785161) (xy 373.411474 -284.825847)
			(xy 373.37477 -284.861102) (xy 373.332886 -284.890012) (xy 373.286907 -284.911829) (xy 373.238023 -284.925989)
			(xy 373.187502 -284.932123) (xy 373.13665 -284.930074) (xy 373.086786 -284.919894) (xy 373.0392 -284.901847)
			(xy 372.995126 -284.876401) (xy 372.955704 -284.844214) (xy 372.921956 -284.80612) (xy 372.894755 -284.763106)
			(xy 372.874807 -284.716286) (xy 372.862628 -284.666872) (xy 372.858533 -284.616144) (xy 372.540022 -284.616144)
			(xy 372.539527 -284.640751) (xy 372.531632 -284.689328) (xy 372.516048 -284.736009) (xy 372.493177 -284.779586)
			(xy 372.463612 -284.81893) (xy 372.428119 -284.853022) (xy 372.387616 -284.880978) (xy 372.343154 -284.902076)
			(xy 372.295883 -284.915768) (xy 372.247028 -284.9217) (xy 372.197853 -284.919719) (xy 372.149634 -284.909875)
			(xy 372.103618 -284.892423) (xy 372.060997 -284.867816) (xy 372.022876 -284.836691) (xy 371.990241 -284.799854)
			(xy 371.963938 -284.758258) (xy 371.944647 -284.712982) (xy 371.93287 -284.665198) (xy 371.92891 -284.616144)
			(xy 371.610636 -284.616144) (xy 371.610124 -284.64159) (xy 371.60196 -284.691824) (xy 371.585844 -284.740098)
			(xy 371.562193 -284.785161) (xy 371.53162 -284.825847) (xy 371.494916 -284.861102) (xy 371.453032 -284.890012)
			(xy 371.407053 -284.911829) (xy 371.358169 -284.925989) (xy 371.307648 -284.932123) (xy 371.256796 -284.930074)
			(xy 371.206932 -284.919894) (xy 371.159346 -284.901847) (xy 371.115272 -284.876401) (xy 371.07585 -284.844214)
			(xy 371.042102 -284.80612) (xy 371.014901 -284.763106) (xy 370.994953 -284.716286) (xy 370.982774 -284.666872)
			(xy 370.978679 -284.616144) (xy 370.670582 -284.616144) (xy 370.67007 -284.64159) (xy 370.661906 -284.691824)
			(xy 370.64579 -284.740098) (xy 370.622139 -284.785161) (xy 370.591566 -284.825847) (xy 370.554862 -284.861102)
			(xy 370.512978 -284.890012) (xy 370.466999 -284.911829) (xy 370.418115 -284.925989) (xy 370.367594 -284.932123)
			(xy 370.316742 -284.930074) (xy 370.266878 -284.919894) (xy 370.219292 -284.901847) (xy 370.175218 -284.876401)
			(xy 370.135796 -284.844214) (xy 370.102048 -284.80612) (xy 370.074847 -284.763106) (xy 370.054899 -284.716286)
			(xy 370.04272 -284.666872) (xy 370.038625 -284.616144) (xy 369.720114 -284.616144) (xy 369.719619 -284.640751)
			(xy 369.711724 -284.689328) (xy 369.69614 -284.736009) (xy 369.673269 -284.779586) (xy 369.643704 -284.81893)
			(xy 369.608211 -284.853022) (xy 369.567708 -284.880978) (xy 369.523246 -284.902076) (xy 369.475975 -284.915768)
			(xy 369.42712 -284.9217) (xy 369.377945 -284.919719) (xy 369.329726 -284.909875) (xy 369.28371 -284.892423)
			(xy 369.241089 -284.867816) (xy 369.202968 -284.836691) (xy 369.170333 -284.799854) (xy 369.14403 -284.758258)
			(xy 369.124739 -284.712982) (xy 369.112962 -284.665198) (xy 369.109002 -284.616144) (xy 368.790474 -284.616144)
			(xy 368.789962 -284.64159) (xy 368.781798 -284.691824) (xy 368.765682 -284.740098) (xy 368.742031 -284.785161)
			(xy 368.711458 -284.825847) (xy 368.674754 -284.861102) (xy 368.63287 -284.890012) (xy 368.586891 -284.911829)
			(xy 368.538007 -284.925989) (xy 368.487486 -284.932123) (xy 368.436634 -284.930074) (xy 368.38677 -284.919894)
			(xy 368.339184 -284.901847) (xy 368.29511 -284.876401) (xy 368.255688 -284.844214) (xy 368.22194 -284.80612)
			(xy 368.194739 -284.763106) (xy 368.174791 -284.716286) (xy 368.162612 -284.666872) (xy 368.158517 -284.616144)
			(xy 367.85042 -284.616144) (xy 367.849908 -284.64159) (xy 367.841744 -284.691824) (xy 367.825628 -284.740098)
			(xy 367.801977 -284.785161) (xy 367.771404 -284.825847) (xy 367.7347 -284.861102) (xy 367.692816 -284.890012)
			(xy 367.646837 -284.911829) (xy 367.597953 -284.925989) (xy 367.547432 -284.932123) (xy 367.49658 -284.930074)
			(xy 367.446716 -284.919894) (xy 367.39913 -284.901847) (xy 367.355056 -284.876401) (xy 367.315634 -284.844214)
			(xy 367.281886 -284.80612) (xy 367.254685 -284.763106) (xy 367.234737 -284.716286) (xy 367.222558 -284.666872)
			(xy 367.218463 -284.616144) (xy 366.900206 -284.616144) (xy 366.899711 -284.640751) (xy 366.891816 -284.689328)
			(xy 366.876232 -284.736009) (xy 366.853361 -284.779586) (xy 366.823796 -284.81893) (xy 366.788303 -284.853022)
			(xy 366.7478 -284.880978) (xy 366.703338 -284.902076) (xy 366.656067 -284.915768) (xy 366.607212 -284.9217)
			(xy 366.558037 -284.919719) (xy 366.509818 -284.909875) (xy 366.463802 -284.892423) (xy 366.421181 -284.867816)
			(xy 366.38306 -284.836691) (xy 366.350425 -284.799854) (xy 366.324122 -284.758258) (xy 366.304831 -284.712982)
			(xy 366.293054 -284.665198) (xy 366.289094 -284.616144) (xy 365.970566 -284.616144) (xy 365.970054 -284.64159)
			(xy 365.96189 -284.691824) (xy 365.945774 -284.740098) (xy 365.922123 -284.785161) (xy 365.89155 -284.825847)
			(xy 365.854846 -284.861102) (xy 365.812962 -284.890012) (xy 365.766983 -284.911829) (xy 365.718099 -284.925989)
			(xy 365.667578 -284.932123) (xy 365.616726 -284.930074) (xy 365.566862 -284.919894) (xy 365.519276 -284.901847)
			(xy 365.475202 -284.876401) (xy 365.43578 -284.844214) (xy 365.402032 -284.80612) (xy 365.374831 -284.763106)
			(xy 365.354883 -284.716286) (xy 365.342704 -284.666872) (xy 365.338609 -284.616144) (xy 365.030512 -284.616144)
			(xy 365.03 -284.64159) (xy 365.021836 -284.691824) (xy 365.00572 -284.740098) (xy 364.982069 -284.785161)
			(xy 364.951496 -284.825847) (xy 364.914792 -284.861102) (xy 364.872908 -284.890012) (xy 364.826929 -284.911829)
			(xy 364.778045 -284.925989) (xy 364.727524 -284.932123) (xy 364.676672 -284.930074) (xy 364.626808 -284.919894)
			(xy 364.579222 -284.901847) (xy 364.535148 -284.876401) (xy 364.495726 -284.844214) (xy 364.461978 -284.80612)
			(xy 364.434777 -284.763106) (xy 364.414829 -284.716286) (xy 364.40265 -284.666872) (xy 364.398555 -284.616144)
			(xy 364.080044 -284.616144) (xy 364.079549 -284.640751) (xy 364.071654 -284.689328) (xy 364.05607 -284.736009)
			(xy 364.033199 -284.779586) (xy 364.003634 -284.81893) (xy 363.968141 -284.853022) (xy 363.927638 -284.880978)
			(xy 363.883176 -284.902076) (xy 363.835905 -284.915768) (xy 363.78705 -284.9217) (xy 363.737875 -284.919719)
			(xy 363.689656 -284.909875) (xy 363.64364 -284.892423) (xy 363.601019 -284.867816) (xy 363.562898 -284.836691)
			(xy 363.530263 -284.799854) (xy 363.50396 -284.758258) (xy 363.484669 -284.712982) (xy 363.472892 -284.665198)
			(xy 363.468932 -284.616144) (xy 363.13999 -284.616144) (xy 363.139495 -284.640751) (xy 363.1316 -284.689328)
			(xy 363.116016 -284.736009) (xy 363.093145 -284.779586) (xy 363.06358 -284.81893) (xy 363.028087 -284.853022)
			(xy 362.987584 -284.880978) (xy 362.943122 -284.902076) (xy 362.895851 -284.915768) (xy 362.846996 -284.9217)
			(xy 362.797821 -284.919719) (xy 362.749602 -284.909875) (xy 362.703586 -284.892423) (xy 362.660965 -284.867816)
			(xy 362.622844 -284.836691) (xy 362.590209 -284.799854) (xy 362.563906 -284.758258) (xy 362.544615 -284.712982)
			(xy 362.532838 -284.665198) (xy 362.528878 -284.616144) (xy 362.20019 -284.616144) (xy 362.199695 -284.640751)
			(xy 362.1918 -284.689328) (xy 362.176216 -284.736009) (xy 362.153345 -284.779586) (xy 362.12378 -284.81893)
			(xy 362.088287 -284.853022) (xy 362.047784 -284.880978) (xy 362.003322 -284.902076) (xy 361.956051 -284.915768)
			(xy 361.907196 -284.9217) (xy 361.858021 -284.919719) (xy 361.809802 -284.909875) (xy 361.763786 -284.892423)
			(xy 361.721165 -284.867816) (xy 361.683044 -284.836691) (xy 361.650409 -284.799854) (xy 361.624106 -284.758258)
			(xy 361.604815 -284.712982) (xy 361.593038 -284.665198) (xy 361.589078 -284.616144) (xy 361.349989 -284.616144)
			(xy 361.357926 -284.848554) (xy 361.365546 -285.07182) (xy 361.366361 -285.081752) (xy 361.374562 -285.099894)
			(xy 361.389054 -285.113544) (xy 361.407653 -285.120646) (xy 361.417616 -285.120842) (xy 361.424728 -285.120842)
			(xy 361.448719 -285.121315) (xy 361.49611 -285.128824) (xy 361.541744 -285.143653) (xy 361.584496 -285.165437)
			(xy 361.623315 -285.19364) (xy 361.657245 -285.227568) (xy 361.685451 -285.266385) (xy 361.707238 -285.309136)
			(xy 361.722071 -285.354768) (xy 361.729584 -285.402159) (xy 361.730036 -285.42615) (xy 362.048547 -285.42615)
			(xy 362.052642 -285.375422) (xy 362.064821 -285.326008) (xy 362.084769 -285.279188) (xy 362.11197 -285.236174)
			(xy 362.145718 -285.19808) (xy 362.18514 -285.165893) (xy 362.229214 -285.140447) (xy 362.2768 -285.1224)
			(xy 362.326664 -285.11222) (xy 362.377516 -285.110171) (xy 362.428037 -285.116305) (xy 362.476921 -285.130465)
			(xy 362.5229 -285.152282) (xy 362.564784 -285.181192) (xy 362.601488 -285.216447) (xy 362.632061 -285.257133)
			(xy 362.655712 -285.302196) (xy 362.671828 -285.35047) (xy 362.679992 -285.400704) (xy 362.680504 -285.42615)
			(xy 362.988601 -285.42615) (xy 362.992696 -285.375422) (xy 363.004875 -285.326008) (xy 363.024823 -285.279188)
			(xy 363.052024 -285.236174) (xy 363.085772 -285.19808) (xy 363.125194 -285.165893) (xy 363.169268 -285.140447)
			(xy 363.216854 -285.1224) (xy 363.266718 -285.11222) (xy 363.31757 -285.110171) (xy 363.368091 -285.116305)
			(xy 363.416975 -285.130465) (xy 363.462954 -285.152282) (xy 363.504838 -285.181192) (xy 363.541542 -285.216447)
			(xy 363.572115 -285.257133) (xy 363.595766 -285.302196) (xy 363.611882 -285.35047) (xy 363.620046 -285.400704)
			(xy 363.620558 -285.42615) (xy 363.939086 -285.42615) (xy 363.943046 -285.377096) (xy 363.954823 -285.329312)
			(xy 363.974114 -285.284036) (xy 364.000417 -285.24244) (xy 364.033052 -285.205603) (xy 364.071173 -285.174478)
			(xy 364.113794 -285.149871) (xy 364.15981 -285.132419) (xy 364.208029 -285.122575) (xy 364.257204 -285.120594)
			(xy 364.306059 -285.126526) (xy 364.35333 -285.140218) (xy 364.397792 -285.161316) (xy 364.438295 -285.189272)
			(xy 364.473788 -285.223364) (xy 364.503353 -285.262708) (xy 364.526224 -285.306285) (xy 364.541808 -285.352966)
			(xy 364.549703 -285.401543) (xy 364.550198 -285.42615) (xy 364.878886 -285.42615) (xy 364.882846 -285.377096)
			(xy 364.894623 -285.329312) (xy 364.913914 -285.284036) (xy 364.940217 -285.24244) (xy 364.972852 -285.205603)
			(xy 365.010973 -285.174478) (xy 365.053594 -285.149871) (xy 365.09961 -285.132419) (xy 365.147829 -285.122575)
			(xy 365.197004 -285.120594) (xy 365.245859 -285.126526) (xy 365.29313 -285.140218) (xy 365.337592 -285.161316)
			(xy 365.378095 -285.189272) (xy 365.413588 -285.223364) (xy 365.443153 -285.262708) (xy 365.466024 -285.306285)
			(xy 365.481608 -285.352966) (xy 365.489503 -285.401543) (xy 365.489998 -285.42615) (xy 365.81894 -285.42615)
			(xy 365.8229 -285.377096) (xy 365.834677 -285.329312) (xy 365.853968 -285.284036) (xy 365.880271 -285.24244)
			(xy 365.912906 -285.205603) (xy 365.951027 -285.174478) (xy 365.993648 -285.149871) (xy 366.039664 -285.132419)
			(xy 366.087883 -285.122575) (xy 366.137058 -285.120594) (xy 366.185913 -285.126526) (xy 366.233184 -285.140218)
			(xy 366.277646 -285.161316) (xy 366.318149 -285.189272) (xy 366.353642 -285.223364) (xy 366.383207 -285.262708)
			(xy 366.406078 -285.306285) (xy 366.421662 -285.352966) (xy 366.429557 -285.401543) (xy 366.430052 -285.42615)
			(xy 366.758994 -285.42615) (xy 366.762954 -285.377096) (xy 366.774731 -285.329312) (xy 366.794022 -285.284036)
			(xy 366.820325 -285.24244) (xy 366.85296 -285.205603) (xy 366.891081 -285.174478) (xy 366.933702 -285.149871)
			(xy 366.979718 -285.132419) (xy 367.027937 -285.122575) (xy 367.077112 -285.120594) (xy 367.125967 -285.126526)
			(xy 367.173238 -285.140218) (xy 367.2177 -285.161316) (xy 367.258203 -285.189272) (xy 367.293696 -285.223364)
			(xy 367.323261 -285.262708) (xy 367.346132 -285.306285) (xy 367.361716 -285.352966) (xy 367.369611 -285.401543)
			(xy 367.370106 -285.42615) (xy 367.699048 -285.42615) (xy 367.703008 -285.377096) (xy 367.714785 -285.329312)
			(xy 367.734076 -285.284036) (xy 367.760379 -285.24244) (xy 367.793014 -285.205603) (xy 367.831135 -285.174478)
			(xy 367.873756 -285.149871) (xy 367.919772 -285.132419) (xy 367.967991 -285.122575) (xy 368.017166 -285.120594)
			(xy 368.066021 -285.126526) (xy 368.113292 -285.140218) (xy 368.157754 -285.161316) (xy 368.198257 -285.189272)
			(xy 368.23375 -285.223364) (xy 368.263315 -285.262708) (xy 368.286186 -285.306285) (xy 368.30177 -285.352966)
			(xy 368.309665 -285.401543) (xy 368.31016 -285.42615) (xy 368.639102 -285.42615) (xy 368.643062 -285.377096)
			(xy 368.654839 -285.329312) (xy 368.67413 -285.284036) (xy 368.700433 -285.24244) (xy 368.733068 -285.205603)
			(xy 368.771189 -285.174478) (xy 368.81381 -285.149871) (xy 368.859826 -285.132419) (xy 368.908045 -285.122575)
			(xy 368.95722 -285.120594) (xy 369.006075 -285.126526) (xy 369.053346 -285.140218) (xy 369.097808 -285.161316)
			(xy 369.138311 -285.189272) (xy 369.173804 -285.223364) (xy 369.203369 -285.262708) (xy 369.22624 -285.306285)
			(xy 369.241824 -285.352966) (xy 369.249719 -285.401543) (xy 369.250214 -285.42615) (xy 369.578902 -285.42615)
			(xy 369.582862 -285.377096) (xy 369.594639 -285.329312) (xy 369.61393 -285.284036) (xy 369.640233 -285.24244)
			(xy 369.672868 -285.205603) (xy 369.710989 -285.174478) (xy 369.75361 -285.149871) (xy 369.799626 -285.132419)
			(xy 369.847845 -285.122575) (xy 369.89702 -285.120594) (xy 369.945875 -285.126526) (xy 369.993146 -285.140218)
			(xy 370.037608 -285.161316) (xy 370.078111 -285.189272) (xy 370.113604 -285.223364) (xy 370.143169 -285.262708)
			(xy 370.16604 -285.306285) (xy 370.181624 -285.352966) (xy 370.189519 -285.401543) (xy 370.190014 -285.42615)
			(xy 370.518956 -285.42615) (xy 370.522916 -285.377096) (xy 370.534693 -285.329312) (xy 370.553984 -285.284036)
			(xy 370.580287 -285.24244) (xy 370.612922 -285.205603) (xy 370.651043 -285.174478) (xy 370.693664 -285.149871)
			(xy 370.73968 -285.132419) (xy 370.787899 -285.122575) (xy 370.837074 -285.120594) (xy 370.885929 -285.126526)
			(xy 370.9332 -285.140218) (xy 370.977662 -285.161316) (xy 371.018165 -285.189272) (xy 371.053658 -285.223364)
			(xy 371.083223 -285.262708) (xy 371.106094 -285.306285) (xy 371.121678 -285.352966) (xy 371.129573 -285.401543)
			(xy 371.130068 -285.42615) (xy 371.45901 -285.42615) (xy 371.46297 -285.377096) (xy 371.474747 -285.329312)
			(xy 371.494038 -285.284036) (xy 371.520341 -285.24244) (xy 371.552976 -285.205603) (xy 371.591097 -285.174478)
			(xy 371.633718 -285.149871) (xy 371.679734 -285.132419) (xy 371.727953 -285.122575) (xy 371.777128 -285.120594)
			(xy 371.825983 -285.126526) (xy 371.873254 -285.140218) (xy 371.917716 -285.161316) (xy 371.958219 -285.189272)
			(xy 371.993712 -285.223364) (xy 372.023277 -285.262708) (xy 372.046148 -285.306285) (xy 372.061732 -285.352966)
			(xy 372.069627 -285.401543) (xy 372.070122 -285.42615) (xy 372.399064 -285.42615) (xy 372.403024 -285.377096)
			(xy 372.414801 -285.329312) (xy 372.434092 -285.284036) (xy 372.460395 -285.24244) (xy 372.49303 -285.205603)
			(xy 372.531151 -285.174478) (xy 372.573772 -285.149871) (xy 372.619788 -285.132419) (xy 372.668007 -285.122575)
			(xy 372.717182 -285.120594) (xy 372.766037 -285.126526) (xy 372.813308 -285.140218) (xy 372.85777 -285.161316)
			(xy 372.898273 -285.189272) (xy 372.933766 -285.223364) (xy 372.963331 -285.262708) (xy 372.986202 -285.306285)
			(xy 373.001786 -285.352966) (xy 373.009681 -285.401543) (xy 373.010176 -285.42615) (xy 373.339118 -285.42615)
			(xy 373.343078 -285.377096) (xy 373.354855 -285.329312) (xy 373.374146 -285.284036) (xy 373.400449 -285.24244)
			(xy 373.433084 -285.205603) (xy 373.471205 -285.174478) (xy 373.513826 -285.149871) (xy 373.559842 -285.132419)
			(xy 373.608061 -285.122575) (xy 373.657236 -285.120594) (xy 373.706091 -285.126526) (xy 373.753362 -285.140218)
			(xy 373.797824 -285.161316) (xy 373.838327 -285.189272) (xy 373.87382 -285.223364) (xy 373.903385 -285.262708)
			(xy 373.926256 -285.306285) (xy 373.94184 -285.352966) (xy 373.949735 -285.401543) (xy 373.95023 -285.42615)
			(xy 373.949735 -285.450757) (xy 373.94184 -285.499334) (xy 373.926256 -285.546015) (xy 373.903385 -285.589592)
			(xy 373.87382 -285.628936) (xy 373.838327 -285.663028) (xy 373.797824 -285.690984) (xy 373.753362 -285.712082)
			(xy 373.706091 -285.725774) (xy 373.657236 -285.731706) (xy 373.608061 -285.729725) (xy 373.559842 -285.719881)
			(xy 373.513826 -285.702429) (xy 373.471205 -285.677822) (xy 373.433084 -285.646697) (xy 373.400449 -285.60986)
			(xy 373.374146 -285.568264) (xy 373.354855 -285.522988) (xy 373.343078 -285.475204) (xy 373.339118 -285.42615)
			(xy 373.010176 -285.42615) (xy 373.009681 -285.450757) (xy 373.001786 -285.499334) (xy 372.986202 -285.546015)
			(xy 372.963331 -285.589592) (xy 372.933766 -285.628936) (xy 372.898273 -285.663028) (xy 372.85777 -285.690984)
			(xy 372.813308 -285.712082) (xy 372.766037 -285.725774) (xy 372.717182 -285.731706) (xy 372.668007 -285.729725)
			(xy 372.619788 -285.719881) (xy 372.573772 -285.702429) (xy 372.531151 -285.677822) (xy 372.49303 -285.646697)
			(xy 372.460395 -285.60986) (xy 372.434092 -285.568264) (xy 372.414801 -285.522988) (xy 372.403024 -285.475204)
			(xy 372.399064 -285.42615) (xy 372.070122 -285.42615) (xy 372.069627 -285.450757) (xy 372.061732 -285.499334)
			(xy 372.046148 -285.546015) (xy 372.023277 -285.589592) (xy 371.993712 -285.628936) (xy 371.958219 -285.663028)
			(xy 371.917716 -285.690984) (xy 371.873254 -285.712082) (xy 371.825983 -285.725774) (xy 371.777128 -285.731706)
			(xy 371.727953 -285.729725) (xy 371.679734 -285.719881) (xy 371.633718 -285.702429) (xy 371.591097 -285.677822)
			(xy 371.552976 -285.646697) (xy 371.520341 -285.60986) (xy 371.494038 -285.568264) (xy 371.474747 -285.522988)
			(xy 371.46297 -285.475204) (xy 371.45901 -285.42615) (xy 371.130068 -285.42615) (xy 371.129573 -285.450757)
			(xy 371.121678 -285.499334) (xy 371.106094 -285.546015) (xy 371.083223 -285.589592) (xy 371.053658 -285.628936)
			(xy 371.018165 -285.663028) (xy 370.977662 -285.690984) (xy 370.9332 -285.712082) (xy 370.885929 -285.725774)
			(xy 370.837074 -285.731706) (xy 370.787899 -285.729725) (xy 370.73968 -285.719881) (xy 370.693664 -285.702429)
			(xy 370.651043 -285.677822) (xy 370.612922 -285.646697) (xy 370.580287 -285.60986) (xy 370.553984 -285.568264)
			(xy 370.534693 -285.522988) (xy 370.522916 -285.475204) (xy 370.518956 -285.42615) (xy 370.190014 -285.42615)
			(xy 370.189519 -285.450757) (xy 370.181624 -285.499334) (xy 370.16604 -285.546015) (xy 370.143169 -285.589592)
			(xy 370.113604 -285.628936) (xy 370.078111 -285.663028) (xy 370.037608 -285.690984) (xy 369.993146 -285.712082)
			(xy 369.945875 -285.725774) (xy 369.89702 -285.731706) (xy 369.847845 -285.729725) (xy 369.799626 -285.719881)
			(xy 369.75361 -285.702429) (xy 369.710989 -285.677822) (xy 369.672868 -285.646697) (xy 369.640233 -285.60986)
			(xy 369.61393 -285.568264) (xy 369.594639 -285.522988) (xy 369.582862 -285.475204) (xy 369.578902 -285.42615)
			(xy 369.250214 -285.42615) (xy 369.249719 -285.450757) (xy 369.241824 -285.499334) (xy 369.22624 -285.546015)
			(xy 369.203369 -285.589592) (xy 369.173804 -285.628936) (xy 369.138311 -285.663028) (xy 369.097808 -285.690984)
			(xy 369.053346 -285.712082) (xy 369.006075 -285.725774) (xy 368.95722 -285.731706) (xy 368.908045 -285.729725)
			(xy 368.859826 -285.719881) (xy 368.81381 -285.702429) (xy 368.771189 -285.677822) (xy 368.733068 -285.646697)
			(xy 368.700433 -285.60986) (xy 368.67413 -285.568264) (xy 368.654839 -285.522988) (xy 368.643062 -285.475204)
			(xy 368.639102 -285.42615) (xy 368.31016 -285.42615) (xy 368.309665 -285.450757) (xy 368.30177 -285.499334)
			(xy 368.286186 -285.546015) (xy 368.263315 -285.589592) (xy 368.23375 -285.628936) (xy 368.198257 -285.663028)
			(xy 368.157754 -285.690984) (xy 368.113292 -285.712082) (xy 368.066021 -285.725774) (xy 368.017166 -285.731706)
			(xy 367.967991 -285.729725) (xy 367.919772 -285.719881) (xy 367.873756 -285.702429) (xy 367.831135 -285.677822)
			(xy 367.793014 -285.646697) (xy 367.760379 -285.60986) (xy 367.734076 -285.568264) (xy 367.714785 -285.522988)
			(xy 367.703008 -285.475204) (xy 367.699048 -285.42615) (xy 367.370106 -285.42615) (xy 367.369611 -285.450757)
			(xy 367.361716 -285.499334) (xy 367.346132 -285.546015) (xy 367.323261 -285.589592) (xy 367.293696 -285.628936)
			(xy 367.258203 -285.663028) (xy 367.2177 -285.690984) (xy 367.173238 -285.712082) (xy 367.125967 -285.725774)
			(xy 367.077112 -285.731706) (xy 367.027937 -285.729725) (xy 366.979718 -285.719881) (xy 366.933702 -285.702429)
			(xy 366.891081 -285.677822) (xy 366.85296 -285.646697) (xy 366.820325 -285.60986) (xy 366.794022 -285.568264)
			(xy 366.774731 -285.522988) (xy 366.762954 -285.475204) (xy 366.758994 -285.42615) (xy 366.430052 -285.42615)
			(xy 366.429557 -285.450757) (xy 366.421662 -285.499334) (xy 366.406078 -285.546015) (xy 366.383207 -285.589592)
			(xy 366.353642 -285.628936) (xy 366.318149 -285.663028) (xy 366.277646 -285.690984) (xy 366.233184 -285.712082)
			(xy 366.185913 -285.725774) (xy 366.137058 -285.731706) (xy 366.087883 -285.729725) (xy 366.039664 -285.719881)
			(xy 365.993648 -285.702429) (xy 365.951027 -285.677822) (xy 365.912906 -285.646697) (xy 365.880271 -285.60986)
			(xy 365.853968 -285.568264) (xy 365.834677 -285.522988) (xy 365.8229 -285.475204) (xy 365.81894 -285.42615)
			(xy 365.489998 -285.42615) (xy 365.489503 -285.450757) (xy 365.481608 -285.499334) (xy 365.466024 -285.546015)
			(xy 365.443153 -285.589592) (xy 365.413588 -285.628936) (xy 365.378095 -285.663028) (xy 365.337592 -285.690984)
			(xy 365.29313 -285.712082) (xy 365.245859 -285.725774) (xy 365.197004 -285.731706) (xy 365.147829 -285.729725)
			(xy 365.09961 -285.719881) (xy 365.053594 -285.702429) (xy 365.010973 -285.677822) (xy 364.972852 -285.646697)
			(xy 364.940217 -285.60986) (xy 364.913914 -285.568264) (xy 364.894623 -285.522988) (xy 364.882846 -285.475204)
			(xy 364.878886 -285.42615) (xy 364.550198 -285.42615) (xy 364.549703 -285.450757) (xy 364.541808 -285.499334)
			(xy 364.526224 -285.546015) (xy 364.503353 -285.589592) (xy 364.473788 -285.628936) (xy 364.438295 -285.663028)
			(xy 364.397792 -285.690984) (xy 364.35333 -285.712082) (xy 364.306059 -285.725774) (xy 364.257204 -285.731706)
			(xy 364.208029 -285.729725) (xy 364.15981 -285.719881) (xy 364.113794 -285.702429) (xy 364.071173 -285.677822)
			(xy 364.033052 -285.646697) (xy 364.000417 -285.60986) (xy 363.974114 -285.568264) (xy 363.954823 -285.522988)
			(xy 363.943046 -285.475204) (xy 363.939086 -285.42615) (xy 363.620558 -285.42615) (xy 363.620046 -285.451596)
			(xy 363.611882 -285.50183) (xy 363.595766 -285.550104) (xy 363.572115 -285.595167) (xy 363.541542 -285.635853)
			(xy 363.504838 -285.671108) (xy 363.462954 -285.700018) (xy 363.416975 -285.721835) (xy 363.368091 -285.735995)
			(xy 363.31757 -285.742129) (xy 363.266718 -285.74008) (xy 363.216854 -285.7299) (xy 363.169268 -285.711853)
			(xy 363.125194 -285.686407) (xy 363.085772 -285.65422) (xy 363.052024 -285.616126) (xy 363.024823 -285.573112)
			(xy 363.004875 -285.526292) (xy 362.992696 -285.476878) (xy 362.988601 -285.42615) (xy 362.680504 -285.42615)
			(xy 362.679992 -285.451596) (xy 362.671828 -285.50183) (xy 362.655712 -285.550104) (xy 362.632061 -285.595167)
			(xy 362.601488 -285.635853) (xy 362.564784 -285.671108) (xy 362.5229 -285.700018) (xy 362.476921 -285.721835)
			(xy 362.428037 -285.735995) (xy 362.377516 -285.742129) (xy 362.326664 -285.74008) (xy 362.2768 -285.7299)
			(xy 362.229214 -285.711853) (xy 362.18514 -285.686407) (xy 362.145718 -285.65422) (xy 362.11197 -285.616126)
			(xy 362.084769 -285.573112) (xy 362.064821 -285.526292) (xy 362.052642 -285.476878) (xy 362.048547 -285.42615)
			(xy 361.730036 -285.42615) (xy 361.729897 -285.438913) (xy 361.727734 -285.464347) (xy 361.725718 -285.47695)
			(xy 361.720848 -285.502447) (xy 361.703667 -285.551427) (xy 361.678457 -285.596798) (xy 361.645942 -285.637257)
			(xy 361.607057 -285.67164) (xy 361.562922 -285.698957) (xy 361.514805 -285.718423) (xy 361.464091 -285.729478)
			(xy 361.43819 -285.731204) (xy 361.417108 -285.73222) (xy 361.389168 -285.7627) (xy 361.405373 -286.236156)
			(xy 363.468932 -286.236156) (xy 363.472892 -286.187102) (xy 363.484669 -286.139318) (xy 363.50396 -286.094042)
			(xy 363.530263 -286.052446) (xy 363.562898 -286.015609) (xy 363.601019 -285.984484) (xy 363.64364 -285.959877)
			(xy 363.689656 -285.942425) (xy 363.737875 -285.932581) (xy 363.78705 -285.9306) (xy 363.835905 -285.936532)
			(xy 363.883176 -285.950224) (xy 363.927638 -285.971322) (xy 363.968141 -285.999278) (xy 364.003634 -286.03337)
			(xy 364.033199 -286.072714) (xy 364.05607 -286.116291) (xy 364.071654 -286.162972) (xy 364.079549 -286.211549)
			(xy 364.080044 -286.236156) (xy 364.398555 -286.236156) (xy 364.40265 -286.185428) (xy 364.414829 -286.136014)
			(xy 364.434777 -286.089194) (xy 364.461978 -286.04618) (xy 364.495726 -286.008086) (xy 364.535148 -285.975899)
			(xy 364.579222 -285.950453) (xy 364.626808 -285.932406) (xy 364.676672 -285.922226) (xy 364.727524 -285.920177)
			(xy 364.778045 -285.926311) (xy 364.826929 -285.940471) (xy 364.872908 -285.962288) (xy 364.914792 -285.991198)
			(xy 364.951496 -286.026453) (xy 364.982069 -286.067139) (xy 365.00572 -286.112202) (xy 365.021836 -286.160476)
			(xy 365.03 -286.21071) (xy 365.030512 -286.236156) (xy 365.338609 -286.236156) (xy 365.342704 -286.185428)
			(xy 365.354883 -286.136014) (xy 365.374831 -286.089194) (xy 365.402032 -286.04618) (xy 365.43578 -286.008086)
			(xy 365.475202 -285.975899) (xy 365.519276 -285.950453) (xy 365.566862 -285.932406) (xy 365.616726 -285.922226)
			(xy 365.667578 -285.920177) (xy 365.718099 -285.926311) (xy 365.766983 -285.940471) (xy 365.812962 -285.962288)
			(xy 365.854846 -285.991198) (xy 365.89155 -286.026453) (xy 365.922123 -286.067139) (xy 365.945774 -286.112202)
			(xy 365.96189 -286.160476) (xy 365.970054 -286.21071) (xy 365.970566 -286.236156) (xy 366.289094 -286.236156)
			(xy 366.293054 -286.187102) (xy 366.304831 -286.139318) (xy 366.324122 -286.094042) (xy 366.350425 -286.052446)
			(xy 366.38306 -286.015609) (xy 366.421181 -285.984484) (xy 366.463802 -285.959877) (xy 366.509818 -285.942425)
			(xy 366.558037 -285.932581) (xy 366.607212 -285.9306) (xy 366.656067 -285.936532) (xy 366.703338 -285.950224)
			(xy 366.7478 -285.971322) (xy 366.788303 -285.999278) (xy 366.823796 -286.03337) (xy 366.853361 -286.072714)
			(xy 366.876232 -286.116291) (xy 366.891816 -286.162972) (xy 366.899711 -286.211549) (xy 366.900206 -286.236156)
			(xy 367.218463 -286.236156) (xy 367.222558 -286.185428) (xy 367.234737 -286.136014) (xy 367.254685 -286.089194)
			(xy 367.281886 -286.04618) (xy 367.315634 -286.008086) (xy 367.355056 -285.975899) (xy 367.39913 -285.950453)
			(xy 367.446716 -285.932406) (xy 367.49658 -285.922226) (xy 367.547432 -285.920177) (xy 367.597953 -285.926311)
			(xy 367.646837 -285.940471) (xy 367.692816 -285.962288) (xy 367.7347 -285.991198) (xy 367.771404 -286.026453)
			(xy 367.801977 -286.067139) (xy 367.825628 -286.112202) (xy 367.841744 -286.160476) (xy 367.849908 -286.21071)
			(xy 367.85042 -286.236156) (xy 368.158517 -286.236156) (xy 368.162612 -286.185428) (xy 368.174791 -286.136014)
			(xy 368.194739 -286.089194) (xy 368.22194 -286.04618) (xy 368.255688 -286.008086) (xy 368.29511 -285.975899)
			(xy 368.339184 -285.950453) (xy 368.38677 -285.932406) (xy 368.436634 -285.922226) (xy 368.487486 -285.920177)
			(xy 368.538007 -285.926311) (xy 368.586891 -285.940471) (xy 368.63287 -285.962288) (xy 368.674754 -285.991198)
			(xy 368.711458 -286.026453) (xy 368.742031 -286.067139) (xy 368.765682 -286.112202) (xy 368.781798 -286.160476)
			(xy 368.789962 -286.21071) (xy 368.790474 -286.236156) (xy 369.109002 -286.236156) (xy 369.112962 -286.187102)
			(xy 369.124739 -286.139318) (xy 369.14403 -286.094042) (xy 369.170333 -286.052446) (xy 369.202968 -286.015609)
			(xy 369.241089 -285.984484) (xy 369.28371 -285.959877) (xy 369.329726 -285.942425) (xy 369.377945 -285.932581)
			(xy 369.42712 -285.9306) (xy 369.475975 -285.936532) (xy 369.523246 -285.950224) (xy 369.567708 -285.971322)
			(xy 369.608211 -285.999278) (xy 369.643704 -286.03337) (xy 369.673269 -286.072714) (xy 369.69614 -286.116291)
			(xy 369.711724 -286.162972) (xy 369.719619 -286.211549) (xy 369.720114 -286.236156) (xy 370.038625 -286.236156)
			(xy 370.04272 -286.185428) (xy 370.054899 -286.136014) (xy 370.074847 -286.089194) (xy 370.102048 -286.04618)
			(xy 370.135796 -286.008086) (xy 370.175218 -285.975899) (xy 370.219292 -285.950453) (xy 370.266878 -285.932406)
			(xy 370.316742 -285.922226) (xy 370.367594 -285.920177) (xy 370.418115 -285.926311) (xy 370.466999 -285.940471)
			(xy 370.512978 -285.962288) (xy 370.554862 -285.991198) (xy 370.591566 -286.026453) (xy 370.622139 -286.067139)
			(xy 370.64579 -286.112202) (xy 370.661906 -286.160476) (xy 370.67007 -286.21071) (xy 370.670582 -286.236156)
			(xy 370.978679 -286.236156) (xy 370.982774 -286.185428) (xy 370.994953 -286.136014) (xy 371.014901 -286.089194)
			(xy 371.042102 -286.04618) (xy 371.07585 -286.008086) (xy 371.115272 -285.975899) (xy 371.159346 -285.950453)
			(xy 371.206932 -285.932406) (xy 371.256796 -285.922226) (xy 371.307648 -285.920177) (xy 371.358169 -285.926311)
			(xy 371.407053 -285.940471) (xy 371.453032 -285.962288) (xy 371.494916 -285.991198) (xy 371.53162 -286.026453)
			(xy 371.562193 -286.067139) (xy 371.585844 -286.112202) (xy 371.60196 -286.160476) (xy 371.610124 -286.21071)
			(xy 371.610636 -286.236156) (xy 371.92891 -286.236156) (xy 371.93287 -286.187102) (xy 371.944647 -286.139318)
			(xy 371.963938 -286.094042) (xy 371.990241 -286.052446) (xy 372.022876 -286.015609) (xy 372.060997 -285.984484)
			(xy 372.103618 -285.959877) (xy 372.149634 -285.942425) (xy 372.197853 -285.932581) (xy 372.247028 -285.9306)
			(xy 372.295883 -285.936532) (xy 372.343154 -285.950224) (xy 372.387616 -285.971322) (xy 372.428119 -285.999278)
			(xy 372.463612 -286.03337) (xy 372.493177 -286.072714) (xy 372.516048 -286.116291) (xy 372.531632 -286.162972)
			(xy 372.539527 -286.211549) (xy 372.540022 -286.236156) (xy 372.858533 -286.236156) (xy 372.862628 -286.185428)
			(xy 372.874807 -286.136014) (xy 372.894755 -286.089194) (xy 372.921956 -286.04618) (xy 372.955704 -286.008086)
			(xy 372.995126 -285.975899) (xy 373.0392 -285.950453) (xy 373.086786 -285.932406) (xy 373.13665 -285.922226)
			(xy 373.187502 -285.920177) (xy 373.238023 -285.926311) (xy 373.286907 -285.940471) (xy 373.332886 -285.962288)
			(xy 373.37477 -285.991198) (xy 373.411474 -286.026453) (xy 373.442047 -286.067139) (xy 373.465698 -286.112202)
			(xy 373.481814 -286.160476) (xy 373.489978 -286.21071) (xy 373.49049 -286.236156) (xy 373.798587 -286.236156)
			(xy 373.802682 -286.185428) (xy 373.814861 -286.136014) (xy 373.834809 -286.089194) (xy 373.86201 -286.04618)
			(xy 373.895758 -286.008086) (xy 373.93518 -285.975899) (xy 373.979254 -285.950453) (xy 374.02684 -285.932406)
			(xy 374.076704 -285.922226) (xy 374.127556 -285.920177) (xy 374.178077 -285.926311) (xy 374.226961 -285.940471)
			(xy 374.27294 -285.962288) (xy 374.314824 -285.991198) (xy 374.351528 -286.026453) (xy 374.382101 -286.067139)
			(xy 374.405752 -286.112202) (xy 374.421868 -286.160476) (xy 374.430032 -286.21071) (xy 374.430544 -286.236156)
			(xy 374.430032 -286.261602) (xy 374.421868 -286.311836) (xy 374.405752 -286.36011) (xy 374.382101 -286.405173)
			(xy 374.351528 -286.445859) (xy 374.314824 -286.481114) (xy 374.27294 -286.510024) (xy 374.226961 -286.531841)
			(xy 374.178077 -286.546001) (xy 374.127556 -286.552135) (xy 374.076704 -286.550086) (xy 374.02684 -286.539906)
			(xy 373.979254 -286.521859) (xy 373.93518 -286.496413) (xy 373.895758 -286.464226) (xy 373.86201 -286.426132)
			(xy 373.834809 -286.383118) (xy 373.814861 -286.336298) (xy 373.802682 -286.286884) (xy 373.798587 -286.236156)
			(xy 373.49049 -286.236156) (xy 373.489978 -286.261602) (xy 373.481814 -286.311836) (xy 373.465698 -286.36011)
			(xy 373.442047 -286.405173) (xy 373.411474 -286.445859) (xy 373.37477 -286.481114) (xy 373.332886 -286.510024)
			(xy 373.286907 -286.531841) (xy 373.238023 -286.546001) (xy 373.187502 -286.552135) (xy 373.13665 -286.550086)
			(xy 373.086786 -286.539906) (xy 373.0392 -286.521859) (xy 372.995126 -286.496413) (xy 372.955704 -286.464226)
			(xy 372.921956 -286.426132) (xy 372.894755 -286.383118) (xy 372.874807 -286.336298) (xy 372.862628 -286.286884)
			(xy 372.858533 -286.236156) (xy 372.540022 -286.236156) (xy 372.539527 -286.260763) (xy 372.531632 -286.30934)
			(xy 372.516048 -286.356021) (xy 372.493177 -286.399598) (xy 372.463612 -286.438942) (xy 372.428119 -286.473034)
			(xy 372.387616 -286.50099) (xy 372.343154 -286.522088) (xy 372.295883 -286.53578) (xy 372.247028 -286.541712)
			(xy 372.197853 -286.539731) (xy 372.149634 -286.529887) (xy 372.103618 -286.512435) (xy 372.060997 -286.487828)
			(xy 372.022876 -286.456703) (xy 371.990241 -286.419866) (xy 371.963938 -286.37827) (xy 371.944647 -286.332994)
			(xy 371.93287 -286.28521) (xy 371.92891 -286.236156) (xy 371.610636 -286.236156) (xy 371.610124 -286.261602)
			(xy 371.60196 -286.311836) (xy 371.585844 -286.36011) (xy 371.562193 -286.405173) (xy 371.53162 -286.445859)
			(xy 371.494916 -286.481114) (xy 371.453032 -286.510024) (xy 371.407053 -286.531841) (xy 371.358169 -286.546001)
			(xy 371.307648 -286.552135) (xy 371.256796 -286.550086) (xy 371.206932 -286.539906) (xy 371.159346 -286.521859)
			(xy 371.115272 -286.496413) (xy 371.07585 -286.464226) (xy 371.042102 -286.426132) (xy 371.014901 -286.383118)
			(xy 370.994953 -286.336298) (xy 370.982774 -286.286884) (xy 370.978679 -286.236156) (xy 370.670582 -286.236156)
			(xy 370.67007 -286.261602) (xy 370.661906 -286.311836) (xy 370.64579 -286.36011) (xy 370.622139 -286.405173)
			(xy 370.591566 -286.445859) (xy 370.554862 -286.481114) (xy 370.512978 -286.510024) (xy 370.466999 -286.531841)
			(xy 370.418115 -286.546001) (xy 370.367594 -286.552135) (xy 370.316742 -286.550086) (xy 370.266878 -286.539906)
			(xy 370.219292 -286.521859) (xy 370.175218 -286.496413) (xy 370.135796 -286.464226) (xy 370.102048 -286.426132)
			(xy 370.074847 -286.383118) (xy 370.054899 -286.336298) (xy 370.04272 -286.286884) (xy 370.038625 -286.236156)
			(xy 369.720114 -286.236156) (xy 369.719619 -286.260763) (xy 369.711724 -286.30934) (xy 369.69614 -286.356021)
			(xy 369.673269 -286.399598) (xy 369.643704 -286.438942) (xy 369.608211 -286.473034) (xy 369.567708 -286.50099)
			(xy 369.523246 -286.522088) (xy 369.475975 -286.53578) (xy 369.42712 -286.541712) (xy 369.377945 -286.539731)
			(xy 369.329726 -286.529887) (xy 369.28371 -286.512435) (xy 369.241089 -286.487828) (xy 369.202968 -286.456703)
			(xy 369.170333 -286.419866) (xy 369.14403 -286.37827) (xy 369.124739 -286.332994) (xy 369.112962 -286.28521)
			(xy 369.109002 -286.236156) (xy 368.790474 -286.236156) (xy 368.789962 -286.261602) (xy 368.781798 -286.311836)
			(xy 368.765682 -286.36011) (xy 368.742031 -286.405173) (xy 368.711458 -286.445859) (xy 368.674754 -286.481114)
			(xy 368.63287 -286.510024) (xy 368.586891 -286.531841) (xy 368.538007 -286.546001) (xy 368.487486 -286.552135)
			(xy 368.436634 -286.550086) (xy 368.38677 -286.539906) (xy 368.339184 -286.521859) (xy 368.29511 -286.496413)
			(xy 368.255688 -286.464226) (xy 368.22194 -286.426132) (xy 368.194739 -286.383118) (xy 368.174791 -286.336298)
			(xy 368.162612 -286.286884) (xy 368.158517 -286.236156) (xy 367.85042 -286.236156) (xy 367.849908 -286.261602)
			(xy 367.841744 -286.311836) (xy 367.825628 -286.36011) (xy 367.801977 -286.405173) (xy 367.771404 -286.445859)
			(xy 367.7347 -286.481114) (xy 367.692816 -286.510024) (xy 367.646837 -286.531841) (xy 367.597953 -286.546001)
			(xy 367.547432 -286.552135) (xy 367.49658 -286.550086) (xy 367.446716 -286.539906) (xy 367.39913 -286.521859)
			(xy 367.355056 -286.496413) (xy 367.315634 -286.464226) (xy 367.281886 -286.426132) (xy 367.254685 -286.383118)
			(xy 367.234737 -286.336298) (xy 367.222558 -286.286884) (xy 367.218463 -286.236156) (xy 366.900206 -286.236156)
			(xy 366.899711 -286.260763) (xy 366.891816 -286.30934) (xy 366.876232 -286.356021) (xy 366.853361 -286.399598)
			(xy 366.823796 -286.438942) (xy 366.788303 -286.473034) (xy 366.7478 -286.50099) (xy 366.703338 -286.522088)
			(xy 366.656067 -286.53578) (xy 366.607212 -286.541712) (xy 366.558037 -286.539731) (xy 366.509818 -286.529887)
			(xy 366.463802 -286.512435) (xy 366.421181 -286.487828) (xy 366.38306 -286.456703) (xy 366.350425 -286.419866)
			(xy 366.324122 -286.37827) (xy 366.304831 -286.332994) (xy 366.293054 -286.28521) (xy 366.289094 -286.236156)
			(xy 365.970566 -286.236156) (xy 365.970054 -286.261602) (xy 365.96189 -286.311836) (xy 365.945774 -286.36011)
			(xy 365.922123 -286.405173) (xy 365.89155 -286.445859) (xy 365.854846 -286.481114) (xy 365.812962 -286.510024)
			(xy 365.766983 -286.531841) (xy 365.718099 -286.546001) (xy 365.667578 -286.552135) (xy 365.616726 -286.550086)
			(xy 365.566862 -286.539906) (xy 365.519276 -286.521859) (xy 365.475202 -286.496413) (xy 365.43578 -286.464226)
			(xy 365.402032 -286.426132) (xy 365.374831 -286.383118) (xy 365.354883 -286.336298) (xy 365.342704 -286.286884)
			(xy 365.338609 -286.236156) (xy 365.030512 -286.236156) (xy 365.03 -286.261602) (xy 365.021836 -286.311836)
			(xy 365.00572 -286.36011) (xy 364.982069 -286.405173) (xy 364.951496 -286.445859) (xy 364.914792 -286.481114)
			(xy 364.872908 -286.510024) (xy 364.826929 -286.531841) (xy 364.778045 -286.546001) (xy 364.727524 -286.552135)
			(xy 364.676672 -286.550086) (xy 364.626808 -286.539906) (xy 364.579222 -286.521859) (xy 364.535148 -286.496413)
			(xy 364.495726 -286.464226) (xy 364.461978 -286.426132) (xy 364.434777 -286.383118) (xy 364.414829 -286.336298)
			(xy 364.40265 -286.286884) (xy 364.398555 -286.236156) (xy 364.080044 -286.236156) (xy 364.079549 -286.260763)
			(xy 364.071654 -286.30934) (xy 364.05607 -286.356021) (xy 364.033199 -286.399598) (xy 364.003634 -286.438942)
			(xy 363.968141 -286.473034) (xy 363.927638 -286.50099) (xy 363.883176 -286.522088) (xy 363.835905 -286.53578)
			(xy 363.78705 -286.541712) (xy 363.737875 -286.539731) (xy 363.689656 -286.529887) (xy 363.64364 -286.512435)
			(xy 363.601019 -286.487828) (xy 363.562898 -286.456703) (xy 363.530263 -286.419866) (xy 363.50396 -286.37827)
			(xy 363.484669 -286.332994) (xy 363.472892 -286.28521) (xy 363.468932 -286.236156) (xy 361.405373 -286.236156)
			(xy 361.41152 -286.415734) (xy 361.41152 -286.71139) (xy 361.437428 -286.740346) (xy 361.456986 -286.742378)
			(xy 361.48165 -286.745493) (xy 361.529575 -286.758691) (xy 361.574729 -286.779481) (xy 361.615917 -286.807313)
			(xy 361.65205 -286.841451) (xy 361.682175 -286.880993) (xy 361.705494 -286.924894) (xy 361.721391 -286.971993)
			(xy 361.729445 -287.021046) (xy 361.729445 -287.045908) (xy 362.048547 -287.045908) (xy 362.052642 -286.99518)
			(xy 362.064821 -286.945766) (xy 362.084769 -286.898946) (xy 362.11197 -286.855932) (xy 362.145718 -286.817838)
			(xy 362.18514 -286.785651) (xy 362.229214 -286.760205) (xy 362.2768 -286.742158) (xy 362.326664 -286.731978)
			(xy 362.377516 -286.729929) (xy 362.428037 -286.736063) (xy 362.476921 -286.750223) (xy 362.5229 -286.77204)
			(xy 362.564784 -286.80095) (xy 362.601488 -286.836205) (xy 362.632061 -286.876891) (xy 362.655712 -286.921954)
			(xy 362.671828 -286.970228) (xy 362.679992 -287.020462) (xy 362.680504 -287.045908) (xy 362.988601 -287.045908)
			(xy 362.992696 -286.99518) (xy 363.004875 -286.945766) (xy 363.024823 -286.898946) (xy 363.052024 -286.855932)
			(xy 363.085772 -286.817838) (xy 363.125194 -286.785651) (xy 363.169268 -286.760205) (xy 363.216854 -286.742158)
			(xy 363.266718 -286.731978) (xy 363.31757 -286.729929) (xy 363.368091 -286.736063) (xy 363.416975 -286.750223)
			(xy 363.462954 -286.77204) (xy 363.504838 -286.80095) (xy 363.541542 -286.836205) (xy 363.572115 -286.876891)
			(xy 363.595766 -286.921954) (xy 363.611882 -286.970228) (xy 363.620046 -287.020462) (xy 363.620558 -287.045908)
			(xy 363.620553 -287.046162) (xy 363.939086 -287.046162) (xy 363.943046 -286.997108) (xy 363.954823 -286.949324)
			(xy 363.974114 -286.904048) (xy 364.000417 -286.862452) (xy 364.033052 -286.825615) (xy 364.071173 -286.79449)
			(xy 364.113794 -286.769883) (xy 364.15981 -286.752431) (xy 364.208029 -286.742587) (xy 364.257204 -286.740606)
			(xy 364.306059 -286.746538) (xy 364.35333 -286.76023) (xy 364.397792 -286.781328) (xy 364.438295 -286.809284)
			(xy 364.473788 -286.843376) (xy 364.503353 -286.88272) (xy 364.526224 -286.926297) (xy 364.541808 -286.972978)
			(xy 364.549703 -287.021555) (xy 364.550193 -287.045908) (xy 366.758994 -287.045908) (xy 366.762954 -286.996854)
			(xy 366.774731 -286.94907) (xy 366.794022 -286.903794) (xy 366.820325 -286.862198) (xy 366.85296 -286.825361)
			(xy 366.891081 -286.794236) (xy 366.933702 -286.769629) (xy 366.979718 -286.752177) (xy 367.027937 -286.742333)
			(xy 367.077112 -286.740352) (xy 367.125967 -286.746284) (xy 367.173238 -286.759976) (xy 367.2177 -286.781074)
			(xy 367.258203 -286.80903) (xy 367.293696 -286.843122) (xy 367.323261 -286.882466) (xy 367.346132 -286.926043)
			(xy 367.361716 -286.972724) (xy 367.369611 -287.021301) (xy 367.370106 -287.045908) (xy 369.578902 -287.045908)
			(xy 369.582862 -286.996854) (xy 369.594639 -286.94907) (xy 369.61393 -286.903794) (xy 369.640233 -286.862198)
			(xy 369.672868 -286.825361) (xy 369.710989 -286.794236) (xy 369.75361 -286.769629) (xy 369.799626 -286.752177)
			(xy 369.847845 -286.742333) (xy 369.89702 -286.740352) (xy 369.945875 -286.746284) (xy 369.993146 -286.759976)
			(xy 370.037608 -286.781074) (xy 370.078111 -286.80903) (xy 370.113604 -286.843122) (xy 370.143169 -286.882466)
			(xy 370.16604 -286.926043) (xy 370.181624 -286.972724) (xy 370.189519 -287.021301) (xy 370.190014 -287.045908)
			(xy 372.399064 -287.045908) (xy 372.403024 -286.996854) (xy 372.414801 -286.94907) (xy 372.434092 -286.903794)
			(xy 372.460395 -286.862198) (xy 372.49303 -286.825361) (xy 372.531151 -286.794236) (xy 372.573772 -286.769629)
			(xy 372.619788 -286.752177) (xy 372.668007 -286.742333) (xy 372.717182 -286.740352) (xy 372.766037 -286.746284)
			(xy 372.813308 -286.759976) (xy 372.85777 -286.781074) (xy 372.898273 -286.80903) (xy 372.933766 -286.843122)
			(xy 372.963331 -286.882466) (xy 372.986202 -286.926043) (xy 373.001786 -286.972724) (xy 373.009681 -287.021301)
			(xy 373.010176 -287.045908) (xy 373.009681 -287.070515) (xy 373.001786 -287.119092) (xy 372.986202 -287.165773)
			(xy 372.963331 -287.20935) (xy 372.933766 -287.248694) (xy 372.898273 -287.282786) (xy 372.85777 -287.310742)
			(xy 372.813308 -287.33184) (xy 372.766037 -287.345532) (xy 372.717182 -287.351464) (xy 372.668007 -287.349483)
			(xy 372.619788 -287.339639) (xy 372.573772 -287.322187) (xy 372.531151 -287.29758) (xy 372.49303 -287.266455)
			(xy 372.460395 -287.229618) (xy 372.434092 -287.188022) (xy 372.414801 -287.142746) (xy 372.403024 -287.094962)
			(xy 372.399064 -287.045908) (xy 370.190014 -287.045908) (xy 370.189519 -287.070515) (xy 370.181624 -287.119092)
			(xy 370.16604 -287.165773) (xy 370.143169 -287.20935) (xy 370.113604 -287.248694) (xy 370.078111 -287.282786)
			(xy 370.037608 -287.310742) (xy 369.993146 -287.33184) (xy 369.945875 -287.345532) (xy 369.89702 -287.351464)
			(xy 369.847845 -287.349483) (xy 369.799626 -287.339639) (xy 369.75361 -287.322187) (xy 369.710989 -287.29758)
			(xy 369.672868 -287.266455) (xy 369.640233 -287.229618) (xy 369.61393 -287.188022) (xy 369.594639 -287.142746)
			(xy 369.582862 -287.094962) (xy 369.578902 -287.045908) (xy 367.370106 -287.045908) (xy 367.369611 -287.070515)
			(xy 367.361716 -287.119092) (xy 367.346132 -287.165773) (xy 367.323261 -287.20935) (xy 367.293696 -287.248694)
			(xy 367.258203 -287.282786) (xy 367.2177 -287.310742) (xy 367.173238 -287.33184) (xy 367.125967 -287.345532)
			(xy 367.077112 -287.351464) (xy 367.027937 -287.349483) (xy 366.979718 -287.339639) (xy 366.933702 -287.322187)
			(xy 366.891081 -287.29758) (xy 366.85296 -287.266455) (xy 366.820325 -287.229618) (xy 366.794022 -287.188022)
			(xy 366.774731 -287.142746) (xy 366.762954 -287.094962) (xy 366.758994 -287.045908) (xy 364.550193 -287.045908)
			(xy 364.550198 -287.046162) (xy 364.549703 -287.070769) (xy 364.541808 -287.119346) (xy 364.526224 -287.166027)
			(xy 364.503353 -287.209604) (xy 364.473788 -287.248948) (xy 364.438295 -287.28304) (xy 364.397792 -287.310996)
			(xy 364.35333 -287.332094) (xy 364.306059 -287.345786) (xy 364.257204 -287.351718) (xy 364.208029 -287.349737)
			(xy 364.15981 -287.339893) (xy 364.113794 -287.322441) (xy 364.071173 -287.297834) (xy 364.033052 -287.266709)
			(xy 364.000417 -287.229872) (xy 363.974114 -287.188276) (xy 363.954823 -287.143) (xy 363.943046 -287.095216)
			(xy 363.939086 -287.046162) (xy 363.620553 -287.046162) (xy 363.620046 -287.071354) (xy 363.611882 -287.121588)
			(xy 363.595766 -287.169862) (xy 363.572115 -287.214925) (xy 363.541542 -287.255611) (xy 363.504838 -287.290866)
			(xy 363.462954 -287.319776) (xy 363.416975 -287.341593) (xy 363.368091 -287.355753) (xy 363.31757 -287.361887)
			(xy 363.266718 -287.359838) (xy 363.216854 -287.349658) (xy 363.169268 -287.331611) (xy 363.125194 -287.306165)
			(xy 363.085772 -287.273978) (xy 363.052024 -287.235884) (xy 363.024823 -287.19287) (xy 363.004875 -287.14605)
			(xy 362.992696 -287.096636) (xy 362.988601 -287.045908) (xy 362.680504 -287.045908) (xy 362.679992 -287.071354)
			(xy 362.671828 -287.121588) (xy 362.655712 -287.169862) (xy 362.632061 -287.214925) (xy 362.601488 -287.255611)
			(xy 362.564784 -287.290866) (xy 362.5229 -287.319776) (xy 362.476921 -287.341593) (xy 362.428037 -287.355753)
			(xy 362.377516 -287.361887) (xy 362.326664 -287.359838) (xy 362.2768 -287.349658) (xy 362.229214 -287.331611)
			(xy 362.18514 -287.306165) (xy 362.145718 -287.273978) (xy 362.11197 -287.235884) (xy 362.084769 -287.19287)
			(xy 362.064821 -287.14605) (xy 362.052642 -287.096636) (xy 362.048547 -287.045908) (xy 361.729445 -287.045908)
			(xy 361.729445 -287.070756) (xy 361.72139 -287.119808) (xy 361.705493 -287.166908) (xy 361.682174 -287.210808)
			(xy 361.652049 -287.25035) (xy 361.615915 -287.284488) (xy 361.574727 -287.31232) (xy 361.529574 -287.333109)
			(xy 361.481648 -287.346307) (xy 361.456986 -287.349438) (xy 361.437428 -287.35147) (xy 361.41152 -287.380426)
			(xy 361.41152 -287.856168) (xy 361.589078 -287.856168) (xy 361.593038 -287.807114) (xy 361.604815 -287.75933)
			(xy 361.624106 -287.714054) (xy 361.650409 -287.672458) (xy 361.683044 -287.635621) (xy 361.721165 -287.604496)
			(xy 361.763786 -287.579889) (xy 361.809802 -287.562437) (xy 361.858021 -287.552593) (xy 361.907196 -287.550612)
			(xy 361.956051 -287.556544) (xy 362.003322 -287.570236) (xy 362.047784 -287.591334) (xy 362.088287 -287.61929)
			(xy 362.12378 -287.653382) (xy 362.153345 -287.692726) (xy 362.176216 -287.736303) (xy 362.1918 -287.782984)
			(xy 362.199695 -287.831561) (xy 362.20019 -287.856168) (xy 362.528878 -287.856168) (xy 362.532838 -287.807114)
			(xy 362.544615 -287.75933) (xy 362.563906 -287.714054) (xy 362.590209 -287.672458) (xy 362.622844 -287.635621)
			(xy 362.660965 -287.604496) (xy 362.703586 -287.579889) (xy 362.749602 -287.562437) (xy 362.797821 -287.552593)
			(xy 362.846996 -287.550612) (xy 362.895851 -287.556544) (xy 362.943122 -287.570236) (xy 362.987584 -287.591334)
			(xy 363.028087 -287.61929) (xy 363.06358 -287.653382) (xy 363.093145 -287.692726) (xy 363.116016 -287.736303)
			(xy 363.1316 -287.782984) (xy 363.139495 -287.831561) (xy 363.13999 -287.856168) (xy 363.468932 -287.856168)
			(xy 363.472892 -287.807114) (xy 363.484669 -287.75933) (xy 363.50396 -287.714054) (xy 363.530263 -287.672458)
			(xy 363.562898 -287.635621) (xy 363.601019 -287.604496) (xy 363.64364 -287.579889) (xy 363.689656 -287.562437)
			(xy 363.737875 -287.552593) (xy 363.78705 -287.550612) (xy 363.835905 -287.556544) (xy 363.883176 -287.570236)
			(xy 363.927638 -287.591334) (xy 363.968141 -287.61929) (xy 364.003634 -287.653382) (xy 364.033199 -287.692726)
			(xy 364.05607 -287.736303) (xy 364.071654 -287.782984) (xy 364.079549 -287.831561) (xy 364.080044 -287.856168)
			(xy 364.398555 -287.856168) (xy 364.40265 -287.80544) (xy 364.414829 -287.756026) (xy 364.434777 -287.709206)
			(xy 364.461978 -287.666192) (xy 364.495726 -287.628098) (xy 364.535148 -287.595911) (xy 364.579222 -287.570465)
			(xy 364.626808 -287.552418) (xy 364.676672 -287.542238) (xy 364.727524 -287.540189) (xy 364.778045 -287.546323)
			(xy 364.826929 -287.560483) (xy 364.872908 -287.5823) (xy 364.914792 -287.61121) (xy 364.951496 -287.646465)
			(xy 364.982069 -287.687151) (xy 365.00572 -287.732214) (xy 365.021836 -287.780488) (xy 365.03 -287.830722)
			(xy 365.030512 -287.856168) (xy 365.338609 -287.856168) (xy 365.342704 -287.80544) (xy 365.354883 -287.756026)
			(xy 365.374831 -287.709206) (xy 365.402032 -287.666192) (xy 365.43578 -287.628098) (xy 365.475202 -287.595911)
			(xy 365.519276 -287.570465) (xy 365.566862 -287.552418) (xy 365.616726 -287.542238) (xy 365.667578 -287.540189)
			(xy 365.718099 -287.546323) (xy 365.766983 -287.560483) (xy 365.812962 -287.5823) (xy 365.854846 -287.61121)
			(xy 365.89155 -287.646465) (xy 365.922123 -287.687151) (xy 365.945774 -287.732214) (xy 365.96189 -287.780488)
			(xy 365.970054 -287.830722) (xy 365.970566 -287.856168) (xy 366.289094 -287.856168) (xy 366.293054 -287.807114)
			(xy 366.304831 -287.75933) (xy 366.324122 -287.714054) (xy 366.350425 -287.672458) (xy 366.38306 -287.635621)
			(xy 366.421181 -287.604496) (xy 366.463802 -287.579889) (xy 366.509818 -287.562437) (xy 366.558037 -287.552593)
			(xy 366.607212 -287.550612) (xy 366.656067 -287.556544) (xy 366.703338 -287.570236) (xy 366.7478 -287.591334)
			(xy 366.788303 -287.61929) (xy 366.823796 -287.653382) (xy 366.853361 -287.692726) (xy 366.876232 -287.736303)
			(xy 366.891816 -287.782984) (xy 366.899711 -287.831561) (xy 366.900206 -287.856168) (xy 367.218463 -287.856168)
			(xy 367.222558 -287.80544) (xy 367.234737 -287.756026) (xy 367.254685 -287.709206) (xy 367.281886 -287.666192)
			(xy 367.315634 -287.628098) (xy 367.355056 -287.595911) (xy 367.39913 -287.570465) (xy 367.446716 -287.552418)
			(xy 367.49658 -287.542238) (xy 367.547432 -287.540189) (xy 367.597953 -287.546323) (xy 367.646837 -287.560483)
			(xy 367.692816 -287.5823) (xy 367.7347 -287.61121) (xy 367.771404 -287.646465) (xy 367.801977 -287.687151)
			(xy 367.825628 -287.732214) (xy 367.841744 -287.780488) (xy 367.849908 -287.830722) (xy 367.85042 -287.856168)
			(xy 368.158517 -287.856168) (xy 368.162612 -287.80544) (xy 368.174791 -287.756026) (xy 368.194739 -287.709206)
			(xy 368.22194 -287.666192) (xy 368.255688 -287.628098) (xy 368.29511 -287.595911) (xy 368.339184 -287.570465)
			(xy 368.38677 -287.552418) (xy 368.436634 -287.542238) (xy 368.487486 -287.540189) (xy 368.538007 -287.546323)
			(xy 368.586891 -287.560483) (xy 368.63287 -287.5823) (xy 368.674754 -287.61121) (xy 368.711458 -287.646465)
			(xy 368.742031 -287.687151) (xy 368.765682 -287.732214) (xy 368.781798 -287.780488) (xy 368.789962 -287.830722)
			(xy 368.790474 -287.856168) (xy 369.109002 -287.856168) (xy 369.112962 -287.807114) (xy 369.124739 -287.75933)
			(xy 369.14403 -287.714054) (xy 369.170333 -287.672458) (xy 369.202968 -287.635621) (xy 369.241089 -287.604496)
			(xy 369.28371 -287.579889) (xy 369.329726 -287.562437) (xy 369.377945 -287.552593) (xy 369.42712 -287.550612)
			(xy 369.475975 -287.556544) (xy 369.523246 -287.570236) (xy 369.567708 -287.591334) (xy 369.608211 -287.61929)
			(xy 369.643704 -287.653382) (xy 369.673269 -287.692726) (xy 369.69614 -287.736303) (xy 369.711724 -287.782984)
			(xy 369.719619 -287.831561) (xy 369.720114 -287.856168) (xy 370.038625 -287.856168) (xy 370.04272 -287.80544)
			(xy 370.054899 -287.756026) (xy 370.074847 -287.709206) (xy 370.102048 -287.666192) (xy 370.135796 -287.628098)
			(xy 370.175218 -287.595911) (xy 370.219292 -287.570465) (xy 370.266878 -287.552418) (xy 370.316742 -287.542238)
			(xy 370.367594 -287.540189) (xy 370.418115 -287.546323) (xy 370.466999 -287.560483) (xy 370.512978 -287.5823)
			(xy 370.554862 -287.61121) (xy 370.591566 -287.646465) (xy 370.622139 -287.687151) (xy 370.64579 -287.732214)
			(xy 370.661906 -287.780488) (xy 370.67007 -287.830722) (xy 370.670582 -287.856168) (xy 370.978679 -287.856168)
			(xy 370.982774 -287.80544) (xy 370.994953 -287.756026) (xy 371.014901 -287.709206) (xy 371.042102 -287.666192)
			(xy 371.07585 -287.628098) (xy 371.115272 -287.595911) (xy 371.159346 -287.570465) (xy 371.206932 -287.552418)
			(xy 371.256796 -287.542238) (xy 371.307648 -287.540189) (xy 371.358169 -287.546323) (xy 371.407053 -287.560483)
			(xy 371.453032 -287.5823) (xy 371.494916 -287.61121) (xy 371.53162 -287.646465) (xy 371.562193 -287.687151)
			(xy 371.585844 -287.732214) (xy 371.60196 -287.780488) (xy 371.610124 -287.830722) (xy 371.610636 -287.856168)
			(xy 371.92891 -287.856168) (xy 371.93287 -287.807114) (xy 371.944647 -287.75933) (xy 371.963938 -287.714054)
			(xy 371.990241 -287.672458) (xy 372.022876 -287.635621) (xy 372.060997 -287.604496) (xy 372.103618 -287.579889)
			(xy 372.149634 -287.562437) (xy 372.197853 -287.552593) (xy 372.247028 -287.550612) (xy 372.295883 -287.556544)
			(xy 372.343154 -287.570236) (xy 372.387616 -287.591334) (xy 372.428119 -287.61929) (xy 372.463612 -287.653382)
			(xy 372.493177 -287.692726) (xy 372.516048 -287.736303) (xy 372.531632 -287.782984) (xy 372.539527 -287.831561)
			(xy 372.540022 -287.856168) (xy 372.858533 -287.856168) (xy 372.862628 -287.80544) (xy 372.874807 -287.756026)
			(xy 372.894755 -287.709206) (xy 372.921956 -287.666192) (xy 372.955704 -287.628098) (xy 372.995126 -287.595911)
			(xy 373.0392 -287.570465) (xy 373.086786 -287.552418) (xy 373.13665 -287.542238) (xy 373.187502 -287.540189)
			(xy 373.238023 -287.546323) (xy 373.286907 -287.560483) (xy 373.332886 -287.5823) (xy 373.37477 -287.61121)
			(xy 373.411474 -287.646465) (xy 373.442047 -287.687151) (xy 373.465698 -287.732214) (xy 373.481814 -287.780488)
			(xy 373.489978 -287.830722) (xy 373.49049 -287.856168) (xy 373.798587 -287.856168) (xy 373.802682 -287.80544)
			(xy 373.814861 -287.756026) (xy 373.834809 -287.709206) (xy 373.86201 -287.666192) (xy 373.895758 -287.628098)
			(xy 373.93518 -287.595911) (xy 373.979254 -287.570465) (xy 374.02684 -287.552418) (xy 374.076704 -287.542238)
			(xy 374.127556 -287.540189) (xy 374.178077 -287.546323) (xy 374.226961 -287.560483) (xy 374.27294 -287.5823)
			(xy 374.314824 -287.61121) (xy 374.351528 -287.646465) (xy 374.382101 -287.687151) (xy 374.405752 -287.732214)
			(xy 374.421868 -287.780488) (xy 374.430032 -287.830722) (xy 374.430544 -287.856168) (xy 374.430032 -287.881614)
			(xy 374.421868 -287.931848) (xy 374.405752 -287.980122) (xy 374.382101 -288.025185) (xy 374.351528 -288.065871)
			(xy 374.314824 -288.101126) (xy 374.27294 -288.130036) (xy 374.226961 -288.151853) (xy 374.178077 -288.166013)
			(xy 374.127556 -288.172147) (xy 374.076704 -288.170098) (xy 374.02684 -288.159918) (xy 373.979254 -288.141871)
			(xy 373.93518 -288.116425) (xy 373.895758 -288.084238) (xy 373.86201 -288.046144) (xy 373.834809 -288.00313)
			(xy 373.814861 -287.95631) (xy 373.802682 -287.906896) (xy 373.798587 -287.856168) (xy 373.49049 -287.856168)
			(xy 373.489978 -287.881614) (xy 373.481814 -287.931848) (xy 373.465698 -287.980122) (xy 373.442047 -288.025185)
			(xy 373.411474 -288.065871) (xy 373.37477 -288.101126) (xy 373.332886 -288.130036) (xy 373.286907 -288.151853)
			(xy 373.238023 -288.166013) (xy 373.187502 -288.172147) (xy 373.13665 -288.170098) (xy 373.086786 -288.159918)
			(xy 373.0392 -288.141871) (xy 372.995126 -288.116425) (xy 372.955704 -288.084238) (xy 372.921956 -288.046144)
			(xy 372.894755 -288.00313) (xy 372.874807 -287.95631) (xy 372.862628 -287.906896) (xy 372.858533 -287.856168)
			(xy 372.540022 -287.856168) (xy 372.539527 -287.880775) (xy 372.531632 -287.929352) (xy 372.516048 -287.976033)
			(xy 372.493177 -288.01961) (xy 372.463612 -288.058954) (xy 372.428119 -288.093046) (xy 372.387616 -288.121002)
			(xy 372.343154 -288.1421) (xy 372.295883 -288.155792) (xy 372.247028 -288.161724) (xy 372.197853 -288.159743)
			(xy 372.149634 -288.149899) (xy 372.103618 -288.132447) (xy 372.060997 -288.10784) (xy 372.022876 -288.076715)
			(xy 371.990241 -288.039878) (xy 371.963938 -287.998282) (xy 371.944647 -287.953006) (xy 371.93287 -287.905222)
			(xy 371.92891 -287.856168) (xy 371.610636 -287.856168) (xy 371.610124 -287.881614) (xy 371.60196 -287.931848)
			(xy 371.585844 -287.980122) (xy 371.562193 -288.025185) (xy 371.53162 -288.065871) (xy 371.494916 -288.101126)
			(xy 371.453032 -288.130036) (xy 371.407053 -288.151853) (xy 371.358169 -288.166013) (xy 371.307648 -288.172147)
			(xy 371.256796 -288.170098) (xy 371.206932 -288.159918) (xy 371.159346 -288.141871) (xy 371.115272 -288.116425)
			(xy 371.07585 -288.084238) (xy 371.042102 -288.046144) (xy 371.014901 -288.00313) (xy 370.994953 -287.95631)
			(xy 370.982774 -287.906896) (xy 370.978679 -287.856168) (xy 370.670582 -287.856168) (xy 370.67007 -287.881614)
			(xy 370.661906 -287.931848) (xy 370.64579 -287.980122) (xy 370.622139 -288.025185) (xy 370.591566 -288.065871)
			(xy 370.554862 -288.101126) (xy 370.512978 -288.130036) (xy 370.466999 -288.151853) (xy 370.418115 -288.166013)
			(xy 370.367594 -288.172147) (xy 370.316742 -288.170098) (xy 370.266878 -288.159918) (xy 370.219292 -288.141871)
			(xy 370.175218 -288.116425) (xy 370.135796 -288.084238) (xy 370.102048 -288.046144) (xy 370.074847 -288.00313)
			(xy 370.054899 -287.95631) (xy 370.04272 -287.906896) (xy 370.038625 -287.856168) (xy 369.720114 -287.856168)
			(xy 369.719619 -287.880775) (xy 369.711724 -287.929352) (xy 369.69614 -287.976033) (xy 369.673269 -288.01961)
			(xy 369.643704 -288.058954) (xy 369.608211 -288.093046) (xy 369.567708 -288.121002) (xy 369.523246 -288.1421)
			(xy 369.475975 -288.155792) (xy 369.42712 -288.161724) (xy 369.377945 -288.159743) (xy 369.329726 -288.149899)
			(xy 369.28371 -288.132447) (xy 369.241089 -288.10784) (xy 369.202968 -288.076715) (xy 369.170333 -288.039878)
			(xy 369.14403 -287.998282) (xy 369.124739 -287.953006) (xy 369.112962 -287.905222) (xy 369.109002 -287.856168)
			(xy 368.790474 -287.856168) (xy 368.789962 -287.881614) (xy 368.781798 -287.931848) (xy 368.765682 -287.980122)
			(xy 368.742031 -288.025185) (xy 368.711458 -288.065871) (xy 368.674754 -288.101126) (xy 368.63287 -288.130036)
			(xy 368.586891 -288.151853) (xy 368.538007 -288.166013) (xy 368.487486 -288.172147) (xy 368.436634 -288.170098)
			(xy 368.38677 -288.159918) (xy 368.339184 -288.141871) (xy 368.29511 -288.116425) (xy 368.255688 -288.084238)
			(xy 368.22194 -288.046144) (xy 368.194739 -288.00313) (xy 368.174791 -287.95631) (xy 368.162612 -287.906896)
			(xy 368.158517 -287.856168) (xy 367.85042 -287.856168) (xy 367.849908 -287.881614) (xy 367.841744 -287.931848)
			(xy 367.825628 -287.980122) (xy 367.801977 -288.025185) (xy 367.771404 -288.065871) (xy 367.7347 -288.101126)
			(xy 367.692816 -288.130036) (xy 367.646837 -288.151853) (xy 367.597953 -288.166013) (xy 367.547432 -288.172147)
			(xy 367.49658 -288.170098) (xy 367.446716 -288.159918) (xy 367.39913 -288.141871) (xy 367.355056 -288.116425)
			(xy 367.315634 -288.084238) (xy 367.281886 -288.046144) (xy 367.254685 -288.00313) (xy 367.234737 -287.95631)
			(xy 367.222558 -287.906896) (xy 367.218463 -287.856168) (xy 366.900206 -287.856168) (xy 366.899711 -287.880775)
			(xy 366.891816 -287.929352) (xy 366.876232 -287.976033) (xy 366.853361 -288.01961) (xy 366.823796 -288.058954)
			(xy 366.788303 -288.093046) (xy 366.7478 -288.121002) (xy 366.703338 -288.1421) (xy 366.656067 -288.155792)
			(xy 366.607212 -288.161724) (xy 366.558037 -288.159743) (xy 366.509818 -288.149899) (xy 366.463802 -288.132447)
			(xy 366.421181 -288.10784) (xy 366.38306 -288.076715) (xy 366.350425 -288.039878) (xy 366.324122 -287.998282)
			(xy 366.304831 -287.953006) (xy 366.293054 -287.905222) (xy 366.289094 -287.856168) (xy 365.970566 -287.856168)
			(xy 365.970054 -287.881614) (xy 365.96189 -287.931848) (xy 365.945774 -287.980122) (xy 365.922123 -288.025185)
			(xy 365.89155 -288.065871) (xy 365.854846 -288.101126) (xy 365.812962 -288.130036) (xy 365.766983 -288.151853)
			(xy 365.718099 -288.166013) (xy 365.667578 -288.172147) (xy 365.616726 -288.170098) (xy 365.566862 -288.159918)
			(xy 365.519276 -288.141871) (xy 365.475202 -288.116425) (xy 365.43578 -288.084238) (xy 365.402032 -288.046144)
			(xy 365.374831 -288.00313) (xy 365.354883 -287.95631) (xy 365.342704 -287.906896) (xy 365.338609 -287.856168)
			(xy 365.030512 -287.856168) (xy 365.03 -287.881614) (xy 365.021836 -287.931848) (xy 365.00572 -287.980122)
			(xy 364.982069 -288.025185) (xy 364.951496 -288.065871) (xy 364.914792 -288.101126) (xy 364.872908 -288.130036)
			(xy 364.826929 -288.151853) (xy 364.778045 -288.166013) (xy 364.727524 -288.172147) (xy 364.676672 -288.170098)
			(xy 364.626808 -288.159918) (xy 364.579222 -288.141871) (xy 364.535148 -288.116425) (xy 364.495726 -288.084238)
			(xy 364.461978 -288.046144) (xy 364.434777 -288.00313) (xy 364.414829 -287.95631) (xy 364.40265 -287.906896)
			(xy 364.398555 -287.856168) (xy 364.080044 -287.856168) (xy 364.079549 -287.880775) (xy 364.071654 -287.929352)
			(xy 364.05607 -287.976033) (xy 364.033199 -288.01961) (xy 364.003634 -288.058954) (xy 363.968141 -288.093046)
			(xy 363.927638 -288.121002) (xy 363.883176 -288.1421) (xy 363.835905 -288.155792) (xy 363.78705 -288.161724)
			(xy 363.737875 -288.159743) (xy 363.689656 -288.149899) (xy 363.64364 -288.132447) (xy 363.601019 -288.10784)
			(xy 363.562898 -288.076715) (xy 363.530263 -288.039878) (xy 363.50396 -287.998282) (xy 363.484669 -287.953006)
			(xy 363.472892 -287.905222) (xy 363.468932 -287.856168) (xy 363.13999 -287.856168) (xy 363.139495 -287.880775)
			(xy 363.1316 -287.929352) (xy 363.116016 -287.976033) (xy 363.093145 -288.01961) (xy 363.06358 -288.058954)
			(xy 363.028087 -288.093046) (xy 362.987584 -288.121002) (xy 362.943122 -288.1421) (xy 362.895851 -288.155792)
			(xy 362.846996 -288.161724) (xy 362.797821 -288.159743) (xy 362.749602 -288.149899) (xy 362.703586 -288.132447)
			(xy 362.660965 -288.10784) (xy 362.622844 -288.076715) (xy 362.590209 -288.039878) (xy 362.563906 -287.998282)
			(xy 362.544615 -287.953006) (xy 362.532838 -287.905222) (xy 362.528878 -287.856168) (xy 362.20019 -287.856168)
			(xy 362.199695 -287.880775) (xy 362.1918 -287.929352) (xy 362.176216 -287.976033) (xy 362.153345 -288.01961)
			(xy 362.12378 -288.058954) (xy 362.088287 -288.093046) (xy 362.047784 -288.121002) (xy 362.003322 -288.1421)
			(xy 361.956051 -288.155792) (xy 361.907196 -288.161724) (xy 361.858021 -288.159743) (xy 361.809802 -288.149899)
			(xy 361.763786 -288.132447) (xy 361.721165 -288.10784) (xy 361.683044 -288.076715) (xy 361.650409 -288.039878)
			(xy 361.624106 -287.998282) (xy 361.604815 -287.953006) (xy 361.593038 -287.905222) (xy 361.589078 -287.856168)
			(xy 361.41152 -287.856168) (xy 361.41152 -288.331402) (xy 361.437428 -288.360358) (xy 361.456986 -288.36239)
			(xy 361.481649 -288.365505) (xy 361.529572 -288.378703) (xy 361.574724 -288.399492) (xy 361.61591 -288.427323)
			(xy 361.652042 -288.46146) (xy 361.682165 -288.501001) (xy 361.705483 -288.5449) (xy 361.721379 -288.591997)
			(xy 361.729434 -288.641048) (xy 361.729433 -288.66592) (xy 362.048547 -288.66592) (xy 362.052642 -288.615192)
			(xy 362.064821 -288.565778) (xy 362.084769 -288.518958) (xy 362.11197 -288.475944) (xy 362.145718 -288.43785)
			(xy 362.18514 -288.405663) (xy 362.229214 -288.380217) (xy 362.2768 -288.36217) (xy 362.326664 -288.35199)
			(xy 362.377516 -288.349941) (xy 362.428037 -288.356075) (xy 362.476921 -288.370235) (xy 362.5229 -288.392052)
			(xy 362.564784 -288.420962) (xy 362.601488 -288.456217) (xy 362.632061 -288.496903) (xy 362.655712 -288.541966)
			(xy 362.671828 -288.59024) (xy 362.679992 -288.640474) (xy 362.680504 -288.66592) (xy 362.988601 -288.66592)
			(xy 362.992696 -288.615192) (xy 363.004875 -288.565778) (xy 363.024823 -288.518958) (xy 363.052024 -288.475944)
			(xy 363.085772 -288.43785) (xy 363.125194 -288.405663) (xy 363.169268 -288.380217) (xy 363.216854 -288.36217)
			(xy 363.266718 -288.35199) (xy 363.31757 -288.349941) (xy 363.368091 -288.356075) (xy 363.416975 -288.370235)
			(xy 363.462954 -288.392052) (xy 363.504838 -288.420962) (xy 363.541542 -288.456217) (xy 363.572115 -288.496903)
			(xy 363.595766 -288.541966) (xy 363.611882 -288.59024) (xy 363.620046 -288.640474) (xy 363.620558 -288.66592)
			(xy 363.939086 -288.66592) (xy 363.943046 -288.616866) (xy 363.954823 -288.569082) (xy 363.974114 -288.523806)
			(xy 364.000417 -288.48221) (xy 364.033052 -288.445373) (xy 364.071173 -288.414248) (xy 364.113794 -288.389641)
			(xy 364.15981 -288.372189) (xy 364.208029 -288.362345) (xy 364.257204 -288.360364) (xy 364.306059 -288.366296)
			(xy 364.35333 -288.379988) (xy 364.397792 -288.401086) (xy 364.438295 -288.429042) (xy 364.473788 -288.463134)
			(xy 364.503353 -288.502478) (xy 364.526224 -288.546055) (xy 364.541808 -288.592736) (xy 364.549703 -288.641313)
			(xy 364.550198 -288.66592) (xy 364.878886 -288.66592) (xy 364.882846 -288.616866) (xy 364.894623 -288.569082)
			(xy 364.913914 -288.523806) (xy 364.940217 -288.48221) (xy 364.972852 -288.445373) (xy 365.010973 -288.414248)
			(xy 365.053594 -288.389641) (xy 365.09961 -288.372189) (xy 365.147829 -288.362345) (xy 365.197004 -288.360364)
			(xy 365.245859 -288.366296) (xy 365.29313 -288.379988) (xy 365.337592 -288.401086) (xy 365.378095 -288.429042)
			(xy 365.413588 -288.463134) (xy 365.443153 -288.502478) (xy 365.466024 -288.546055) (xy 365.481608 -288.592736)
			(xy 365.489503 -288.641313) (xy 365.489998 -288.66592) (xy 365.81894 -288.66592) (xy 365.8229 -288.616866)
			(xy 365.834677 -288.569082) (xy 365.853968 -288.523806) (xy 365.880271 -288.48221) (xy 365.912906 -288.445373)
			(xy 365.951027 -288.414248) (xy 365.993648 -288.389641) (xy 366.039664 -288.372189) (xy 366.087883 -288.362345)
			(xy 366.137058 -288.360364) (xy 366.185913 -288.366296) (xy 366.233184 -288.379988) (xy 366.277646 -288.401086)
			(xy 366.318149 -288.429042) (xy 366.353642 -288.463134) (xy 366.383207 -288.502478) (xy 366.406078 -288.546055)
			(xy 366.421662 -288.592736) (xy 366.429557 -288.641313) (xy 366.430052 -288.66592) (xy 366.758994 -288.66592)
			(xy 366.762954 -288.616866) (xy 366.774731 -288.569082) (xy 366.794022 -288.523806) (xy 366.820325 -288.48221)
			(xy 366.85296 -288.445373) (xy 366.891081 -288.414248) (xy 366.933702 -288.389641) (xy 366.979718 -288.372189)
			(xy 367.027937 -288.362345) (xy 367.077112 -288.360364) (xy 367.125967 -288.366296) (xy 367.173238 -288.379988)
			(xy 367.2177 -288.401086) (xy 367.258203 -288.429042) (xy 367.293696 -288.463134) (xy 367.323261 -288.502478)
			(xy 367.346132 -288.546055) (xy 367.361716 -288.592736) (xy 367.369611 -288.641313) (xy 367.370106 -288.66592)
			(xy 367.699048 -288.66592) (xy 367.703008 -288.616866) (xy 367.714785 -288.569082) (xy 367.734076 -288.523806)
			(xy 367.760379 -288.48221) (xy 367.793014 -288.445373) (xy 367.831135 -288.414248) (xy 367.873756 -288.389641)
			(xy 367.919772 -288.372189) (xy 367.967991 -288.362345) (xy 368.017166 -288.360364) (xy 368.066021 -288.366296)
			(xy 368.113292 -288.379988) (xy 368.157754 -288.401086) (xy 368.198257 -288.429042) (xy 368.23375 -288.463134)
			(xy 368.263315 -288.502478) (xy 368.286186 -288.546055) (xy 368.30177 -288.592736) (xy 368.309665 -288.641313)
			(xy 368.31016 -288.66592) (xy 368.639102 -288.66592) (xy 368.643062 -288.616866) (xy 368.654839 -288.569082)
			(xy 368.67413 -288.523806) (xy 368.700433 -288.48221) (xy 368.733068 -288.445373) (xy 368.771189 -288.414248)
			(xy 368.81381 -288.389641) (xy 368.859826 -288.372189) (xy 368.908045 -288.362345) (xy 368.95722 -288.360364)
			(xy 369.006075 -288.366296) (xy 369.053346 -288.379988) (xy 369.097808 -288.401086) (xy 369.138311 -288.429042)
			(xy 369.173804 -288.463134) (xy 369.203369 -288.502478) (xy 369.22624 -288.546055) (xy 369.241824 -288.592736)
			(xy 369.249719 -288.641313) (xy 369.250214 -288.66592) (xy 369.578902 -288.66592) (xy 369.582862 -288.616866)
			(xy 369.594639 -288.569082) (xy 369.61393 -288.523806) (xy 369.640233 -288.48221) (xy 369.672868 -288.445373)
			(xy 369.710989 -288.414248) (xy 369.75361 -288.389641) (xy 369.799626 -288.372189) (xy 369.847845 -288.362345)
			(xy 369.89702 -288.360364) (xy 369.945875 -288.366296) (xy 369.993146 -288.379988) (xy 370.037608 -288.401086)
			(xy 370.078111 -288.429042) (xy 370.113604 -288.463134) (xy 370.143169 -288.502478) (xy 370.16604 -288.546055)
			(xy 370.181624 -288.592736) (xy 370.189519 -288.641313) (xy 370.190014 -288.66592) (xy 370.518956 -288.66592)
			(xy 370.522916 -288.616866) (xy 370.534693 -288.569082) (xy 370.553984 -288.523806) (xy 370.580287 -288.48221)
			(xy 370.612922 -288.445373) (xy 370.651043 -288.414248) (xy 370.693664 -288.389641) (xy 370.73968 -288.372189)
			(xy 370.787899 -288.362345) (xy 370.837074 -288.360364) (xy 370.885929 -288.366296) (xy 370.9332 -288.379988)
			(xy 370.977662 -288.401086) (xy 371.018165 -288.429042) (xy 371.053658 -288.463134) (xy 371.083223 -288.502478)
			(xy 371.106094 -288.546055) (xy 371.121678 -288.592736) (xy 371.129573 -288.641313) (xy 371.130068 -288.66592)
			(xy 371.45901 -288.66592) (xy 371.46297 -288.616866) (xy 371.474747 -288.569082) (xy 371.494038 -288.523806)
			(xy 371.520341 -288.48221) (xy 371.552976 -288.445373) (xy 371.591097 -288.414248) (xy 371.633718 -288.389641)
			(xy 371.679734 -288.372189) (xy 371.727953 -288.362345) (xy 371.777128 -288.360364) (xy 371.825983 -288.366296)
			(xy 371.873254 -288.379988) (xy 371.917716 -288.401086) (xy 371.958219 -288.429042) (xy 371.993712 -288.463134)
			(xy 372.023277 -288.502478) (xy 372.046148 -288.546055) (xy 372.061732 -288.592736) (xy 372.069627 -288.641313)
			(xy 372.070122 -288.66592) (xy 372.399064 -288.66592) (xy 372.403024 -288.616866) (xy 372.414801 -288.569082)
			(xy 372.434092 -288.523806) (xy 372.460395 -288.48221) (xy 372.49303 -288.445373) (xy 372.531151 -288.414248)
			(xy 372.573772 -288.389641) (xy 372.619788 -288.372189) (xy 372.668007 -288.362345) (xy 372.717182 -288.360364)
			(xy 372.766037 -288.366296) (xy 372.813308 -288.379988) (xy 372.85777 -288.401086) (xy 372.898273 -288.429042)
			(xy 372.933766 -288.463134) (xy 372.963331 -288.502478) (xy 372.986202 -288.546055) (xy 373.001786 -288.592736)
			(xy 373.009681 -288.641313) (xy 373.010176 -288.66592) (xy 373.339118 -288.66592) (xy 373.343078 -288.616866)
			(xy 373.354855 -288.569082) (xy 373.374146 -288.523806) (xy 373.400449 -288.48221) (xy 373.433084 -288.445373)
			(xy 373.471205 -288.414248) (xy 373.513826 -288.389641) (xy 373.559842 -288.372189) (xy 373.608061 -288.362345)
			(xy 373.657236 -288.360364) (xy 373.706091 -288.366296) (xy 373.753362 -288.379988) (xy 373.797824 -288.401086)
			(xy 373.838327 -288.429042) (xy 373.87382 -288.463134) (xy 373.903385 -288.502478) (xy 373.926256 -288.546055)
			(xy 373.94184 -288.592736) (xy 373.949735 -288.641313) (xy 373.95023 -288.66592) (xy 373.949735 -288.690527)
			(xy 373.94184 -288.739104) (xy 373.926256 -288.785785) (xy 373.903385 -288.829362) (xy 373.87382 -288.868706)
			(xy 373.838327 -288.902798) (xy 373.797824 -288.930754) (xy 373.753362 -288.951852) (xy 373.706091 -288.965544)
			(xy 373.657236 -288.971476) (xy 373.608061 -288.969495) (xy 373.559842 -288.959651) (xy 373.513826 -288.942199)
			(xy 373.471205 -288.917592) (xy 373.433084 -288.886467) (xy 373.400449 -288.84963) (xy 373.374146 -288.808034)
			(xy 373.354855 -288.762758) (xy 373.343078 -288.714974) (xy 373.339118 -288.66592) (xy 373.010176 -288.66592)
			(xy 373.009681 -288.690527) (xy 373.001786 -288.739104) (xy 372.986202 -288.785785) (xy 372.963331 -288.829362)
			(xy 372.933766 -288.868706) (xy 372.898273 -288.902798) (xy 372.85777 -288.930754) (xy 372.813308 -288.951852)
			(xy 372.766037 -288.965544) (xy 372.717182 -288.971476) (xy 372.668007 -288.969495) (xy 372.619788 -288.959651)
			(xy 372.573772 -288.942199) (xy 372.531151 -288.917592) (xy 372.49303 -288.886467) (xy 372.460395 -288.84963)
			(xy 372.434092 -288.808034) (xy 372.414801 -288.762758) (xy 372.403024 -288.714974) (xy 372.399064 -288.66592)
			(xy 372.070122 -288.66592) (xy 372.069627 -288.690527) (xy 372.061732 -288.739104) (xy 372.046148 -288.785785)
			(xy 372.023277 -288.829362) (xy 371.993712 -288.868706) (xy 371.958219 -288.902798) (xy 371.917716 -288.930754)
			(xy 371.873254 -288.951852) (xy 371.825983 -288.965544) (xy 371.777128 -288.971476) (xy 371.727953 -288.969495)
			(xy 371.679734 -288.959651) (xy 371.633718 -288.942199) (xy 371.591097 -288.917592) (xy 371.552976 -288.886467)
			(xy 371.520341 -288.84963) (xy 371.494038 -288.808034) (xy 371.474747 -288.762758) (xy 371.46297 -288.714974)
			(xy 371.45901 -288.66592) (xy 371.130068 -288.66592) (xy 371.129573 -288.690527) (xy 371.121678 -288.739104)
			(xy 371.106094 -288.785785) (xy 371.083223 -288.829362) (xy 371.053658 -288.868706) (xy 371.018165 -288.902798)
			(xy 370.977662 -288.930754) (xy 370.9332 -288.951852) (xy 370.885929 -288.965544) (xy 370.837074 -288.971476)
			(xy 370.787899 -288.969495) (xy 370.73968 -288.959651) (xy 370.693664 -288.942199) (xy 370.651043 -288.917592)
			(xy 370.612922 -288.886467) (xy 370.580287 -288.84963) (xy 370.553984 -288.808034) (xy 370.534693 -288.762758)
			(xy 370.522916 -288.714974) (xy 370.518956 -288.66592) (xy 370.190014 -288.66592) (xy 370.189519 -288.690527)
			(xy 370.181624 -288.739104) (xy 370.16604 -288.785785) (xy 370.143169 -288.829362) (xy 370.113604 -288.868706)
			(xy 370.078111 -288.902798) (xy 370.037608 -288.930754) (xy 369.993146 -288.951852) (xy 369.945875 -288.965544)
			(xy 369.89702 -288.971476) (xy 369.847845 -288.969495) (xy 369.799626 -288.959651) (xy 369.75361 -288.942199)
			(xy 369.710989 -288.917592) (xy 369.672868 -288.886467) (xy 369.640233 -288.84963) (xy 369.61393 -288.808034)
			(xy 369.594639 -288.762758) (xy 369.582862 -288.714974) (xy 369.578902 -288.66592) (xy 369.250214 -288.66592)
			(xy 369.249719 -288.690527) (xy 369.241824 -288.739104) (xy 369.22624 -288.785785) (xy 369.203369 -288.829362)
			(xy 369.173804 -288.868706) (xy 369.138311 -288.902798) (xy 369.097808 -288.930754) (xy 369.053346 -288.951852)
			(xy 369.006075 -288.965544) (xy 368.95722 -288.971476) (xy 368.908045 -288.969495) (xy 368.859826 -288.959651)
			(xy 368.81381 -288.942199) (xy 368.771189 -288.917592) (xy 368.733068 -288.886467) (xy 368.700433 -288.84963)
			(xy 368.67413 -288.808034) (xy 368.654839 -288.762758) (xy 368.643062 -288.714974) (xy 368.639102 -288.66592)
			(xy 368.31016 -288.66592) (xy 368.309665 -288.690527) (xy 368.30177 -288.739104) (xy 368.286186 -288.785785)
			(xy 368.263315 -288.829362) (xy 368.23375 -288.868706) (xy 368.198257 -288.902798) (xy 368.157754 -288.930754)
			(xy 368.113292 -288.951852) (xy 368.066021 -288.965544) (xy 368.017166 -288.971476) (xy 367.967991 -288.969495)
			(xy 367.919772 -288.959651) (xy 367.873756 -288.942199) (xy 367.831135 -288.917592) (xy 367.793014 -288.886467)
			(xy 367.760379 -288.84963) (xy 367.734076 -288.808034) (xy 367.714785 -288.762758) (xy 367.703008 -288.714974)
			(xy 367.699048 -288.66592) (xy 367.370106 -288.66592) (xy 367.369611 -288.690527) (xy 367.361716 -288.739104)
			(xy 367.346132 -288.785785) (xy 367.323261 -288.829362) (xy 367.293696 -288.868706) (xy 367.258203 -288.902798)
			(xy 367.2177 -288.930754) (xy 367.173238 -288.951852) (xy 367.125967 -288.965544) (xy 367.077112 -288.971476)
			(xy 367.027937 -288.969495) (xy 366.979718 -288.959651) (xy 366.933702 -288.942199) (xy 366.891081 -288.917592)
			(xy 366.85296 -288.886467) (xy 366.820325 -288.84963) (xy 366.794022 -288.808034) (xy 366.774731 -288.762758)
			(xy 366.762954 -288.714974) (xy 366.758994 -288.66592) (xy 366.430052 -288.66592) (xy 366.429557 -288.690527)
			(xy 366.421662 -288.739104) (xy 366.406078 -288.785785) (xy 366.383207 -288.829362) (xy 366.353642 -288.868706)
			(xy 366.318149 -288.902798) (xy 366.277646 -288.930754) (xy 366.233184 -288.951852) (xy 366.185913 -288.965544)
			(xy 366.137058 -288.971476) (xy 366.087883 -288.969495) (xy 366.039664 -288.959651) (xy 365.993648 -288.942199)
			(xy 365.951027 -288.917592) (xy 365.912906 -288.886467) (xy 365.880271 -288.84963) (xy 365.853968 -288.808034)
			(xy 365.834677 -288.762758) (xy 365.8229 -288.714974) (xy 365.81894 -288.66592) (xy 365.489998 -288.66592)
			(xy 365.489503 -288.690527) (xy 365.481608 -288.739104) (xy 365.466024 -288.785785) (xy 365.443153 -288.829362)
			(xy 365.413588 -288.868706) (xy 365.378095 -288.902798) (xy 365.337592 -288.930754) (xy 365.29313 -288.951852)
			(xy 365.245859 -288.965544) (xy 365.197004 -288.971476) (xy 365.147829 -288.969495) (xy 365.09961 -288.959651)
			(xy 365.053594 -288.942199) (xy 365.010973 -288.917592) (xy 364.972852 -288.886467) (xy 364.940217 -288.84963)
			(xy 364.913914 -288.808034) (xy 364.894623 -288.762758) (xy 364.882846 -288.714974) (xy 364.878886 -288.66592)
			(xy 364.550198 -288.66592) (xy 364.549703 -288.690527) (xy 364.541808 -288.739104) (xy 364.526224 -288.785785)
			(xy 364.503353 -288.829362) (xy 364.473788 -288.868706) (xy 364.438295 -288.902798) (xy 364.397792 -288.930754)
			(xy 364.35333 -288.951852) (xy 364.306059 -288.965544) (xy 364.257204 -288.971476) (xy 364.208029 -288.969495)
			(xy 364.15981 -288.959651) (xy 364.113794 -288.942199) (xy 364.071173 -288.917592) (xy 364.033052 -288.886467)
			(xy 364.000417 -288.84963) (xy 363.974114 -288.808034) (xy 363.954823 -288.762758) (xy 363.943046 -288.714974)
			(xy 363.939086 -288.66592) (xy 363.620558 -288.66592) (xy 363.620046 -288.691366) (xy 363.611882 -288.7416)
			(xy 363.595766 -288.789874) (xy 363.572115 -288.834937) (xy 363.541542 -288.875623) (xy 363.504838 -288.910878)
			(xy 363.462954 -288.939788) (xy 363.416975 -288.961605) (xy 363.368091 -288.975765) (xy 363.31757 -288.981899)
			(xy 363.266718 -288.97985) (xy 363.216854 -288.96967) (xy 363.169268 -288.951623) (xy 363.125194 -288.926177)
			(xy 363.085772 -288.89399) (xy 363.052024 -288.855896) (xy 363.024823 -288.812882) (xy 363.004875 -288.766062)
			(xy 362.992696 -288.716648) (xy 362.988601 -288.66592) (xy 362.680504 -288.66592) (xy 362.679992 -288.691366)
			(xy 362.671828 -288.7416) (xy 362.655712 -288.789874) (xy 362.632061 -288.834937) (xy 362.601488 -288.875623)
			(xy 362.564784 -288.910878) (xy 362.5229 -288.939788) (xy 362.476921 -288.961605) (xy 362.428037 -288.975765)
			(xy 362.377516 -288.981899) (xy 362.326664 -288.97985) (xy 362.2768 -288.96967) (xy 362.229214 -288.951623)
			(xy 362.18514 -288.926177) (xy 362.145718 -288.89399) (xy 362.11197 -288.855896) (xy 362.084769 -288.812882)
			(xy 362.064821 -288.766062) (xy 362.052642 -288.716648) (xy 362.048547 -288.66592) (xy 361.729433 -288.66592)
			(xy 361.729433 -288.690756) (xy 361.721378 -288.739807) (xy 361.705482 -288.786904) (xy 361.682163 -288.830803)
			(xy 361.65204 -288.870343) (xy 361.615907 -288.904479) (xy 361.57472 -288.93231) (xy 361.529568 -288.953098)
			(xy 361.481645 -288.966296) (xy 361.456986 -288.96945) (xy 361.437428 -288.971482) (xy 361.41152 -289.000438)
			(xy 361.41152 -289.475926) (xy 363.468932 -289.475926) (xy 363.472892 -289.426872) (xy 363.484669 -289.379088)
			(xy 363.50396 -289.333812) (xy 363.530263 -289.292216) (xy 363.562898 -289.255379) (xy 363.601019 -289.224254)
			(xy 363.64364 -289.199647) (xy 363.689656 -289.182195) (xy 363.737875 -289.172351) (xy 363.78705 -289.17037)
			(xy 363.835905 -289.176302) (xy 363.883176 -289.189994) (xy 363.927638 -289.211092) (xy 363.968141 -289.239048)
			(xy 364.003634 -289.27314) (xy 364.033199 -289.312484) (xy 364.05607 -289.356061) (xy 364.071654 -289.402742)
			(xy 364.079549 -289.451319) (xy 364.080044 -289.475926) (xy 364.398555 -289.475926) (xy 364.40265 -289.425198)
			(xy 364.414829 -289.375784) (xy 364.434777 -289.328964) (xy 364.461978 -289.28595) (xy 364.495726 -289.247856)
			(xy 364.535148 -289.215669) (xy 364.579222 -289.190223) (xy 364.626808 -289.172176) (xy 364.676672 -289.161996)
			(xy 364.727524 -289.159947) (xy 364.778045 -289.166081) (xy 364.826929 -289.180241) (xy 364.872908 -289.202058)
			(xy 364.914792 -289.230968) (xy 364.951496 -289.266223) (xy 364.982069 -289.306909) (xy 365.00572 -289.351972)
			(xy 365.021836 -289.400246) (xy 365.03 -289.45048) (xy 365.030512 -289.475926) (xy 365.338609 -289.475926)
			(xy 365.342704 -289.425198) (xy 365.354883 -289.375784) (xy 365.374831 -289.328964) (xy 365.402032 -289.28595)
			(xy 365.43578 -289.247856) (xy 365.475202 -289.215669) (xy 365.519276 -289.190223) (xy 365.566862 -289.172176)
			(xy 365.616726 -289.161996) (xy 365.667578 -289.159947) (xy 365.718099 -289.166081) (xy 365.766983 -289.180241)
			(xy 365.812962 -289.202058) (xy 365.854846 -289.230968) (xy 365.89155 -289.266223) (xy 365.922123 -289.306909)
			(xy 365.945774 -289.351972) (xy 365.96189 -289.400246) (xy 365.970054 -289.45048) (xy 365.970566 -289.475926)
			(xy 366.289094 -289.475926) (xy 366.293054 -289.426872) (xy 366.304831 -289.379088) (xy 366.324122 -289.333812)
			(xy 366.350425 -289.292216) (xy 366.38306 -289.255379) (xy 366.421181 -289.224254) (xy 366.463802 -289.199647)
			(xy 366.509818 -289.182195) (xy 366.558037 -289.172351) (xy 366.607212 -289.17037) (xy 366.656067 -289.176302)
			(xy 366.703338 -289.189994) (xy 366.7478 -289.211092) (xy 366.788303 -289.239048) (xy 366.823796 -289.27314)
			(xy 366.853361 -289.312484) (xy 366.876232 -289.356061) (xy 366.891816 -289.402742) (xy 366.899711 -289.451319)
			(xy 366.900206 -289.475926) (xy 367.218463 -289.475926) (xy 367.222558 -289.425198) (xy 367.234737 -289.375784)
			(xy 367.254685 -289.328964) (xy 367.281886 -289.28595) (xy 367.315634 -289.247856) (xy 367.355056 -289.215669)
			(xy 367.39913 -289.190223) (xy 367.446716 -289.172176) (xy 367.49658 -289.161996) (xy 367.547432 -289.159947)
			(xy 367.597953 -289.166081) (xy 367.646837 -289.180241) (xy 367.692816 -289.202058) (xy 367.7347 -289.230968)
			(xy 367.771404 -289.266223) (xy 367.801977 -289.306909) (xy 367.825628 -289.351972) (xy 367.841744 -289.400246)
			(xy 367.849908 -289.45048) (xy 367.85042 -289.475926) (xy 368.158517 -289.475926) (xy 368.162612 -289.425198)
			(xy 368.174791 -289.375784) (xy 368.194739 -289.328964) (xy 368.22194 -289.28595) (xy 368.255688 -289.247856)
			(xy 368.29511 -289.215669) (xy 368.339184 -289.190223) (xy 368.38677 -289.172176) (xy 368.436634 -289.161996)
			(xy 368.487486 -289.159947) (xy 368.538007 -289.166081) (xy 368.586891 -289.180241) (xy 368.63287 -289.202058)
			(xy 368.674754 -289.230968) (xy 368.711458 -289.266223) (xy 368.742031 -289.306909) (xy 368.765682 -289.351972)
			(xy 368.781798 -289.400246) (xy 368.789962 -289.45048) (xy 368.790474 -289.475926) (xy 369.109002 -289.475926)
			(xy 369.112962 -289.426872) (xy 369.124739 -289.379088) (xy 369.14403 -289.333812) (xy 369.170333 -289.292216)
			(xy 369.202968 -289.255379) (xy 369.241089 -289.224254) (xy 369.28371 -289.199647) (xy 369.329726 -289.182195)
			(xy 369.377945 -289.172351) (xy 369.42712 -289.17037) (xy 369.475975 -289.176302) (xy 369.523246 -289.189994)
			(xy 369.567708 -289.211092) (xy 369.608211 -289.239048) (xy 369.643704 -289.27314) (xy 369.673269 -289.312484)
			(xy 369.69614 -289.356061) (xy 369.711724 -289.402742) (xy 369.719619 -289.451319) (xy 369.720114 -289.475926)
			(xy 370.038625 -289.475926) (xy 370.04272 -289.425198) (xy 370.054899 -289.375784) (xy 370.074847 -289.328964)
			(xy 370.102048 -289.28595) (xy 370.135796 -289.247856) (xy 370.175218 -289.215669) (xy 370.219292 -289.190223)
			(xy 370.266878 -289.172176) (xy 370.316742 -289.161996) (xy 370.367594 -289.159947) (xy 370.418115 -289.166081)
			(xy 370.466999 -289.180241) (xy 370.512978 -289.202058) (xy 370.554862 -289.230968) (xy 370.591566 -289.266223)
			(xy 370.622139 -289.306909) (xy 370.64579 -289.351972) (xy 370.661906 -289.400246) (xy 370.67007 -289.45048)
			(xy 370.670582 -289.475926) (xy 370.978679 -289.475926) (xy 370.982774 -289.425198) (xy 370.994953 -289.375784)
			(xy 371.014901 -289.328964) (xy 371.042102 -289.28595) (xy 371.07585 -289.247856) (xy 371.115272 -289.215669)
			(xy 371.159346 -289.190223) (xy 371.206932 -289.172176) (xy 371.256796 -289.161996) (xy 371.307648 -289.159947)
			(xy 371.358169 -289.166081) (xy 371.407053 -289.180241) (xy 371.453032 -289.202058) (xy 371.494916 -289.230968)
			(xy 371.53162 -289.266223) (xy 371.562193 -289.306909) (xy 371.585844 -289.351972) (xy 371.60196 -289.400246)
			(xy 371.610124 -289.45048) (xy 371.610636 -289.475926) (xy 371.92891 -289.475926) (xy 371.93287 -289.426872)
			(xy 371.944647 -289.379088) (xy 371.963938 -289.333812) (xy 371.990241 -289.292216) (xy 372.022876 -289.255379)
			(xy 372.060997 -289.224254) (xy 372.103618 -289.199647) (xy 372.149634 -289.182195) (xy 372.197853 -289.172351)
			(xy 372.247028 -289.17037) (xy 372.295883 -289.176302) (xy 372.343154 -289.189994) (xy 372.387616 -289.211092)
			(xy 372.428119 -289.239048) (xy 372.463612 -289.27314) (xy 372.493177 -289.312484) (xy 372.516048 -289.356061)
			(xy 372.531632 -289.402742) (xy 372.539527 -289.451319) (xy 372.540022 -289.475926) (xy 372.858533 -289.475926)
			(xy 372.862628 -289.425198) (xy 372.874807 -289.375784) (xy 372.894755 -289.328964) (xy 372.921956 -289.28595)
			(xy 372.955704 -289.247856) (xy 372.995126 -289.215669) (xy 373.0392 -289.190223) (xy 373.086786 -289.172176)
			(xy 373.13665 -289.161996) (xy 373.187502 -289.159947) (xy 373.238023 -289.166081) (xy 373.286907 -289.180241)
			(xy 373.332886 -289.202058) (xy 373.37477 -289.230968) (xy 373.411474 -289.266223) (xy 373.442047 -289.306909)
			(xy 373.465698 -289.351972) (xy 373.481814 -289.400246) (xy 373.489978 -289.45048) (xy 373.49049 -289.475926)
			(xy 373.798587 -289.475926) (xy 373.802682 -289.425198) (xy 373.814861 -289.375784) (xy 373.834809 -289.328964)
			(xy 373.86201 -289.28595) (xy 373.895758 -289.247856) (xy 373.93518 -289.215669) (xy 373.979254 -289.190223)
			(xy 374.02684 -289.172176) (xy 374.076704 -289.161996) (xy 374.127556 -289.159947) (xy 374.178077 -289.166081)
			(xy 374.226961 -289.180241) (xy 374.27294 -289.202058) (xy 374.314824 -289.230968) (xy 374.351528 -289.266223)
			(xy 374.382101 -289.306909) (xy 374.405752 -289.351972) (xy 374.421868 -289.400246) (xy 374.430032 -289.45048)
			(xy 374.430544 -289.475926) (xy 374.430032 -289.501372) (xy 374.421868 -289.551606) (xy 374.405752 -289.59988)
			(xy 374.382101 -289.644943) (xy 374.351528 -289.685629) (xy 374.314824 -289.720884) (xy 374.27294 -289.749794)
			(xy 374.226961 -289.771611) (xy 374.178077 -289.785771) (xy 374.127556 -289.791905) (xy 374.076704 -289.789856)
			(xy 374.02684 -289.779676) (xy 373.979254 -289.761629) (xy 373.93518 -289.736183) (xy 373.895758 -289.703996)
			(xy 373.86201 -289.665902) (xy 373.834809 -289.622888) (xy 373.814861 -289.576068) (xy 373.802682 -289.526654)
			(xy 373.798587 -289.475926) (xy 373.49049 -289.475926) (xy 373.489978 -289.501372) (xy 373.481814 -289.551606)
			(xy 373.465698 -289.59988) (xy 373.442047 -289.644943) (xy 373.411474 -289.685629) (xy 373.37477 -289.720884)
			(xy 373.332886 -289.749794) (xy 373.286907 -289.771611) (xy 373.238023 -289.785771) (xy 373.187502 -289.791905)
			(xy 373.13665 -289.789856) (xy 373.086786 -289.779676) (xy 373.0392 -289.761629) (xy 372.995126 -289.736183)
			(xy 372.955704 -289.703996) (xy 372.921956 -289.665902) (xy 372.894755 -289.622888) (xy 372.874807 -289.576068)
			(xy 372.862628 -289.526654) (xy 372.858533 -289.475926) (xy 372.540022 -289.475926) (xy 372.539527 -289.500533)
			(xy 372.531632 -289.54911) (xy 372.516048 -289.595791) (xy 372.493177 -289.639368) (xy 372.463612 -289.678712)
			(xy 372.428119 -289.712804) (xy 372.387616 -289.74076) (xy 372.343154 -289.761858) (xy 372.295883 -289.77555)
			(xy 372.247028 -289.781482) (xy 372.197853 -289.779501) (xy 372.149634 -289.769657) (xy 372.103618 -289.752205)
			(xy 372.060997 -289.727598) (xy 372.022876 -289.696473) (xy 371.990241 -289.659636) (xy 371.963938 -289.61804)
			(xy 371.944647 -289.572764) (xy 371.93287 -289.52498) (xy 371.92891 -289.475926) (xy 371.610636 -289.475926)
			(xy 371.610124 -289.501372) (xy 371.60196 -289.551606) (xy 371.585844 -289.59988) (xy 371.562193 -289.644943)
			(xy 371.53162 -289.685629) (xy 371.494916 -289.720884) (xy 371.453032 -289.749794) (xy 371.407053 -289.771611)
			(xy 371.358169 -289.785771) (xy 371.307648 -289.791905) (xy 371.256796 -289.789856) (xy 371.206932 -289.779676)
			(xy 371.159346 -289.761629) (xy 371.115272 -289.736183) (xy 371.07585 -289.703996) (xy 371.042102 -289.665902)
			(xy 371.014901 -289.622888) (xy 370.994953 -289.576068) (xy 370.982774 -289.526654) (xy 370.978679 -289.475926)
			(xy 370.670582 -289.475926) (xy 370.67007 -289.501372) (xy 370.661906 -289.551606) (xy 370.64579 -289.59988)
			(xy 370.622139 -289.644943) (xy 370.591566 -289.685629) (xy 370.554862 -289.720884) (xy 370.512978 -289.749794)
			(xy 370.466999 -289.771611) (xy 370.418115 -289.785771) (xy 370.367594 -289.791905) (xy 370.316742 -289.789856)
			(xy 370.266878 -289.779676) (xy 370.219292 -289.761629) (xy 370.175218 -289.736183) (xy 370.135796 -289.703996)
			(xy 370.102048 -289.665902) (xy 370.074847 -289.622888) (xy 370.054899 -289.576068) (xy 370.04272 -289.526654)
			(xy 370.038625 -289.475926) (xy 369.720114 -289.475926) (xy 369.719619 -289.500533) (xy 369.711724 -289.54911)
			(xy 369.69614 -289.595791) (xy 369.673269 -289.639368) (xy 369.643704 -289.678712) (xy 369.608211 -289.712804)
			(xy 369.567708 -289.74076) (xy 369.523246 -289.761858) (xy 369.475975 -289.77555) (xy 369.42712 -289.781482)
			(xy 369.377945 -289.779501) (xy 369.329726 -289.769657) (xy 369.28371 -289.752205) (xy 369.241089 -289.727598)
			(xy 369.202968 -289.696473) (xy 369.170333 -289.659636) (xy 369.14403 -289.61804) (xy 369.124739 -289.572764)
			(xy 369.112962 -289.52498) (xy 369.109002 -289.475926) (xy 368.790474 -289.475926) (xy 368.789962 -289.501372)
			(xy 368.781798 -289.551606) (xy 368.765682 -289.59988) (xy 368.742031 -289.644943) (xy 368.711458 -289.685629)
			(xy 368.674754 -289.720884) (xy 368.63287 -289.749794) (xy 368.586891 -289.771611) (xy 368.538007 -289.785771)
			(xy 368.487486 -289.791905) (xy 368.436634 -289.789856) (xy 368.38677 -289.779676) (xy 368.339184 -289.761629)
			(xy 368.29511 -289.736183) (xy 368.255688 -289.703996) (xy 368.22194 -289.665902) (xy 368.194739 -289.622888)
			(xy 368.174791 -289.576068) (xy 368.162612 -289.526654) (xy 368.158517 -289.475926) (xy 367.85042 -289.475926)
			(xy 367.849908 -289.501372) (xy 367.841744 -289.551606) (xy 367.825628 -289.59988) (xy 367.801977 -289.644943)
			(xy 367.771404 -289.685629) (xy 367.7347 -289.720884) (xy 367.692816 -289.749794) (xy 367.646837 -289.771611)
			(xy 367.597953 -289.785771) (xy 367.547432 -289.791905) (xy 367.49658 -289.789856) (xy 367.446716 -289.779676)
			(xy 367.39913 -289.761629) (xy 367.355056 -289.736183) (xy 367.315634 -289.703996) (xy 367.281886 -289.665902)
			(xy 367.254685 -289.622888) (xy 367.234737 -289.576068) (xy 367.222558 -289.526654) (xy 367.218463 -289.475926)
			(xy 366.900206 -289.475926) (xy 366.899711 -289.500533) (xy 366.891816 -289.54911) (xy 366.876232 -289.595791)
			(xy 366.853361 -289.639368) (xy 366.823796 -289.678712) (xy 366.788303 -289.712804) (xy 366.7478 -289.74076)
			(xy 366.703338 -289.761858) (xy 366.656067 -289.77555) (xy 366.607212 -289.781482) (xy 366.558037 -289.779501)
			(xy 366.509818 -289.769657) (xy 366.463802 -289.752205) (xy 366.421181 -289.727598) (xy 366.38306 -289.696473)
			(xy 366.350425 -289.659636) (xy 366.324122 -289.61804) (xy 366.304831 -289.572764) (xy 366.293054 -289.52498)
			(xy 366.289094 -289.475926) (xy 365.970566 -289.475926) (xy 365.970054 -289.501372) (xy 365.96189 -289.551606)
			(xy 365.945774 -289.59988) (xy 365.922123 -289.644943) (xy 365.89155 -289.685629) (xy 365.854846 -289.720884)
			(xy 365.812962 -289.749794) (xy 365.766983 -289.771611) (xy 365.718099 -289.785771) (xy 365.667578 -289.791905)
			(xy 365.616726 -289.789856) (xy 365.566862 -289.779676) (xy 365.519276 -289.761629) (xy 365.475202 -289.736183)
			(xy 365.43578 -289.703996) (xy 365.402032 -289.665902) (xy 365.374831 -289.622888) (xy 365.354883 -289.576068)
			(xy 365.342704 -289.526654) (xy 365.338609 -289.475926) (xy 365.030512 -289.475926) (xy 365.03 -289.501372)
			(xy 365.021836 -289.551606) (xy 365.00572 -289.59988) (xy 364.982069 -289.644943) (xy 364.951496 -289.685629)
			(xy 364.914792 -289.720884) (xy 364.872908 -289.749794) (xy 364.826929 -289.771611) (xy 364.778045 -289.785771)
			(xy 364.727524 -289.791905) (xy 364.676672 -289.789856) (xy 364.626808 -289.779676) (xy 364.579222 -289.761629)
			(xy 364.535148 -289.736183) (xy 364.495726 -289.703996) (xy 364.461978 -289.665902) (xy 364.434777 -289.622888)
			(xy 364.414829 -289.576068) (xy 364.40265 -289.526654) (xy 364.398555 -289.475926) (xy 364.080044 -289.475926)
			(xy 364.079549 -289.500533) (xy 364.071654 -289.54911) (xy 364.05607 -289.595791) (xy 364.033199 -289.639368)
			(xy 364.003634 -289.678712) (xy 363.968141 -289.712804) (xy 363.927638 -289.74076) (xy 363.883176 -289.761858)
			(xy 363.835905 -289.77555) (xy 363.78705 -289.781482) (xy 363.737875 -289.779501) (xy 363.689656 -289.769657)
			(xy 363.64364 -289.752205) (xy 363.601019 -289.727598) (xy 363.562898 -289.696473) (xy 363.530263 -289.659636)
			(xy 363.50396 -289.61804) (xy 363.484669 -289.572764) (xy 363.472892 -289.52498) (xy 363.468932 -289.475926)
			(xy 361.41152 -289.475926) (xy 361.41152 -289.951414) (xy 361.437428 -289.98037) (xy 361.456986 -289.982402)
			(xy 361.481648 -289.985517) (xy 361.529569 -289.998715) (xy 361.574719 -290.019503) (xy 361.615904 -290.047333)
			(xy 361.652034 -290.081469) (xy 361.682156 -290.121008) (xy 361.705473 -290.164906) (xy 361.721368 -290.212001)
			(xy 361.729422 -290.26105) (xy 361.729421 -290.285932) (xy 362.048547 -290.285932) (xy 362.052642 -290.235204)
			(xy 362.064821 -290.18579) (xy 362.084769 -290.13897) (xy 362.11197 -290.095956) (xy 362.145718 -290.057862)
			(xy 362.18514 -290.025675) (xy 362.229214 -290.000229) (xy 362.2768 -289.982182) (xy 362.326664 -289.972002)
			(xy 362.377516 -289.969953) (xy 362.428037 -289.976087) (xy 362.476921 -289.990247) (xy 362.5229 -290.012064)
			(xy 362.564784 -290.040974) (xy 362.601488 -290.076229) (xy 362.632061 -290.116915) (xy 362.655712 -290.161978)
			(xy 362.671828 -290.210252) (xy 362.679992 -290.260486) (xy 362.680504 -290.285932) (xy 362.988601 -290.285932)
			(xy 362.992696 -290.235204) (xy 363.004875 -290.18579) (xy 363.024823 -290.13897) (xy 363.052024 -290.095956)
			(xy 363.085772 -290.057862) (xy 363.125194 -290.025675) (xy 363.169268 -290.000229) (xy 363.216854 -289.982182)
			(xy 363.266718 -289.972002) (xy 363.31757 -289.969953) (xy 363.368091 -289.976087) (xy 363.416975 -289.990247)
			(xy 363.462954 -290.012064) (xy 363.504838 -290.040974) (xy 363.541542 -290.076229) (xy 363.572115 -290.116915)
			(xy 363.595766 -290.161978) (xy 363.611882 -290.210252) (xy 363.620046 -290.260486) (xy 363.620558 -290.285932)
			(xy 363.939086 -290.285932) (xy 363.943046 -290.236878) (xy 363.954823 -290.189094) (xy 363.974114 -290.143818)
			(xy 364.000417 -290.102222) (xy 364.033052 -290.065385) (xy 364.071173 -290.03426) (xy 364.113794 -290.009653)
			(xy 364.15981 -289.992201) (xy 364.208029 -289.982357) (xy 364.257204 -289.980376) (xy 364.306059 -289.986308)
			(xy 364.35333 -290) (xy 364.397792 -290.021098) (xy 364.438295 -290.049054) (xy 364.473788 -290.083146)
			(xy 364.503353 -290.12249) (xy 364.526224 -290.166067) (xy 364.541808 -290.212748) (xy 364.549703 -290.261325)
			(xy 364.550198 -290.285932) (xy 366.758994 -290.285932) (xy 366.762954 -290.236878) (xy 366.774731 -290.189094)
			(xy 366.794022 -290.143818) (xy 366.820325 -290.102222) (xy 366.85296 -290.065385) (xy 366.891081 -290.03426)
			(xy 366.933702 -290.009653) (xy 366.979718 -289.992201) (xy 367.027937 -289.982357) (xy 367.077112 -289.980376)
			(xy 367.125967 -289.986308) (xy 367.173238 -290) (xy 367.2177 -290.021098) (xy 367.258203 -290.049054)
			(xy 367.293696 -290.083146) (xy 367.323261 -290.12249) (xy 367.346132 -290.166067) (xy 367.361716 -290.212748)
			(xy 367.369611 -290.261325) (xy 367.370106 -290.285932) (xy 369.578902 -290.285932) (xy 369.582862 -290.236878)
			(xy 369.594639 -290.189094) (xy 369.61393 -290.143818) (xy 369.640233 -290.102222) (xy 369.672868 -290.065385)
			(xy 369.710989 -290.03426) (xy 369.75361 -290.009653) (xy 369.799626 -289.992201) (xy 369.847845 -289.982357)
			(xy 369.89702 -289.980376) (xy 369.945875 -289.986308) (xy 369.993146 -290) (xy 370.037608 -290.021098)
			(xy 370.078111 -290.049054) (xy 370.113604 -290.083146) (xy 370.143169 -290.12249) (xy 370.16604 -290.166067)
			(xy 370.181624 -290.212748) (xy 370.189519 -290.261325) (xy 370.190014 -290.285932) (xy 372.399064 -290.285932)
			(xy 372.403024 -290.236878) (xy 372.414801 -290.189094) (xy 372.434092 -290.143818) (xy 372.460395 -290.102222)
			(xy 372.49303 -290.065385) (xy 372.531151 -290.03426) (xy 372.573772 -290.009653) (xy 372.619788 -289.992201)
			(xy 372.668007 -289.982357) (xy 372.717182 -289.980376) (xy 372.766037 -289.986308) (xy 372.813308 -290)
			(xy 372.85777 -290.021098) (xy 372.898273 -290.049054) (xy 372.933766 -290.083146) (xy 372.963331 -290.12249)
			(xy 372.986202 -290.166067) (xy 373.001786 -290.212748) (xy 373.009681 -290.261325) (xy 373.010176 -290.285932)
			(xy 373.009681 -290.310539) (xy 373.001786 -290.359116) (xy 372.986202 -290.405797) (xy 372.963331 -290.449374)
			(xy 372.933766 -290.488718) (xy 372.898273 -290.52281) (xy 372.85777 -290.550766) (xy 372.813308 -290.571864)
			(xy 372.766037 -290.585556) (xy 372.717182 -290.591488) (xy 372.668007 -290.589507) (xy 372.619788 -290.579663)
			(xy 372.573772 -290.562211) (xy 372.531151 -290.537604) (xy 372.49303 -290.506479) (xy 372.460395 -290.469642)
			(xy 372.434092 -290.428046) (xy 372.414801 -290.38277) (xy 372.403024 -290.334986) (xy 372.399064 -290.285932)
			(xy 370.190014 -290.285932) (xy 370.189519 -290.310539) (xy 370.181624 -290.359116) (xy 370.16604 -290.405797)
			(xy 370.143169 -290.449374) (xy 370.113604 -290.488718) (xy 370.078111 -290.52281) (xy 370.037608 -290.550766)
			(xy 369.993146 -290.571864) (xy 369.945875 -290.585556) (xy 369.89702 -290.591488) (xy 369.847845 -290.589507)
			(xy 369.799626 -290.579663) (xy 369.75361 -290.562211) (xy 369.710989 -290.537604) (xy 369.672868 -290.506479)
			(xy 369.640233 -290.469642) (xy 369.61393 -290.428046) (xy 369.594639 -290.38277) (xy 369.582862 -290.334986)
			(xy 369.578902 -290.285932) (xy 367.370106 -290.285932) (xy 367.369611 -290.310539) (xy 367.361716 -290.359116)
			(xy 367.346132 -290.405797) (xy 367.323261 -290.449374) (xy 367.293696 -290.488718) (xy 367.258203 -290.52281)
			(xy 367.2177 -290.550766) (xy 367.173238 -290.571864) (xy 367.125967 -290.585556) (xy 367.077112 -290.591488)
			(xy 367.027937 -290.589507) (xy 366.979718 -290.579663) (xy 366.933702 -290.562211) (xy 366.891081 -290.537604)
			(xy 366.85296 -290.506479) (xy 366.820325 -290.469642) (xy 366.794022 -290.428046) (xy 366.774731 -290.38277)
			(xy 366.762954 -290.334986) (xy 366.758994 -290.285932) (xy 364.550198 -290.285932) (xy 364.549703 -290.310539)
			(xy 364.541808 -290.359116) (xy 364.526224 -290.405797) (xy 364.503353 -290.449374) (xy 364.473788 -290.488718)
			(xy 364.438295 -290.52281) (xy 364.397792 -290.550766) (xy 364.35333 -290.571864) (xy 364.306059 -290.585556)
			(xy 364.257204 -290.591488) (xy 364.208029 -290.589507) (xy 364.15981 -290.579663) (xy 364.113794 -290.562211)
			(xy 364.071173 -290.537604) (xy 364.033052 -290.506479) (xy 364.000417 -290.469642) (xy 363.974114 -290.428046)
			(xy 363.954823 -290.38277) (xy 363.943046 -290.334986) (xy 363.939086 -290.285932) (xy 363.620558 -290.285932)
			(xy 363.620046 -290.311378) (xy 363.611882 -290.361612) (xy 363.595766 -290.409886) (xy 363.572115 -290.454949)
			(xy 363.541542 -290.495635) (xy 363.504838 -290.53089) (xy 363.462954 -290.5598) (xy 363.416975 -290.581617)
			(xy 363.368091 -290.595777) (xy 363.31757 -290.601911) (xy 363.266718 -290.599862) (xy 363.216854 -290.589682)
			(xy 363.169268 -290.571635) (xy 363.125194 -290.546189) (xy 363.085772 -290.514002) (xy 363.052024 -290.475908)
			(xy 363.024823 -290.432894) (xy 363.004875 -290.386074) (xy 362.992696 -290.33666) (xy 362.988601 -290.285932)
			(xy 362.680504 -290.285932) (xy 362.679992 -290.311378) (xy 362.671828 -290.361612) (xy 362.655712 -290.409886)
			(xy 362.632061 -290.454949) (xy 362.601488 -290.495635) (xy 362.564784 -290.53089) (xy 362.5229 -290.5598)
			(xy 362.476921 -290.581617) (xy 362.428037 -290.595777) (xy 362.377516 -290.601911) (xy 362.326664 -290.599862)
			(xy 362.2768 -290.589682) (xy 362.229214 -290.571635) (xy 362.18514 -290.546189) (xy 362.145718 -290.514002)
			(xy 362.11197 -290.475908) (xy 362.084769 -290.432894) (xy 362.064821 -290.386074) (xy 362.052642 -290.33666)
			(xy 362.048547 -290.285932) (xy 361.729421 -290.285932) (xy 361.729421 -290.310756) (xy 361.721366 -290.359805)
			(xy 361.70547 -290.4069) (xy 361.682152 -290.450798) (xy 361.65203 -290.490336) (xy 361.615898 -290.524471)
			(xy 361.574713 -290.5523) (xy 361.529563 -290.573088) (xy 361.481641 -290.586284) (xy 361.456986 -290.589462)
			(xy 361.437428 -290.591494) (xy 361.41152 -290.62045) (xy 361.41152 -291.095938) (xy 363.468932 -291.095938)
			(xy 363.472892 -291.046884) (xy 363.484669 -290.9991) (xy 363.50396 -290.953824) (xy 363.530263 -290.912228)
			(xy 363.562898 -290.875391) (xy 363.601019 -290.844266) (xy 363.64364 -290.819659) (xy 363.689656 -290.802207)
			(xy 363.737875 -290.792363) (xy 363.78705 -290.790382) (xy 363.835905 -290.796314) (xy 363.883176 -290.810006)
			(xy 363.927638 -290.831104) (xy 363.968141 -290.85906) (xy 364.003634 -290.893152) (xy 364.033199 -290.932496)
			(xy 364.05607 -290.976073) (xy 364.071654 -291.022754) (xy 364.079549 -291.071331) (xy 364.080044 -291.095938)
			(xy 364.398555 -291.095938) (xy 364.40265 -291.04521) (xy 364.414829 -290.995796) (xy 364.434777 -290.948976)
			(xy 364.461978 -290.905962) (xy 364.495726 -290.867868) (xy 364.535148 -290.835681) (xy 364.579222 -290.810235)
			(xy 364.626808 -290.792188) (xy 364.676672 -290.782008) (xy 364.727524 -290.779959) (xy 364.778045 -290.786093)
			(xy 364.826929 -290.800253) (xy 364.872908 -290.82207) (xy 364.914792 -290.85098) (xy 364.951496 -290.886235)
			(xy 364.982069 -290.926921) (xy 365.00572 -290.971984) (xy 365.021836 -291.020258) (xy 365.03 -291.070492)
			(xy 365.030512 -291.095938) (xy 365.338609 -291.095938) (xy 365.342704 -291.04521) (xy 365.354883 -290.995796)
			(xy 365.374831 -290.948976) (xy 365.402032 -290.905962) (xy 365.43578 -290.867868) (xy 365.475202 -290.835681)
			(xy 365.519276 -290.810235) (xy 365.566862 -290.792188) (xy 365.616726 -290.782008) (xy 365.667578 -290.779959)
			(xy 365.718099 -290.786093) (xy 365.766983 -290.800253) (xy 365.812962 -290.82207) (xy 365.854846 -290.85098)
			(xy 365.89155 -290.886235) (xy 365.922123 -290.926921) (xy 365.945774 -290.971984) (xy 365.96189 -291.020258)
			(xy 365.970054 -291.070492) (xy 365.970566 -291.095938) (xy 366.289094 -291.095938) (xy 366.293054 -291.046884)
			(xy 366.304831 -290.9991) (xy 366.324122 -290.953824) (xy 366.350425 -290.912228) (xy 366.38306 -290.875391)
			(xy 366.421181 -290.844266) (xy 366.463802 -290.819659) (xy 366.509818 -290.802207) (xy 366.558037 -290.792363)
			(xy 366.607212 -290.790382) (xy 366.656067 -290.796314) (xy 366.703338 -290.810006) (xy 366.7478 -290.831104)
			(xy 366.788303 -290.85906) (xy 366.823796 -290.893152) (xy 366.853361 -290.932496) (xy 366.876232 -290.976073)
			(xy 366.891816 -291.022754) (xy 366.899711 -291.071331) (xy 366.900206 -291.095938) (xy 367.218463 -291.095938)
			(xy 367.222558 -291.04521) (xy 367.234737 -290.995796) (xy 367.254685 -290.948976) (xy 367.281886 -290.905962)
			(xy 367.315634 -290.867868) (xy 367.355056 -290.835681) (xy 367.39913 -290.810235) (xy 367.446716 -290.792188)
			(xy 367.49658 -290.782008) (xy 367.547432 -290.779959) (xy 367.597953 -290.786093) (xy 367.646837 -290.800253)
			(xy 367.692816 -290.82207) (xy 367.7347 -290.85098) (xy 367.771404 -290.886235) (xy 367.801977 -290.926921)
			(xy 367.825628 -290.971984) (xy 367.841744 -291.020258) (xy 367.849908 -291.070492) (xy 367.85042 -291.095938)
			(xy 368.158517 -291.095938) (xy 368.162612 -291.04521) (xy 368.174791 -290.995796) (xy 368.194739 -290.948976)
			(xy 368.22194 -290.905962) (xy 368.255688 -290.867868) (xy 368.29511 -290.835681) (xy 368.339184 -290.810235)
			(xy 368.38677 -290.792188) (xy 368.436634 -290.782008) (xy 368.487486 -290.779959) (xy 368.538007 -290.786093)
			(xy 368.586891 -290.800253) (xy 368.63287 -290.82207) (xy 368.674754 -290.85098) (xy 368.711458 -290.886235)
			(xy 368.742031 -290.926921) (xy 368.765682 -290.971984) (xy 368.781798 -291.020258) (xy 368.789962 -291.070492)
			(xy 368.790474 -291.095938) (xy 369.109002 -291.095938) (xy 369.112962 -291.046884) (xy 369.124739 -290.9991)
			(xy 369.14403 -290.953824) (xy 369.170333 -290.912228) (xy 369.202968 -290.875391) (xy 369.241089 -290.844266)
			(xy 369.28371 -290.819659) (xy 369.329726 -290.802207) (xy 369.377945 -290.792363) (xy 369.42712 -290.790382)
			(xy 369.475975 -290.796314) (xy 369.523246 -290.810006) (xy 369.567708 -290.831104) (xy 369.608211 -290.85906)
			(xy 369.643704 -290.893152) (xy 369.673269 -290.932496) (xy 369.69614 -290.976073) (xy 369.711724 -291.022754)
			(xy 369.719619 -291.071331) (xy 369.720114 -291.095938) (xy 370.038625 -291.095938) (xy 370.04272 -291.04521)
			(xy 370.054899 -290.995796) (xy 370.074847 -290.948976) (xy 370.102048 -290.905962) (xy 370.135796 -290.867868)
			(xy 370.175218 -290.835681) (xy 370.219292 -290.810235) (xy 370.266878 -290.792188) (xy 370.316742 -290.782008)
			(xy 370.367594 -290.779959) (xy 370.418115 -290.786093) (xy 370.466999 -290.800253) (xy 370.512978 -290.82207)
			(xy 370.554862 -290.85098) (xy 370.591566 -290.886235) (xy 370.622139 -290.926921) (xy 370.64579 -290.971984)
			(xy 370.661906 -291.020258) (xy 370.67007 -291.070492) (xy 370.670582 -291.095938) (xy 370.978679 -291.095938)
			(xy 370.982774 -291.04521) (xy 370.994953 -290.995796) (xy 371.014901 -290.948976) (xy 371.042102 -290.905962)
			(xy 371.07585 -290.867868) (xy 371.115272 -290.835681) (xy 371.159346 -290.810235) (xy 371.206932 -290.792188)
			(xy 371.256796 -290.782008) (xy 371.307648 -290.779959) (xy 371.358169 -290.786093) (xy 371.407053 -290.800253)
			(xy 371.453032 -290.82207) (xy 371.494916 -290.85098) (xy 371.53162 -290.886235) (xy 371.562193 -290.926921)
			(xy 371.585844 -290.971984) (xy 371.60196 -291.020258) (xy 371.610124 -291.070492) (xy 371.610636 -291.095938)
			(xy 371.92891 -291.095938) (xy 371.93287 -291.046884) (xy 371.944647 -290.9991) (xy 371.963938 -290.953824)
			(xy 371.990241 -290.912228) (xy 372.022876 -290.875391) (xy 372.060997 -290.844266) (xy 372.103618 -290.819659)
			(xy 372.149634 -290.802207) (xy 372.197853 -290.792363) (xy 372.247028 -290.790382) (xy 372.295883 -290.796314)
			(xy 372.343154 -290.810006) (xy 372.387616 -290.831104) (xy 372.428119 -290.85906) (xy 372.463612 -290.893152)
			(xy 372.493177 -290.932496) (xy 372.516048 -290.976073) (xy 372.531632 -291.022754) (xy 372.539527 -291.071331)
			(xy 372.540022 -291.095938) (xy 372.858533 -291.095938) (xy 372.862628 -291.04521) (xy 372.874807 -290.995796)
			(xy 372.894755 -290.948976) (xy 372.921956 -290.905962) (xy 372.955704 -290.867868) (xy 372.995126 -290.835681)
			(xy 373.0392 -290.810235) (xy 373.086786 -290.792188) (xy 373.13665 -290.782008) (xy 373.187502 -290.779959)
			(xy 373.238023 -290.786093) (xy 373.286907 -290.800253) (xy 373.332886 -290.82207) (xy 373.37477 -290.85098)
			(xy 373.411474 -290.886235) (xy 373.442047 -290.926921) (xy 373.465698 -290.971984) (xy 373.481814 -291.020258)
			(xy 373.489978 -291.070492) (xy 373.49049 -291.095938) (xy 373.798587 -291.095938) (xy 373.802682 -291.04521)
			(xy 373.814861 -290.995796) (xy 373.834809 -290.948976) (xy 373.86201 -290.905962) (xy 373.895758 -290.867868)
			(xy 373.93518 -290.835681) (xy 373.979254 -290.810235) (xy 374.02684 -290.792188) (xy 374.076704 -290.782008)
			(xy 374.127556 -290.779959) (xy 374.178077 -290.786093) (xy 374.226961 -290.800253) (xy 374.27294 -290.82207)
			(xy 374.314824 -290.85098) (xy 374.351528 -290.886235) (xy 374.382101 -290.926921) (xy 374.405752 -290.971984)
			(xy 374.421868 -291.020258) (xy 374.430032 -291.070492) (xy 374.430544 -291.095938) (xy 374.749072 -291.095938)
			(xy 374.753032 -291.046884) (xy 374.764809 -290.9991) (xy 374.7841 -290.953824) (xy 374.810403 -290.912228)
			(xy 374.843038 -290.875391) (xy 374.881159 -290.844266) (xy 374.92378 -290.819659) (xy 374.969796 -290.802207)
			(xy 375.018015 -290.792363) (xy 375.06719 -290.790382) (xy 375.116045 -290.796314) (xy 375.163316 -290.810006)
			(xy 375.207778 -290.831104) (xy 375.248281 -290.85906) (xy 375.283774 -290.893152) (xy 375.313339 -290.932496)
			(xy 375.33621 -290.976073) (xy 375.351794 -291.022754) (xy 375.359689 -291.071331) (xy 375.360184 -291.095938)
			(xy 375.359689 -291.120545) (xy 375.351794 -291.169122) (xy 375.33621 -291.215803) (xy 375.313339 -291.25938)
			(xy 375.283774 -291.298724) (xy 375.248281 -291.332816) (xy 375.207778 -291.360772) (xy 375.163316 -291.38187)
			(xy 375.116045 -291.395562) (xy 375.06719 -291.401494) (xy 375.018015 -291.399513) (xy 374.969796 -291.389669)
			(xy 374.92378 -291.372217) (xy 374.881159 -291.34761) (xy 374.843038 -291.316485) (xy 374.810403 -291.279648)
			(xy 374.7841 -291.238052) (xy 374.764809 -291.192776) (xy 374.753032 -291.144992) (xy 374.749072 -291.095938)
			(xy 374.430544 -291.095938) (xy 374.430032 -291.121384) (xy 374.421868 -291.171618) (xy 374.405752 -291.219892)
			(xy 374.382101 -291.264955) (xy 374.351528 -291.305641) (xy 374.314824 -291.340896) (xy 374.27294 -291.369806)
			(xy 374.226961 -291.391623) (xy 374.178077 -291.405783) (xy 374.127556 -291.411917) (xy 374.076704 -291.409868)
			(xy 374.02684 -291.399688) (xy 373.979254 -291.381641) (xy 373.93518 -291.356195) (xy 373.895758 -291.324008)
			(xy 373.86201 -291.285914) (xy 373.834809 -291.2429) (xy 373.814861 -291.19608) (xy 373.802682 -291.146666)
			(xy 373.798587 -291.095938) (xy 373.49049 -291.095938) (xy 373.489978 -291.121384) (xy 373.481814 -291.171618)
			(xy 373.465698 -291.219892) (xy 373.442047 -291.264955) (xy 373.411474 -291.305641) (xy 373.37477 -291.340896)
			(xy 373.332886 -291.369806) (xy 373.286907 -291.391623) (xy 373.238023 -291.405783) (xy 373.187502 -291.411917)
			(xy 373.13665 -291.409868) (xy 373.086786 -291.399688) (xy 373.0392 -291.381641) (xy 372.995126 -291.356195)
			(xy 372.955704 -291.324008) (xy 372.921956 -291.285914) (xy 372.894755 -291.2429) (xy 372.874807 -291.19608)
			(xy 372.862628 -291.146666) (xy 372.858533 -291.095938) (xy 372.540022 -291.095938) (xy 372.539527 -291.120545)
			(xy 372.531632 -291.169122) (xy 372.516048 -291.215803) (xy 372.493177 -291.25938) (xy 372.463612 -291.298724)
			(xy 372.428119 -291.332816) (xy 372.387616 -291.360772) (xy 372.343154 -291.38187) (xy 372.295883 -291.395562)
			(xy 372.247028 -291.401494) (xy 372.197853 -291.399513) (xy 372.149634 -291.389669) (xy 372.103618 -291.372217)
			(xy 372.060997 -291.34761) (xy 372.022876 -291.316485) (xy 371.990241 -291.279648) (xy 371.963938 -291.238052)
			(xy 371.944647 -291.192776) (xy 371.93287 -291.144992) (xy 371.92891 -291.095938) (xy 371.610636 -291.095938)
			(xy 371.610124 -291.121384) (xy 371.60196 -291.171618) (xy 371.585844 -291.219892) (xy 371.562193 -291.264955)
			(xy 371.53162 -291.305641) (xy 371.494916 -291.340896) (xy 371.453032 -291.369806) (xy 371.407053 -291.391623)
			(xy 371.358169 -291.405783) (xy 371.307648 -291.411917) (xy 371.256796 -291.409868) (xy 371.206932 -291.399688)
			(xy 371.159346 -291.381641) (xy 371.115272 -291.356195) (xy 371.07585 -291.324008) (xy 371.042102 -291.285914)
			(xy 371.014901 -291.2429) (xy 370.994953 -291.19608) (xy 370.982774 -291.146666) (xy 370.978679 -291.095938)
			(xy 370.670582 -291.095938) (xy 370.67007 -291.121384) (xy 370.661906 -291.171618) (xy 370.64579 -291.219892)
			(xy 370.622139 -291.264955) (xy 370.591566 -291.305641) (xy 370.554862 -291.340896) (xy 370.512978 -291.369806)
			(xy 370.466999 -291.391623) (xy 370.418115 -291.405783) (xy 370.367594 -291.411917) (xy 370.316742 -291.409868)
			(xy 370.266878 -291.399688) (xy 370.219292 -291.381641) (xy 370.175218 -291.356195) (xy 370.135796 -291.324008)
			(xy 370.102048 -291.285914) (xy 370.074847 -291.2429) (xy 370.054899 -291.19608) (xy 370.04272 -291.146666)
			(xy 370.038625 -291.095938) (xy 369.720114 -291.095938) (xy 369.719619 -291.120545) (xy 369.711724 -291.169122)
			(xy 369.69614 -291.215803) (xy 369.673269 -291.25938) (xy 369.643704 -291.298724) (xy 369.608211 -291.332816)
			(xy 369.567708 -291.360772) (xy 369.523246 -291.38187) (xy 369.475975 -291.395562) (xy 369.42712 -291.401494)
			(xy 369.377945 -291.399513) (xy 369.329726 -291.389669) (xy 369.28371 -291.372217) (xy 369.241089 -291.34761)
			(xy 369.202968 -291.316485) (xy 369.170333 -291.279648) (xy 369.14403 -291.238052) (xy 369.124739 -291.192776)
			(xy 369.112962 -291.144992) (xy 369.109002 -291.095938) (xy 368.790474 -291.095938) (xy 368.789962 -291.121384)
			(xy 368.781798 -291.171618) (xy 368.765682 -291.219892) (xy 368.742031 -291.264955) (xy 368.711458 -291.305641)
			(xy 368.674754 -291.340896) (xy 368.63287 -291.369806) (xy 368.586891 -291.391623) (xy 368.538007 -291.405783)
			(xy 368.487486 -291.411917) (xy 368.436634 -291.409868) (xy 368.38677 -291.399688) (xy 368.339184 -291.381641)
			(xy 368.29511 -291.356195) (xy 368.255688 -291.324008) (xy 368.22194 -291.285914) (xy 368.194739 -291.2429)
			(xy 368.174791 -291.19608) (xy 368.162612 -291.146666) (xy 368.158517 -291.095938) (xy 367.85042 -291.095938)
			(xy 367.849908 -291.121384) (xy 367.841744 -291.171618) (xy 367.825628 -291.219892) (xy 367.801977 -291.264955)
			(xy 367.771404 -291.305641) (xy 367.7347 -291.340896) (xy 367.692816 -291.369806) (xy 367.646837 -291.391623)
			(xy 367.597953 -291.405783) (xy 367.547432 -291.411917) (xy 367.49658 -291.409868) (xy 367.446716 -291.399688)
			(xy 367.39913 -291.381641) (xy 367.355056 -291.356195) (xy 367.315634 -291.324008) (xy 367.281886 -291.285914)
			(xy 367.254685 -291.2429) (xy 367.234737 -291.19608) (xy 367.222558 -291.146666) (xy 367.218463 -291.095938)
			(xy 366.900206 -291.095938) (xy 366.899711 -291.120545) (xy 366.891816 -291.169122) (xy 366.876232 -291.215803)
			(xy 366.853361 -291.25938) (xy 366.823796 -291.298724) (xy 366.788303 -291.332816) (xy 366.7478 -291.360772)
			(xy 366.703338 -291.38187) (xy 366.656067 -291.395562) (xy 366.607212 -291.401494) (xy 366.558037 -291.399513)
			(xy 366.509818 -291.389669) (xy 366.463802 -291.372217) (xy 366.421181 -291.34761) (xy 366.38306 -291.316485)
			(xy 366.350425 -291.279648) (xy 366.324122 -291.238052) (xy 366.304831 -291.192776) (xy 366.293054 -291.144992)
			(xy 366.289094 -291.095938) (xy 365.970566 -291.095938) (xy 365.970054 -291.121384) (xy 365.96189 -291.171618)
			(xy 365.945774 -291.219892) (xy 365.922123 -291.264955) (xy 365.89155 -291.305641) (xy 365.854846 -291.340896)
			(xy 365.812962 -291.369806) (xy 365.766983 -291.391623) (xy 365.718099 -291.405783) (xy 365.667578 -291.411917)
			(xy 365.616726 -291.409868) (xy 365.566862 -291.399688) (xy 365.519276 -291.381641) (xy 365.475202 -291.356195)
			(xy 365.43578 -291.324008) (xy 365.402032 -291.285914) (xy 365.374831 -291.2429) (xy 365.354883 -291.19608)
			(xy 365.342704 -291.146666) (xy 365.338609 -291.095938) (xy 365.030512 -291.095938) (xy 365.03 -291.121384)
			(xy 365.021836 -291.171618) (xy 365.00572 -291.219892) (xy 364.982069 -291.264955) (xy 364.951496 -291.305641)
			(xy 364.914792 -291.340896) (xy 364.872908 -291.369806) (xy 364.826929 -291.391623) (xy 364.778045 -291.405783)
			(xy 364.727524 -291.411917) (xy 364.676672 -291.409868) (xy 364.626808 -291.399688) (xy 364.579222 -291.381641)
			(xy 364.535148 -291.356195) (xy 364.495726 -291.324008) (xy 364.461978 -291.285914) (xy 364.434777 -291.2429)
			(xy 364.414829 -291.19608) (xy 364.40265 -291.146666) (xy 364.398555 -291.095938) (xy 364.080044 -291.095938)
			(xy 364.079549 -291.120545) (xy 364.071654 -291.169122) (xy 364.05607 -291.215803) (xy 364.033199 -291.25938)
			(xy 364.003634 -291.298724) (xy 363.968141 -291.332816) (xy 363.927638 -291.360772) (xy 363.883176 -291.38187)
			(xy 363.835905 -291.395562) (xy 363.78705 -291.401494) (xy 363.737875 -291.399513) (xy 363.689656 -291.389669)
			(xy 363.64364 -291.372217) (xy 363.601019 -291.34761) (xy 363.562898 -291.316485) (xy 363.530263 -291.279648)
			(xy 363.50396 -291.238052) (xy 363.484669 -291.192776) (xy 363.472892 -291.144992) (xy 363.468932 -291.095938)
			(xy 361.41152 -291.095938) (xy 361.41152 -291.571426) (xy 361.437428 -291.600382) (xy 361.456986 -291.602414)
			(xy 361.481647 -291.605529) (xy 361.529567 -291.618726) (xy 361.574714 -291.639514) (xy 361.615897 -291.667343)
			(xy 361.652026 -291.701478) (xy 361.682147 -291.741016) (xy 361.705462 -291.784912) (xy 361.721357 -291.832006)
			(xy 361.72941 -291.881053) (xy 361.729409 -291.905944) (xy 362.058978 -291.905944) (xy 362.062938 -291.85689)
			(xy 362.074715 -291.809106) (xy 362.094006 -291.76383) (xy 362.120309 -291.722234) (xy 362.152944 -291.685397)
			(xy 362.191065 -291.654272) (xy 362.233686 -291.629665) (xy 362.279702 -291.612213) (xy 362.327921 -291.602369)
			(xy 362.377096 -291.600388) (xy 362.425951 -291.60632) (xy 362.473222 -291.620012) (xy 362.517684 -291.64111)
			(xy 362.558187 -291.669066) (xy 362.59368 -291.703158) (xy 362.623245 -291.742502) (xy 362.646116 -291.786079)
			(xy 362.6617 -291.83276) (xy 362.669595 -291.881337) (xy 362.67009 -291.905944) (xy 362.999032 -291.905944)
			(xy 363.002992 -291.85689) (xy 363.014769 -291.809106) (xy 363.03406 -291.76383) (xy 363.060363 -291.722234)
			(xy 363.092998 -291.685397) (xy 363.131119 -291.654272) (xy 363.17374 -291.629665) (xy 363.219756 -291.612213)
			(xy 363.267975 -291.602369) (xy 363.31715 -291.600388) (xy 363.366005 -291.60632) (xy 363.413276 -291.620012)
			(xy 363.457738 -291.64111) (xy 363.498241 -291.669066) (xy 363.533734 -291.703158) (xy 363.563299 -291.742502)
			(xy 363.58617 -291.786079) (xy 363.601754 -291.83276) (xy 363.609649 -291.881337) (xy 363.610144 -291.905944)
			(xy 364.878886 -291.905944) (xy 364.882846 -291.85689) (xy 364.894623 -291.809106) (xy 364.913914 -291.76383)
			(xy 364.940217 -291.722234) (xy 364.972852 -291.685397) (xy 365.010973 -291.654272) (xy 365.053594 -291.629665)
			(xy 365.09961 -291.612213) (xy 365.147829 -291.602369) (xy 365.197004 -291.600388) (xy 365.245859 -291.60632)
			(xy 365.29313 -291.620012) (xy 365.337592 -291.64111) (xy 365.378095 -291.669066) (xy 365.413588 -291.703158)
			(xy 365.443153 -291.742502) (xy 365.466024 -291.786079) (xy 365.481608 -291.83276) (xy 365.489503 -291.881337)
			(xy 365.489998 -291.905944) (xy 365.81894 -291.905944) (xy 365.8229 -291.85689) (xy 365.834677 -291.809106)
			(xy 365.853968 -291.76383) (xy 365.880271 -291.722234) (xy 365.912906 -291.685397) (xy 365.951027 -291.654272)
			(xy 365.993648 -291.629665) (xy 366.039664 -291.612213) (xy 366.087883 -291.602369) (xy 366.137058 -291.600388)
			(xy 366.185913 -291.60632) (xy 366.233184 -291.620012) (xy 366.277646 -291.64111) (xy 366.318149 -291.669066)
			(xy 366.353642 -291.703158) (xy 366.383207 -291.742502) (xy 366.406078 -291.786079) (xy 366.421662 -291.83276)
			(xy 366.429557 -291.881337) (xy 366.430052 -291.905944) (xy 367.699048 -291.905944) (xy 367.703008 -291.85689)
			(xy 367.714785 -291.809106) (xy 367.734076 -291.76383) (xy 367.760379 -291.722234) (xy 367.793014 -291.685397)
			(xy 367.831135 -291.654272) (xy 367.873756 -291.629665) (xy 367.919772 -291.612213) (xy 367.967991 -291.602369)
			(xy 368.017166 -291.600388) (xy 368.066021 -291.60632) (xy 368.113292 -291.620012) (xy 368.157754 -291.64111)
			(xy 368.198257 -291.669066) (xy 368.23375 -291.703158) (xy 368.263315 -291.742502) (xy 368.286186 -291.786079)
			(xy 368.30177 -291.83276) (xy 368.309665 -291.881337) (xy 368.31016 -291.905944) (xy 368.639102 -291.905944)
			(xy 368.643062 -291.85689) (xy 368.654839 -291.809106) (xy 368.67413 -291.76383) (xy 368.700433 -291.722234)
			(xy 368.733068 -291.685397) (xy 368.771189 -291.654272) (xy 368.81381 -291.629665) (xy 368.859826 -291.612213)
			(xy 368.908045 -291.602369) (xy 368.95722 -291.600388) (xy 369.006075 -291.60632) (xy 369.053346 -291.620012)
			(xy 369.097808 -291.64111) (xy 369.138311 -291.669066) (xy 369.173804 -291.703158) (xy 369.203369 -291.742502)
			(xy 369.22624 -291.786079) (xy 369.241824 -291.83276) (xy 369.249719 -291.881337) (xy 369.250214 -291.905944)
			(xy 370.518956 -291.905944) (xy 370.522916 -291.85689) (xy 370.534693 -291.809106) (xy 370.553984 -291.76383)
			(xy 370.580287 -291.722234) (xy 370.612922 -291.685397) (xy 370.651043 -291.654272) (xy 370.693664 -291.629665)
			(xy 370.73968 -291.612213) (xy 370.787899 -291.602369) (xy 370.837074 -291.600388) (xy 370.885929 -291.60632)
			(xy 370.9332 -291.620012) (xy 370.977662 -291.64111) (xy 371.018165 -291.669066) (xy 371.053658 -291.703158)
			(xy 371.083223 -291.742502) (xy 371.106094 -291.786079) (xy 371.121678 -291.83276) (xy 371.129573 -291.881337)
			(xy 371.130068 -291.905944) (xy 371.45901 -291.905944) (xy 371.46297 -291.85689) (xy 371.474747 -291.809106)
			(xy 371.494038 -291.76383) (xy 371.520341 -291.722234) (xy 371.552976 -291.685397) (xy 371.591097 -291.654272)
			(xy 371.633718 -291.629665) (xy 371.679734 -291.612213) (xy 371.727953 -291.602369) (xy 371.777128 -291.600388)
			(xy 371.825983 -291.60632) (xy 371.873254 -291.620012) (xy 371.917716 -291.64111) (xy 371.958219 -291.669066)
			(xy 371.993712 -291.703158) (xy 372.023277 -291.742502) (xy 372.046148 -291.786079) (xy 372.061732 -291.83276)
			(xy 372.069627 -291.881337) (xy 372.070122 -291.905944) (xy 373.339118 -291.905944) (xy 373.343078 -291.85689)
			(xy 373.354855 -291.809106) (xy 373.374146 -291.76383) (xy 373.400449 -291.722234) (xy 373.433084 -291.685397)
			(xy 373.471205 -291.654272) (xy 373.513826 -291.629665) (xy 373.559842 -291.612213) (xy 373.608061 -291.602369)
			(xy 373.657236 -291.600388) (xy 373.706091 -291.60632) (xy 373.753362 -291.620012) (xy 373.797824 -291.64111)
			(xy 373.838327 -291.669066) (xy 373.87382 -291.703158) (xy 373.903385 -291.742502) (xy 373.926256 -291.786079)
			(xy 373.94184 -291.83276) (xy 373.949735 -291.881337) (xy 373.95023 -291.905944) (xy 374.278918 -291.905944)
			(xy 374.282878 -291.85689) (xy 374.294655 -291.809106) (xy 374.313946 -291.76383) (xy 374.340249 -291.722234)
			(xy 374.372884 -291.685397) (xy 374.411005 -291.654272) (xy 374.453626 -291.629665) (xy 374.499642 -291.612213)
			(xy 374.547861 -291.602369) (xy 374.597036 -291.600388) (xy 374.645891 -291.60632) (xy 374.693162 -291.620012)
			(xy 374.737624 -291.64111) (xy 374.778127 -291.669066) (xy 374.81362 -291.703158) (xy 374.843185 -291.742502)
			(xy 374.866056 -291.786079) (xy 374.88164 -291.83276) (xy 374.889535 -291.881337) (xy 374.89003 -291.905944)
			(xy 374.889535 -291.930551) (xy 374.88164 -291.979128) (xy 374.866056 -292.025809) (xy 374.843185 -292.069386)
			(xy 374.81362 -292.10873) (xy 374.778127 -292.142822) (xy 374.737624 -292.170778) (xy 374.693162 -292.191876)
			(xy 374.645891 -292.205568) (xy 374.597036 -292.2115) (xy 374.547861 -292.209519) (xy 374.499642 -292.199675)
			(xy 374.453626 -292.182223) (xy 374.411005 -292.157616) (xy 374.372884 -292.126491) (xy 374.340249 -292.089654)
			(xy 374.313946 -292.048058) (xy 374.294655 -292.002782) (xy 374.282878 -291.954998) (xy 374.278918 -291.905944)
			(xy 373.95023 -291.905944) (xy 373.949735 -291.930551) (xy 373.94184 -291.979128) (xy 373.926256 -292.025809)
			(xy 373.903385 -292.069386) (xy 373.87382 -292.10873) (xy 373.838327 -292.142822) (xy 373.797824 -292.170778)
			(xy 373.753362 -292.191876) (xy 373.706091 -292.205568) (xy 373.657236 -292.2115) (xy 373.608061 -292.209519)
			(xy 373.559842 -292.199675) (xy 373.513826 -292.182223) (xy 373.471205 -292.157616) (xy 373.433084 -292.126491)
			(xy 373.400449 -292.089654) (xy 373.374146 -292.048058) (xy 373.354855 -292.002782) (xy 373.343078 -291.954998)
			(xy 373.339118 -291.905944) (xy 372.070122 -291.905944) (xy 372.069627 -291.930551) (xy 372.061732 -291.979128)
			(xy 372.046148 -292.025809) (xy 372.023277 -292.069386) (xy 371.993712 -292.10873) (xy 371.958219 -292.142822)
			(xy 371.917716 -292.170778) (xy 371.873254 -292.191876) (xy 371.825983 -292.205568) (xy 371.777128 -292.2115)
			(xy 371.727953 -292.209519) (xy 371.679734 -292.199675) (xy 371.633718 -292.182223) (xy 371.591097 -292.157616)
			(xy 371.552976 -292.126491) (xy 371.520341 -292.089654) (xy 371.494038 -292.048058) (xy 371.474747 -292.002782)
			(xy 371.46297 -291.954998) (xy 371.45901 -291.905944) (xy 371.130068 -291.905944) (xy 371.129573 -291.930551)
			(xy 371.121678 -291.979128) (xy 371.106094 -292.025809) (xy 371.083223 -292.069386) (xy 371.053658 -292.10873)
			(xy 371.018165 -292.142822) (xy 370.977662 -292.170778) (xy 370.9332 -292.191876) (xy 370.885929 -292.205568)
			(xy 370.837074 -292.2115) (xy 370.787899 -292.209519) (xy 370.73968 -292.199675) (xy 370.693664 -292.182223)
			(xy 370.651043 -292.157616) (xy 370.612922 -292.126491) (xy 370.580287 -292.089654) (xy 370.553984 -292.048058)
			(xy 370.534693 -292.002782) (xy 370.522916 -291.954998) (xy 370.518956 -291.905944) (xy 369.250214 -291.905944)
			(xy 369.249719 -291.930551) (xy 369.241824 -291.979128) (xy 369.22624 -292.025809) (xy 369.203369 -292.069386)
			(xy 369.173804 -292.10873) (xy 369.138311 -292.142822) (xy 369.097808 -292.170778) (xy 369.053346 -292.191876)
			(xy 369.006075 -292.205568) (xy 368.95722 -292.2115) (xy 368.908045 -292.209519) (xy 368.859826 -292.199675)
			(xy 368.81381 -292.182223) (xy 368.771189 -292.157616) (xy 368.733068 -292.126491) (xy 368.700433 -292.089654)
			(xy 368.67413 -292.048058) (xy 368.654839 -292.002782) (xy 368.643062 -291.954998) (xy 368.639102 -291.905944)
			(xy 368.31016 -291.905944) (xy 368.309665 -291.930551) (xy 368.30177 -291.979128) (xy 368.286186 -292.025809)
			(xy 368.263315 -292.069386) (xy 368.23375 -292.10873) (xy 368.198257 -292.142822) (xy 368.157754 -292.170778)
			(xy 368.113292 -292.191876) (xy 368.066021 -292.205568) (xy 368.017166 -292.2115) (xy 367.967991 -292.209519)
			(xy 367.919772 -292.199675) (xy 367.873756 -292.182223) (xy 367.831135 -292.157616) (xy 367.793014 -292.126491)
			(xy 367.760379 -292.089654) (xy 367.734076 -292.048058) (xy 367.714785 -292.002782) (xy 367.703008 -291.954998)
			(xy 367.699048 -291.905944) (xy 366.430052 -291.905944) (xy 366.429557 -291.930551) (xy 366.421662 -291.979128)
			(xy 366.406078 -292.025809) (xy 366.383207 -292.069386) (xy 366.353642 -292.10873) (xy 366.318149 -292.142822)
			(xy 366.277646 -292.170778) (xy 366.233184 -292.191876) (xy 366.185913 -292.205568) (xy 366.137058 -292.2115)
			(xy 366.087883 -292.209519) (xy 366.039664 -292.199675) (xy 365.993648 -292.182223) (xy 365.951027 -292.157616)
			(xy 365.912906 -292.126491) (xy 365.880271 -292.089654) (xy 365.853968 -292.048058) (xy 365.834677 -292.002782)
			(xy 365.8229 -291.954998) (xy 365.81894 -291.905944) (xy 365.489998 -291.905944) (xy 365.489503 -291.930551)
			(xy 365.481608 -291.979128) (xy 365.466024 -292.025809) (xy 365.443153 -292.069386) (xy 365.413588 -292.10873)
			(xy 365.378095 -292.142822) (xy 365.337592 -292.170778) (xy 365.29313 -292.191876) (xy 365.245859 -292.205568)
			(xy 365.197004 -292.2115) (xy 365.147829 -292.209519) (xy 365.09961 -292.199675) (xy 365.053594 -292.182223)
			(xy 365.010973 -292.157616) (xy 364.972852 -292.126491) (xy 364.940217 -292.089654) (xy 364.913914 -292.048058)
			(xy 364.894623 -292.002782) (xy 364.882846 -291.954998) (xy 364.878886 -291.905944) (xy 363.610144 -291.905944)
			(xy 363.609649 -291.930551) (xy 363.601754 -291.979128) (xy 363.58617 -292.025809) (xy 363.563299 -292.069386)
			(xy 363.533734 -292.10873) (xy 363.498241 -292.142822) (xy 363.457738 -292.170778) (xy 363.413276 -292.191876)
			(xy 363.366005 -292.205568) (xy 363.31715 -292.2115) (xy 363.267975 -292.209519) (xy 363.219756 -292.199675)
			(xy 363.17374 -292.182223) (xy 363.131119 -292.157616) (xy 363.092998 -292.126491) (xy 363.060363 -292.089654)
			(xy 363.03406 -292.048058) (xy 363.014769 -292.002782) (xy 363.002992 -291.954998) (xy 362.999032 -291.905944)
			(xy 362.67009 -291.905944) (xy 362.669595 -291.930551) (xy 362.6617 -291.979128) (xy 362.646116 -292.025809)
			(xy 362.623245 -292.069386) (xy 362.59368 -292.10873) (xy 362.558187 -292.142822) (xy 362.517684 -292.170778)
			(xy 362.473222 -292.191876) (xy 362.425951 -292.205568) (xy 362.377096 -292.2115) (xy 362.327921 -292.209519)
			(xy 362.279702 -292.199675) (xy 362.233686 -292.182223) (xy 362.191065 -292.157616) (xy 362.152944 -292.126491)
			(xy 362.120309 -292.089654) (xy 362.094006 -292.048058) (xy 362.074715 -292.002782) (xy 362.062938 -291.954998)
			(xy 362.058978 -291.905944) (xy 361.729409 -291.905944) (xy 361.729409 -291.930757) (xy 361.721355 -291.979803)
			(xy 361.705459 -292.026897) (xy 361.682142 -292.070792) (xy 361.65202 -292.110329) (xy 361.61589 -292.144462)
			(xy 361.574706 -292.17229) (xy 361.529558 -292.193077) (xy 361.481638 -292.206273) (xy 361.456986 -292.209474)
			(xy 361.437428 -292.211506) (xy 361.41152 -292.240462) (xy 361.41152 -292.71595) (xy 361.589078 -292.71595)
			(xy 361.593038 -292.666896) (xy 361.604815 -292.619112) (xy 361.624106 -292.573836) (xy 361.650409 -292.53224)
			(xy 361.683044 -292.495403) (xy 361.721165 -292.464278) (xy 361.763786 -292.439671) (xy 361.809802 -292.422219)
			(xy 361.858021 -292.412375) (xy 361.907196 -292.410394) (xy 361.956051 -292.416326) (xy 362.003322 -292.430018)
			(xy 362.047784 -292.451116) (xy 362.088287 -292.479072) (xy 362.12378 -292.513164) (xy 362.153345 -292.552508)
			(xy 362.176216 -292.596085) (xy 362.1918 -292.642766) (xy 362.199695 -292.691343) (xy 362.20019 -292.71595)
			(xy 362.199695 -292.740557) (xy 362.1918 -292.789134) (xy 362.176216 -292.835815) (xy 362.153345 -292.879392)
			(xy 362.12378 -292.918736) (xy 362.088287 -292.952828) (xy 362.047784 -292.980784) (xy 362.003322 -293.001882)
			(xy 361.956051 -293.015574) (xy 361.907196 -293.021506) (xy 361.858021 -293.019525) (xy 361.809802 -293.009681)
			(xy 361.763786 -292.992229) (xy 361.721165 -292.967622) (xy 361.683044 -292.936497) (xy 361.650409 -292.89966)
			(xy 361.624106 -292.858064) (xy 361.604815 -292.812788) (xy 361.593038 -292.765004) (xy 361.589078 -292.71595)
			(xy 361.41152 -292.71595) (xy 361.41152 -293.191438) (xy 361.437428 -293.220394) (xy 361.456986 -293.222426)
			(xy 361.481654 -293.225541) (xy 361.529588 -293.238741) (xy 361.574749 -293.259534) (xy 361.615945 -293.287369)
			(xy 361.652085 -293.321512) (xy 361.682215 -293.361061) (xy 361.705539 -293.404968) (xy 361.721439 -293.452075)
			(xy 361.729497 -293.501136) (xy 361.729497 -293.525956) (xy 362.058978 -293.525956) (xy 362.062938 -293.476902)
			(xy 362.074715 -293.429118) (xy 362.094006 -293.383842) (xy 362.120309 -293.342246) (xy 362.152944 -293.305409)
			(xy 362.191065 -293.274284) (xy 362.233686 -293.249677) (xy 362.279702 -293.232225) (xy 362.327921 -293.222381)
			(xy 362.377096 -293.2204) (xy 362.425951 -293.226332) (xy 362.473222 -293.240024) (xy 362.517684 -293.261122)
			(xy 362.558187 -293.289078) (xy 362.59368 -293.32317) (xy 362.623245 -293.362514) (xy 362.646116 -293.406091)
			(xy 362.6617 -293.452772) (xy 362.669595 -293.501349) (xy 362.67009 -293.525956) (xy 362.998778 -293.525956)
			(xy 363.002738 -293.476902) (xy 363.014515 -293.429118) (xy 363.033806 -293.383842) (xy 363.060109 -293.342246)
			(xy 363.092744 -293.305409) (xy 363.130865 -293.274284) (xy 363.173486 -293.249677) (xy 363.219502 -293.232225)
			(xy 363.267721 -293.222381) (xy 363.316896 -293.2204) (xy 363.365751 -293.226332) (xy 363.413022 -293.240024)
			(xy 363.457484 -293.261122) (xy 363.497987 -293.289078) (xy 363.53348 -293.32317) (xy 363.563045 -293.362514)
			(xy 363.585916 -293.406091) (xy 363.6015 -293.452772) (xy 363.609395 -293.501349) (xy 363.60989 -293.525956)
			(xy 363.939086 -293.525956) (xy 363.943046 -293.476902) (xy 363.954823 -293.429118) (xy 363.974114 -293.383842)
			(xy 364.000417 -293.342246) (xy 364.033052 -293.305409) (xy 364.071173 -293.274284) (xy 364.113794 -293.249677)
			(xy 364.15981 -293.232225) (xy 364.208029 -293.222381) (xy 364.257204 -293.2204) (xy 364.306059 -293.226332)
			(xy 364.35333 -293.240024) (xy 364.397792 -293.261122) (xy 364.438295 -293.289078) (xy 364.473788 -293.32317)
			(xy 364.503353 -293.362514) (xy 364.526224 -293.406091) (xy 364.541808 -293.452772) (xy 364.549703 -293.501349)
			(xy 364.550198 -293.525956) (xy 364.549703 -293.550563) (xy 364.541808 -293.59914) (xy 364.526224 -293.645821)
			(xy 364.503353 -293.689398) (xy 364.473788 -293.728742) (xy 364.438295 -293.762834) (xy 364.397792 -293.79079)
			(xy 364.35333 -293.811888) (xy 364.306059 -293.82558) (xy 364.257204 -293.831512) (xy 364.208029 -293.829531)
			(xy 364.15981 -293.819687) (xy 364.113794 -293.802235) (xy 364.071173 -293.777628) (xy 364.033052 -293.746503)
			(xy 364.000417 -293.709666) (xy 363.974114 -293.66807) (xy 363.954823 -293.622794) (xy 363.943046 -293.57501)
			(xy 363.939086 -293.525956) (xy 363.60989 -293.525956) (xy 363.609395 -293.550563) (xy 363.6015 -293.59914)
			(xy 363.585916 -293.645821) (xy 363.563045 -293.689398) (xy 363.53348 -293.728742) (xy 363.497987 -293.762834)
			(xy 363.457484 -293.79079) (xy 363.413022 -293.811888) (xy 363.365751 -293.82558) (xy 363.316896 -293.831512)
			(xy 363.267721 -293.829531) (xy 363.219502 -293.819687) (xy 363.173486 -293.802235) (xy 363.130865 -293.777628)
			(xy 363.092744 -293.746503) (xy 363.060109 -293.709666) (xy 363.033806 -293.66807) (xy 363.014515 -293.622794)
			(xy 363.002738 -293.57501) (xy 362.998778 -293.525956) (xy 362.67009 -293.525956) (xy 362.669595 -293.550563)
			(xy 362.6617 -293.59914) (xy 362.646116 -293.645821) (xy 362.623245 -293.689398) (xy 362.59368 -293.728742)
			(xy 362.558187 -293.762834) (xy 362.517684 -293.79079) (xy 362.473222 -293.811888) (xy 362.425951 -293.82558)
			(xy 362.377096 -293.831512) (xy 362.327921 -293.829531) (xy 362.279702 -293.819687) (xy 362.233686 -293.802235)
			(xy 362.191065 -293.777628) (xy 362.152944 -293.746503) (xy 362.120309 -293.709666) (xy 362.094006 -293.66807)
			(xy 362.074715 -293.622794) (xy 362.062938 -293.57501) (xy 362.058978 -293.525956) (xy 361.729497 -293.525956)
			(xy 361.729497 -293.550854) (xy 361.721442 -293.599916) (xy 361.705543 -293.647023) (xy 361.68222 -293.690932)
			(xy 361.652091 -293.730481) (xy 361.615952 -293.764625) (xy 361.574757 -293.792462) (xy 361.529597 -293.813256)
			(xy 361.481663 -293.826457) (xy 361.456986 -293.829486) (xy 361.437428 -293.831518) (xy 361.41152 -293.860474)
			(xy 361.41152 -294.335962) (xy 361.589078 -294.335962) (xy 361.593038 -294.286908) (xy 361.604815 -294.239124)
			(xy 361.624106 -294.193848) (xy 361.650409 -294.152252) (xy 361.683044 -294.115415) (xy 361.721165 -294.08429)
			(xy 361.763786 -294.059683) (xy 361.809802 -294.042231) (xy 361.858021 -294.032387) (xy 361.907196 -294.030406)
			(xy 361.956051 -294.036338) (xy 362.003322 -294.05003) (xy 362.047784 -294.071128) (xy 362.088287 -294.099084)
			(xy 362.12378 -294.133176) (xy 362.153345 -294.17252) (xy 362.176216 -294.216097) (xy 362.1918 -294.262778)
			(xy 362.199695 -294.311355) (xy 362.20019 -294.335962) (xy 362.529132 -294.335962) (xy 362.533092 -294.286908)
			(xy 362.544869 -294.239124) (xy 362.56416 -294.193848) (xy 362.590463 -294.152252) (xy 362.623098 -294.115415)
			(xy 362.661219 -294.08429) (xy 362.70384 -294.059683) (xy 362.749856 -294.042231) (xy 362.798075 -294.032387)
			(xy 362.84725 -294.030406) (xy 362.896105 -294.036338) (xy 362.943376 -294.05003) (xy 362.987838 -294.071128)
			(xy 363.028341 -294.099084) (xy 363.063834 -294.133176) (xy 363.093399 -294.17252) (xy 363.11627 -294.216097)
			(xy 363.131854 -294.262778) (xy 363.139749 -294.311355) (xy 363.140244 -294.335962) (xy 363.468932 -294.335962)
			(xy 363.472892 -294.286908) (xy 363.484669 -294.239124) (xy 363.50396 -294.193848) (xy 363.530263 -294.152252)
			(xy 363.562898 -294.115415) (xy 363.601019 -294.08429) (xy 363.64364 -294.059683) (xy 363.689656 -294.042231)
			(xy 363.737875 -294.032387) (xy 363.78705 -294.030406) (xy 363.835905 -294.036338) (xy 363.883176 -294.05003)
			(xy 363.927638 -294.071128) (xy 363.968141 -294.099084) (xy 364.003634 -294.133176) (xy 364.033199 -294.17252)
			(xy 364.05607 -294.216097) (xy 364.071654 -294.262778) (xy 364.079549 -294.311355) (xy 364.080044 -294.335962)
			(xy 364.079549 -294.360569) (xy 364.071654 -294.409146) (xy 364.05607 -294.455827) (xy 364.033199 -294.499404)
			(xy 364.003634 -294.538748) (xy 363.968141 -294.57284) (xy 363.927638 -294.600796) (xy 363.883176 -294.621894)
			(xy 363.835905 -294.635586) (xy 363.78705 -294.641518) (xy 363.737875 -294.639537) (xy 363.689656 -294.629693)
			(xy 363.64364 -294.612241) (xy 363.601019 -294.587634) (xy 363.562898 -294.556509) (xy 363.530263 -294.519672)
			(xy 363.50396 -294.478076) (xy 363.484669 -294.4328) (xy 363.472892 -294.385016) (xy 363.468932 -294.335962)
			(xy 363.140244 -294.335962) (xy 363.139749 -294.360569) (xy 363.131854 -294.409146) (xy 363.11627 -294.455827)
			(xy 363.093399 -294.499404) (xy 363.063834 -294.538748) (xy 363.028341 -294.57284) (xy 362.987838 -294.600796)
			(xy 362.943376 -294.621894) (xy 362.896105 -294.635586) (xy 362.84725 -294.641518) (xy 362.798075 -294.639537)
			(xy 362.749856 -294.629693) (xy 362.70384 -294.612241) (xy 362.661219 -294.587634) (xy 362.623098 -294.556509)
			(xy 362.590463 -294.519672) (xy 362.56416 -294.478076) (xy 362.544869 -294.4328) (xy 362.533092 -294.385016)
			(xy 362.529132 -294.335962) (xy 362.20019 -294.335962) (xy 362.199695 -294.360569) (xy 362.1918 -294.409146)
			(xy 362.176216 -294.455827) (xy 362.153345 -294.499404) (xy 362.12378 -294.538748) (xy 362.088287 -294.57284)
			(xy 362.047784 -294.600796) (xy 362.003322 -294.621894) (xy 361.956051 -294.635586) (xy 361.907196 -294.641518)
			(xy 361.858021 -294.639537) (xy 361.809802 -294.629693) (xy 361.763786 -294.612241) (xy 361.721165 -294.587634)
			(xy 361.683044 -294.556509) (xy 361.650409 -294.519672) (xy 361.624106 -294.478076) (xy 361.604815 -294.4328)
			(xy 361.593038 -294.385016) (xy 361.589078 -294.335962) (xy 361.41152 -294.335962) (xy 361.41152 -294.81145)
			(xy 361.437428 -294.840406) (xy 361.456986 -294.842438) (xy 361.481655 -294.845552) (xy 361.529591 -294.858748)
			(xy 361.574756 -294.879536) (xy 361.615957 -294.907366) (xy 361.652105 -294.941503) (xy 361.682245 -294.981044)
			(xy 361.705582 -295.024947) (xy 361.721499 -295.072049) (xy 361.729574 -295.121109) (xy 361.730036 -295.145968)
			(xy 362.058978 -295.145968) (xy 362.062938 -295.096914) (xy 362.074715 -295.04913) (xy 362.094006 -295.003854)
			(xy 362.120309 -294.962258) (xy 362.152944 -294.925421) (xy 362.191065 -294.894296) (xy 362.233686 -294.869689)
			(xy 362.279702 -294.852237) (xy 362.327921 -294.842393) (xy 362.377096 -294.840412) (xy 362.425951 -294.846344)
			(xy 362.473222 -294.860036) (xy 362.517684 -294.881134) (xy 362.558187 -294.90909) (xy 362.59368 -294.943182)
			(xy 362.623245 -294.982526) (xy 362.646116 -295.026103) (xy 362.6617 -295.072784) (xy 362.669595 -295.121361)
			(xy 362.67009 -295.145968) (xy 362.669595 -295.170575) (xy 362.6617 -295.219152) (xy 362.646116 -295.265833)
			(xy 362.623245 -295.30941) (xy 362.59368 -295.348754) (xy 362.558187 -295.382846) (xy 362.517684 -295.410802)
			(xy 362.473222 -295.4319) (xy 362.425951 -295.445592) (xy 362.377096 -295.451524) (xy 362.327921 -295.449543)
			(xy 362.279702 -295.439699) (xy 362.233686 -295.422247) (xy 362.191065 -295.39764) (xy 362.152944 -295.366515)
			(xy 362.120309 -295.329678) (xy 362.094006 -295.288082) (xy 362.074715 -295.242806) (xy 362.062938 -295.195022)
			(xy 362.058978 -295.145968) (xy 361.730036 -295.145968) (xy 361.729542 -295.170924) (xy 361.721429 -295.220174)
			(xy 361.705414 -295.267447) (xy 361.681923 -295.311487) (xy 361.651582 -295.35112) (xy 361.6152 -295.38529)
			(xy 361.573744 -295.413087) (xy 361.55122 -295.423844) (xy 361.53979 -295.429178) (xy 361.52455 -295.448482)
			(xy 361.507278 -295.543224) (xy 361.505848 -295.555482) (xy 361.51329 -295.578968) (xy 361.521502 -295.588182)
			(xy 361.683554 -295.750234) (xy 361.690952 -295.757079) (xy 361.709551 -295.764804) (xy 361.719622 -295.76522)
		)
		(stroke
			(width 0)
			(type solid)
		)
		(fill yes)
		(layer "In15.Cu")
		(net "PVDDCR_CPU1_P0")
	)
	(gr_poly
		(pts
			(xy 394.722858 -299.83938) (xy 394.732732 -299.838912) (xy 394.751018 -299.831457) (xy 394.758418 -299.824902)
			(xy 394.758672 -299.824648) (xy 395.432534 -299.150786) (xy 395.433042 -299.150278) (xy 395.43963 -299.142899)
			(xy 395.447093 -299.1246) (xy 395.44752 -299.114718) (xy 395.44752 -268.763242) (xy 395.447087 -268.753176)
			(xy 395.43936 -268.734585) (xy 395.432534 -268.727174) (xy 395.15034 -268.44498) (xy 395.143058 -268.438362)
			(xy 395.12493 -268.430759) (xy 395.105272 -268.430563) (xy 395.095984 -268.433804) (xy 395.09573 -268.433804)
			(xy 395.068625 -268.443853) (xy 395.011854 -268.454717) (xy 394.982954 -268.455394) (xy 394.958966 -268.45492)
			(xy 394.91158 -268.447408) (xy 394.865953 -268.432576) (xy 394.823208 -268.41079) (xy 394.784397 -268.382586)
			(xy 394.750475 -268.348658) (xy 394.722278 -268.309841) (xy 394.700501 -268.267091) (xy 394.685678 -268.221461)
			(xy 394.678175 -268.174075) (xy 394.677646 -268.150086) (xy 394.67832 -268.121186) (xy 394.68919 -268.064417)
			(xy 394.699236 -268.03731) (xy 394.699236 -268.037056) (xy 394.702392 -268.027752) (xy 394.702174 -268.008125)
			(xy 394.694632 -267.990002) (xy 394.68806 -267.9827) (xy 393.372086 -266.666726) (xy 393.364974 -266.65936)
			(xy 393.346178 -266.65174) (xy 392.379454 -266.65174) (xy 392.37539 -266.651994) (xy 392.36722 -266.652918)
			(xy 392.352062 -266.659265) (xy 392.345672 -266.66444) (xy 392.341608 -266.668504) (xy 392.28395 -266.732766)
			(xy 392.277346 -266.753086) (xy 392.278362 -266.764008) (xy 392.28014 -266.796012) (xy 392.279618 -266.821267)
			(xy 392.271305 -266.871089) (xy 392.254904 -266.918863) (xy 392.230863 -266.963286) (xy 392.199839 -267.003146)
			(xy 392.162677 -267.037356) (xy 392.120391 -267.064982) (xy 392.074135 -267.085272) (xy 392.02517 -267.097672)
			(xy 391.974832 -267.101843) (xy 391.924494 -267.097672) (xy 391.875529 -267.085272) (xy 391.829273 -267.064982)
			(xy 391.786987 -267.037356) (xy 391.749825 -267.003146) (xy 391.718801 -266.963286) (xy 391.69476 -266.918863)
			(xy 391.678359 -266.871089) (xy 391.670046 -266.821267) (xy 391.669524 -266.796012) (xy 391.671302 -266.764008)
			(xy 391.672318 -266.753086) (xy 391.665714 -266.732766) (xy 391.608056 -266.668504) (xy 391.603992 -266.66444)
			(xy 391.5976 -266.659271) (xy 391.582442 -266.652934) (xy 391.574274 -266.651994) (xy 391.57021 -266.65174)
			(xy 391.44321 -266.65174) (xy 391.432551 -266.652198) (xy 391.413085 -266.660883) (xy 391.405618 -266.668504)
			(xy 391.347706 -266.732766) (xy 391.34542 -266.739878) (xy 391.347785 -266.753791) (xy 391.350326 -266.7819)
			(xy 391.3505 -266.796012) (xy 391.350013 -266.820822) (xy 391.342251 -266.86983) (xy 391.326918 -266.91702)
			(xy 391.304391 -266.961231) (xy 391.275226 -267.001374) (xy 391.24014 -267.03646) (xy 391.199997 -267.065625)
			(xy 391.155786 -267.088152) (xy 391.108596 -267.103485) (xy 391.059588 -267.111247) (xy 391.009968 -267.111247)
			(xy 390.96096 -267.103485) (xy 390.91377 -267.088152) (xy 390.869559 -267.065625) (xy 390.829416 -267.03646)
			(xy 390.79433 -267.001374) (xy 390.765165 -266.961231) (xy 390.742638 -266.91702) (xy 390.727305 -266.86983)
			(xy 390.719543 -266.820822) (xy 390.719056 -266.796012) (xy 390.719221 -266.7819) (xy 390.721761 -266.75379)
			(xy 390.724136 -266.739878) (xy 390.72185 -266.732766) (xy 390.663938 -266.668504) (xy 390.656394 -266.660993)
			(xy 390.636975 -266.652325) (xy 390.626346 -266.65174) (xy 390.499346 -266.65174) (xy 390.495282 -266.651994)
			(xy 390.487112 -266.652919) (xy 390.471956 -266.659268) (xy 390.465564 -266.66444) (xy 390.4615 -266.668504)
			(xy 390.403842 -266.732766) (xy 390.397238 -266.753086) (xy 390.398254 -266.764008) (xy 390.400032 -266.796012)
			(xy 390.39951 -266.821267) (xy 390.391197 -266.871089) (xy 390.374796 -266.918863) (xy 390.350755 -266.963286)
			(xy 390.319731 -267.003146) (xy 390.282569 -267.037356) (xy 390.240283 -267.064982) (xy 390.194027 -267.085272)
			(xy 390.145062 -267.097672) (xy 390.094724 -267.101843) (xy 390.044386 -267.097672) (xy 389.995421 -267.085272)
			(xy 389.949165 -267.064982) (xy 389.906879 -267.037356) (xy 389.869717 -267.003146) (xy 389.838693 -266.963286)
			(xy 389.814652 -266.918863) (xy 389.798251 -266.871089) (xy 389.789938 -266.821267) (xy 389.789416 -266.796012)
			(xy 389.791194 -266.764008) (xy 389.79221 -266.753086) (xy 389.785606 -266.732766) (xy 389.727948 -266.668504)
			(xy 389.723884 -266.66444) (xy 389.717492 -266.659272) (xy 389.702333 -266.652938) (xy 389.694166 -266.651994)
			(xy 389.690102 -266.65174) (xy 389.563356 -266.65174) (xy 389.552693 -266.652189) (xy 389.533213 -266.660863)
			(xy 389.525764 -266.668504) (xy 389.467852 -266.732766) (xy 389.465566 -266.739878) (xy 389.467865 -266.753797)
			(xy 389.470283 -266.781905) (xy 389.470392 -266.796012) (xy 389.469906 -266.820802) (xy 389.46215 -266.86977)
			(xy 389.446829 -266.916923) (xy 389.42432 -266.961098) (xy 389.395178 -267.001209) (xy 389.360121 -267.036266)
			(xy 389.32001 -267.065408) (xy 389.275835 -267.087917) (xy 389.228682 -267.103238) (xy 389.179714 -267.110994)
			(xy 389.130134 -267.110994) (xy 389.081166 -267.103238) (xy 389.034013 -267.087917) (xy 388.989838 -267.065408)
			(xy 388.949727 -267.036266) (xy 388.91467 -267.001209) (xy 388.885528 -266.961098) (xy 388.863019 -266.916923)
			(xy 388.847698 -266.86977) (xy 388.839942 -266.820802) (xy 388.839456 -266.796012) (xy 388.839548 -266.781904)
			(xy 388.841961 -266.753794) (xy 388.844282 -266.739878) (xy 388.841996 -266.732766) (xy 388.784084 -266.668504)
			(xy 388.776537 -266.661002) (xy 388.757117 -266.652354) (xy 388.746492 -266.65174) (xy 388.619492 -266.65174)
			(xy 388.615428 -266.651994) (xy 388.607255 -266.652912) (xy 388.59209 -266.659251) (xy 388.58571 -266.66444)
			(xy 388.581646 -266.668504) (xy 388.523988 -266.732766) (xy 388.517384 -266.753086) (xy 388.5184 -266.764008)
			(xy 388.520178 -266.796012) (xy 388.519656 -266.821267) (xy 388.511343 -266.871089) (xy 388.494942 -266.918863)
			(xy 388.470901 -266.963286) (xy 388.439877 -267.003146) (xy 388.402715 -267.037356) (xy 388.360429 -267.064982)
			(xy 388.314173 -267.085272) (xy 388.265208 -267.097672) (xy 388.21487 -267.101843) (xy 388.164532 -267.097672)
			(xy 388.115567 -267.085272) (xy 388.069311 -267.064982) (xy 388.027025 -267.037356) (xy 387.989863 -267.003146)
			(xy 387.958839 -266.963286) (xy 387.934798 -266.918863) (xy 387.918397 -266.871089) (xy 387.910084 -266.821267)
			(xy 387.909562 -266.796012) (xy 387.91134 -266.764008) (xy 387.912356 -266.753086) (xy 387.905752 -266.732766)
			(xy 387.848094 -266.668504) (xy 387.84403 -266.66444) (xy 387.83764 -266.659266) (xy 387.822482 -266.652918)
			(xy 387.814312 -266.651994) (xy 387.810248 -266.65174) (xy 387.683248 -266.65174) (xy 387.672586 -266.652191)
			(xy 387.653108 -266.660866) (xy 387.645656 -266.668504) (xy 387.587744 -266.732766) (xy 387.585458 -266.739878)
			(xy 387.587756 -266.753797) (xy 387.590174 -266.781905) (xy 387.590284 -266.796012) (xy 387.589798 -266.820802)
			(xy 387.582042 -266.86977) (xy 387.566721 -266.916923) (xy 387.544212 -266.961098) (xy 387.51507 -267.001209)
			(xy 387.480013 -267.036266) (xy 387.439902 -267.065408) (xy 387.395727 -267.087917) (xy 387.348574 -267.103238)
			(xy 387.299606 -267.110994) (xy 387.250026 -267.110994) (xy 387.201058 -267.103238) (xy 387.153905 -267.087917)
			(xy 387.10973 -267.065408) (xy 387.069619 -267.036266) (xy 387.034562 -267.001209) (xy 387.00542 -266.961098)
			(xy 386.982911 -266.916923) (xy 386.96759 -266.86977) (xy 386.959834 -266.820802) (xy 386.959348 -266.796012)
			(xy 386.959865 -266.769797) (xy 386.968526 -266.718088) (xy 386.985612 -266.668521) (xy 387.010652 -266.622457)
			(xy 387.04296 -266.581165) (xy 387.081646 -266.545778) (xy 387.103366 -266.53109) (xy 387.113272 -266.524486)
			(xy 387.12521 -266.505182) (xy 387.133338 -266.423394) (xy 387.133803 -266.416546) (xy 387.131488 -266.403024)
			(xy 387.128766 -266.396724) (xy 387.124956 -266.388596) (xy 387.00329 -266.26693) (xy 386.995428 -266.259647)
			(xy 386.975466 -266.251904) (xy 386.954085 -266.25303) (xy 386.944362 -266.257532) (xy 386.944108 -266.257786)
			(xy 386.943854 -266.257786) (xy 386.922236 -266.268356) (xy 386.876496 -266.283301) (xy 386.828976 -266.290868)
			(xy 386.804916 -266.291314) (xy 386.799582 -266.291314) (xy 386.773522 -266.29033) (xy 386.722294 -266.28058)
			(xy 386.673466 -266.262272) (xy 386.628457 -266.235938) (xy 386.588573 -266.202343) (xy 386.554975 -266.162462)
			(xy 386.528637 -266.117454) (xy 386.510326 -266.068628) (xy 386.500572 -266.017401) (xy 386.499608 -265.99134)
			(xy 386.499608 -265.987784) (xy 386.499608 -265.986006) (xy 386.500086 -265.96195) (xy 386.507674 -265.914439)
			(xy 386.522602 -265.868701) (xy 386.533136 -265.847068) (xy 386.533136 -265.846814) (xy 386.53339 -265.84656)
			(xy 386.537696 -265.836787) (xy 386.538764 -265.815483) (xy 386.531143 -265.795561) (xy 386.523992 -265.787632)
			(xy 386.195824 -265.459464) (xy 386.188966 -265.455908) (xy 386.167811 -265.444373) (xy 386.12896 -265.415874)
			(xy 386.094893 -265.381801) (xy 386.0664 -265.342946) (xy 386.054854 -265.321796) (xy 386.051298 -265.314938)
			(xy 385.872228 -265.135868) (xy 385.865066 -265.129325) (xy 385.847246 -265.121698) (xy 385.827869 -265.121214)
			(xy 385.818634 -265.124184) (xy 385.71805 -265.161268) (xy 385.70027 -265.18489) (xy 385.699 -265.199876)
			(xy 385.696515 -265.225082) (xy 385.684262 -265.274225) (xy 385.664068 -265.320672) (xy 385.636486 -265.36315)
			(xy 385.602274 -265.400495) (xy 385.562369 -265.431683) (xy 385.517865 -265.45586) (xy 385.469981 -265.472361)
			(xy 385.420031 -265.480736) (xy 385.394708 -265.481308) (xy 385.370714 -265.480862) (xy 385.323318 -265.473357)
			(xy 385.277679 -265.458529) (xy 385.234922 -265.436744) (xy 385.196099 -265.408538) (xy 385.162167 -265.374607)
			(xy 385.13396 -265.335785) (xy 385.112174 -265.293028) (xy 385.097345 -265.24739) (xy 385.089838 -265.199994)
			(xy 385.0894 -265.176) (xy 385.089892 -265.150666) (xy 385.098243 -265.100691) (xy 385.114732 -265.052782)
			(xy 385.138907 -265.008254) (xy 385.170104 -264.968329) (xy 385.207466 -264.934105) (xy 385.249967 -264.906521)
			(xy 385.29644 -264.886334) (xy 385.345608 -264.874099) (xy 385.370832 -264.871708) (xy 385.385818 -264.870438)
			(xy 385.40944 -264.852658) (xy 385.446524 -264.752074) (xy 385.449527 -264.74284) (xy 385.449079 -264.723443)
			(xy 385.441425 -264.705615) (xy 385.43484 -264.69848) (xy 385.300728 -264.564368) (xy 385.293036 -264.557408)
			(xy 385.273762 -264.54979) (xy 385.26339 -264.549636) (xy 385.178554 -264.552176) (xy 385.160012 -264.560812)
			(xy 385.1529 -264.56894) (xy 385.135367 -264.58784) (xy 385.095122 -264.620051) (xy 385.050039 -264.645046)
			(xy 385.001398 -264.662115) (xy 384.950582 -264.670774) (xy 384.924808 -264.671302) (xy 384.900815 -264.670856)
			(xy 384.853419 -264.663351) (xy 384.80778 -264.648523) (xy 384.765023 -264.626738) (xy 384.726201 -264.598532)
			(xy 384.692269 -264.5646) (xy 384.664063 -264.525778) (xy 384.642278 -264.483022) (xy 384.62745 -264.437383)
			(xy 384.619944 -264.389987) (xy 384.6195 -264.365994) (xy 384.620036 -264.34022) (xy 384.628694 -264.289405)
			(xy 384.645763 -264.240766) (xy 384.670757 -264.195684) (xy 384.702967 -264.15544) (xy 384.721862 -264.137902)
			(xy 384.72999 -264.13079) (xy 384.738626 -264.112248) (xy 384.741166 -264.027412) (xy 384.740989 -264.017043)
			(xy 384.733387 -263.997769) (xy 384.726434 -263.990074) (xy 384.599434 -263.863074) (xy 384.594392 -263.858417)
			(xy 384.582422 -263.851711) (xy 384.575812 -263.849866) (xy 384.57251 -263.84885) (xy 384.544273 -263.859437)
			(xy 384.485058 -263.870819) (xy 384.454908 -263.871456) (xy 384.430116 -263.870996) (xy 384.381143 -263.86324)
			(xy 384.333987 -263.847918) (xy 384.289808 -263.825408) (xy 384.249694 -263.796264) (xy 384.214633 -263.761203)
			(xy 384.18549 -263.721089) (xy 384.16298 -263.67691) (xy 384.147659 -263.629753) (xy 384.139904 -263.58078)
			(xy 384.13944 -263.555988) (xy 384.139872 -263.531053) (xy 384.14766 -263.481798) (xy 384.154934 -263.457944)
			(xy 384.159506 -263.444228) (xy 384.152902 -263.416542) (xy 384.108706 -263.372346) (xy 384.101594 -263.36498)
			(xy 384.082798 -263.35736) (xy 383.910078 -263.35736) (xy 383.898448 -263.357919) (xy 383.877529 -263.368086)
			(xy 383.869946 -263.376918) (xy 383.813558 -263.449054) (xy 383.808478 -263.471914) (xy 383.811272 -263.483344)
			(xy 383.815406 -263.501221) (xy 383.819867 -263.537642) (xy 383.820162 -263.555988) (xy 383.81964 -263.581243)
			(xy 383.811327 -263.631065) (xy 383.794926 -263.678839) (xy 383.770885 -263.723262) (xy 383.739861 -263.763122)
			(xy 383.702699 -263.797332) (xy 383.660413 -263.824958) (xy 383.614157 -263.845248) (xy 383.565192 -263.857648)
			(xy 383.514854 -263.861819) (xy 383.464516 -263.857648) (xy 383.415551 -263.845248) (xy 383.369295 -263.824958)
			(xy 383.327009 -263.797332) (xy 383.289847 -263.763122) (xy 383.258823 -263.723262) (xy 383.234782 -263.678839)
			(xy 383.218381 -263.631065) (xy 383.210068 -263.581243) (xy 383.209546 -263.555988) (xy 383.209849 -263.537642)
			(xy 383.214304 -263.501221) (xy 383.218436 -263.483344) (xy 383.22123 -263.471914) (xy 383.21615 -263.449054)
			(xy 383.159762 -263.376918) (xy 383.152176 -263.368079) (xy 383.131265 -263.357875) (xy 383.11963 -263.35736)
			(xy 382.97866 -263.35736) (xy 382.969516 -263.358122) (xy 382.960372 -263.3599) (xy 382.951228 -263.36244)
			(xy 382.942592 -263.365742) (xy 382.877568 -263.4488) (xy 382.875282 -263.459214) (xy 382.882317 -263.482785)
			(xy 382.889841 -263.531393) (xy 382.890268 -263.555988) (xy 382.889782 -263.580778) (xy 382.882026 -263.629746)
			(xy 382.866705 -263.676899) (xy 382.844196 -263.721074) (xy 382.815054 -263.761185) (xy 382.779997 -263.796242)
			(xy 382.739886 -263.825384) (xy 382.695711 -263.847893) (xy 382.648558 -263.863214) (xy 382.59959 -263.87097)
			(xy 382.55001 -263.87097) (xy 382.501042 -263.863214) (xy 382.453889 -263.847893) (xy 382.409714 -263.825384)
			(xy 382.369603 -263.796242) (xy 382.334546 -263.761185) (xy 382.305404 -263.721074) (xy 382.282895 -263.676899)
			(xy 382.267574 -263.629746) (xy 382.259818 -263.580778) (xy 382.259332 -263.555988) (xy 382.259745 -263.531393)
			(xy 382.267277 -263.482784) (xy 382.274318 -263.459214) (xy 382.272032 -263.4488) (xy 382.215898 -263.376918)
			(xy 382.21145 -263.371562) (xy 382.200232 -263.363329) (xy 382.1938 -263.360662) (xy 382.18491 -263.35736)
			(xy 382.02997 -263.35736) (xy 382.018341 -263.357921) (xy 381.997424 -263.36809) (xy 381.989838 -263.376918)
			(xy 381.93345 -263.449054) (xy 381.92837 -263.471914) (xy 381.931164 -263.483344) (xy 381.935298 -263.501221)
			(xy 381.939759 -263.537642) (xy 381.940054 -263.555988) (xy 381.939532 -263.581243) (xy 381.931219 -263.631065)
			(xy 381.914818 -263.678839) (xy 381.890777 -263.723262) (xy 381.859753 -263.763122) (xy 381.822591 -263.797332)
			(xy 381.780305 -263.824958) (xy 381.734049 -263.845248) (xy 381.685084 -263.857648) (xy 381.634746 -263.861819)
			(xy 381.584408 -263.857648) (xy 381.535443 -263.845248) (xy 381.489187 -263.824958) (xy 381.446901 -263.797332)
			(xy 381.409739 -263.763122) (xy 381.378715 -263.723262) (xy 381.354674 -263.678839) (xy 381.338273 -263.631065)
			(xy 381.32996 -263.581243) (xy 381.329438 -263.555988) (xy 381.32974 -263.537642) (xy 381.334195 -263.501221)
			(xy 381.338328 -263.483344) (xy 381.341122 -263.471914) (xy 381.336042 -263.449054) (xy 381.279654 -263.376918)
			(xy 381.272068 -263.36808) (xy 381.251157 -263.35788) (xy 381.239522 -263.35736) (xy 381.098806 -263.35736)
			(xy 381.089662 -263.358122) (xy 381.080518 -263.3599) (xy 381.071374 -263.36244) (xy 381.062738 -263.365742)
			(xy 380.997714 -263.4488) (xy 380.995428 -263.459214) (xy 381.002545 -263.482772) (xy 381.010204 -263.531383)
			(xy 381.010668 -263.555988) (xy 381.010181 -263.580798) (xy 381.002419 -263.629806) (xy 380.987086 -263.676996)
			(xy 380.964559 -263.721207) (xy 380.935394 -263.76135) (xy 380.900308 -263.796436) (xy 380.860165 -263.825601)
			(xy 380.815954 -263.848128) (xy 380.768764 -263.863461) (xy 380.719756 -263.871223) (xy 380.670136 -263.871223)
			(xy 380.621128 -263.863461) (xy 380.573938 -263.848128) (xy 380.529727 -263.825601) (xy 380.489584 -263.796436)
			(xy 380.454498 -263.76135) (xy 380.425333 -263.721207) (xy 380.402806 -263.676996) (xy 380.387473 -263.629806)
			(xy 380.379711 -263.580798) (xy 380.379224 -263.555988) (xy 380.379719 -263.531386) (xy 380.387379 -263.48278)
			(xy 380.394464 -263.459214) (xy 380.392178 -263.4488) (xy 380.336044 -263.376918) (xy 380.331599 -263.371559)
			(xy 380.320384 -263.363316) (xy 380.313946 -263.360662) (xy 380.305056 -263.35736) (xy 380.158752 -263.35736)
			(xy 380.149608 -263.358122) (xy 380.140464 -263.3599) (xy 380.13132 -263.36244) (xy 380.122684 -263.365742)
			(xy 380.05766 -263.4488) (xy 380.055374 -263.459214) (xy 380.062409 -263.482785) (xy 380.069934 -263.531393)
			(xy 380.07036 -263.555988) (xy 380.069874 -263.580778) (xy 380.062118 -263.629746) (xy 380.046797 -263.676899)
			(xy 380.024288 -263.721074) (xy 379.995146 -263.761185) (xy 379.960089 -263.796242) (xy 379.919978 -263.825384)
			(xy 379.875803 -263.847893) (xy 379.82865 -263.863214) (xy 379.779682 -263.87097) (xy 379.730102 -263.87097)
			(xy 379.681134 -263.863214) (xy 379.633981 -263.847893) (xy 379.589806 -263.825384) (xy 379.549695 -263.796242)
			(xy 379.514638 -263.761185) (xy 379.485496 -263.721074) (xy 379.462987 -263.676899) (xy 379.447666 -263.629746)
			(xy 379.43991 -263.580778) (xy 379.439424 -263.555988) (xy 379.439837 -263.531393) (xy 379.447369 -263.482784)
			(xy 379.45441 -263.459214) (xy 379.452124 -263.4488) (xy 379.39599 -263.376918) (xy 379.391547 -263.371555)
			(xy 379.380336 -263.363303) (xy 379.373892 -263.360662) (xy 379.365002 -263.35736) (xy 378.278644 -263.35736)
			(xy 378.2695 -263.358122) (xy 378.260356 -263.3599) (xy 378.251212 -263.36244) (xy 378.242576 -263.365742)
			(xy 378.177552 -263.4488) (xy 378.175266 -263.459214) (xy 378.182301 -263.482785) (xy 378.189826 -263.531393)
			(xy 378.190252 -263.555988) (xy 378.189766 -263.580778) (xy 378.18201 -263.629746) (xy 378.166689 -263.676899)
			(xy 378.14418 -263.721074) (xy 378.115038 -263.761185) (xy 378.079981 -263.796242) (xy 378.03987 -263.825384)
			(xy 377.995695 -263.847893) (xy 377.948542 -263.863214) (xy 377.899574 -263.87097) (xy 377.849994 -263.87097)
			(xy 377.801026 -263.863214) (xy 377.753873 -263.847893) (xy 377.709698 -263.825384) (xy 377.669587 -263.796242)
			(xy 377.63453 -263.761185) (xy 377.605388 -263.721074) (xy 377.582879 -263.676899) (xy 377.567558 -263.629746)
			(xy 377.559802 -263.580778) (xy 377.559316 -263.555988) (xy 377.559729 -263.531393) (xy 377.567261 -263.482784)
			(xy 377.574302 -263.459214) (xy 377.572016 -263.4488) (xy 377.515882 -263.376918) (xy 377.511439 -263.371556)
			(xy 377.500227 -263.363305) (xy 377.493784 -263.360662) (xy 377.484894 -263.35736) (xy 377.329954 -263.35736)
			(xy 377.318327 -263.357924) (xy 377.297415 -263.368097) (xy 377.289822 -263.376918) (xy 377.233434 -263.449054)
			(xy 377.228354 -263.471914) (xy 377.231148 -263.483344) (xy 377.235282 -263.501221) (xy 377.239743 -263.537642)
			(xy 377.240038 -263.555988) (xy 377.239516 -263.581243) (xy 377.231203 -263.631065) (xy 377.214802 -263.678839)
			(xy 377.190761 -263.723262) (xy 377.159737 -263.763122) (xy 377.122575 -263.797332) (xy 377.080289 -263.824958)
			(xy 377.034033 -263.845248) (xy 376.985068 -263.857648) (xy 376.93473 -263.861819) (xy 376.884392 -263.857648)
			(xy 376.835427 -263.845248) (xy 376.789171 -263.824958) (xy 376.746885 -263.797332) (xy 376.709723 -263.763122)
			(xy 376.678699 -263.723262) (xy 376.654658 -263.678839) (xy 376.638257 -263.631065) (xy 376.629944 -263.581243)
			(xy 376.629422 -263.555988) (xy 376.629724 -263.537642) (xy 376.634179 -263.501221) (xy 376.638312 -263.483344)
			(xy 376.641106 -263.471914) (xy 376.636026 -263.449054) (xy 376.579638 -263.376918) (xy 376.572051 -263.368083)
			(xy 376.55114 -263.357889) (xy 376.539506 -263.35736) (xy 376.39879 -263.35736) (xy 376.389646 -263.358122)
			(xy 376.380502 -263.3599) (xy 376.371358 -263.36244) (xy 376.362722 -263.365742) (xy 376.297698 -263.4488)
			(xy 376.295412 -263.459214) (xy 376.302528 -263.482772) (xy 376.310185 -263.531383) (xy 376.310652 -263.555988)
			(xy 376.310165 -263.580798) (xy 376.302403 -263.629806) (xy 376.28707 -263.676996) (xy 376.264543 -263.721207)
			(xy 376.235378 -263.76135) (xy 376.200292 -263.796436) (xy 376.160149 -263.825601) (xy 376.115938 -263.848128)
			(xy 376.068748 -263.863461) (xy 376.01974 -263.871223) (xy 375.97012 -263.871223) (xy 375.921112 -263.863461)
			(xy 375.873922 -263.848128) (xy 375.829711 -263.825601) (xy 375.789568 -263.796436) (xy 375.754482 -263.76135)
			(xy 375.725317 -263.721207) (xy 375.70279 -263.676996) (xy 375.687457 -263.629806) (xy 375.679695 -263.580798)
			(xy 375.679208 -263.555988) (xy 375.679703 -263.531386) (xy 375.687363 -263.482779) (xy 375.694448 -263.459214)
			(xy 375.692162 -263.4488) (xy 375.636028 -263.376918) (xy 375.631582 -263.37156) (xy 375.620365 -263.363321)
			(xy 375.61393 -263.360662) (xy 375.60504 -263.35736) (xy 375.4501 -263.35736) (xy 375.438479 -263.357935)
			(xy 375.417585 -263.368121) (xy 375.409968 -263.376918) (xy 375.35358 -263.449054) (xy 375.3485 -263.471914)
			(xy 375.351294 -263.483344) (xy 375.355429 -263.501221) (xy 375.359891 -263.537642) (xy 375.360184 -263.555988)
			(xy 375.359662 -263.581243) (xy 375.351349 -263.631065) (xy 375.334948 -263.678839) (xy 375.310907 -263.723262)
			(xy 375.279883 -263.763122) (xy 375.242721 -263.797332) (xy 375.200435 -263.824958) (xy 375.154179 -263.845248)
			(xy 375.105214 -263.857648) (xy 375.054876 -263.861819) (xy 375.004538 -263.857648) (xy 374.955573 -263.845248)
			(xy 374.909317 -263.824958) (xy 374.867031 -263.797332) (xy 374.829869 -263.763122) (xy 374.798845 -263.723262)
			(xy 374.774804 -263.678839) (xy 374.758403 -263.631065) (xy 374.75009 -263.581243) (xy 374.749568 -263.555988)
			(xy 374.749871 -263.537642) (xy 374.754326 -263.501221) (xy 374.758458 -263.483344) (xy 374.761252 -263.471914)
			(xy 374.756172 -263.449054) (xy 374.699784 -263.376918) (xy 374.6922 -263.368075) (xy 374.671289 -263.357862)
			(xy 374.659652 -263.35736) (xy 373.569992 -263.35736) (xy 373.558372 -263.357937) (xy 373.53748 -263.368125)
			(xy 373.52986 -263.376918) (xy 373.473472 -263.449054) (xy 373.468392 -263.471914) (xy 373.471186 -263.483344)
			(xy 373.475321 -263.501221) (xy 373.479783 -263.537642) (xy 373.480076 -263.555988) (xy 373.479554 -263.581243)
			(xy 373.471241 -263.631065) (xy 373.45484 -263.678839) (xy 373.430799 -263.723262) (xy 373.399775 -263.763122)
			(xy 373.362613 -263.797332) (xy 373.320327 -263.824958) (xy 373.274071 -263.845248) (xy 373.225106 -263.857648)
			(xy 373.174768 -263.861819) (xy 373.12443 -263.857648) (xy 373.075465 -263.845248) (xy 373.029209 -263.824958)
			(xy 372.986923 -263.797332) (xy 372.949761 -263.763122) (xy 372.918737 -263.723262) (xy 372.894696 -263.678839)
			(xy 372.878295 -263.631065) (xy 372.869982 -263.581243) (xy 372.86946 -263.555988) (xy 372.869763 -263.537642)
			(xy 372.874218 -263.501221) (xy 372.87835 -263.483344) (xy 372.881144 -263.471914) (xy 372.876064 -263.449054)
			(xy 372.819676 -263.376918) (xy 372.812091 -263.368076) (xy 372.791181 -263.357867) (xy 372.779544 -263.35736)
			(xy 371.690138 -263.35736) (xy 371.678513 -263.357927) (xy 371.657606 -263.368104) (xy 371.650006 -263.376918)
			(xy 371.593618 -263.449054) (xy 371.588538 -263.471914) (xy 371.591332 -263.483344) (xy 371.595466 -263.501221)
			(xy 371.599928 -263.537642) (xy 371.600222 -263.555988) (xy 371.5997 -263.581243) (xy 371.591387 -263.631065)
			(xy 371.574986 -263.678839) (xy 371.550945 -263.723262) (xy 371.519921 -263.763122) (xy 371.482759 -263.797332)
			(xy 371.440473 -263.824958) (xy 371.394217 -263.845248) (xy 371.345252 -263.857648) (xy 371.294914 -263.861819)
			(xy 371.244576 -263.857648) (xy 371.195611 -263.845248) (xy 371.149355 -263.824958) (xy 371.107069 -263.797332)
			(xy 371.069907 -263.763122) (xy 371.038883 -263.723262) (xy 371.014842 -263.678839) (xy 370.998441 -263.631065)
			(xy 370.990128 -263.581243) (xy 370.989606 -263.555988) (xy 370.989909 -263.537642) (xy 370.994365 -263.501221)
			(xy 370.998496 -263.483344) (xy 371.00129 -263.471914) (xy 370.99621 -263.449054) (xy 370.939822 -263.376918)
			(xy 370.932233 -263.368086) (xy 370.911323 -263.357898) (xy 370.89969 -263.35736) (xy 369.81003 -263.35736)
			(xy 369.798406 -263.357929) (xy 369.777502 -263.368108) (xy 369.769898 -263.376918) (xy 369.71351 -263.449054)
			(xy 369.70843 -263.471914) (xy 369.711224 -263.483344) (xy 369.715358 -263.501221) (xy 369.71982 -263.537642)
			(xy 369.720114 -263.555988) (xy 369.719592 -263.581243) (xy 369.711279 -263.631065) (xy 369.694878 -263.678839)
			(xy 369.670837 -263.723262) (xy 369.639813 -263.763122) (xy 369.602651 -263.797332) (xy 369.560365 -263.824958)
			(xy 369.514109 -263.845248) (xy 369.465144 -263.857648) (xy 369.414806 -263.861819) (xy 369.364468 -263.857648)
			(xy 369.315503 -263.845248) (xy 369.269247 -263.824958) (xy 369.226961 -263.797332) (xy 369.189799 -263.763122)
			(xy 369.158775 -263.723262) (xy 369.134734 -263.678839) (xy 369.118333 -263.631065) (xy 369.11002 -263.581243)
			(xy 369.109498 -263.555988) (xy 369.10994 -263.532682) (xy 369.117029 -263.486612) (xy 369.131041 -263.442157)
			(xy 369.15165 -263.400348) (xy 369.178377 -263.36216) (xy 369.2106 -263.328479) (xy 369.247569 -263.30009)
			(xy 369.288425 -263.277653) (xy 369.310158 -263.269222) (xy 369.322604 -263.26465) (xy 369.339622 -263.245346)
			(xy 369.361212 -263.148826) (xy 369.362725 -263.14042) (xy 369.360727 -263.123468) (xy 369.353305 -263.108095)
			(xy 369.347496 -263.101836) (xy 368.215926 -261.970266) (xy 368.208814 -261.9629) (xy 368.190018 -261.95528)
			(xy 366.090962 -261.95528) (xy 366.080895 -261.954849) (xy 366.062303 -261.947123) (xy 366.054894 -261.940294)
			(xy 365.63808 -261.52348) (xy 365.631323 -261.517211) (xy 365.614564 -261.509572) (xy 365.596184 -261.508403)
			(xy 365.58728 -261.51078) (xy 365.572294 -261.515352) (xy 365.566452 -261.519162) (xy 365.545568 -261.532027)
			(xy 365.500929 -261.552356) (xy 365.453856 -261.566141) (xy 365.405303 -261.573102) (xy 365.380778 -261.573518)
			(xy 365.355079 -261.573036) (xy 365.304257 -261.565373) (xy 365.255144 -261.550221) (xy 365.208838 -261.527918)
			(xy 365.166372 -261.498964) (xy 365.128697 -261.464003) (xy 365.096652 -261.423819) (xy 365.070955 -261.379307)
			(xy 365.052178 -261.331462) (xy 365.040741 -261.281353) (xy 365.0369 -261.2301) (xy 365.040741 -261.178847)
			(xy 365.052178 -261.128738) (xy 365.070955 -261.080893) (xy 365.096652 -261.036381) (xy 365.128697 -260.996197)
			(xy 365.166372 -260.961236) (xy 365.208838 -260.932282) (xy 365.255144 -260.909979) (xy 365.304257 -260.894827)
			(xy 365.355079 -260.887164) (xy 365.380778 -260.886702) (xy 365.409925 -260.887321) (xy 365.467382 -260.897156)
			(xy 365.495078 -260.90626) (xy 365.507016 -260.910324) (xy 365.531146 -260.907022) (xy 365.60887 -260.851904)
			(xy 365.618452 -260.844327) (xy 365.629717 -260.822696) (xy 365.63046 -260.810502) (xy 365.63046 -260.699758)
			(xy 365.629693 -260.687574) (xy 365.618423 -260.665957) (xy 365.60887 -260.658356) (xy 365.531146 -260.603238)
			(xy 365.507016 -260.599936) (xy 365.495078 -260.604) (xy 365.467396 -260.613153) (xy 365.409929 -260.622981)
			(xy 365.380778 -260.623558) (xy 365.378746 -260.623558) (xy 365.351868 -260.622876) (xy 365.298813 -260.614179)
			(xy 365.247761 -260.597319) (xy 365.199962 -260.572709) (xy 365.156582 -260.540949) (xy 365.118682 -260.502816)
			(xy 365.087189 -260.459243) (xy 365.062872 -260.411293) (xy 365.046325 -260.360139) (xy 365.037953 -260.307032)
			(xy 365.03737 -260.28015) (xy 365.03788 -260.253114) (xy 365.04636 -260.199713) (xy 365.063105 -260.148299)
			(xy 365.087699 -260.100145) (xy 365.119535 -260.05644) (xy 365.157826 -260.018263) (xy 365.201627 -259.986559)
			(xy 365.249855 -259.96211) (xy 365.301319 -259.94552) (xy 365.327946 -259.940806) (xy 365.34217 -259.93852)
			(xy 365.364014 -259.920232) (xy 365.39678 -259.82041) (xy 365.399269 -259.811368) (xy 365.398272 -259.792656)
			(xy 365.390635 -259.775544) (xy 365.384334 -259.768594) (xy 365.279686 -259.663946) (xy 365.27577 -259.660197)
			(xy 365.266675 -259.654301) (xy 365.261652 -259.652262) (xy 365.23041 -259.6388) (xy 365.230156 -259.6388)
			(xy 365.219316 -259.633349) (xy 365.198343 -259.621145) (xy 365.188246 -259.614416) (xy 365.181841 -259.610382)
			(xy 365.167364 -259.605982) (xy 365.159798 -259.60578) (xy 364.545372 -259.60578) (xy 364.541054 -259.606034)
			(xy 364.532056 -259.607126) (xy 364.515654 -259.61481) (xy 364.50905 -259.62102) (xy 364.504224 -259.626862)
			(xy 364.455964 -259.693156) (xy 364.44945 -259.703192) (xy 364.445621 -259.726778) (xy 364.448598 -259.738368)
			(xy 364.448852 -259.73913) (xy 364.456617 -259.764726) (xy 364.465043 -259.817544) (xy 364.465616 -259.844286)
			(xy 364.465616 -259.848604) (xy 364.464823 -259.875406) (xy 364.455942 -259.928284) (xy 364.438951 -259.979139)
			(xy 364.414264 -260.026735) (xy 364.382479 -260.069916) (xy 364.344369 -260.107633) (xy 364.300861 -260.138969)
			(xy 364.253012 -260.163163) (xy 364.201984 -260.179626) (xy 364.149017 -260.187959) (xy 364.095399 -260.187959)
			(xy 364.042432 -260.179626) (xy 363.991404 -260.163163) (xy 363.943555 -260.138969) (xy 363.900047 -260.107633)
			(xy 363.861937 -260.069916) (xy 363.830152 -260.026735) (xy 363.805465 -259.979139) (xy 363.788474 -259.928284)
			(xy 363.779593 -259.875406) (xy 363.7788 -259.848604) (xy 363.7788 -259.844794) (xy 363.77934 -259.817924)
			(xy 363.787763 -259.764848) (xy 363.795564 -259.73913) (xy 363.795818 -259.738368) (xy 363.798785 -259.72678)
			(xy 363.794949 -259.703199) (xy 363.788452 -259.693156) (xy 363.740192 -259.626862) (xy 363.735366 -259.62102)
			(xy 363.728746 -259.614836) (xy 363.712351 -259.607157) (xy 363.703362 -259.606034) (xy 363.699044 -259.60578)
			(xy 361.945428 -259.60578) (xy 361.94111 -259.606034) (xy 361.932115 -259.607133) (xy 361.915724 -259.614827)
			(xy 361.909106 -259.62102) (xy 361.90428 -259.626862) (xy 361.85602 -259.693156) (xy 361.849501 -259.703191)
			(xy 361.845667 -259.726779) (xy 361.848654 -259.738368) (xy 361.848908 -259.73913) (xy 361.856674 -259.764726)
			(xy 361.865101 -259.817544) (xy 361.865672 -259.844286) (xy 361.865672 -259.848604) (xy 361.864879 -259.875406)
			(xy 361.855998 -259.928284) (xy 361.839007 -259.979139) (xy 361.81432 -260.026735) (xy 361.782535 -260.069916)
			(xy 361.744425 -260.107633) (xy 361.700917 -260.138969) (xy 361.653068 -260.163163) (xy 361.60204 -260.179626)
			(xy 361.549073 -260.187959) (xy 361.495455 -260.187959) (xy 361.442488 -260.179626) (xy 361.39146 -260.163163)
			(xy 361.343611 -260.138969) (xy 361.300103 -260.107633) (xy 361.261993 -260.069916) (xy 361.230208 -260.026735)
			(xy 361.205521 -259.979139) (xy 361.18853 -259.928284) (xy 361.179649 -259.875406) (xy 361.178856 -259.848604)
			(xy 361.178856 -259.844794) (xy 361.179397 -259.817924) (xy 361.187821 -259.764849) (xy 361.19562 -259.73913)
			(xy 361.195874 -259.738368) (xy 361.198842 -259.72678) (xy 361.195004 -259.7032) (xy 361.188508 -259.693156)
			(xy 361.140248 -259.626862) (xy 361.135422 -259.62102) (xy 361.128799 -259.614842) (xy 361.112403 -259.607177)
			(xy 361.103418 -259.606034) (xy 361.0991 -259.60578) (xy 360.363262 -259.60578) (xy 360.353195 -259.605349)
			(xy 360.334603 -259.597623) (xy 360.327194 -259.590794) (xy 359.711244 -258.974844) (xy 359.703116 -258.966716)
			(xy 359.682034 -258.959096) (xy 359.58145 -258.968494) (xy 359.561892 -258.979924) (xy 359.555542 -258.989322)
			(xy 359.539398 -259.011916) (xy 359.501029 -259.052056) (xy 359.456698 -259.085495) (xy 359.407563 -259.111361)
			(xy 359.354904 -259.128981) (xy 359.300096 -259.137893) (xy 359.272332 -259.13842) (xy 359.245497 -259.137905)
			(xy 359.19248 -259.129561) (xy 359.141406 -259.113071) (xy 359.093519 -259.088836) (xy 359.049986 -259.057447)
			(xy 359.011865 -259.019668) (xy 358.980085 -258.976419) (xy 358.955421 -258.928753) (xy 358.938471 -258.877829)
			(xy 358.92965 -258.824889) (xy 358.928924 -258.79806) (xy 358.928924 -258.794758) (xy 358.929338 -258.771146)
			(xy 358.935845 -258.724372) (xy 358.941878 -258.70154) (xy 358.941878 -258.701032) (xy 358.944489 -258.68958)
			(xy 358.94013 -258.666527) (xy 358.933496 -258.656836) (xy 358.884728 -258.59232) (xy 358.877174 -258.583258)
			(xy 358.856121 -258.572671) (xy 358.844342 -258.572) (xy 357.378762 -258.572) (xy 357.368695 -258.57243)
			(xy 357.350101 -258.580154) (xy 357.342694 -258.586986) (xy 357.121968 -258.807712) (xy 357.114602 -258.823206)
			(xy 357.113586 -258.831842) (xy 357.110538 -258.854448) (xy 357.110284 -258.854702) (xy 357.108474 -258.864917)
			(xy 357.103769 -258.885123) (xy 357.100886 -258.895088) (xy 357.0986 -258.902454) (xy 357.0986 -259.737606)
			(xy 357.100886 -259.744972) (xy 357.107812 -259.769403) (xy 357.115218 -259.81964) (xy 357.115178 -259.845048)
			(xy 358.928419 -259.845048) (xy 358.932449 -259.79255) (xy 358.944446 -259.741282) (xy 358.964129 -259.692447)
			(xy 358.991035 -259.647188) (xy 359.024535 -259.606567) (xy 359.063843 -259.571536) (xy 359.108038 -259.542916)
			(xy 359.156083 -259.521377) (xy 359.206854 -259.507425) (xy 359.259159 -259.501387) (xy 359.311773 -259.503404)
			(xy 359.363463 -259.513428) (xy 359.413016 -259.531226) (xy 359.459272 -259.556379) (xy 359.501146 -259.588298)
			(xy 359.537658 -259.626236) (xy 359.56795 -259.669302) (xy 359.591313 -259.716487) (xy 359.607199 -259.766686)
			(xy 359.615236 -259.818722) (xy 359.61574 -259.845048) (xy 359.615236 -259.871374) (xy 359.607199 -259.92341)
			(xy 359.591313 -259.973609) (xy 359.56795 -260.020794) (xy 359.537658 -260.06386) (xy 359.501146 -260.101798)
			(xy 359.459272 -260.133717) (xy 359.413016 -260.15887) (xy 359.363463 -260.176668) (xy 359.311773 -260.186692)
			(xy 359.259159 -260.188709) (xy 359.206854 -260.182671) (xy 359.156083 -260.168719) (xy 359.108038 -260.14718)
			(xy 359.063843 -260.11856) (xy 359.024535 -260.083529) (xy 358.991035 -260.042908) (xy 358.964129 -259.997649)
			(xy 358.944446 -259.948814) (xy 358.932449 -259.897546) (xy 358.928419 -259.845048) (xy 357.115178 -259.845048)
			(xy 357.115139 -259.87042) (xy 357.111808 -259.895594) (xy 357.112062 -259.895594) (xy 357.110062 -259.908017)
			(xy 357.10447 -259.932554) (xy 357.100886 -259.944616) (xy 357.0986 -259.951982) (xy 357.0986 -260.983222)
			(xy 357.099036 -260.9929) (xy 357.106198 -261.010884) (xy 357.119473 -261.024973) (xy 357.128064 -261.02945)
			(xy 357.225346 -261.074408) (xy 357.254556 -261.070344) (xy 357.265986 -261.060692) (xy 357.284687 -261.045416)
			(xy 357.325561 -261.019707) (xy 357.36963 -260.999968) (xy 357.416026 -260.986588) (xy 357.463838 -260.97983)
			(xy 357.487982 -260.979412) (xy 357.513682 -260.979867) (xy 357.564508 -260.987525) (xy 357.613626 -261.002674)
			(xy 357.659936 -261.024973) (xy 357.702406 -261.053927) (xy 357.740086 -261.088887) (xy 357.772134 -261.129072)
			(xy 357.797835 -261.173586) (xy 357.816614 -261.221432) (xy 357.828052 -261.271544) (xy 357.831894 -261.3228)
			(xy 357.831893 -261.32282) (xy 358.094029 -261.32282) (xy 358.098059 -261.270322) (xy 358.110056 -261.219054)
			(xy 358.129739 -261.170219) (xy 358.156645 -261.12496) (xy 358.190145 -261.084339) (xy 358.229453 -261.049308)
			(xy 358.273648 -261.020688) (xy 358.321693 -260.999149) (xy 358.372464 -260.985197) (xy 358.424769 -260.979159)
			(xy 358.477383 -260.981176) (xy 358.529073 -260.9912) (xy 358.578626 -261.008998) (xy 358.624882 -261.034151)
			(xy 358.666756 -261.06607) (xy 358.703268 -261.104008) (xy 358.73356 -261.147074) (xy 358.756923 -261.194259)
			(xy 358.772809 -261.244458) (xy 358.780846 -261.296494) (xy 358.78135 -261.32282) (xy 359.043989 -261.32282)
			(xy 359.048019 -261.270322) (xy 359.060016 -261.219054) (xy 359.079699 -261.170219) (xy 359.106605 -261.12496)
			(xy 359.140105 -261.084339) (xy 359.179413 -261.049308) (xy 359.223608 -261.020688) (xy 359.271653 -260.999149)
			(xy 359.322424 -260.985197) (xy 359.374729 -260.979159) (xy 359.427343 -260.981176) (xy 359.479033 -260.9912)
			(xy 359.528586 -261.008998) (xy 359.574842 -261.034151) (xy 359.616716 -261.06607) (xy 359.653228 -261.104008)
			(xy 359.68352 -261.147074) (xy 359.706883 -261.194259) (xy 359.722769 -261.244458) (xy 359.730806 -261.296494)
			(xy 359.73131 -261.32282) (xy 359.993949 -261.32282) (xy 359.997979 -261.270322) (xy 360.009976 -261.219054)
			(xy 360.029659 -261.170219) (xy 360.056565 -261.12496) (xy 360.090065 -261.084339) (xy 360.129373 -261.049308)
			(xy 360.173568 -261.020688) (xy 360.221613 -260.999149) (xy 360.272384 -260.985197) (xy 360.324689 -260.979159)
			(xy 360.377303 -260.981176) (xy 360.428993 -260.9912) (xy 360.478546 -261.008998) (xy 360.524802 -261.034151)
			(xy 360.566676 -261.06607) (xy 360.603188 -261.104008) (xy 360.63348 -261.147074) (xy 360.656843 -261.194259)
			(xy 360.672729 -261.244458) (xy 360.680766 -261.296494) (xy 360.68127 -261.32282) (xy 360.944163 -261.32282)
			(xy 360.948193 -261.270322) (xy 360.96019 -261.219054) (xy 360.979873 -261.170219) (xy 361.006779 -261.12496)
			(xy 361.040279 -261.084339) (xy 361.079587 -261.049308) (xy 361.123782 -261.020688) (xy 361.171827 -260.999149)
			(xy 361.222598 -260.985197) (xy 361.274903 -260.979159) (xy 361.327517 -260.981176) (xy 361.379207 -260.9912)
			(xy 361.42876 -261.008998) (xy 361.475016 -261.034151) (xy 361.51689 -261.06607) (xy 361.553402 -261.104008)
			(xy 361.583694 -261.147074) (xy 361.607057 -261.194259) (xy 361.622943 -261.244458) (xy 361.63098 -261.296494)
			(xy 361.631484 -261.32282) (xy 361.894123 -261.32282) (xy 361.898153 -261.270322) (xy 361.91015 -261.219054)
			(xy 361.929833 -261.170219) (xy 361.956739 -261.12496) (xy 361.990239 -261.084339) (xy 362.029547 -261.049308)
			(xy 362.073742 -261.020688) (xy 362.121787 -260.999149) (xy 362.172558 -260.985197) (xy 362.224863 -260.979159)
			(xy 362.277477 -260.981176) (xy 362.329167 -260.9912) (xy 362.37872 -261.008998) (xy 362.424976 -261.034151)
			(xy 362.46685 -261.06607) (xy 362.503362 -261.104008) (xy 362.533654 -261.147074) (xy 362.557017 -261.194259)
			(xy 362.572903 -261.244458) (xy 362.58094 -261.296494) (xy 362.581444 -261.32282) (xy 362.844083 -261.32282)
			(xy 362.848113 -261.270322) (xy 362.86011 -261.219054) (xy 362.879793 -261.170219) (xy 362.906699 -261.12496)
			(xy 362.940199 -261.084339) (xy 362.979507 -261.049308) (xy 363.023702 -261.020688) (xy 363.071747 -260.999149)
			(xy 363.122518 -260.985197) (xy 363.174823 -260.979159) (xy 363.227437 -260.981176) (xy 363.279127 -260.9912)
			(xy 363.32868 -261.008998) (xy 363.374936 -261.034151) (xy 363.41681 -261.06607) (xy 363.453322 -261.104008)
			(xy 363.483614 -261.147074) (xy 363.506977 -261.194259) (xy 363.522863 -261.244458) (xy 363.5309 -261.296494)
			(xy 363.531404 -261.32282) (xy 363.794043 -261.32282) (xy 363.798073 -261.270322) (xy 363.81007 -261.219054)
			(xy 363.829753 -261.170219) (xy 363.856659 -261.12496) (xy 363.890159 -261.084339) (xy 363.929467 -261.049308)
			(xy 363.973662 -261.020688) (xy 364.021707 -260.999149) (xy 364.072478 -260.985197) (xy 364.124783 -260.979159)
			(xy 364.177397 -260.981176) (xy 364.229087 -260.9912) (xy 364.27864 -261.008998) (xy 364.324896 -261.034151)
			(xy 364.36677 -261.06607) (xy 364.403282 -261.104008) (xy 364.433574 -261.147074) (xy 364.456937 -261.194259)
			(xy 364.472823 -261.244458) (xy 364.48086 -261.296494) (xy 364.481364 -261.32282) (xy 364.48086 -261.349146)
			(xy 364.472823 -261.401182) (xy 364.456937 -261.451381) (xy 364.433574 -261.498566) (xy 364.403282 -261.541632)
			(xy 364.36677 -261.57957) (xy 364.324896 -261.611489) (xy 364.27864 -261.636642) (xy 364.229087 -261.65444)
			(xy 364.177397 -261.664464) (xy 364.124783 -261.666481) (xy 364.072478 -261.660443) (xy 364.021707 -261.646491)
			(xy 363.973662 -261.624952) (xy 363.929467 -261.596332) (xy 363.890159 -261.561301) (xy 363.856659 -261.52068)
			(xy 363.829753 -261.475421) (xy 363.81007 -261.426586) (xy 363.798073 -261.375318) (xy 363.794043 -261.32282)
			(xy 363.531404 -261.32282) (xy 363.5309 -261.349146) (xy 363.522863 -261.401182) (xy 363.506977 -261.451381)
			(xy 363.483614 -261.498566) (xy 363.453322 -261.541632) (xy 363.41681 -261.57957) (xy 363.374936 -261.611489)
			(xy 363.32868 -261.636642) (xy 363.279127 -261.65444) (xy 363.227437 -261.664464) (xy 363.174823 -261.666481)
			(xy 363.122518 -261.660443) (xy 363.071747 -261.646491) (xy 363.023702 -261.624952) (xy 362.979507 -261.596332)
			(xy 362.940199 -261.561301) (xy 362.906699 -261.52068) (xy 362.879793 -261.475421) (xy 362.86011 -261.426586)
			(xy 362.848113 -261.375318) (xy 362.844083 -261.32282) (xy 362.581444 -261.32282) (xy 362.58094 -261.349146)
			(xy 362.572903 -261.401182) (xy 362.557017 -261.451381) (xy 362.533654 -261.498566) (xy 362.503362 -261.541632)
			(xy 362.46685 -261.57957) (xy 362.424976 -261.611489) (xy 362.37872 -261.636642) (xy 362.329167 -261.65444)
			(xy 362.277477 -261.664464) (xy 362.224863 -261.666481) (xy 362.172558 -261.660443) (xy 362.121787 -261.646491)
			(xy 362.073742 -261.624952) (xy 362.029547 -261.596332) (xy 361.990239 -261.561301) (xy 361.956739 -261.52068)
			(xy 361.929833 -261.475421) (xy 361.91015 -261.426586) (xy 361.898153 -261.375318) (xy 361.894123 -261.32282)
			(xy 361.631484 -261.32282) (xy 361.63098 -261.349146) (xy 361.622943 -261.401182) (xy 361.607057 -261.451381)
			(xy 361.583694 -261.498566) (xy 361.553402 -261.541632) (xy 361.51689 -261.57957) (xy 361.475016 -261.611489)
			(xy 361.42876 -261.636642) (xy 361.379207 -261.65444) (xy 361.327517 -261.664464) (xy 361.274903 -261.666481)
			(xy 361.222598 -261.660443) (xy 361.171827 -261.646491) (xy 361.123782 -261.624952) (xy 361.079587 -261.596332)
			(xy 361.040279 -261.561301) (xy 361.006779 -261.52068) (xy 360.979873 -261.475421) (xy 360.96019 -261.426586)
			(xy 360.948193 -261.375318) (xy 360.944163 -261.32282) (xy 360.68127 -261.32282) (xy 360.680766 -261.349146)
			(xy 360.672729 -261.401182) (xy 360.656843 -261.451381) (xy 360.63348 -261.498566) (xy 360.603188 -261.541632)
			(xy 360.566676 -261.57957) (xy 360.524802 -261.611489) (xy 360.478546 -261.636642) (xy 360.428993 -261.65444)
			(xy 360.377303 -261.664464) (xy 360.324689 -261.666481) (xy 360.272384 -261.660443) (xy 360.221613 -261.646491)
			(xy 360.173568 -261.624952) (xy 360.129373 -261.596332) (xy 360.090065 -261.561301) (xy 360.056565 -261.52068)
			(xy 360.029659 -261.475421) (xy 360.009976 -261.426586) (xy 359.997979 -261.375318) (xy 359.993949 -261.32282)
			(xy 359.73131 -261.32282) (xy 359.730806 -261.349146) (xy 359.722769 -261.401182) (xy 359.706883 -261.451381)
			(xy 359.68352 -261.498566) (xy 359.653228 -261.541632) (xy 359.616716 -261.57957) (xy 359.574842 -261.611489)
			(xy 359.528586 -261.636642) (xy 359.479033 -261.65444) (xy 359.427343 -261.664464) (xy 359.374729 -261.666481)
			(xy 359.322424 -261.660443) (xy 359.271653 -261.646491) (xy 359.223608 -261.624952) (xy 359.179413 -261.596332)
			(xy 359.140105 -261.561301) (xy 359.106605 -261.52068) (xy 359.079699 -261.475421) (xy 359.060016 -261.426586)
			(xy 359.048019 -261.375318) (xy 359.043989 -261.32282) (xy 358.78135 -261.32282) (xy 358.780846 -261.349146)
			(xy 358.772809 -261.401182) (xy 358.756923 -261.451381) (xy 358.73356 -261.498566) (xy 358.703268 -261.541632)
			(xy 358.666756 -261.57957) (xy 358.624882 -261.611489) (xy 358.578626 -261.636642) (xy 358.529073 -261.65444)
			(xy 358.477383 -261.664464) (xy 358.424769 -261.666481) (xy 358.372464 -261.660443) (xy 358.321693 -261.646491)
			(xy 358.273648 -261.624952) (xy 358.229453 -261.596332) (xy 358.190145 -261.561301) (xy 358.156645 -261.52068)
			(xy 358.129739 -261.475421) (xy 358.110056 -261.426586) (xy 358.098059 -261.375318) (xy 358.094029 -261.32282)
			(xy 357.831893 -261.32282) (xy 357.828052 -261.374056) (xy 357.816614 -261.424168) (xy 357.797835 -261.472014)
			(xy 357.772134 -261.516528) (xy 357.740086 -261.556713) (xy 357.702406 -261.591673) (xy 357.659936 -261.620627)
			(xy 357.613626 -261.642926) (xy 357.564508 -261.658075) (xy 357.513682 -261.665733) (xy 357.487982 -261.666228)
			(xy 357.461091 -261.665711) (xy 357.407964 -261.657335) (xy 357.356795 -261.640776) (xy 357.308834 -261.616437)
			(xy 357.265257 -261.584916) (xy 357.22713 -261.546984) (xy 357.195386 -261.503569) (xy 357.170801 -261.455734)
			(xy 357.153979 -261.40465) (xy 357.149146 -261.378192) (xy 357.146606 -261.363714) (xy 357.128318 -261.342378)
			(xy 357.028496 -261.31012) (xy 357.01949 -261.307684) (xy 357.000876 -261.308718) (xy 356.983844 -261.316296)
			(xy 356.976934 -261.322566) (xy 356.861872 -261.437628) (xy 356.858062 -261.447534) (xy 356.847214 -261.473837)
			(xy 356.818104 -261.522718) (xy 356.781337 -261.566136) (xy 356.73792 -261.602902) (xy 356.689039 -261.632013)
			(xy 356.662736 -261.64286) (xy 356.65283 -261.64667) (xy 356.290626 -262.008874) (xy 356.283225 -262.015712)
			(xy 356.264626 -262.023423) (xy 356.254558 -262.02386) (xy 353.872546 -262.02386) (xy 353.861799 -262.024345)
			(xy 353.842201 -262.033166) (xy 353.8347 -262.040878) (xy 353.776788 -262.106156) (xy 353.770438 -262.126984)
			(xy 353.771708 -262.137906) (xy 353.77291 -262.148405) (xy 353.774183 -262.169502) (xy 353.774248 -262.18007)
			(xy 365.036865 -262.18007) (xy 365.040895 -262.127572) (xy 365.052892 -262.076304) (xy 365.072575 -262.027469)
			(xy 365.099481 -261.98221) (xy 365.132981 -261.941589) (xy 365.172289 -261.906558) (xy 365.216484 -261.877938)
			(xy 365.264529 -261.856399) (xy 365.3153 -261.842447) (xy 365.367605 -261.836409) (xy 365.420219 -261.838426)
			(xy 365.471909 -261.84845) (xy 365.521462 -261.866248) (xy 365.567718 -261.891401) (xy 365.609592 -261.92332)
			(xy 365.646104 -261.961258) (xy 365.676396 -262.004324) (xy 365.699759 -262.051509) (xy 365.715645 -262.101708)
			(xy 365.723682 -262.153744) (xy 365.724186 -262.18007) (xy 365.723682 -262.206396) (xy 365.715645 -262.258432)
			(xy 365.699759 -262.308631) (xy 365.676396 -262.355816) (xy 365.646104 -262.398882) (xy 365.609592 -262.43682)
			(xy 365.567718 -262.468739) (xy 365.521462 -262.493892) (xy 365.471909 -262.51169) (xy 365.420219 -262.521714)
			(xy 365.367605 -262.523731) (xy 365.3153 -262.517693) (xy 365.264529 -262.503741) (xy 365.216484 -262.482202)
			(xy 365.172289 -262.453582) (xy 365.132981 -262.418551) (xy 365.099481 -262.37793) (xy 365.072575 -262.332671)
			(xy 365.052892 -262.283836) (xy 365.040895 -262.232568) (xy 365.036865 -262.18007) (xy 353.774248 -262.18007)
			(xy 353.773768 -262.205769) (xy 353.766107 -262.256593) (xy 353.750958 -262.305707) (xy 353.728657 -262.352015)
			(xy 353.699704 -262.394482) (xy 353.664744 -262.432159) (xy 353.62456 -262.464205) (xy 353.580048 -262.489904)
			(xy 353.532203 -262.508681) (xy 353.482094 -262.520119) (xy 353.43084 -262.52396) (xy 353.379586 -262.520119)
			(xy 353.329477 -262.508681) (xy 353.281632 -262.489904) (xy 353.23712 -262.464205) (xy 353.196936 -262.432159)
			(xy 353.161976 -262.394482) (xy 353.133023 -262.352015) (xy 353.110722 -262.305707) (xy 353.095573 -262.256593)
			(xy 353.087912 -262.205769) (xy 353.087432 -262.18007) (xy 353.087495 -262.169502) (xy 353.088764 -262.148405)
			(xy 353.089972 -262.137906) (xy 353.091242 -262.126984) (xy 353.084892 -262.106156) (xy 353.02698 -262.040878)
			(xy 353.019413 -262.033262) (xy 352.999853 -262.024471) (xy 352.989134 -262.02386) (xy 350.933766 -262.02386)
			(xy 350.908366 -262.040624) (xy 350.90227 -262.054848) (xy 350.891844 -262.078176) (xy 350.864389 -262.121267)
			(xy 350.830145 -262.159187) (xy 350.790068 -262.19088) (xy 350.745276 -262.215461) (xy 350.697017 -262.232245)
			(xy 350.646639 -262.240763) (xy 350.621092 -262.241284) (xy 350.598306 -262.240869) (xy 350.553239 -262.23411)
			(xy 350.509676 -262.22073) (xy 350.468585 -262.201024) (xy 350.430879 -262.175431) (xy 350.397395 -262.144519)
			(xy 350.38284 -262.126984) (xy 350.375982 -262.118348) (xy 350.357186 -262.108696) (xy 350.270572 -262.104124)
			(xy 350.259861 -262.103996) (xy 350.239862 -262.11162) (xy 350.231964 -262.118856) (xy 350.083628 -262.267192)
			(xy 350.076818 -262.274515) (xy 350.069084 -262.292939) (xy 350.069015 -262.31292) (xy 350.072452 -262.32231)
			(xy 350.107758 -262.408924) (xy 350.110861 -262.415839) (xy 350.120416 -262.427593) (xy 350.126554 -262.432038)
			(xy 350.132743 -262.435931) (xy 350.146683 -262.440318) (xy 350.153986 -262.440674) (xy 350.15424 -262.440674)
			(xy 350.178075 -262.44137) (xy 350.225102 -262.449251) (xy 350.270332 -262.464345) (xy 350.312666 -262.486288)
			(xy 350.351074 -262.514544) (xy 350.384623 -262.548427) (xy 350.412498 -262.587113) (xy 350.43402 -262.629661)
			(xy 350.448666 -262.675039) (xy 350.456081 -262.722141) (xy 350.4565 -262.745982) (xy 350.456462 -262.748014)
			(xy 350.78214 -262.748014) (xy 350.7861 -262.69896) (xy 350.797877 -262.651176) (xy 350.817168 -262.6059)
			(xy 350.843471 -262.564304) (xy 350.876106 -262.527467) (xy 350.914227 -262.496342) (xy 350.956848 -262.471735)
			(xy 351.002864 -262.454283) (xy 351.051083 -262.444439) (xy 351.100258 -262.442458) (xy 351.149113 -262.44839)
			(xy 351.196384 -262.462082) (xy 351.240846 -262.48318) (xy 351.281349 -262.511136) (xy 351.316842 -262.545228)
			(xy 351.346407 -262.584572) (xy 351.369278 -262.628149) (xy 351.384862 -262.67483) (xy 351.392757 -262.723407)
			(xy 351.393252 -262.748014) (xy 351.722194 -262.748014) (xy 351.726154 -262.69896) (xy 351.737931 -262.651176)
			(xy 351.757222 -262.6059) (xy 351.783525 -262.564304) (xy 351.81616 -262.527467) (xy 351.854281 -262.496342)
			(xy 351.896902 -262.471735) (xy 351.942918 -262.454283) (xy 351.991137 -262.444439) (xy 352.040312 -262.442458)
			(xy 352.089167 -262.44839) (xy 352.136438 -262.462082) (xy 352.1809 -262.48318) (xy 352.221403 -262.511136)
			(xy 352.256896 -262.545228) (xy 352.286461 -262.584572) (xy 352.309332 -262.628149) (xy 352.324916 -262.67483)
			(xy 352.332811 -262.723407) (xy 352.333306 -262.748014) (xy 352.332811 -262.772621) (xy 352.324916 -262.821198)
			(xy 352.309332 -262.867879) (xy 352.286461 -262.911456) (xy 352.256896 -262.9508) (xy 352.221403 -262.984892)
			(xy 352.1809 -263.012848) (xy 352.136438 -263.033946) (xy 352.089167 -263.047638) (xy 352.040312 -263.05357)
			(xy 351.991137 -263.051589) (xy 351.942918 -263.041745) (xy 351.896902 -263.024293) (xy 351.854281 -262.999686)
			(xy 351.81616 -262.968561) (xy 351.783525 -262.931724) (xy 351.757222 -262.890128) (xy 351.737931 -262.844852)
			(xy 351.726154 -262.797068) (xy 351.722194 -262.748014) (xy 351.393252 -262.748014) (xy 351.392757 -262.772621)
			(xy 351.384862 -262.821198) (xy 351.369278 -262.867879) (xy 351.346407 -262.911456) (xy 351.316842 -262.9508)
			(xy 351.281349 -262.984892) (xy 351.240846 -263.012848) (xy 351.196384 -263.033946) (xy 351.149113 -263.047638)
			(xy 351.100258 -263.05357) (xy 351.051083 -263.051589) (xy 351.002864 -263.041745) (xy 350.956848 -263.024293)
			(xy 350.914227 -262.999686) (xy 350.876106 -262.968561) (xy 350.843471 -262.931724) (xy 350.817168 -262.890128)
			(xy 350.797877 -262.844852) (xy 350.7861 -262.797068) (xy 350.78214 -262.748014) (xy 350.456462 -262.748014)
			(xy 350.456055 -262.769976) (xy 350.448551 -262.817373) (xy 350.433724 -262.863013) (xy 350.411939 -262.905771)
			(xy 350.383734 -262.944594) (xy 350.349802 -262.978527) (xy 350.310979 -263.006734) (xy 350.268222 -263.02852)
			(xy 350.222583 -263.043348) (xy 350.175186 -263.050854) (xy 350.151192 -263.05129) (xy 350.127367 -263.050832)
			(xy 350.080294 -263.043427) (xy 350.034944 -263.028799) (xy 349.992418 -263.007302) (xy 349.953748 -262.979459)
			(xy 349.919873 -262.945946) (xy 349.891617 -262.907577) (xy 349.869665 -262.865283) (xy 349.854551 -262.820093)
			(xy 349.846642 -262.773103) (xy 349.845884 -262.749284) (xy 349.845884 -262.748776) (xy 349.845472 -262.741483)
			(xy 349.84109 -262.727556) (xy 349.837248 -262.721344) (xy 349.832809 -262.715199) (xy 349.821058 -262.705634)
			(xy 349.814134 -262.702548) (xy 349.72752 -262.667242) (xy 349.718104 -262.663949) (xy 349.698176 -262.664051)
			(xy 349.679775 -262.671701) (xy 349.672402 -262.678418) (xy 349.496888 -262.853932) (xy 349.493078 -262.86333)
			(xy 349.483471 -262.885213) (xy 349.458465 -262.925937) (xy 349.42742 -262.962268) (xy 349.391096 -262.993321)
			(xy 349.350378 -263.018338) (xy 349.328486 -263.027922) (xy 349.319088 -263.031732) (xy 349.181166 -263.169654)
			(xy 349.1738 -263.176766) (xy 349.16618 -263.195562) (xy 349.16618 -263.555988) (xy 349.375234 -263.555988)
			(xy 349.379194 -263.506934) (xy 349.390971 -263.45915) (xy 349.410262 -263.413874) (xy 349.436565 -263.372278)
			(xy 349.4692 -263.335441) (xy 349.507321 -263.304316) (xy 349.549942 -263.279709) (xy 349.595958 -263.262257)
			(xy 349.644177 -263.252413) (xy 349.693352 -263.250432) (xy 349.742207 -263.256364) (xy 349.789478 -263.270056)
			(xy 349.83394 -263.291154) (xy 349.874443 -263.31911) (xy 349.909936 -263.353202) (xy 349.939501 -263.392546)
			(xy 349.962372 -263.436123) (xy 349.977956 -263.482804) (xy 349.985851 -263.531381) (xy 349.986346 -263.555988)
			(xy 350.315288 -263.555988) (xy 350.319248 -263.506934) (xy 350.331025 -263.45915) (xy 350.350316 -263.413874)
			(xy 350.376619 -263.372278) (xy 350.409254 -263.335441) (xy 350.447375 -263.304316) (xy 350.489996 -263.279709)
			(xy 350.536012 -263.262257) (xy 350.584231 -263.252413) (xy 350.633406 -263.250432) (xy 350.682261 -263.256364)
			(xy 350.729532 -263.270056) (xy 350.773994 -263.291154) (xy 350.814497 -263.31911) (xy 350.84999 -263.353202)
			(xy 350.879555 -263.392546) (xy 350.902426 -263.436123) (xy 350.91801 -263.482804) (xy 350.925905 -263.531381)
			(xy 350.9264 -263.555988) (xy 350.925905 -263.580595) (xy 350.91801 -263.629172) (xy 350.902426 -263.675853)
			(xy 350.879555 -263.71943) (xy 350.84999 -263.758774) (xy 350.814497 -263.792866) (xy 350.773994 -263.820822)
			(xy 350.729532 -263.84192) (xy 350.714376 -263.84631) (xy 359.174291 -263.84631) (xy 359.178321 -263.793812)
			(xy 359.190318 -263.742544) (xy 359.210001 -263.693709) (xy 359.236907 -263.64845) (xy 359.270407 -263.607829)
			(xy 359.309715 -263.572798) (xy 359.35391 -263.544178) (xy 359.401955 -263.522639) (xy 359.452726 -263.508687)
			(xy 359.505031 -263.502649) (xy 359.557645 -263.504666) (xy 359.609335 -263.51469) (xy 359.658888 -263.532488)
			(xy 359.705144 -263.557641) (xy 359.747018 -263.58956) (xy 359.78353 -263.627498) (xy 359.813822 -263.670564)
			(xy 359.837185 -263.717749) (xy 359.853071 -263.767948) (xy 359.861108 -263.819984) (xy 359.861612 -263.84631)
			(xy 359.861108 -263.872636) (xy 359.853071 -263.924672) (xy 359.837185 -263.974871) (xy 359.813822 -264.022056)
			(xy 359.78353 -264.065122) (xy 359.747018 -264.10306) (xy 359.705144 -264.134979) (xy 359.658888 -264.160132)
			(xy 359.609335 -264.17793) (xy 359.557645 -264.187954) (xy 359.505031 -264.189971) (xy 359.452726 -264.183933)
			(xy 359.401955 -264.169981) (xy 359.35391 -264.148442) (xy 359.309715 -264.119822) (xy 359.270407 -264.084791)
			(xy 359.236907 -264.04417) (xy 359.210001 -263.998911) (xy 359.190318 -263.950076) (xy 359.178321 -263.898808)
			(xy 359.174291 -263.84631) (xy 350.714376 -263.84631) (xy 350.682261 -263.855612) (xy 350.633406 -263.861544)
			(xy 350.584231 -263.859563) (xy 350.536012 -263.849719) (xy 350.489996 -263.832267) (xy 350.447375 -263.80766)
			(xy 350.409254 -263.776535) (xy 350.376619 -263.739698) (xy 350.350316 -263.698102) (xy 350.331025 -263.652826)
			(xy 350.319248 -263.605042) (xy 350.315288 -263.555988) (xy 349.986346 -263.555988) (xy 349.985851 -263.580595)
			(xy 349.977956 -263.629172) (xy 349.962372 -263.675853) (xy 349.939501 -263.71943) (xy 349.909936 -263.758774)
			(xy 349.874443 -263.792866) (xy 349.83394 -263.820822) (xy 349.789478 -263.84192) (xy 349.742207 -263.855612)
			(xy 349.693352 -263.861544) (xy 349.644177 -263.859563) (xy 349.595958 -263.849719) (xy 349.549942 -263.832267)
			(xy 349.507321 -263.80766) (xy 349.4692 -263.776535) (xy 349.436565 -263.739698) (xy 349.410262 -263.698102)
			(xy 349.390971 -263.652826) (xy 349.379194 -263.605042) (xy 349.375234 -263.555988) (xy 349.16618 -263.555988)
			(xy 349.16618 -264.365994) (xy 349.845388 -264.365994) (xy 349.849348 -264.31694) (xy 349.861125 -264.269156)
			(xy 349.880416 -264.22388) (xy 349.906719 -264.182284) (xy 349.939354 -264.145447) (xy 349.977475 -264.114322)
			(xy 350.020096 -264.089715) (xy 350.066112 -264.072263) (xy 350.114331 -264.062419) (xy 350.163506 -264.060438)
			(xy 350.212361 -264.06637) (xy 350.259632 -264.080062) (xy 350.304094 -264.10116) (xy 350.344597 -264.129116)
			(xy 350.38009 -264.163208) (xy 350.409655 -264.202552) (xy 350.432526 -264.246129) (xy 350.44811 -264.29281)
			(xy 350.456005 -264.341387) (xy 350.4565 -264.365994) (xy 350.456459 -264.368026) (xy 351.722194 -264.368026)
			(xy 351.726154 -264.318972) (xy 351.737931 -264.271188) (xy 351.757222 -264.225912) (xy 351.783525 -264.184316)
			(xy 351.81616 -264.147479) (xy 351.854281 -264.116354) (xy 351.896902 -264.091747) (xy 351.942918 -264.074295)
			(xy 351.991137 -264.064451) (xy 352.040312 -264.06247) (xy 352.089167 -264.068402) (xy 352.136438 -264.082094)
			(xy 352.1809 -264.103192) (xy 352.221403 -264.131148) (xy 352.256896 -264.16524) (xy 352.286461 -264.204584)
			(xy 352.309332 -264.248161) (xy 352.324916 -264.294842) (xy 352.332811 -264.343419) (xy 352.333306 -264.368026)
			(xy 353.602302 -264.368026) (xy 353.606262 -264.318972) (xy 353.618039 -264.271188) (xy 353.63733 -264.225912)
			(xy 353.663633 -264.184316) (xy 353.696268 -264.147479) (xy 353.734389 -264.116354) (xy 353.77701 -264.091747)
			(xy 353.823026 -264.074295) (xy 353.871245 -264.064451) (xy 353.92042 -264.06247) (xy 353.969275 -264.068402)
			(xy 354.016546 -264.082094) (xy 354.061008 -264.103192) (xy 354.101511 -264.131148) (xy 354.137004 -264.16524)
			(xy 354.166569 -264.204584) (xy 354.18944 -264.248161) (xy 354.205024 -264.294842) (xy 354.212919 -264.343419)
			(xy 354.213414 -264.368026) (xy 355.482156 -264.368026) (xy 355.486116 -264.318972) (xy 355.497893 -264.271188)
			(xy 355.517184 -264.225912) (xy 355.543487 -264.184316) (xy 355.576122 -264.147479) (xy 355.614243 -264.116354)
			(xy 355.656864 -264.091747) (xy 355.70288 -264.074295) (xy 355.751099 -264.064451) (xy 355.800274 -264.06247)
			(xy 355.849129 -264.068402) (xy 355.8964 -264.082094) (xy 355.940862 -264.103192) (xy 355.981365 -264.131148)
			(xy 356.016858 -264.16524) (xy 356.046423 -264.204584) (xy 356.069294 -264.248161) (xy 356.084878 -264.294842)
			(xy 356.092773 -264.343419) (xy 356.093268 -264.368026) (xy 363.00208 -264.368026) (xy 363.00604 -264.318972)
			(xy 363.017817 -264.271188) (xy 363.037108 -264.225912) (xy 363.063411 -264.184316) (xy 363.096046 -264.147479)
			(xy 363.134167 -264.116354) (xy 363.176788 -264.091747) (xy 363.222804 -264.074295) (xy 363.271023 -264.064451)
			(xy 363.320198 -264.06247) (xy 363.369053 -264.068402) (xy 363.416324 -264.082094) (xy 363.460786 -264.103192)
			(xy 363.501289 -264.131148) (xy 363.536782 -264.16524) (xy 363.566347 -264.204584) (xy 363.589218 -264.248161)
			(xy 363.604802 -264.294842) (xy 363.612697 -264.343419) (xy 363.613192 -264.368026) (xy 364.882188 -264.368026)
			(xy 364.886148 -264.318972) (xy 364.897925 -264.271188) (xy 364.917216 -264.225912) (xy 364.943519 -264.184316)
			(xy 364.976154 -264.147479) (xy 365.014275 -264.116354) (xy 365.056896 -264.091747) (xy 365.102912 -264.074295)
			(xy 365.151131 -264.064451) (xy 365.200306 -264.06247) (xy 365.249161 -264.068402) (xy 365.296432 -264.082094)
			(xy 365.340894 -264.103192) (xy 365.381397 -264.131148) (xy 365.41689 -264.16524) (xy 365.446455 -264.204584)
			(xy 365.469326 -264.248161) (xy 365.48491 -264.294842) (xy 365.492805 -264.343419) (xy 365.4933 -264.368026)
			(xy 366.762042 -264.368026) (xy 366.766002 -264.318972) (xy 366.777779 -264.271188) (xy 366.79707 -264.225912)
			(xy 366.823373 -264.184316) (xy 366.856008 -264.147479) (xy 366.894129 -264.116354) (xy 366.93675 -264.091747)
			(xy 366.982766 -264.074295) (xy 367.030985 -264.064451) (xy 367.08016 -264.06247) (xy 367.129015 -264.068402)
			(xy 367.176286 -264.082094) (xy 367.220748 -264.103192) (xy 367.261251 -264.131148) (xy 367.296744 -264.16524)
			(xy 367.326309 -264.204584) (xy 367.34918 -264.248161) (xy 367.364764 -264.294842) (xy 367.372659 -264.343419)
			(xy 367.373154 -264.368026) (xy 368.639864 -264.368026) (xy 368.643824 -264.318972) (xy 368.655601 -264.271188)
			(xy 368.674892 -264.225912) (xy 368.701195 -264.184316) (xy 368.73383 -264.147479) (xy 368.771951 -264.116354)
			(xy 368.814572 -264.091747) (xy 368.860588 -264.074295) (xy 368.908807 -264.064451) (xy 368.957982 -264.06247)
			(xy 369.006837 -264.068402) (xy 369.054108 -264.082094) (xy 369.09857 -264.103192) (xy 369.139073 -264.131148)
			(xy 369.174566 -264.16524) (xy 369.204131 -264.204584) (xy 369.227002 -264.248161) (xy 369.242586 -264.294842)
			(xy 369.250481 -264.343419) (xy 369.250935 -264.365994) (xy 370.518956 -264.365994) (xy 370.522916 -264.31694)
			(xy 370.534693 -264.269156) (xy 370.553984 -264.22388) (xy 370.580287 -264.182284) (xy 370.612922 -264.145447)
			(xy 370.651043 -264.114322) (xy 370.693664 -264.089715) (xy 370.73968 -264.072263) (xy 370.787899 -264.062419)
			(xy 370.837074 -264.060438) (xy 370.885929 -264.06637) (xy 370.9332 -264.080062) (xy 370.977662 -264.10116)
			(xy 371.018165 -264.129116) (xy 371.053658 -264.163208) (xy 371.083223 -264.202552) (xy 371.106094 -264.246129)
			(xy 371.121678 -264.29281) (xy 371.129573 -264.341387) (xy 371.130068 -264.365994) (xy 372.399064 -264.365994)
			(xy 372.403024 -264.31694) (xy 372.414801 -264.269156) (xy 372.434092 -264.22388) (xy 372.460395 -264.182284)
			(xy 372.49303 -264.145447) (xy 372.531151 -264.114322) (xy 372.573772 -264.089715) (xy 372.619788 -264.072263)
			(xy 372.668007 -264.062419) (xy 372.717182 -264.060438) (xy 372.766037 -264.06637) (xy 372.813308 -264.080062)
			(xy 372.85777 -264.10116) (xy 372.898273 -264.129116) (xy 372.933766 -264.163208) (xy 372.963331 -264.202552)
			(xy 372.986202 -264.246129) (xy 373.001786 -264.29281) (xy 373.009681 -264.341387) (xy 373.010176 -264.365994)
			(xy 374.278918 -264.365994) (xy 374.282878 -264.31694) (xy 374.294655 -264.269156) (xy 374.313946 -264.22388)
			(xy 374.340249 -264.182284) (xy 374.372884 -264.145447) (xy 374.411005 -264.114322) (xy 374.453626 -264.089715)
			(xy 374.499642 -264.072263) (xy 374.547861 -264.062419) (xy 374.597036 -264.060438) (xy 374.645891 -264.06637)
			(xy 374.693162 -264.080062) (xy 374.737624 -264.10116) (xy 374.778127 -264.129116) (xy 374.81362 -264.163208)
			(xy 374.843185 -264.202552) (xy 374.866056 -264.246129) (xy 374.88164 -264.29281) (xy 374.889535 -264.341387)
			(xy 374.89003 -264.365994) (xy 376.148595 -264.365994) (xy 376.15269 -264.315266) (xy 376.164869 -264.265852)
			(xy 376.184817 -264.219032) (xy 376.212018 -264.176018) (xy 376.245766 -264.137924) (xy 376.285188 -264.105737)
			(xy 376.329262 -264.080291) (xy 376.376848 -264.062244) (xy 376.426712 -264.052064) (xy 376.477564 -264.050015)
			(xy 376.528085 -264.056149) (xy 376.576969 -264.070309) (xy 376.622948 -264.092126) (xy 376.664832 -264.121036)
			(xy 376.701536 -264.156291) (xy 376.732109 -264.196977) (xy 376.75576 -264.24204) (xy 376.771876 -264.290314)
			(xy 376.78004 -264.340548) (xy 376.780552 -264.365994) (xy 377.088649 -264.365994) (xy 377.092744 -264.315266)
			(xy 377.104923 -264.265852) (xy 377.124871 -264.219032) (xy 377.152072 -264.176018) (xy 377.18582 -264.137924)
			(xy 377.225242 -264.105737) (xy 377.269316 -264.080291) (xy 377.316902 -264.062244) (xy 377.366766 -264.052064)
			(xy 377.417618 -264.050015) (xy 377.468139 -264.056149) (xy 377.517023 -264.070309) (xy 377.563002 -264.092126)
			(xy 377.604886 -264.121036) (xy 377.64159 -264.156291) (xy 377.672163 -264.196977) (xy 377.695814 -264.24204)
			(xy 377.71193 -264.290314) (xy 377.720094 -264.340548) (xy 377.720606 -264.365994) (xy 378.039134 -264.365994)
			(xy 378.043094 -264.31694) (xy 378.054871 -264.269156) (xy 378.074162 -264.22388) (xy 378.100465 -264.182284)
			(xy 378.1331 -264.145447) (xy 378.171221 -264.114322) (xy 378.213842 -264.089715) (xy 378.259858 -264.072263)
			(xy 378.308077 -264.062419) (xy 378.357252 -264.060438) (xy 378.406107 -264.06637) (xy 378.453378 -264.080062)
			(xy 378.49784 -264.10116) (xy 378.538343 -264.129116) (xy 378.573836 -264.163208) (xy 378.603401 -264.202552)
			(xy 378.626272 -264.246129) (xy 378.641856 -264.29281) (xy 378.649751 -264.341387) (xy 378.650246 -264.365994)
			(xy 378.968503 -264.365994) (xy 378.972598 -264.315266) (xy 378.984777 -264.265852) (xy 379.004725 -264.219032)
			(xy 379.031926 -264.176018) (xy 379.065674 -264.137924) (xy 379.105096 -264.105737) (xy 379.14917 -264.080291)
			(xy 379.196756 -264.062244) (xy 379.24662 -264.052064) (xy 379.297472 -264.050015) (xy 379.347993 -264.056149)
			(xy 379.396877 -264.070309) (xy 379.442856 -264.092126) (xy 379.48474 -264.121036) (xy 379.521444 -264.156291)
			(xy 379.552017 -264.196977) (xy 379.575668 -264.24204) (xy 379.591784 -264.290314) (xy 379.599948 -264.340548)
			(xy 379.60046 -264.365994) (xy 379.918988 -264.365994) (xy 379.922948 -264.31694) (xy 379.934725 -264.269156)
			(xy 379.954016 -264.22388) (xy 379.980319 -264.182284) (xy 380.012954 -264.145447) (xy 380.051075 -264.114322)
			(xy 380.093696 -264.089715) (xy 380.139712 -264.072263) (xy 380.187931 -264.062419) (xy 380.237106 -264.060438)
			(xy 380.285961 -264.06637) (xy 380.333232 -264.080062) (xy 380.377694 -264.10116) (xy 380.418197 -264.129116)
			(xy 380.45369 -264.163208) (xy 380.483255 -264.202552) (xy 380.506126 -264.246129) (xy 380.52171 -264.29281)
			(xy 380.529605 -264.341387) (xy 380.5301 -264.365994) (xy 380.848611 -264.365994) (xy 380.852706 -264.315266)
			(xy 380.864885 -264.265852) (xy 380.884833 -264.219032) (xy 380.912034 -264.176018) (xy 380.945782 -264.137924)
			(xy 380.985204 -264.105737) (xy 381.029278 -264.080291) (xy 381.076864 -264.062244) (xy 381.126728 -264.052064)
			(xy 381.17758 -264.050015) (xy 381.228101 -264.056149) (xy 381.276985 -264.070309) (xy 381.322964 -264.092126)
			(xy 381.364848 -264.121036) (xy 381.401552 -264.156291) (xy 381.432125 -264.196977) (xy 381.455776 -264.24204)
			(xy 381.471892 -264.290314) (xy 381.480056 -264.340548) (xy 381.480568 -264.365994) (xy 381.799096 -264.365994)
			(xy 381.803056 -264.31694) (xy 381.814833 -264.269156) (xy 381.834124 -264.22388) (xy 381.860427 -264.182284)
			(xy 381.893062 -264.145447) (xy 381.931183 -264.114322) (xy 381.973804 -264.089715) (xy 382.01982 -264.072263)
			(xy 382.068039 -264.062419) (xy 382.117214 -264.060438) (xy 382.166069 -264.06637) (xy 382.21334 -264.080062)
			(xy 382.257802 -264.10116) (xy 382.298305 -264.129116) (xy 382.333798 -264.163208) (xy 382.363363 -264.202552)
			(xy 382.386234 -264.246129) (xy 382.401818 -264.29281) (xy 382.409713 -264.341387) (xy 382.410208 -264.365994)
			(xy 382.728465 -264.365994) (xy 382.73256 -264.315266) (xy 382.744739 -264.265852) (xy 382.764687 -264.219032)
			(xy 382.791888 -264.176018) (xy 382.825636 -264.137924) (xy 382.865058 -264.105737) (xy 382.909132 -264.080291)
			(xy 382.956718 -264.062244) (xy 383.006582 -264.052064) (xy 383.057434 -264.050015) (xy 383.107955 -264.056149)
			(xy 383.156839 -264.070309) (xy 383.202818 -264.092126) (xy 383.244702 -264.121036) (xy 383.281406 -264.156291)
			(xy 383.311979 -264.196977) (xy 383.33563 -264.24204) (xy 383.351746 -264.290314) (xy 383.35991 -264.340548)
			(xy 383.360422 -264.365994) (xy 383.668519 -264.365994) (xy 383.672614 -264.315266) (xy 383.684793 -264.265852)
			(xy 383.704741 -264.219032) (xy 383.731942 -264.176018) (xy 383.76569 -264.137924) (xy 383.805112 -264.105737)
			(xy 383.849186 -264.080291) (xy 383.896772 -264.062244) (xy 383.946636 -264.052064) (xy 383.997488 -264.050015)
			(xy 384.048009 -264.056149) (xy 384.096893 -264.070309) (xy 384.142872 -264.092126) (xy 384.184756 -264.121036)
			(xy 384.22146 -264.156291) (xy 384.252033 -264.196977) (xy 384.275684 -264.24204) (xy 384.2918 -264.290314)
			(xy 384.299964 -264.340548) (xy 384.300476 -264.365994) (xy 384.299964 -264.39144) (xy 384.2918 -264.441674)
			(xy 384.275684 -264.489948) (xy 384.252033 -264.535011) (xy 384.22146 -264.575697) (xy 384.184756 -264.610952)
			(xy 384.142872 -264.639862) (xy 384.096893 -264.661679) (xy 384.048009 -264.675839) (xy 383.997488 -264.681973)
			(xy 383.946636 -264.679924) (xy 383.896772 -264.669744) (xy 383.849186 -264.651697) (xy 383.805112 -264.626251)
			(xy 383.76569 -264.594064) (xy 383.731942 -264.55597) (xy 383.704741 -264.512956) (xy 383.684793 -264.466136)
			(xy 383.672614 -264.416722) (xy 383.668519 -264.365994) (xy 383.360422 -264.365994) (xy 383.35991 -264.39144)
			(xy 383.351746 -264.441674) (xy 383.33563 -264.489948) (xy 383.311979 -264.535011) (xy 383.281406 -264.575697)
			(xy 383.244702 -264.610952) (xy 383.202818 -264.639862) (xy 383.156839 -264.661679) (xy 383.107955 -264.675839)
			(xy 383.057434 -264.681973) (xy 383.006582 -264.679924) (xy 382.956718 -264.669744) (xy 382.909132 -264.651697)
			(xy 382.865058 -264.626251) (xy 382.825636 -264.594064) (xy 382.791888 -264.55597) (xy 382.764687 -264.512956)
			(xy 382.744739 -264.466136) (xy 382.73256 -264.416722) (xy 382.728465 -264.365994) (xy 382.410208 -264.365994)
			(xy 382.409713 -264.390601) (xy 382.401818 -264.439178) (xy 382.386234 -264.485859) (xy 382.363363 -264.529436)
			(xy 382.333798 -264.56878) (xy 382.298305 -264.602872) (xy 382.257802 -264.630828) (xy 382.21334 -264.651926)
			(xy 382.166069 -264.665618) (xy 382.117214 -264.67155) (xy 382.068039 -264.669569) (xy 382.01982 -264.659725)
			(xy 381.973804 -264.642273) (xy 381.931183 -264.617666) (xy 381.893062 -264.586541) (xy 381.860427 -264.549704)
			(xy 381.834124 -264.508108) (xy 381.814833 -264.462832) (xy 381.803056 -264.415048) (xy 381.799096 -264.365994)
			(xy 381.480568 -264.365994) (xy 381.480056 -264.39144) (xy 381.471892 -264.441674) (xy 381.455776 -264.489948)
			(xy 381.432125 -264.535011) (xy 381.401552 -264.575697) (xy 381.364848 -264.610952) (xy 381.322964 -264.639862)
			(xy 381.276985 -264.661679) (xy 381.228101 -264.675839) (xy 381.17758 -264.681973) (xy 381.126728 -264.679924)
			(xy 381.076864 -264.669744) (xy 381.029278 -264.651697) (xy 380.985204 -264.626251) (xy 380.945782 -264.594064)
			(xy 380.912034 -264.55597) (xy 380.884833 -264.512956) (xy 380.864885 -264.466136) (xy 380.852706 -264.416722)
			(xy 380.848611 -264.365994) (xy 380.5301 -264.365994) (xy 380.529605 -264.390601) (xy 380.52171 -264.439178)
			(xy 380.506126 -264.485859) (xy 380.483255 -264.529436) (xy 380.45369 -264.56878) (xy 380.418197 -264.602872)
			(xy 380.377694 -264.630828) (xy 380.333232 -264.651926) (xy 380.285961 -264.665618) (xy 380.237106 -264.67155)
			(xy 380.187931 -264.669569) (xy 380.139712 -264.659725) (xy 380.093696 -264.642273) (xy 380.051075 -264.617666)
			(xy 380.012954 -264.586541) (xy 379.980319 -264.549704) (xy 379.954016 -264.508108) (xy 379.934725 -264.462832)
			(xy 379.922948 -264.415048) (xy 379.918988 -264.365994) (xy 379.60046 -264.365994) (xy 379.599948 -264.39144)
			(xy 379.591784 -264.441674) (xy 379.575668 -264.489948) (xy 379.552017 -264.535011) (xy 379.521444 -264.575697)
			(xy 379.48474 -264.610952) (xy 379.442856 -264.639862) (xy 379.396877 -264.661679) (xy 379.347993 -264.675839)
			(xy 379.297472 -264.681973) (xy 379.24662 -264.679924) (xy 379.196756 -264.669744) (xy 379.14917 -264.651697)
			(xy 379.105096 -264.626251) (xy 379.065674 -264.594064) (xy 379.031926 -264.55597) (xy 379.004725 -264.512956)
			(xy 378.984777 -264.466136) (xy 378.972598 -264.416722) (xy 378.968503 -264.365994) (xy 378.650246 -264.365994)
			(xy 378.649751 -264.390601) (xy 378.641856 -264.439178) (xy 378.626272 -264.485859) (xy 378.603401 -264.529436)
			(xy 378.573836 -264.56878) (xy 378.538343 -264.602872) (xy 378.49784 -264.630828) (xy 378.453378 -264.651926)
			(xy 378.406107 -264.665618) (xy 378.357252 -264.67155) (xy 378.308077 -264.669569) (xy 378.259858 -264.659725)
			(xy 378.213842 -264.642273) (xy 378.171221 -264.617666) (xy 378.1331 -264.586541) (xy 378.100465 -264.549704)
			(xy 378.074162 -264.508108) (xy 378.054871 -264.462832) (xy 378.043094 -264.415048) (xy 378.039134 -264.365994)
			(xy 377.720606 -264.365994) (xy 377.720094 -264.39144) (xy 377.71193 -264.441674) (xy 377.695814 -264.489948)
			(xy 377.672163 -264.535011) (xy 377.64159 -264.575697) (xy 377.604886 -264.610952) (xy 377.563002 -264.639862)
			(xy 377.517023 -264.661679) (xy 377.468139 -264.675839) (xy 377.417618 -264.681973) (xy 377.366766 -264.679924)
			(xy 377.316902 -264.669744) (xy 377.269316 -264.651697) (xy 377.225242 -264.626251) (xy 377.18582 -264.594064)
			(xy 377.152072 -264.55597) (xy 377.124871 -264.512956) (xy 377.104923 -264.466136) (xy 377.092744 -264.416722)
			(xy 377.088649 -264.365994) (xy 376.780552 -264.365994) (xy 376.78004 -264.39144) (xy 376.771876 -264.441674)
			(xy 376.75576 -264.489948) (xy 376.732109 -264.535011) (xy 376.701536 -264.575697) (xy 376.664832 -264.610952)
			(xy 376.622948 -264.639862) (xy 376.576969 -264.661679) (xy 376.528085 -264.675839) (xy 376.477564 -264.681973)
			(xy 376.426712 -264.679924) (xy 376.376848 -264.669744) (xy 376.329262 -264.651697) (xy 376.285188 -264.626251)
			(xy 376.245766 -264.594064) (xy 376.212018 -264.55597) (xy 376.184817 -264.512956) (xy 376.164869 -264.466136)
			(xy 376.15269 -264.416722) (xy 376.148595 -264.365994) (xy 374.89003 -264.365994) (xy 374.889535 -264.390601)
			(xy 374.88164 -264.439178) (xy 374.866056 -264.485859) (xy 374.843185 -264.529436) (xy 374.81362 -264.56878)
			(xy 374.778127 -264.602872) (xy 374.737624 -264.630828) (xy 374.693162 -264.651926) (xy 374.645891 -264.665618)
			(xy 374.597036 -264.67155) (xy 374.547861 -264.669569) (xy 374.499642 -264.659725) (xy 374.453626 -264.642273)
			(xy 374.411005 -264.617666) (xy 374.372884 -264.586541) (xy 374.340249 -264.549704) (xy 374.313946 -264.508108)
			(xy 374.294655 -264.462832) (xy 374.282878 -264.415048) (xy 374.278918 -264.365994) (xy 373.010176 -264.365994)
			(xy 373.009681 -264.390601) (xy 373.001786 -264.439178) (xy 372.986202 -264.485859) (xy 372.963331 -264.529436)
			(xy 372.933766 -264.56878) (xy 372.898273 -264.602872) (xy 372.85777 -264.630828) (xy 372.813308 -264.651926)
			(xy 372.766037 -264.665618) (xy 372.717182 -264.67155) (xy 372.668007 -264.669569) (xy 372.619788 -264.659725)
			(xy 372.573772 -264.642273) (xy 372.531151 -264.617666) (xy 372.49303 -264.586541) (xy 372.460395 -264.549704)
			(xy 372.434092 -264.508108) (xy 372.414801 -264.462832) (xy 372.403024 -264.415048) (xy 372.399064 -264.365994)
			(xy 371.130068 -264.365994) (xy 371.129573 -264.390601) (xy 371.121678 -264.439178) (xy 371.106094 -264.485859)
			(xy 371.083223 -264.529436) (xy 371.053658 -264.56878) (xy 371.018165 -264.602872) (xy 370.977662 -264.630828)
			(xy 370.9332 -264.651926) (xy 370.885929 -264.665618) (xy 370.837074 -264.67155) (xy 370.787899 -264.669569)
			(xy 370.73968 -264.659725) (xy 370.693664 -264.642273) (xy 370.651043 -264.617666) (xy 370.612922 -264.586541)
			(xy 370.580287 -264.549704) (xy 370.553984 -264.508108) (xy 370.534693 -264.462832) (xy 370.522916 -264.415048)
			(xy 370.518956 -264.365994) (xy 369.250935 -264.365994) (xy 369.250976 -264.368026) (xy 369.250481 -264.392633)
			(xy 369.242586 -264.44121) (xy 369.227002 -264.487891) (xy 369.204131 -264.531468) (xy 369.174566 -264.570812)
			(xy 369.139073 -264.604904) (xy 369.09857 -264.63286) (xy 369.054108 -264.653958) (xy 369.006837 -264.66765)
			(xy 368.957982 -264.673582) (xy 368.908807 -264.671601) (xy 368.860588 -264.661757) (xy 368.814572 -264.644305)
			(xy 368.771951 -264.619698) (xy 368.73383 -264.588573) (xy 368.701195 -264.551736) (xy 368.674892 -264.51014)
			(xy 368.655601 -264.464864) (xy 368.643824 -264.41708) (xy 368.639864 -264.368026) (xy 367.373154 -264.368026)
			(xy 367.372659 -264.392633) (xy 367.364764 -264.44121) (xy 367.34918 -264.487891) (xy 367.326309 -264.531468)
			(xy 367.296744 -264.570812) (xy 367.261251 -264.604904) (xy 367.220748 -264.63286) (xy 367.176286 -264.653958)
			(xy 367.129015 -264.66765) (xy 367.08016 -264.673582) (xy 367.030985 -264.671601) (xy 366.982766 -264.661757)
			(xy 366.93675 -264.644305) (xy 366.894129 -264.619698) (xy 366.856008 -264.588573) (xy 366.823373 -264.551736)
			(xy 366.79707 -264.51014) (xy 366.777779 -264.464864) (xy 366.766002 -264.41708) (xy 366.762042 -264.368026)
			(xy 365.4933 -264.368026) (xy 365.492805 -264.392633) (xy 365.48491 -264.44121) (xy 365.469326 -264.487891)
			(xy 365.446455 -264.531468) (xy 365.41689 -264.570812) (xy 365.381397 -264.604904) (xy 365.340894 -264.63286)
			(xy 365.296432 -264.653958) (xy 365.249161 -264.66765) (xy 365.200306 -264.673582) (xy 365.151131 -264.671601)
			(xy 365.102912 -264.661757) (xy 365.056896 -264.644305) (xy 365.014275 -264.619698) (xy 364.976154 -264.588573)
			(xy 364.943519 -264.551736) (xy 364.917216 -264.51014) (xy 364.897925 -264.464864) (xy 364.886148 -264.41708)
			(xy 364.882188 -264.368026) (xy 363.613192 -264.368026) (xy 363.612697 -264.392633) (xy 363.604802 -264.44121)
			(xy 363.589218 -264.487891) (xy 363.566347 -264.531468) (xy 363.536782 -264.570812) (xy 363.501289 -264.604904)
			(xy 363.460786 -264.63286) (xy 363.416324 -264.653958) (xy 363.369053 -264.66765) (xy 363.320198 -264.673582)
			(xy 363.271023 -264.671601) (xy 363.222804 -264.661757) (xy 363.176788 -264.644305) (xy 363.134167 -264.619698)
			(xy 363.096046 -264.588573) (xy 363.063411 -264.551736) (xy 363.037108 -264.51014) (xy 363.017817 -264.464864)
			(xy 363.00604 -264.41708) (xy 363.00208 -264.368026) (xy 356.093268 -264.368026) (xy 356.092773 -264.392633)
			(xy 356.084878 -264.44121) (xy 356.069294 -264.487891) (xy 356.046423 -264.531468) (xy 356.016858 -264.570812)
			(xy 355.981365 -264.604904) (xy 355.940862 -264.63286) (xy 355.8964 -264.653958) (xy 355.849129 -264.66765)
			(xy 355.800274 -264.673582) (xy 355.751099 -264.671601) (xy 355.70288 -264.661757) (xy 355.656864 -264.644305)
			(xy 355.614243 -264.619698) (xy 355.576122 -264.588573) (xy 355.543487 -264.551736) (xy 355.517184 -264.51014)
			(xy 355.497893 -264.464864) (xy 355.486116 -264.41708) (xy 355.482156 -264.368026) (xy 354.213414 -264.368026)
			(xy 354.212919 -264.392633) (xy 354.205024 -264.44121) (xy 354.18944 -264.487891) (xy 354.166569 -264.531468)
			(xy 354.137004 -264.570812) (xy 354.101511 -264.604904) (xy 354.061008 -264.63286) (xy 354.016546 -264.653958)
			(xy 353.969275 -264.66765) (xy 353.92042 -264.673582) (xy 353.871245 -264.671601) (xy 353.823026 -264.661757)
			(xy 353.77701 -264.644305) (xy 353.734389 -264.619698) (xy 353.696268 -264.588573) (xy 353.663633 -264.551736)
			(xy 353.63733 -264.51014) (xy 353.618039 -264.464864) (xy 353.606262 -264.41708) (xy 353.602302 -264.368026)
			(xy 352.333306 -264.368026) (xy 352.332811 -264.392633) (xy 352.324916 -264.44121) (xy 352.309332 -264.487891)
			(xy 352.286461 -264.531468) (xy 352.256896 -264.570812) (xy 352.221403 -264.604904) (xy 352.1809 -264.63286)
			(xy 352.136438 -264.653958) (xy 352.089167 -264.66765) (xy 352.040312 -264.673582) (xy 351.991137 -264.671601)
			(xy 351.942918 -264.661757) (xy 351.896902 -264.644305) (xy 351.854281 -264.619698) (xy 351.81616 -264.588573)
			(xy 351.783525 -264.551736) (xy 351.757222 -264.51014) (xy 351.737931 -264.464864) (xy 351.726154 -264.41708)
			(xy 351.722194 -264.368026) (xy 350.456459 -264.368026) (xy 350.456005 -264.390601) (xy 350.44811 -264.439178)
			(xy 350.432526 -264.485859) (xy 350.409655 -264.529436) (xy 350.38009 -264.56878) (xy 350.344597 -264.602872)
			(xy 350.304094 -264.630828) (xy 350.259632 -264.651926) (xy 350.212361 -264.665618) (xy 350.163506 -264.67155)
			(xy 350.114331 -264.669569) (xy 350.066112 -264.659725) (xy 350.020096 -264.642273) (xy 349.977475 -264.617666)
			(xy 349.939354 -264.586541) (xy 349.906719 -264.549704) (xy 349.880416 -264.508108) (xy 349.861125 -264.462832)
			(xy 349.849348 -264.415048) (xy 349.845388 -264.365994) (xy 349.16618 -264.365994) (xy 349.16618 -264.86231)
			(xy 359.174291 -264.86231) (xy 359.178321 -264.809812) (xy 359.190318 -264.758544) (xy 359.210001 -264.709709)
			(xy 359.236907 -264.66445) (xy 359.270407 -264.623829) (xy 359.309715 -264.588798) (xy 359.35391 -264.560178)
			(xy 359.401955 -264.538639) (xy 359.452726 -264.524687) (xy 359.505031 -264.518649) (xy 359.557645 -264.520666)
			(xy 359.609335 -264.53069) (xy 359.658888 -264.548488) (xy 359.705144 -264.573641) (xy 359.747018 -264.60556)
			(xy 359.78353 -264.643498) (xy 359.813822 -264.686564) (xy 359.837185 -264.733749) (xy 359.853071 -264.783948)
			(xy 359.861108 -264.835984) (xy 359.861612 -264.86231) (xy 359.861108 -264.888636) (xy 359.853071 -264.940672)
			(xy 359.837185 -264.990871) (xy 359.813822 -265.038056) (xy 359.78353 -265.081122) (xy 359.747018 -265.11906)
			(xy 359.705144 -265.150979) (xy 359.659131 -265.176) (xy 369.109002 -265.176) (xy 369.112962 -265.126946)
			(xy 369.124739 -265.079162) (xy 369.14403 -265.033886) (xy 369.170333 -264.99229) (xy 369.202968 -264.955453)
			(xy 369.241089 -264.924328) (xy 369.28371 -264.899721) (xy 369.329726 -264.882269) (xy 369.377945 -264.872425)
			(xy 369.42712 -264.870444) (xy 369.475975 -264.876376) (xy 369.523246 -264.890068) (xy 369.567708 -264.911166)
			(xy 369.608211 -264.939122) (xy 369.643704 -264.973214) (xy 369.673269 -265.012558) (xy 369.69614 -265.056135)
			(xy 369.711724 -265.102816) (xy 369.719619 -265.151393) (xy 369.720114 -265.176) (xy 370.98911 -265.176)
			(xy 370.99307 -265.126946) (xy 371.004847 -265.079162) (xy 371.024138 -265.033886) (xy 371.050441 -264.99229)
			(xy 371.083076 -264.955453) (xy 371.121197 -264.924328) (xy 371.163818 -264.899721) (xy 371.209834 -264.882269)
			(xy 371.258053 -264.872425) (xy 371.307228 -264.870444) (xy 371.356083 -264.876376) (xy 371.403354 -264.890068)
			(xy 371.447816 -264.911166) (xy 371.488319 -264.939122) (xy 371.523812 -264.973214) (xy 371.553377 -265.012558)
			(xy 371.576248 -265.056135) (xy 371.591832 -265.102816) (xy 371.599727 -265.151393) (xy 371.600222 -265.176)
			(xy 372.868964 -265.176) (xy 372.872924 -265.126946) (xy 372.884701 -265.079162) (xy 372.903992 -265.033886)
			(xy 372.930295 -264.99229) (xy 372.96293 -264.955453) (xy 373.001051 -264.924328) (xy 373.043672 -264.899721)
			(xy 373.089688 -264.882269) (xy 373.137907 -264.872425) (xy 373.187082 -264.870444) (xy 373.235937 -264.876376)
			(xy 373.283208 -264.890068) (xy 373.32767 -264.911166) (xy 373.368173 -264.939122) (xy 373.403666 -264.973214)
			(xy 373.433231 -265.012558) (xy 373.456102 -265.056135) (xy 373.471686 -265.102816) (xy 373.479581 -265.151393)
			(xy 373.480076 -265.176) (xy 374.749072 -265.176) (xy 374.753032 -265.126946) (xy 374.764809 -265.079162)
			(xy 374.7841 -265.033886) (xy 374.810403 -264.99229) (xy 374.843038 -264.955453) (xy 374.881159 -264.924328)
			(xy 374.92378 -264.899721) (xy 374.969796 -264.882269) (xy 375.018015 -264.872425) (xy 375.06719 -264.870444)
			(xy 375.116045 -264.876376) (xy 375.163316 -264.890068) (xy 375.207778 -264.911166) (xy 375.248281 -264.939122)
			(xy 375.283774 -264.973214) (xy 375.313339 -265.012558) (xy 375.33621 -265.056135) (xy 375.351794 -265.102816)
			(xy 375.359689 -265.151393) (xy 375.360184 -265.176) (xy 375.678695 -265.176) (xy 375.68279 -265.125272)
			(xy 375.694969 -265.075858) (xy 375.714917 -265.029038) (xy 375.742118 -264.986024) (xy 375.775866 -264.94793)
			(xy 375.815288 -264.915743) (xy 375.859362 -264.890297) (xy 375.906948 -264.87225) (xy 375.956812 -264.86207)
			(xy 376.007664 -264.860021) (xy 376.058185 -264.866155) (xy 376.107069 -264.880315) (xy 376.153048 -264.902132)
			(xy 376.194932 -264.931042) (xy 376.231636 -264.966297) (xy 376.262209 -265.006983) (xy 376.28586 -265.052046)
			(xy 376.301976 -265.10032) (xy 376.31014 -265.150554) (xy 376.310652 -265.176) (xy 376.628926 -265.176)
			(xy 376.632886 -265.126946) (xy 376.644663 -265.079162) (xy 376.663954 -265.033886) (xy 376.690257 -264.99229)
			(xy 376.722892 -264.955453) (xy 376.761013 -264.924328) (xy 376.803634 -264.899721) (xy 376.84965 -264.882269)
			(xy 376.897869 -264.872425) (xy 376.947044 -264.870444) (xy 376.995899 -264.876376) (xy 377.04317 -264.890068)
			(xy 377.087632 -264.911166) (xy 377.128135 -264.939122) (xy 377.163628 -264.973214) (xy 377.193193 -265.012558)
			(xy 377.216064 -265.056135) (xy 377.231648 -265.102816) (xy 377.239543 -265.151393) (xy 377.240038 -265.176)
			(xy 377.56898 -265.176) (xy 377.57294 -265.126946) (xy 377.584717 -265.079162) (xy 377.604008 -265.033886)
			(xy 377.630311 -264.99229) (xy 377.662946 -264.955453) (xy 377.701067 -264.924328) (xy 377.743688 -264.899721)
			(xy 377.789704 -264.882269) (xy 377.837923 -264.872425) (xy 377.887098 -264.870444) (xy 377.935953 -264.876376)
			(xy 377.983224 -264.890068) (xy 378.027686 -264.911166) (xy 378.068189 -264.939122) (xy 378.103682 -264.973214)
			(xy 378.133247 -265.012558) (xy 378.156118 -265.056135) (xy 378.171702 -265.102816) (xy 378.179597 -265.151393)
			(xy 378.180092 -265.176) (xy 378.509034 -265.176) (xy 378.512994 -265.126946) (xy 378.524771 -265.079162)
			(xy 378.544062 -265.033886) (xy 378.570365 -264.99229) (xy 378.603 -264.955453) (xy 378.641121 -264.924328)
			(xy 378.683742 -264.899721) (xy 378.729758 -264.882269) (xy 378.777977 -264.872425) (xy 378.827152 -264.870444)
			(xy 378.876007 -264.876376) (xy 378.923278 -264.890068) (xy 378.96774 -264.911166) (xy 379.008243 -264.939122)
			(xy 379.043736 -264.973214) (xy 379.073301 -265.012558) (xy 379.096172 -265.056135) (xy 379.111756 -265.102816)
			(xy 379.119651 -265.151393) (xy 379.120146 -265.176) (xy 379.438657 -265.176) (xy 379.442752 -265.125272)
			(xy 379.454931 -265.075858) (xy 379.474879 -265.029038) (xy 379.50208 -264.986024) (xy 379.535828 -264.94793)
			(xy 379.57525 -264.915743) (xy 379.619324 -264.890297) (xy 379.66691 -264.87225) (xy 379.716774 -264.86207)
			(xy 379.767626 -264.860021) (xy 379.818147 -264.866155) (xy 379.867031 -264.880315) (xy 379.91301 -264.902132)
			(xy 379.954894 -264.931042) (xy 379.991598 -264.966297) (xy 380.022171 -265.006983) (xy 380.045822 -265.052046)
			(xy 380.061938 -265.10032) (xy 380.070102 -265.150554) (xy 380.070614 -265.176) (xy 380.388888 -265.176)
			(xy 380.392848 -265.126946) (xy 380.404625 -265.079162) (xy 380.423916 -265.033886) (xy 380.450219 -264.99229)
			(xy 380.482854 -264.955453) (xy 380.520975 -264.924328) (xy 380.563596 -264.899721) (xy 380.609612 -264.882269)
			(xy 380.657831 -264.872425) (xy 380.707006 -264.870444) (xy 380.755861 -264.876376) (xy 380.803132 -264.890068)
			(xy 380.847594 -264.911166) (xy 380.888097 -264.939122) (xy 380.92359 -264.973214) (xy 380.953155 -265.012558)
			(xy 380.976026 -265.056135) (xy 380.99161 -265.102816) (xy 380.999505 -265.151393) (xy 381 -265.176)
			(xy 381.328942 -265.176) (xy 381.332902 -265.126946) (xy 381.344679 -265.079162) (xy 381.36397 -265.033886)
			(xy 381.390273 -264.99229) (xy 381.422908 -264.955453) (xy 381.461029 -264.924328) (xy 381.50365 -264.899721)
			(xy 381.549666 -264.882269) (xy 381.597885 -264.872425) (xy 381.64706 -264.870444) (xy 381.695915 -264.876376)
			(xy 381.743186 -264.890068) (xy 381.787648 -264.911166) (xy 381.828151 -264.939122) (xy 381.863644 -264.973214)
			(xy 381.893209 -265.012558) (xy 381.91608 -265.056135) (xy 381.931664 -265.102816) (xy 381.939559 -265.151393)
			(xy 381.940054 -265.176) (xy 382.258565 -265.176) (xy 382.26266 -265.125272) (xy 382.274839 -265.075858)
			(xy 382.294787 -265.029038) (xy 382.321988 -264.986024) (xy 382.355736 -264.94793) (xy 382.395158 -264.915743)
			(xy 382.439232 -264.890297) (xy 382.486818 -264.87225) (xy 382.536682 -264.86207) (xy 382.587534 -264.860021)
			(xy 382.638055 -264.866155) (xy 382.686939 -264.880315) (xy 382.732918 -264.902132) (xy 382.774802 -264.931042)
			(xy 382.811506 -264.966297) (xy 382.842079 -265.006983) (xy 382.86573 -265.052046) (xy 382.881846 -265.10032)
			(xy 382.89001 -265.150554) (xy 382.890522 -265.176) (xy 383.20905 -265.176) (xy 383.21301 -265.126946)
			(xy 383.224787 -265.079162) (xy 383.244078 -265.033886) (xy 383.270381 -264.99229) (xy 383.303016 -264.955453)
			(xy 383.341137 -264.924328) (xy 383.383758 -264.899721) (xy 383.429774 -264.882269) (xy 383.477993 -264.872425)
			(xy 383.527168 -264.870444) (xy 383.576023 -264.876376) (xy 383.623294 -264.890068) (xy 383.667756 -264.911166)
			(xy 383.708259 -264.939122) (xy 383.743752 -264.973214) (xy 383.773317 -265.012558) (xy 383.796188 -265.056135)
			(xy 383.811772 -265.102816) (xy 383.819667 -265.151393) (xy 383.820162 -265.176) (xy 384.149104 -265.176)
			(xy 384.153064 -265.126946) (xy 384.164841 -265.079162) (xy 384.184132 -265.033886) (xy 384.210435 -264.99229)
			(xy 384.24307 -264.955453) (xy 384.281191 -264.924328) (xy 384.323812 -264.899721) (xy 384.369828 -264.882269)
			(xy 384.418047 -264.872425) (xy 384.467222 -264.870444) (xy 384.516077 -264.876376) (xy 384.563348 -264.890068)
			(xy 384.60781 -264.911166) (xy 384.648313 -264.939122) (xy 384.683806 -264.973214) (xy 384.713371 -265.012558)
			(xy 384.736242 -265.056135) (xy 384.751826 -265.102816) (xy 384.759721 -265.151393) (xy 384.760216 -265.176)
			(xy 384.759721 -265.200607) (xy 384.751826 -265.249184) (xy 384.736242 -265.295865) (xy 384.713371 -265.339442)
			(xy 384.683806 -265.378786) (xy 384.648313 -265.412878) (xy 384.60781 -265.440834) (xy 384.563348 -265.461932)
			(xy 384.516077 -265.475624) (xy 384.467222 -265.481556) (xy 384.418047 -265.479575) (xy 384.369828 -265.469731)
			(xy 384.323812 -265.452279) (xy 384.281191 -265.427672) (xy 384.24307 -265.396547) (xy 384.210435 -265.35971)
			(xy 384.184132 -265.318114) (xy 384.164841 -265.272838) (xy 384.153064 -265.225054) (xy 384.149104 -265.176)
			(xy 383.820162 -265.176) (xy 383.819667 -265.200607) (xy 383.811772 -265.249184) (xy 383.796188 -265.295865)
			(xy 383.773317 -265.339442) (xy 383.743752 -265.378786) (xy 383.708259 -265.412878) (xy 383.667756 -265.440834)
			(xy 383.623294 -265.461932) (xy 383.576023 -265.475624) (xy 383.527168 -265.481556) (xy 383.477993 -265.479575)
			(xy 383.429774 -265.469731) (xy 383.383758 -265.452279) (xy 383.341137 -265.427672) (xy 383.303016 -265.396547)
			(xy 383.270381 -265.35971) (xy 383.244078 -265.318114) (xy 383.224787 -265.272838) (xy 383.21301 -265.225054)
			(xy 383.20905 -265.176) (xy 382.890522 -265.176) (xy 382.89001 -265.201446) (xy 382.881846 -265.25168)
			(xy 382.86573 -265.299954) (xy 382.842079 -265.345017) (xy 382.811506 -265.385703) (xy 382.774802 -265.420958)
			(xy 382.732918 -265.449868) (xy 382.686939 -265.471685) (xy 382.638055 -265.485845) (xy 382.587534 -265.491979)
			(xy 382.536682 -265.48993) (xy 382.486818 -265.47975) (xy 382.439232 -265.461703) (xy 382.395158 -265.436257)
			(xy 382.355736 -265.40407) (xy 382.321988 -265.365976) (xy 382.294787 -265.322962) (xy 382.274839 -265.276142)
			(xy 382.26266 -265.226728) (xy 382.258565 -265.176) (xy 381.940054 -265.176) (xy 381.939559 -265.200607)
			(xy 381.931664 -265.249184) (xy 381.91608 -265.295865) (xy 381.893209 -265.339442) (xy 381.863644 -265.378786)
			(xy 381.828151 -265.412878) (xy 381.787648 -265.440834) (xy 381.743186 -265.461932) (xy 381.695915 -265.475624)
			(xy 381.64706 -265.481556) (xy 381.597885 -265.479575) (xy 381.549666 -265.469731) (xy 381.50365 -265.452279)
			(xy 381.461029 -265.427672) (xy 381.422908 -265.396547) (xy 381.390273 -265.35971) (xy 381.36397 -265.318114)
			(xy 381.344679 -265.272838) (xy 381.332902 -265.225054) (xy 381.328942 -265.176) (xy 381 -265.176)
			(xy 380.999505 -265.200607) (xy 380.99161 -265.249184) (xy 380.976026 -265.295865) (xy 380.953155 -265.339442)
			(xy 380.92359 -265.378786) (xy 380.888097 -265.412878) (xy 380.847594 -265.440834) (xy 380.803132 -265.461932)
			(xy 380.755861 -265.475624) (xy 380.707006 -265.481556) (xy 380.657831 -265.479575) (xy 380.609612 -265.469731)
			(xy 380.563596 -265.452279) (xy 380.520975 -265.427672) (xy 380.482854 -265.396547) (xy 380.450219 -265.35971)
			(xy 380.423916 -265.318114) (xy 380.404625 -265.272838) (xy 380.392848 -265.225054) (xy 380.388888 -265.176)
			(xy 380.070614 -265.176) (xy 380.070102 -265.201446) (xy 380.061938 -265.25168) (xy 380.045822 -265.299954)
			(xy 380.022171 -265.345017) (xy 379.991598 -265.385703) (xy 379.954894 -265.420958) (xy 379.91301 -265.449868)
			(xy 379.867031 -265.471685) (xy 379.818147 -265.485845) (xy 379.767626 -265.491979) (xy 379.716774 -265.48993)
			(xy 379.66691 -265.47975) (xy 379.619324 -265.461703) (xy 379.57525 -265.436257) (xy 379.535828 -265.40407)
			(xy 379.50208 -265.365976) (xy 379.474879 -265.322962) (xy 379.454931 -265.276142) (xy 379.442752 -265.226728)
			(xy 379.438657 -265.176) (xy 379.120146 -265.176) (xy 379.119651 -265.200607) (xy 379.111756 -265.249184)
			(xy 379.096172 -265.295865) (xy 379.073301 -265.339442) (xy 379.043736 -265.378786) (xy 379.008243 -265.412878)
			(xy 378.96774 -265.440834) (xy 378.923278 -265.461932) (xy 378.876007 -265.475624) (xy 378.827152 -265.481556)
			(xy 378.777977 -265.479575) (xy 378.729758 -265.469731) (xy 378.683742 -265.452279) (xy 378.641121 -265.427672)
			(xy 378.603 -265.396547) (xy 378.570365 -265.35971) (xy 378.544062 -265.318114) (xy 378.524771 -265.272838)
			(xy 378.512994 -265.225054) (xy 378.509034 -265.176) (xy 378.180092 -265.176) (xy 378.179597 -265.200607)
			(xy 378.171702 -265.249184) (xy 378.156118 -265.295865) (xy 378.133247 -265.339442) (xy 378.103682 -265.378786)
			(xy 378.068189 -265.412878) (xy 378.027686 -265.440834) (xy 377.983224 -265.461932) (xy 377.935953 -265.475624)
			(xy 377.887098 -265.481556) (xy 377.837923 -265.479575) (xy 377.789704 -265.469731) (xy 377.743688 -265.452279)
			(xy 377.701067 -265.427672) (xy 377.662946 -265.396547) (xy 377.630311 -265.35971) (xy 377.604008 -265.318114)
			(xy 377.584717 -265.272838) (xy 377.57294 -265.225054) (xy 377.56898 -265.176) (xy 377.240038 -265.176)
			(xy 377.239543 -265.200607) (xy 377.231648 -265.249184) (xy 377.216064 -265.295865) (xy 377.193193 -265.339442)
			(xy 377.163628 -265.378786) (xy 377.128135 -265.412878) (xy 377.087632 -265.440834) (xy 377.04317 -265.461932)
			(xy 376.995899 -265.475624) (xy 376.947044 -265.481556) (xy 376.897869 -265.479575) (xy 376.84965 -265.469731)
			(xy 376.803634 -265.452279) (xy 376.761013 -265.427672) (xy 376.722892 -265.396547) (xy 376.690257 -265.35971)
			(xy 376.663954 -265.318114) (xy 376.644663 -265.272838) (xy 376.632886 -265.225054) (xy 376.628926 -265.176)
			(xy 376.310652 -265.176) (xy 376.31014 -265.201446) (xy 376.301976 -265.25168) (xy 376.28586 -265.299954)
			(xy 376.262209 -265.345017) (xy 376.231636 -265.385703) (xy 376.194932 -265.420958) (xy 376.153048 -265.449868)
			(xy 376.107069 -265.471685) (xy 376.058185 -265.485845) (xy 376.007664 -265.491979) (xy 375.956812 -265.48993)
			(xy 375.906948 -265.47975) (xy 375.859362 -265.461703) (xy 375.815288 -265.436257) (xy 375.775866 -265.40407)
			(xy 375.742118 -265.365976) (xy 375.714917 -265.322962) (xy 375.694969 -265.276142) (xy 375.68279 -265.226728)
			(xy 375.678695 -265.176) (xy 375.360184 -265.176) (xy 375.359689 -265.200607) (xy 375.351794 -265.249184)
			(xy 375.33621 -265.295865) (xy 375.313339 -265.339442) (xy 375.283774 -265.378786) (xy 375.248281 -265.412878)
			(xy 375.207778 -265.440834) (xy 375.163316 -265.461932) (xy 375.116045 -265.475624) (xy 375.06719 -265.481556)
			(xy 375.018015 -265.479575) (xy 374.969796 -265.469731) (xy 374.92378 -265.452279) (xy 374.881159 -265.427672)
			(xy 374.843038 -265.396547) (xy 374.810403 -265.35971) (xy 374.7841 -265.318114) (xy 374.764809 -265.272838)
			(xy 374.753032 -265.225054) (xy 374.749072 -265.176) (xy 373.480076 -265.176) (xy 373.479581 -265.200607)
			(xy 373.471686 -265.249184) (xy 373.456102 -265.295865) (xy 373.433231 -265.339442) (xy 373.403666 -265.378786)
			(xy 373.368173 -265.412878) (xy 373.32767 -265.440834) (xy 373.283208 -265.461932) (xy 373.235937 -265.475624)
			(xy 373.187082 -265.481556) (xy 373.137907 -265.479575) (xy 373.089688 -265.469731) (xy 373.043672 -265.452279)
			(xy 373.001051 -265.427672) (xy 372.96293 -265.396547) (xy 372.930295 -265.35971) (xy 372.903992 -265.318114)
			(xy 372.884701 -265.272838) (xy 372.872924 -265.225054) (xy 372.868964 -265.176) (xy 371.600222 -265.176)
			(xy 371.599727 -265.200607) (xy 371.591832 -265.249184) (xy 371.576248 -265.295865) (xy 371.553377 -265.339442)
			(xy 371.523812 -265.378786) (xy 371.488319 -265.412878) (xy 371.447816 -265.440834) (xy 371.403354 -265.461932)
			(xy 371.356083 -265.475624) (xy 371.307228 -265.481556) (xy 371.258053 -265.479575) (xy 371.209834 -265.469731)
			(xy 371.163818 -265.452279) (xy 371.121197 -265.427672) (xy 371.083076 -265.396547) (xy 371.050441 -265.35971)
			(xy 371.024138 -265.318114) (xy 371.004847 -265.272838) (xy 370.99307 -265.225054) (xy 370.98911 -265.176)
			(xy 369.720114 -265.176) (xy 369.719619 -265.200607) (xy 369.711724 -265.249184) (xy 369.69614 -265.295865)
			(xy 369.673269 -265.339442) (xy 369.643704 -265.378786) (xy 369.608211 -265.412878) (xy 369.567708 -265.440834)
			(xy 369.523246 -265.461932) (xy 369.475975 -265.475624) (xy 369.42712 -265.481556) (xy 369.377945 -265.479575)
			(xy 369.329726 -265.469731) (xy 369.28371 -265.452279) (xy 369.241089 -265.427672) (xy 369.202968 -265.396547)
			(xy 369.170333 -265.35971) (xy 369.14403 -265.318114) (xy 369.124739 -265.272838) (xy 369.112962 -265.225054)
			(xy 369.109002 -265.176) (xy 359.659131 -265.176) (xy 359.658888 -265.176132) (xy 359.609335 -265.19393)
			(xy 359.557645 -265.203954) (xy 359.505031 -265.205971) (xy 359.452726 -265.199933) (xy 359.401955 -265.185981)
			(xy 359.35391 -265.164442) (xy 359.309715 -265.135822) (xy 359.270407 -265.100791) (xy 359.236907 -265.06017)
			(xy 359.210001 -265.014911) (xy 359.190318 -264.966076) (xy 359.178321 -264.914808) (xy 359.174291 -264.86231)
			(xy 349.16618 -264.86231) (xy 349.16618 -265.176) (xy 349.375234 -265.176) (xy 349.379194 -265.126946)
			(xy 349.390971 -265.079162) (xy 349.410262 -265.033886) (xy 349.436565 -264.99229) (xy 349.4692 -264.955453)
			(xy 349.507321 -264.924328) (xy 349.549942 -264.899721) (xy 349.595958 -264.882269) (xy 349.644177 -264.872425)
			(xy 349.693352 -264.870444) (xy 349.742207 -264.876376) (xy 349.789478 -264.890068) (xy 349.83394 -264.911166)
			(xy 349.874443 -264.939122) (xy 349.909936 -264.973214) (xy 349.939501 -265.012558) (xy 349.962372 -265.056135)
			(xy 349.977956 -265.102816) (xy 349.985851 -265.151393) (xy 349.986346 -265.176) (xy 349.985851 -265.200607)
			(xy 349.977956 -265.249184) (xy 349.962372 -265.295865) (xy 349.939501 -265.339442) (xy 349.909936 -265.378786)
			(xy 349.874443 -265.412878) (xy 349.83394 -265.440834) (xy 349.789478 -265.461932) (xy 349.742207 -265.475624)
			(xy 349.693352 -265.481556) (xy 349.644177 -265.479575) (xy 349.595958 -265.469731) (xy 349.549942 -265.452279)
			(xy 349.507321 -265.427672) (xy 349.4692 -265.396547) (xy 349.436565 -265.35971) (xy 349.410262 -265.318114)
			(xy 349.390971 -265.272838) (xy 349.379194 -265.225054) (xy 349.375234 -265.176) (xy 349.16618 -265.176)
			(xy 349.16618 -266.036298) (xy 349.166636 -266.046177) (xy 349.174072 -266.064483) (xy 349.180658 -266.071858)
			(xy 349.180912 -266.072112) (xy 349.331534 -266.222734) (xy 349.332042 -266.223242) (xy 349.339422 -266.229827)
			(xy 349.357721 -266.237283) (xy 349.367602 -266.23772) (xy 349.772986 -266.23772) (xy 349.785494 -266.237074)
			(xy 349.807598 -266.225359) (xy 349.81515 -266.215368) (xy 349.869252 -266.135358) (xy 349.872046 -266.110212)
			(xy 349.867474 -266.098528) (xy 349.857444 -266.071483) (xy 349.846581 -266.014842) (xy 349.845884 -265.986006)
			(xy 349.846406 -265.960751) (xy 349.854719 -265.910929) (xy 349.87112 -265.863155) (xy 349.895161 -265.818732)
			(xy 349.926185 -265.778872) (xy 349.963347 -265.744662) (xy 350.005633 -265.717036) (xy 350.051889 -265.696746)
			(xy 350.100854 -265.684346) (xy 350.151192 -265.680175) (xy 350.20153 -265.684346) (xy 350.250495 -265.696746)
			(xy 350.296751 -265.717036) (xy 350.339037 -265.744662) (xy 350.376199 -265.778872) (xy 350.407223 -265.818732)
			(xy 350.431264 -265.863155) (xy 350.447665 -265.910929) (xy 350.455978 -265.960751) (xy 350.4565 -265.986006)
			(xy 350.455813 -266.014843) (xy 350.444952 -266.071487) (xy 350.43491 -266.098528) (xy 350.430338 -266.110212)
			(xy 350.433132 -266.135358) (xy 350.487234 -266.215368) (xy 350.494765 -266.225383) (xy 350.516882 -266.237096)
			(xy 350.529398 -266.23772) (xy 351.65284 -266.23772) (xy 351.665353 -266.237084) (xy 351.687475 -266.22538)
			(xy 351.695004 -266.215368) (xy 351.749106 -266.135358) (xy 351.7519 -266.110212) (xy 351.747328 -266.098528)
			(xy 351.7373 -266.071483) (xy 351.726438 -266.014842) (xy 351.725738 -265.986006) (xy 351.72626 -265.960751)
			(xy 351.734573 -265.910929) (xy 351.750974 -265.863155) (xy 351.775015 -265.818732) (xy 351.806039 -265.778872)
			(xy 351.843201 -265.744662) (xy 351.885487 -265.717036) (xy 351.931743 -265.696746) (xy 351.980708 -265.684346)
			(xy 352.031046 -265.680175) (xy 352.081384 -265.684346) (xy 352.130349 -265.696746) (xy 352.176605 -265.717036)
			(xy 352.218891 -265.744662) (xy 352.256053 -265.778872) (xy 352.287077 -265.818732) (xy 352.311118 -265.863155)
			(xy 352.327519 -265.910929) (xy 352.335832 -265.960751) (xy 352.336354 -265.986006) (xy 352.335966 -266.008885)
			(xy 352.329168 -266.054135) (xy 352.315682 -266.097861) (xy 352.295811 -266.139079) (xy 352.283268 -266.158218)
			(xy 352.278696 -266.164568) (xy 352.274378 -266.179046) (xy 352.274378 -266.18692) (xy 352.274869 -266.196927)
			(xy 352.282531 -266.215415) (xy 352.296683 -266.229568) (xy 352.315171 -266.237231) (xy 352.325178 -266.23772)
			(xy 352.327718 -266.23772) (xy 352.337596 -266.237261) (xy 352.355896 -266.22982) (xy 352.363278 -266.223242)
			(xy 352.363532 -266.222988) (xy 352.36658 -266.21994) (xy 352.375724 -266.21613) (xy 352.380352 -266.214359)
			(xy 352.390074 -266.212444) (xy 352.395028 -266.21232) (xy 353.523804 -266.21232) (xy 353.529138 -266.212066)
			(xy 353.538385 -266.210656) (xy 353.555042 -266.202179) (xy 353.56165 -266.195556) (xy 353.564952 -266.191492)
			(xy 353.620578 -266.115038) (xy 353.624388 -266.091416) (xy 353.620578 -266.079732) (xy 353.613705 -266.056912)
			(xy 353.606308 -266.009834) (xy 353.605846 -265.986006) (xy 353.606368 -265.960751) (xy 353.614681 -265.910929)
			(xy 353.631082 -265.863155) (xy 353.655123 -265.818732) (xy 353.686147 -265.778872) (xy 353.723309 -265.744662)
			(xy 353.765595 -265.717036) (xy 353.811851 -265.696746) (xy 353.860816 -265.684346) (xy 353.911154 -265.680175)
			(xy 353.961492 -265.684346) (xy 354.010457 -265.696746) (xy 354.056713 -265.717036) (xy 354.098999 -265.744662)
			(xy 354.136161 -265.778872) (xy 354.167185 -265.818732) (xy 354.191226 -265.863155) (xy 354.207627 -265.910929)
			(xy 354.21594 -265.960751) (xy 354.216462 -265.986006) (xy 354.216005 -266.009834) (xy 354.208603 -266.056912)
			(xy 354.20173 -266.079732) (xy 354.19792 -266.091416) (xy 354.20173 -266.115038) (xy 354.257356 -266.191492)
			(xy 354.260658 -266.195556) (xy 354.267183 -266.20229) (xy 354.283882 -266.210788) (xy 354.29317 -266.212066)
			(xy 354.298504 -266.21232) (xy 355.403658 -266.21232) (xy 355.408992 -266.212066) (xy 355.418243 -266.210663)
			(xy 355.434912 -266.202196) (xy 355.441504 -266.195556) (xy 355.444806 -266.191492) (xy 355.500432 -266.115038)
			(xy 355.504242 -266.091416) (xy 355.500432 -266.079732) (xy 355.493558 -266.056912) (xy 355.486159 -266.009834)
			(xy 355.4857 -265.986006) (xy 355.486222 -265.960751) (xy 355.494535 -265.910929) (xy 355.510936 -265.863155)
			(xy 355.534977 -265.818732) (xy 355.566001 -265.778872) (xy 355.603163 -265.744662) (xy 355.645449 -265.717036)
			(xy 355.691705 -265.696746) (xy 355.74067 -265.684346) (xy 355.791008 -265.680175) (xy 355.841346 -265.684346)
			(xy 355.890311 -265.696746) (xy 355.936567 -265.717036) (xy 355.978853 -265.744662) (xy 356.016015 -265.778872)
			(xy 356.047039 -265.818732) (xy 356.07108 -265.863155) (xy 356.087481 -265.910929) (xy 356.095794 -265.960751)
			(xy 356.096316 -265.986006) (xy 356.095858 -266.009834) (xy 356.088455 -266.056911) (xy 356.081584 -266.079732)
			(xy 356.077774 -266.091416) (xy 356.081584 -266.115038) (xy 356.13721 -266.191492) (xy 356.140512 -266.195556)
			(xy 356.14704 -266.202283) (xy 356.163741 -266.210764) (xy 356.173024 -266.212066) (xy 356.178358 -266.21232)
			(xy 357.283766 -266.21232) (xy 357.2891 -266.212066) (xy 357.29835 -266.210662) (xy 357.315017 -266.202193)
			(xy 357.321612 -266.195556) (xy 357.324914 -266.191492) (xy 357.38054 -266.115038) (xy 357.38435 -266.091416)
			(xy 357.38054 -266.079732) (xy 357.373666 -266.056912) (xy 357.366267 -266.009834) (xy 357.365808 -265.986006)
			(xy 357.36633 -265.960751) (xy 357.374643 -265.910929) (xy 357.391044 -265.863155) (xy 357.415085 -265.818732)
			(xy 357.446109 -265.778872) (xy 357.483271 -265.744662) (xy 357.525557 -265.717036) (xy 357.571813 -265.696746)
			(xy 357.620778 -265.684346) (xy 357.671116 -265.680175) (xy 357.721454 -265.684346) (xy 357.770419 -265.696746)
			(xy 357.816675 -265.717036) (xy 357.858961 -265.744662) (xy 357.896123 -265.778872) (xy 357.927147 -265.818732)
			(xy 357.951188 -265.863155) (xy 357.967589 -265.910929) (xy 357.975902 -265.960751) (xy 357.976424 -265.986006)
			(xy 357.975966 -266.009834) (xy 357.968563 -266.056912) (xy 357.961692 -266.079732) (xy 357.957882 -266.091416)
			(xy 357.961692 -266.115038) (xy 358.017318 -266.191492) (xy 358.02062 -266.195556) (xy 358.027148 -266.202281)
			(xy 358.04385 -266.21076) (xy 358.053132 -266.212066) (xy 358.058466 -266.21232) (xy 361.037378 -266.21232)
			(xy 361.042712 -266.212066) (xy 361.051961 -266.21066) (xy 361.068625 -266.202189) (xy 361.075224 -266.195556)
			(xy 361.078526 -266.191492) (xy 361.134152 -266.115038) (xy 361.137962 -266.091416) (xy 361.134152 -266.079732)
			(xy 361.12728 -266.056912) (xy 361.119883 -266.009834) (xy 361.11942 -265.986006) (xy 361.119942 -265.960751)
			(xy 361.128255 -265.910929) (xy 361.144656 -265.863155) (xy 361.168697 -265.818732) (xy 361.199721 -265.778872)
			(xy 361.236883 -265.744662) (xy 361.279169 -265.717036) (xy 361.325425 -265.696746) (xy 361.37439 -265.684346)
			(xy 361.424728 -265.680175) (xy 361.475066 -265.684346) (xy 361.524031 -265.696746) (xy 361.570287 -265.717036)
			(xy 361.612573 -265.744662) (xy 361.649735 -265.778872) (xy 361.680759 -265.818732) (xy 361.7048 -265.863155)
			(xy 361.721201 -265.910929) (xy 361.729514 -265.960751) (xy 361.730036 -265.986006) (xy 361.729578 -266.009834)
			(xy 361.722176 -266.056912) (xy 361.715304 -266.079732) (xy 361.711494 -266.091416) (xy 361.715304 -266.115038)
			(xy 361.77093 -266.191492) (xy 361.774232 -266.195556) (xy 361.780761 -266.20228) (xy 361.797464 -266.210754)
			(xy 361.806744 -266.212066) (xy 361.812078 -266.21232) (xy 362.917486 -266.21232) (xy 362.92282 -266.212066)
			(xy 362.932069 -266.210659) (xy 362.94873 -266.202186) (xy 362.955332 -266.195556) (xy 362.958634 -266.191492)
			(xy 363.01426 -266.115038) (xy 363.01807 -266.091416) (xy 363.01426 -266.079732) (xy 363.007387 -266.056912)
			(xy 362.999991 -266.009834) (xy 362.999528 -265.986006) (xy 363.00005 -265.960751) (xy 363.008363 -265.910929)
			(xy 363.024764 -265.863155) (xy 363.048805 -265.818732) (xy 363.079829 -265.778872) (xy 363.116991 -265.744662)
			(xy 363.159277 -265.717036) (xy 363.205533 -265.696746) (xy 363.254498 -265.684346) (xy 363.304836 -265.680175)
			(xy 363.355174 -265.684346) (xy 363.404139 -265.696746) (xy 363.450395 -265.717036) (xy 363.492681 -265.744662)
			(xy 363.529843 -265.778872) (xy 363.560867 -265.818732) (xy 363.584908 -265.863155) (xy 363.601309 -265.910929)
			(xy 363.609622 -265.960751) (xy 363.610144 -265.986006) (xy 363.609686 -266.009834) (xy 363.602284 -266.056912)
			(xy 363.595412 -266.079732) (xy 363.591602 -266.091416) (xy 363.595412 -266.115038) (xy 363.651038 -266.191492)
			(xy 363.65434 -266.195556) (xy 363.660864 -266.202292) (xy 363.677563 -266.210797) (xy 363.686852 -266.212066)
			(xy 363.692186 -266.21232) (xy 364.79734 -266.21232) (xy 364.802674 -266.212066) (xy 364.811927 -266.210666)
			(xy 364.828599 -266.202203) (xy 364.835186 -266.195556) (xy 364.838488 -266.191492) (xy 364.894114 -266.115038)
			(xy 364.897924 -266.091416) (xy 364.894114 -266.079732) (xy 364.88724 -266.056912) (xy 364.879842 -266.009834)
			(xy 364.879382 -265.986006) (xy 364.879904 -265.960751) (xy 364.888217 -265.910929) (xy 364.904618 -265.863155)
			(xy 364.928659 -265.818732) (xy 364.959683 -265.778872) (xy 364.996845 -265.744662) (xy 365.039131 -265.717036)
			(xy 365.085387 -265.696746) (xy 365.134352 -265.684346) (xy 365.18469 -265.680175) (xy 365.235028 -265.684346)
			(xy 365.283993 -265.696746) (xy 365.330249 -265.717036) (xy 365.372535 -265.744662) (xy 365.409697 -265.778872)
			(xy 365.440721 -265.818732) (xy 365.464762 -265.863155) (xy 365.481163 -265.910929) (xy 365.489476 -265.960751)
			(xy 365.489998 -265.986006) (xy 365.489541 -266.009834) (xy 365.48214 -266.056912) (xy 365.475266 -266.079732)
			(xy 365.471456 -266.091416) (xy 365.475266 -266.115038) (xy 365.530892 -266.191492) (xy 365.534194 -266.195556)
			(xy 365.540721 -266.202285) (xy 365.557422 -266.210772) (xy 365.566706 -266.212066) (xy 365.57204 -266.21232)
			(xy 366.677448 -266.21232) (xy 366.682782 -266.212066) (xy 366.692034 -266.210665) (xy 366.708705 -266.2022)
			(xy 366.715294 -266.195556) (xy 366.718596 -266.191492) (xy 366.774222 -266.115038) (xy 366.778032 -266.091416)
			(xy 366.774222 -266.079732) (xy 366.767348 -266.056912) (xy 366.75995 -266.009834) (xy 366.75949 -265.986006)
			(xy 366.760012 -265.960751) (xy 366.768325 -265.910929) (xy 366.784726 -265.863155) (xy 366.808767 -265.818732)
			(xy 366.839791 -265.778872) (xy 366.876953 -265.744662) (xy 366.919239 -265.717036) (xy 366.965495 -265.696746)
			(xy 367.01446 -265.684346) (xy 367.064798 -265.680175) (xy 367.115136 -265.684346) (xy 367.164101 -265.696746)
			(xy 367.210357 -265.717036) (xy 367.252643 -265.744662) (xy 367.289805 -265.778872) (xy 367.320829 -265.818732)
			(xy 367.34487 -265.863155) (xy 367.361271 -265.910929) (xy 367.369584 -265.960751) (xy 367.370106 -265.986006)
			(xy 367.369649 -266.009834) (xy 367.362248 -266.056912) (xy 367.355374 -266.079732) (xy 367.351564 -266.091416)
			(xy 367.355374 -266.115038) (xy 367.411 -266.191492) (xy 367.414302 -266.195556) (xy 367.420829 -266.202284)
			(xy 367.437531 -266.210768) (xy 367.446814 -266.212066) (xy 367.452148 -266.21232) (xy 368.557556 -266.21232)
			(xy 368.56289 -266.212066) (xy 368.572141 -266.210664) (xy 368.58881 -266.202197) (xy 368.595402 -266.195556)
			(xy 368.598704 -266.191492) (xy 368.65433 -266.115038) (xy 368.65814 -266.091416) (xy 368.65433 -266.079732)
			(xy 368.647456 -266.056912) (xy 368.640057 -266.009834) (xy 368.639598 -265.986006) (xy 368.64012 -265.960751)
			(xy 368.648433 -265.910929) (xy 368.664834 -265.863155) (xy 368.688875 -265.818732) (xy 368.719899 -265.778872)
			(xy 368.757061 -265.744662) (xy 368.799347 -265.717036) (xy 368.845603 -265.696746) (xy 368.894568 -265.684346)
			(xy 368.944906 -265.680175) (xy 368.995244 -265.684346) (xy 369.044209 -265.696746) (xy 369.090465 -265.717036)
			(xy 369.132751 -265.744662) (xy 369.169913 -265.778872) (xy 369.200937 -265.818732) (xy 369.224978 -265.863155)
			(xy 369.241379 -265.910929) (xy 369.249692 -265.960751) (xy 369.250214 -265.986006) (xy 369.249757 -266.009834)
			(xy 369.242356 -266.056912) (xy 369.235482 -266.079732) (xy 369.231672 -266.091416) (xy 369.235482 -266.115038)
			(xy 369.291108 -266.191492) (xy 369.29441 -266.195556) (xy 369.300938 -266.202283) (xy 369.317639 -266.210765)
			(xy 369.326922 -266.212066) (xy 369.332256 -266.21232) (xy 370.43741 -266.21232) (xy 370.442744 -266.212066)
			(xy 370.451991 -266.210655) (xy 370.468646 -266.202177) (xy 370.475256 -266.195556) (xy 370.478558 -266.191492)
			(xy 370.534184 -266.115038) (xy 370.537994 -266.091416) (xy 370.534184 -266.079732) (xy 370.527311 -266.056912)
			(xy 370.519913 -266.009834) (xy 370.519452 -265.986006) (xy 370.519974 -265.960751) (xy 370.528287 -265.910929)
			(xy 370.544688 -265.863155) (xy 370.568729 -265.818732) (xy 370.599753 -265.778872) (xy 370.636915 -265.744662)
			(xy 370.679201 -265.717036) (xy 370.725457 -265.696746) (xy 370.774422 -265.684346) (xy 370.82476 -265.680175)
			(xy 370.875098 -265.684346) (xy 370.924063 -265.696746) (xy 370.970319 -265.717036) (xy 371.012605 -265.744662)
			(xy 371.049767 -265.778872) (xy 371.080791 -265.818732) (xy 371.104832 -265.863155) (xy 371.121233 -265.910929)
			(xy 371.129546 -265.960751) (xy 371.130068 -265.986006) (xy 371.129611 -266.009834) (xy 371.122209 -266.056912)
			(xy 371.115336 -266.079732) (xy 371.111526 -266.091416) (xy 371.115336 -266.115038) (xy 371.170962 -266.191492)
			(xy 371.174264 -266.195556) (xy 371.180789 -266.202289) (xy 371.197489 -266.210786) (xy 371.206776 -266.212066)
			(xy 371.21211 -266.21232) (xy 372.317518 -266.21232) (xy 372.322852 -266.212066) (xy 372.332106 -266.21067)
			(xy 372.348785 -266.202211) (xy 372.355364 -266.195556) (xy 372.358666 -266.191492) (xy 372.414292 -266.115038)
			(xy 372.418102 -266.091416) (xy 372.414292 -266.079732) (xy 372.407419 -266.056912) (xy 372.400021 -266.009834)
			(xy 372.39956 -265.986006) (xy 372.400082 -265.960751) (xy 372.408395 -265.910929) (xy 372.424796 -265.863155)
			(xy 372.448837 -265.818732) (xy 372.479861 -265.778872) (xy 372.517023 -265.744662) (xy 372.559309 -265.717036)
			(xy 372.605565 -265.696746) (xy 372.65453 -265.684346) (xy 372.704868 -265.680175) (xy 372.755206 -265.684346)
			(xy 372.804171 -265.696746) (xy 372.850427 -265.717036) (xy 372.892713 -265.744662) (xy 372.929875 -265.778872)
			(xy 372.960899 -265.818732) (xy 372.98494 -265.863155) (xy 373.001341 -265.910929) (xy 373.009654 -265.960751)
			(xy 373.010176 -265.986006) (xy 374.278918 -265.986006) (xy 374.282878 -265.936952) (xy 374.294655 -265.889168)
			(xy 374.313946 -265.843892) (xy 374.340249 -265.802296) (xy 374.372884 -265.765459) (xy 374.411005 -265.734334)
			(xy 374.453626 -265.709727) (xy 374.499642 -265.692275) (xy 374.547861 -265.682431) (xy 374.597036 -265.68045)
			(xy 374.645891 -265.686382) (xy 374.693162 -265.700074) (xy 374.737624 -265.721172) (xy 374.778127 -265.749128)
			(xy 374.81362 -265.78322) (xy 374.843185 -265.822564) (xy 374.866056 -265.866141) (xy 374.88164 -265.912822)
			(xy 374.889535 -265.961399) (xy 374.89003 -265.986006) (xy 376.148595 -265.986006) (xy 376.15269 -265.935278)
			(xy 376.164869 -265.885864) (xy 376.184817 -265.839044) (xy 376.212018 -265.79603) (xy 376.245766 -265.757936)
			(xy 376.285188 -265.725749) (xy 376.329262 -265.700303) (xy 376.376848 -265.682256) (xy 376.426712 -265.672076)
			(xy 376.477564 -265.670027) (xy 376.528085 -265.676161) (xy 376.576969 -265.690321) (xy 376.622948 -265.712138)
			(xy 376.664832 -265.741048) (xy 376.701536 -265.776303) (xy 376.732109 -265.816989) (xy 376.75576 -265.862052)
			(xy 376.771876 -265.910326) (xy 376.78004 -265.96056) (xy 376.780552 -265.986006) (xy 377.09908 -265.986006)
			(xy 377.10304 -265.936952) (xy 377.114817 -265.889168) (xy 377.134108 -265.843892) (xy 377.160411 -265.802296)
			(xy 377.193046 -265.765459) (xy 377.231167 -265.734334) (xy 377.273788 -265.709727) (xy 377.319804 -265.692275)
			(xy 377.368023 -265.682431) (xy 377.417198 -265.68045) (xy 377.466053 -265.686382) (xy 377.513324 -265.700074)
			(xy 377.557786 -265.721172) (xy 377.598289 -265.749128) (xy 377.633782 -265.78322) (xy 377.663347 -265.822564)
			(xy 377.686218 -265.866141) (xy 377.701802 -265.912822) (xy 377.709697 -265.961399) (xy 377.710192 -265.986006)
			(xy 378.968503 -265.986006) (xy 378.972598 -265.935278) (xy 378.984777 -265.885864) (xy 379.004725 -265.839044)
			(xy 379.031926 -265.79603) (xy 379.065674 -265.757936) (xy 379.105096 -265.725749) (xy 379.14917 -265.700303)
			(xy 379.196756 -265.682256) (xy 379.24662 -265.672076) (xy 379.297472 -265.670027) (xy 379.347993 -265.676161)
			(xy 379.396877 -265.690321) (xy 379.442856 -265.712138) (xy 379.48474 -265.741048) (xy 379.521444 -265.776303)
			(xy 379.552017 -265.816989) (xy 379.575668 -265.862052) (xy 379.591784 -265.910326) (xy 379.599948 -265.96056)
			(xy 379.60046 -265.986006) (xy 379.918988 -265.986006) (xy 379.922948 -265.936952) (xy 379.934725 -265.889168)
			(xy 379.954016 -265.843892) (xy 379.980319 -265.802296) (xy 380.012954 -265.765459) (xy 380.051075 -265.734334)
			(xy 380.093696 -265.709727) (xy 380.139712 -265.692275) (xy 380.187931 -265.682431) (xy 380.237106 -265.68045)
			(xy 380.285961 -265.686382) (xy 380.333232 -265.700074) (xy 380.377694 -265.721172) (xy 380.418197 -265.749128)
			(xy 380.45369 -265.78322) (xy 380.483255 -265.822564) (xy 380.506126 -265.866141) (xy 380.52171 -265.912822)
			(xy 380.529605 -265.961399) (xy 380.5301 -265.986006) (xy 380.859042 -265.986006) (xy 380.863002 -265.936952)
			(xy 380.874779 -265.889168) (xy 380.89407 -265.843892) (xy 380.920373 -265.802296) (xy 380.953008 -265.765459)
			(xy 380.991129 -265.734334) (xy 381.03375 -265.709727) (xy 381.079766 -265.692275) (xy 381.127985 -265.682431)
			(xy 381.17716 -265.68045) (xy 381.226015 -265.686382) (xy 381.273286 -265.700074) (xy 381.317748 -265.721172)
			(xy 381.358251 -265.749128) (xy 381.393744 -265.78322) (xy 381.423309 -265.822564) (xy 381.44618 -265.866141)
			(xy 381.461764 -265.912822) (xy 381.469659 -265.961399) (xy 381.470154 -265.986006) (xy 381.799096 -265.986006)
			(xy 381.803056 -265.936952) (xy 381.814833 -265.889168) (xy 381.834124 -265.843892) (xy 381.860427 -265.802296)
			(xy 381.893062 -265.765459) (xy 381.931183 -265.734334) (xy 381.973804 -265.709727) (xy 382.01982 -265.692275)
			(xy 382.068039 -265.682431) (xy 382.117214 -265.68045) (xy 382.166069 -265.686382) (xy 382.21334 -265.700074)
			(xy 382.257802 -265.721172) (xy 382.298305 -265.749128) (xy 382.333798 -265.78322) (xy 382.363363 -265.822564)
			(xy 382.386234 -265.866141) (xy 382.401818 -265.912822) (xy 382.409713 -265.961399) (xy 382.410208 -265.986006)
			(xy 382.728465 -265.986006) (xy 382.73256 -265.935278) (xy 382.744739 -265.885864) (xy 382.764687 -265.839044)
			(xy 382.791888 -265.79603) (xy 382.825636 -265.757936) (xy 382.865058 -265.725749) (xy 382.909132 -265.700303)
			(xy 382.956718 -265.682256) (xy 383.006582 -265.672076) (xy 383.057434 -265.670027) (xy 383.107955 -265.676161)
			(xy 383.156839 -265.690321) (xy 383.202818 -265.712138) (xy 383.244702 -265.741048) (xy 383.281406 -265.776303)
			(xy 383.311979 -265.816989) (xy 383.33563 -265.862052) (xy 383.351746 -265.910326) (xy 383.35991 -265.96056)
			(xy 383.360422 -265.986006) (xy 383.67895 -265.986006) (xy 383.68291 -265.936952) (xy 383.694687 -265.889168)
			(xy 383.713978 -265.843892) (xy 383.740281 -265.802296) (xy 383.772916 -265.765459) (xy 383.811037 -265.734334)
			(xy 383.853658 -265.709727) (xy 383.899674 -265.692275) (xy 383.947893 -265.682431) (xy 383.997068 -265.68045)
			(xy 384.045923 -265.686382) (xy 384.093194 -265.700074) (xy 384.137656 -265.721172) (xy 384.178159 -265.749128)
			(xy 384.213652 -265.78322) (xy 384.243217 -265.822564) (xy 384.266088 -265.866141) (xy 384.281672 -265.912822)
			(xy 384.289567 -265.961399) (xy 384.290062 -265.986006) (xy 385.548627 -265.986006) (xy 385.552722 -265.935278)
			(xy 385.564901 -265.885864) (xy 385.584849 -265.839044) (xy 385.61205 -265.79603) (xy 385.645798 -265.757936)
			(xy 385.68522 -265.725749) (xy 385.729294 -265.700303) (xy 385.77688 -265.682256) (xy 385.826744 -265.672076)
			(xy 385.877596 -265.670027) (xy 385.928117 -265.676161) (xy 385.977001 -265.690321) (xy 386.02298 -265.712138)
			(xy 386.064864 -265.741048) (xy 386.101568 -265.776303) (xy 386.132141 -265.816989) (xy 386.155792 -265.862052)
			(xy 386.171908 -265.910326) (xy 386.180072 -265.96056) (xy 386.180584 -265.986006) (xy 386.180072 -266.011452)
			(xy 386.171908 -266.061686) (xy 386.155792 -266.10996) (xy 386.132141 -266.155023) (xy 386.101568 -266.195709)
			(xy 386.064864 -266.230964) (xy 386.02298 -266.259874) (xy 385.977001 -266.281691) (xy 385.928117 -266.295851)
			(xy 385.877596 -266.301985) (xy 385.826744 -266.299936) (xy 385.77688 -266.289756) (xy 385.729294 -266.271709)
			(xy 385.68522 -266.246263) (xy 385.645798 -266.214076) (xy 385.61205 -266.175982) (xy 385.584849 -266.132968)
			(xy 385.564901 -266.086148) (xy 385.552722 -266.036734) (xy 385.548627 -265.986006) (xy 384.290062 -265.986006)
			(xy 384.289567 -266.010613) (xy 384.281672 -266.05919) (xy 384.266088 -266.105871) (xy 384.243217 -266.149448)
			(xy 384.213652 -266.188792) (xy 384.178159 -266.222884) (xy 384.137656 -266.25084) (xy 384.093194 -266.271938)
			(xy 384.045923 -266.28563) (xy 383.997068 -266.291562) (xy 383.947893 -266.289581) (xy 383.899674 -266.279737)
			(xy 383.853658 -266.262285) (xy 383.811037 -266.237678) (xy 383.772916 -266.206553) (xy 383.740281 -266.169716)
			(xy 383.713978 -266.12812) (xy 383.694687 -266.082844) (xy 383.68291 -266.03506) (xy 383.67895 -265.986006)
			(xy 383.360422 -265.986006) (xy 383.35991 -266.011452) (xy 383.351746 -266.061686) (xy 383.33563 -266.10996)
			(xy 383.311979 -266.155023) (xy 383.281406 -266.195709) (xy 383.244702 -266.230964) (xy 383.202818 -266.259874)
			(xy 383.156839 -266.281691) (xy 383.107955 -266.295851) (xy 383.057434 -266.301985) (xy 383.006582 -266.299936)
			(xy 382.956718 -266.289756) (xy 382.909132 -266.271709) (xy 382.865058 -266.246263) (xy 382.825636 -266.214076)
			(xy 382.791888 -266.175982) (xy 382.764687 -266.132968) (xy 382.744739 -266.086148) (xy 382.73256 -266.036734)
			(xy 382.728465 -265.986006) (xy 382.410208 -265.986006) (xy 382.409713 -266.010613) (xy 382.401818 -266.05919)
			(xy 382.386234 -266.105871) (xy 382.363363 -266.149448) (xy 382.333798 -266.188792) (xy 382.298305 -266.222884)
			(xy 382.257802 -266.25084) (xy 382.21334 -266.271938) (xy 382.166069 -266.28563) (xy 382.117214 -266.291562)
			(xy 382.068039 -266.289581) (xy 382.01982 -266.279737) (xy 381.973804 -266.262285) (xy 381.931183 -266.237678)
			(xy 381.893062 -266.206553) (xy 381.860427 -266.169716) (xy 381.834124 -266.12812) (xy 381.814833 -266.082844)
			(xy 381.803056 -266.03506) (xy 381.799096 -265.986006) (xy 381.470154 -265.986006) (xy 381.469659 -266.010613)
			(xy 381.461764 -266.05919) (xy 381.44618 -266.105871) (xy 381.423309 -266.149448) (xy 381.393744 -266.188792)
			(xy 381.358251 -266.222884) (xy 381.317748 -266.25084) (xy 381.273286 -266.271938) (xy 381.226015 -266.28563)
			(xy 381.17716 -266.291562) (xy 381.127985 -266.289581) (xy 381.079766 -266.279737) (xy 381.03375 -266.262285)
			(xy 380.991129 -266.237678) (xy 380.953008 -266.206553) (xy 380.920373 -266.169716) (xy 380.89407 -266.12812)
			(xy 380.874779 -266.082844) (xy 380.863002 -266.03506) (xy 380.859042 -265.986006) (xy 380.5301 -265.986006)
			(xy 380.529605 -266.010613) (xy 380.52171 -266.05919) (xy 380.506126 -266.105871) (xy 380.483255 -266.149448)
			(xy 380.45369 -266.188792) (xy 380.418197 -266.222884) (xy 380.377694 -266.25084) (xy 380.333232 -266.271938)
			(xy 380.285961 -266.28563) (xy 380.237106 -266.291562) (xy 380.187931 -266.289581) (xy 380.139712 -266.279737)
			(xy 380.093696 -266.262285) (xy 380.051075 -266.237678) (xy 380.012954 -266.206553) (xy 379.980319 -266.169716)
			(xy 379.954016 -266.12812) (xy 379.934725 -266.082844) (xy 379.922948 -266.03506) (xy 379.918988 -265.986006)
			(xy 379.60046 -265.986006) (xy 379.599948 -266.011452) (xy 379.591784 -266.061686) (xy 379.575668 -266.10996)
			(xy 379.552017 -266.155023) (xy 379.521444 -266.195709) (xy 379.48474 -266.230964) (xy 379.442856 -266.259874)
			(xy 379.396877 -266.281691) (xy 379.347993 -266.295851) (xy 379.297472 -266.301985) (xy 379.24662 -266.299936)
			(xy 379.196756 -266.289756) (xy 379.14917 -266.271709) (xy 379.105096 -266.246263) (xy 379.065674 -266.214076)
			(xy 379.031926 -266.175982) (xy 379.004725 -266.132968) (xy 378.984777 -266.086148) (xy 378.972598 -266.036734)
			(xy 378.968503 -265.986006) (xy 377.710192 -265.986006) (xy 377.709697 -266.010613) (xy 377.701802 -266.05919)
			(xy 377.686218 -266.105871) (xy 377.663347 -266.149448) (xy 377.633782 -266.188792) (xy 377.598289 -266.222884)
			(xy 377.557786 -266.25084) (xy 377.513324 -266.271938) (xy 377.466053 -266.28563) (xy 377.417198 -266.291562)
			(xy 377.368023 -266.289581) (xy 377.319804 -266.279737) (xy 377.273788 -266.262285) (xy 377.231167 -266.237678)
			(xy 377.193046 -266.206553) (xy 377.160411 -266.169716) (xy 377.134108 -266.12812) (xy 377.114817 -266.082844)
			(xy 377.10304 -266.03506) (xy 377.09908 -265.986006) (xy 376.780552 -265.986006) (xy 376.78004 -266.011452)
			(xy 376.771876 -266.061686) (xy 376.75576 -266.10996) (xy 376.732109 -266.155023) (xy 376.701536 -266.195709)
			(xy 376.664832 -266.230964) (xy 376.622948 -266.259874) (xy 376.576969 -266.281691) (xy 376.528085 -266.295851)
			(xy 376.477564 -266.301985) (xy 376.426712 -266.299936) (xy 376.376848 -266.289756) (xy 376.329262 -266.271709)
			(xy 376.285188 -266.246263) (xy 376.245766 -266.214076) (xy 376.212018 -266.175982) (xy 376.184817 -266.132968)
			(xy 376.164869 -266.086148) (xy 376.15269 -266.036734) (xy 376.148595 -265.986006) (xy 374.89003 -265.986006)
			(xy 374.889535 -266.010613) (xy 374.88164 -266.05919) (xy 374.866056 -266.105871) (xy 374.843185 -266.149448)
			(xy 374.81362 -266.188792) (xy 374.778127 -266.222884) (xy 374.737624 -266.25084) (xy 374.693162 -266.271938)
			(xy 374.645891 -266.28563) (xy 374.597036 -266.291562) (xy 374.547861 -266.289581) (xy 374.499642 -266.279737)
			(xy 374.453626 -266.262285) (xy 374.411005 -266.237678) (xy 374.372884 -266.206553) (xy 374.340249 -266.169716)
			(xy 374.313946 -266.12812) (xy 374.294655 -266.082844) (xy 374.282878 -266.03506) (xy 374.278918 -265.986006)
			(xy 373.010176 -265.986006) (xy 373.009719 -266.009834) (xy 373.002317 -266.056912) (xy 372.995444 -266.079732)
			(xy 372.991634 -266.091416) (xy 372.995444 -266.115038) (xy 373.05107 -266.191492) (xy 373.054372 -266.195556)
			(xy 373.060898 -266.202288) (xy 373.077598 -266.210782) (xy 373.086884 -266.212066) (xy 373.092218 -266.21232)
			(xy 373.986298 -266.21232) (xy 373.996368 -266.212743) (xy 374.014971 -266.220459) (xy 374.022366 -266.227306)
			(xy 374.58396 -266.7889) (xy 374.590717 -266.795166) (xy 374.607474 -266.802794) (xy 374.62585 -266.80395)
			(xy 374.63476 -266.8016) (xy 374.73382 -266.771374) (xy 374.752616 -266.750546) (xy 374.75541 -266.73683)
			(xy 374.761043 -266.711171) (xy 374.779901 -266.662144) (xy 374.806866 -266.617065) (xy 374.841144 -266.577263)
			(xy 374.881726 -266.54391) (xy 374.927413 -266.517989) (xy 374.976861 -266.500265) (xy 375.028612 -266.49126)
			(xy 375.054876 -266.490704) (xy 375.07887 -266.491148) (xy 375.126268 -266.498652) (xy 375.171908 -266.513479)
			(xy 375.214666 -266.535263) (xy 375.25349 -266.563468) (xy 375.287424 -266.5974) (xy 375.315631 -266.636223)
			(xy 375.337417 -266.678981) (xy 375.352245 -266.724621) (xy 375.359751 -266.772018) (xy 375.360184 -266.796012)
			(xy 375.678695 -266.796012) (xy 375.68279 -266.745284) (xy 375.694969 -266.69587) (xy 375.714917 -266.64905)
			(xy 375.742118 -266.606036) (xy 375.775866 -266.567942) (xy 375.815288 -266.535755) (xy 375.859362 -266.510309)
			(xy 375.906948 -266.492262) (xy 375.956812 -266.482082) (xy 376.007664 -266.480033) (xy 376.058185 -266.486167)
			(xy 376.107069 -266.500327) (xy 376.153048 -266.522144) (xy 376.194932 -266.551054) (xy 376.231636 -266.586309)
			(xy 376.262209 -266.626995) (xy 376.28586 -266.672058) (xy 376.301976 -266.720332) (xy 376.31014 -266.770566)
			(xy 376.310652 -266.796012) (xy 376.628926 -266.796012) (xy 376.632886 -266.746958) (xy 376.644663 -266.699174)
			(xy 376.663954 -266.653898) (xy 376.690257 -266.612302) (xy 376.722892 -266.575465) (xy 376.761013 -266.54434)
			(xy 376.803634 -266.519733) (xy 376.84965 -266.502281) (xy 376.897869 -266.492437) (xy 376.947044 -266.490456)
			(xy 376.995899 -266.496388) (xy 377.04317 -266.51008) (xy 377.087632 -266.531178) (xy 377.128135 -266.559134)
			(xy 377.163628 -266.593226) (xy 377.193193 -266.63257) (xy 377.216064 -266.676147) (xy 377.231648 -266.722828)
			(xy 377.239543 -266.771405) (xy 377.240038 -266.796012) (xy 377.558549 -266.796012) (xy 377.562644 -266.745284)
			(xy 377.574823 -266.69587) (xy 377.594771 -266.64905) (xy 377.621972 -266.606036) (xy 377.65572 -266.567942)
			(xy 377.695142 -266.535755) (xy 377.739216 -266.510309) (xy 377.786802 -266.492262) (xy 377.836666 -266.482082)
			(xy 377.887518 -266.480033) (xy 377.938039 -266.486167) (xy 377.986923 -266.500327) (xy 378.032902 -266.522144)
			(xy 378.074786 -266.551054) (xy 378.11149 -266.586309) (xy 378.142063 -266.626995) (xy 378.165714 -266.672058)
			(xy 378.18183 -266.720332) (xy 378.189994 -266.770566) (xy 378.190506 -266.796012) (xy 378.509034 -266.796012)
			(xy 378.512994 -266.746958) (xy 378.524771 -266.699174) (xy 378.544062 -266.653898) (xy 378.570365 -266.612302)
			(xy 378.603 -266.575465) (xy 378.641121 -266.54434) (xy 378.683742 -266.519733) (xy 378.729758 -266.502281)
			(xy 378.777977 -266.492437) (xy 378.827152 -266.490456) (xy 378.876007 -266.496388) (xy 378.923278 -266.51008)
			(xy 378.96774 -266.531178) (xy 379.008243 -266.559134) (xy 379.043736 -266.593226) (xy 379.073301 -266.63257)
			(xy 379.096172 -266.676147) (xy 379.111756 -266.722828) (xy 379.119651 -266.771405) (xy 379.120146 -266.796012)
			(xy 379.438657 -266.796012) (xy 379.442752 -266.745284) (xy 379.454931 -266.69587) (xy 379.474879 -266.64905)
			(xy 379.50208 -266.606036) (xy 379.535828 -266.567942) (xy 379.57525 -266.535755) (xy 379.619324 -266.510309)
			(xy 379.66691 -266.492262) (xy 379.716774 -266.482082) (xy 379.767626 -266.480033) (xy 379.818147 -266.486167)
			(xy 379.867031 -266.500327) (xy 379.91301 -266.522144) (xy 379.954894 -266.551054) (xy 379.991598 -266.586309)
			(xy 380.022171 -266.626995) (xy 380.045822 -266.672058) (xy 380.061938 -266.720332) (xy 380.070102 -266.770566)
			(xy 380.070614 -266.796012) (xy 380.378711 -266.796012) (xy 380.382806 -266.745284) (xy 380.394985 -266.69587)
			(xy 380.414933 -266.64905) (xy 380.442134 -266.606036) (xy 380.475882 -266.567942) (xy 380.515304 -266.535755)
			(xy 380.559378 -266.510309) (xy 380.606964 -266.492262) (xy 380.656828 -266.482082) (xy 380.70768 -266.480033)
			(xy 380.758201 -266.486167) (xy 380.807085 -266.500327) (xy 380.853064 -266.522144) (xy 380.894948 -266.551054)
			(xy 380.931652 -266.586309) (xy 380.962225 -266.626995) (xy 380.985876 -266.672058) (xy 381.001992 -266.720332)
			(xy 381.010156 -266.770566) (xy 381.010668 -266.796012) (xy 381.328942 -266.796012) (xy 381.332902 -266.746958)
			(xy 381.344679 -266.699174) (xy 381.36397 -266.653898) (xy 381.390273 -266.612302) (xy 381.422908 -266.575465)
			(xy 381.461029 -266.54434) (xy 381.50365 -266.519733) (xy 381.549666 -266.502281) (xy 381.597885 -266.492437)
			(xy 381.64706 -266.490456) (xy 381.695915 -266.496388) (xy 381.743186 -266.51008) (xy 381.787648 -266.531178)
			(xy 381.828151 -266.559134) (xy 381.863644 -266.593226) (xy 381.893209 -266.63257) (xy 381.91608 -266.676147)
			(xy 381.931664 -266.722828) (xy 381.939559 -266.771405) (xy 381.940054 -266.796012) (xy 382.258565 -266.796012)
			(xy 382.26266 -266.745284) (xy 382.274839 -266.69587) (xy 382.294787 -266.64905) (xy 382.321988 -266.606036)
			(xy 382.355736 -266.567942) (xy 382.395158 -266.535755) (xy 382.439232 -266.510309) (xy 382.486818 -266.492262)
			(xy 382.536682 -266.482082) (xy 382.587534 -266.480033) (xy 382.638055 -266.486167) (xy 382.686939 -266.500327)
			(xy 382.732918 -266.522144) (xy 382.774802 -266.551054) (xy 382.811506 -266.586309) (xy 382.842079 -266.626995)
			(xy 382.86573 -266.672058) (xy 382.881846 -266.720332) (xy 382.89001 -266.770566) (xy 382.890522 -266.796012)
			(xy 383.20905 -266.796012) (xy 383.21301 -266.746958) (xy 383.224787 -266.699174) (xy 383.244078 -266.653898)
			(xy 383.270381 -266.612302) (xy 383.303016 -266.575465) (xy 383.341137 -266.54434) (xy 383.383758 -266.519733)
			(xy 383.429774 -266.502281) (xy 383.477993 -266.492437) (xy 383.527168 -266.490456) (xy 383.576023 -266.496388)
			(xy 383.623294 -266.51008) (xy 383.667756 -266.531178) (xy 383.708259 -266.559134) (xy 383.743752 -266.593226)
			(xy 383.773317 -266.63257) (xy 383.796188 -266.676147) (xy 383.811772 -266.722828) (xy 383.819667 -266.771405)
			(xy 383.820162 -266.796012) (xy 384.138673 -266.796012) (xy 384.142768 -266.745284) (xy 384.154947 -266.69587)
			(xy 384.174895 -266.64905) (xy 384.202096 -266.606036) (xy 384.235844 -266.567942) (xy 384.275266 -266.535755)
			(xy 384.31934 -266.510309) (xy 384.366926 -266.492262) (xy 384.41679 -266.482082) (xy 384.467642 -266.480033)
			(xy 384.518163 -266.486167) (xy 384.567047 -266.500327) (xy 384.613026 -266.522144) (xy 384.65491 -266.551054)
			(xy 384.691614 -266.586309) (xy 384.722187 -266.626995) (xy 384.745838 -266.672058) (xy 384.761954 -266.720332)
			(xy 384.770118 -266.770566) (xy 384.77063 -266.796012) (xy 385.088904 -266.796012) (xy 385.092864 -266.746958)
			(xy 385.104641 -266.699174) (xy 385.123932 -266.653898) (xy 385.150235 -266.612302) (xy 385.18287 -266.575465)
			(xy 385.220991 -266.54434) (xy 385.263612 -266.519733) (xy 385.309628 -266.502281) (xy 385.357847 -266.492437)
			(xy 385.407022 -266.490456) (xy 385.455877 -266.496388) (xy 385.503148 -266.51008) (xy 385.54761 -266.531178)
			(xy 385.588113 -266.559134) (xy 385.623606 -266.593226) (xy 385.653171 -266.63257) (xy 385.676042 -266.676147)
			(xy 385.691626 -266.722828) (xy 385.699521 -266.771405) (xy 385.700016 -266.796012) (xy 386.018527 -266.796012)
			(xy 386.022622 -266.745284) (xy 386.034801 -266.69587) (xy 386.054749 -266.64905) (xy 386.08195 -266.606036)
			(xy 386.115698 -266.567942) (xy 386.15512 -266.535755) (xy 386.199194 -266.510309) (xy 386.24678 -266.492262)
			(xy 386.296644 -266.482082) (xy 386.347496 -266.480033) (xy 386.398017 -266.486167) (xy 386.446901 -266.500327)
			(xy 386.49288 -266.522144) (xy 386.534764 -266.551054) (xy 386.571468 -266.586309) (xy 386.602041 -266.626995)
			(xy 386.625692 -266.672058) (xy 386.641808 -266.720332) (xy 386.649972 -266.770566) (xy 386.650484 -266.796012)
			(xy 386.649972 -266.821458) (xy 386.641808 -266.871692) (xy 386.625692 -266.919966) (xy 386.602041 -266.965029)
			(xy 386.571468 -267.005715) (xy 386.534764 -267.04097) (xy 386.49288 -267.06988) (xy 386.446901 -267.091697)
			(xy 386.398017 -267.105857) (xy 386.347496 -267.111991) (xy 386.296644 -267.109942) (xy 386.24678 -267.099762)
			(xy 386.199194 -267.081715) (xy 386.15512 -267.056269) (xy 386.115698 -267.024082) (xy 386.08195 -266.985988)
			(xy 386.054749 -266.942974) (xy 386.034801 -266.896154) (xy 386.022622 -266.84674) (xy 386.018527 -266.796012)
			(xy 385.700016 -266.796012) (xy 385.699521 -266.820619) (xy 385.691626 -266.869196) (xy 385.676042 -266.915877)
			(xy 385.653171 -266.959454) (xy 385.623606 -266.998798) (xy 385.588113 -267.03289) (xy 385.54761 -267.060846)
			(xy 385.503148 -267.081944) (xy 385.455877 -267.095636) (xy 385.407022 -267.101568) (xy 385.357847 -267.099587)
			(xy 385.309628 -267.089743) (xy 385.263612 -267.072291) (xy 385.220991 -267.047684) (xy 385.18287 -267.016559)
			(xy 385.150235 -266.979722) (xy 385.123932 -266.938126) (xy 385.104641 -266.89285) (xy 385.092864 -266.845066)
			(xy 385.088904 -266.796012) (xy 384.77063 -266.796012) (xy 384.770118 -266.821458) (xy 384.761954 -266.871692)
			(xy 384.745838 -266.919966) (xy 384.722187 -266.965029) (xy 384.691614 -267.005715) (xy 384.65491 -267.04097)
			(xy 384.613026 -267.06988) (xy 384.567047 -267.091697) (xy 384.518163 -267.105857) (xy 384.467642 -267.111991)
			(xy 384.41679 -267.109942) (xy 384.366926 -267.099762) (xy 384.31934 -267.081715) (xy 384.275266 -267.056269)
			(xy 384.235844 -267.024082) (xy 384.202096 -266.985988) (xy 384.174895 -266.942974) (xy 384.154947 -266.896154)
			(xy 384.142768 -266.84674) (xy 384.138673 -266.796012) (xy 383.820162 -266.796012) (xy 383.819667 -266.820619)
			(xy 383.811772 -266.869196) (xy 383.796188 -266.915877) (xy 383.773317 -266.959454) (xy 383.743752 -266.998798)
			(xy 383.708259 -267.03289) (xy 383.667756 -267.060846) (xy 383.623294 -267.081944) (xy 383.576023 -267.095636)
			(xy 383.527168 -267.101568) (xy 383.477993 -267.099587) (xy 383.429774 -267.089743) (xy 383.383758 -267.072291)
			(xy 383.341137 -267.047684) (xy 383.303016 -267.016559) (xy 383.270381 -266.979722) (xy 383.244078 -266.938126)
			(xy 383.224787 -266.89285) (xy 383.21301 -266.845066) (xy 383.20905 -266.796012) (xy 382.890522 -266.796012)
			(xy 382.89001 -266.821458) (xy 382.881846 -266.871692) (xy 382.86573 -266.919966) (xy 382.842079 -266.965029)
			(xy 382.811506 -267.005715) (xy 382.774802 -267.04097) (xy 382.732918 -267.06988) (xy 382.686939 -267.091697)
			(xy 382.638055 -267.105857) (xy 382.587534 -267.111991) (xy 382.536682 -267.109942) (xy 382.486818 -267.099762)
			(xy 382.439232 -267.081715) (xy 382.395158 -267.056269) (xy 382.355736 -267.024082) (xy 382.321988 -266.985988)
			(xy 382.294787 -266.942974) (xy 382.274839 -266.896154) (xy 382.26266 -266.84674) (xy 382.258565 -266.796012)
			(xy 381.940054 -266.796012) (xy 381.939559 -266.820619) (xy 381.931664 -266.869196) (xy 381.91608 -266.915877)
			(xy 381.893209 -266.959454) (xy 381.863644 -266.998798) (xy 381.828151 -267.03289) (xy 381.787648 -267.060846)
			(xy 381.743186 -267.081944) (xy 381.695915 -267.095636) (xy 381.64706 -267.101568) (xy 381.597885 -267.099587)
			(xy 381.549666 -267.089743) (xy 381.50365 -267.072291) (xy 381.461029 -267.047684) (xy 381.422908 -267.016559)
			(xy 381.390273 -266.979722) (xy 381.36397 -266.938126) (xy 381.344679 -266.89285) (xy 381.332902 -266.845066)
			(xy 381.328942 -266.796012) (xy 381.010668 -266.796012) (xy 381.010156 -266.821458) (xy 381.001992 -266.871692)
			(xy 380.985876 -266.919966) (xy 380.962225 -266.965029) (xy 380.931652 -267.005715) (xy 380.894948 -267.04097)
			(xy 380.853064 -267.06988) (xy 380.807085 -267.091697) (xy 380.758201 -267.105857) (xy 380.70768 -267.111991)
			(xy 380.656828 -267.109942) (xy 380.606964 -267.099762) (xy 380.559378 -267.081715) (xy 380.515304 -267.056269)
			(xy 380.475882 -267.024082) (xy 380.442134 -266.985988) (xy 380.414933 -266.942974) (xy 380.394985 -266.896154)
			(xy 380.382806 -266.84674) (xy 380.378711 -266.796012) (xy 380.070614 -266.796012) (xy 380.070102 -266.821458)
			(xy 380.061938 -266.871692) (xy 380.045822 -266.919966) (xy 380.022171 -266.965029) (xy 379.991598 -267.005715)
			(xy 379.954894 -267.04097) (xy 379.91301 -267.06988) (xy 379.867031 -267.091697) (xy 379.818147 -267.105857)
			(xy 379.767626 -267.111991) (xy 379.716774 -267.109942) (xy 379.66691 -267.099762) (xy 379.619324 -267.081715)
			(xy 379.57525 -267.056269) (xy 379.535828 -267.024082) (xy 379.50208 -266.985988) (xy 379.474879 -266.942974)
			(xy 379.454931 -266.896154) (xy 379.442752 -266.84674) (xy 379.438657 -266.796012) (xy 379.120146 -266.796012)
			(xy 379.119651 -266.820619) (xy 379.111756 -266.869196) (xy 379.096172 -266.915877) (xy 379.073301 -266.959454)
			(xy 379.043736 -266.998798) (xy 379.008243 -267.03289) (xy 378.96774 -267.060846) (xy 378.923278 -267.081944)
			(xy 378.876007 -267.095636) (xy 378.827152 -267.101568) (xy 378.777977 -267.099587) (xy 378.729758 -267.089743)
			(xy 378.683742 -267.072291) (xy 378.641121 -267.047684) (xy 378.603 -267.016559) (xy 378.570365 -266.979722)
			(xy 378.544062 -266.938126) (xy 378.524771 -266.89285) (xy 378.512994 -266.845066) (xy 378.509034 -266.796012)
			(xy 378.190506 -266.796012) (xy 378.189994 -266.821458) (xy 378.18183 -266.871692) (xy 378.165714 -266.919966)
			(xy 378.142063 -266.965029) (xy 378.11149 -267.005715) (xy 378.074786 -267.04097) (xy 378.032902 -267.06988)
			(xy 377.986923 -267.091697) (xy 377.938039 -267.105857) (xy 377.887518 -267.111991) (xy 377.836666 -267.109942)
			(xy 377.786802 -267.099762) (xy 377.739216 -267.081715) (xy 377.695142 -267.056269) (xy 377.65572 -267.024082)
			(xy 377.621972 -266.985988) (xy 377.594771 -266.942974) (xy 377.574823 -266.896154) (xy 377.562644 -266.84674)
			(xy 377.558549 -266.796012) (xy 377.240038 -266.796012) (xy 377.239543 -266.820619) (xy 377.231648 -266.869196)
			(xy 377.216064 -266.915877) (xy 377.193193 -266.959454) (xy 377.163628 -266.998798) (xy 377.128135 -267.03289)
			(xy 377.087632 -267.060846) (xy 377.04317 -267.081944) (xy 376.995899 -267.095636) (xy 376.947044 -267.101568)
			(xy 376.897869 -267.099587) (xy 376.84965 -267.089743) (xy 376.803634 -267.072291) (xy 376.761013 -267.047684)
			(xy 376.722892 -267.016559) (xy 376.690257 -266.979722) (xy 376.663954 -266.938126) (xy 376.644663 -266.89285)
			(xy 376.632886 -266.845066) (xy 376.628926 -266.796012) (xy 376.310652 -266.796012) (xy 376.31014 -266.821458)
			(xy 376.301976 -266.871692) (xy 376.28586 -266.919966) (xy 376.262209 -266.965029) (xy 376.231636 -267.005715)
			(xy 376.194932 -267.04097) (xy 376.153048 -267.06988) (xy 376.107069 -267.091697) (xy 376.058185 -267.105857)
			(xy 376.007664 -267.111991) (xy 375.956812 -267.109942) (xy 375.906948 -267.099762) (xy 375.859362 -267.081715)
			(xy 375.815288 -267.056269) (xy 375.775866 -267.024082) (xy 375.742118 -266.985988) (xy 375.714917 -266.942974)
			(xy 375.694969 -266.896154) (xy 375.68279 -266.84674) (xy 375.678695 -266.796012) (xy 375.360184 -266.796012)
			(xy 375.359644 -266.822282) (xy 375.350665 -266.874048) (xy 375.332956 -266.923513) (xy 375.307041 -266.969216)
			(xy 375.273684 -267.009807) (xy 375.23387 -267.04409) (xy 375.188776 -267.07105) (xy 375.139732 -267.089892)
			(xy 375.114058 -267.095478) (xy 375.100342 -267.098272) (xy 375.079514 -267.117068) (xy 375.049288 -267.216128)
			(xy 375.047 -267.225042) (xy 375.048201 -267.243392) (xy 375.055756 -267.260158) (xy 375.061988 -267.266928)
			(xy 375.181114 -267.386054) (xy 375.187961 -267.393451) (xy 375.195689 -267.412051) (xy 375.1961 -267.422122)
			(xy 375.1961 -267.606018) (xy 376.159026 -267.606018) (xy 376.162986 -267.556964) (xy 376.174763 -267.50918)
			(xy 376.194054 -267.463904) (xy 376.220357 -267.422308) (xy 376.252992 -267.385471) (xy 376.291113 -267.354346)
			(xy 376.333734 -267.329739) (xy 376.37975 -267.312287) (xy 376.427969 -267.302443) (xy 376.477144 -267.300462)
			(xy 376.525999 -267.306394) (xy 376.57327 -267.320086) (xy 376.617732 -267.341184) (xy 376.658235 -267.36914)
			(xy 376.693728 -267.403232) (xy 376.723293 -267.442576) (xy 376.746164 -267.486153) (xy 376.761748 -267.532834)
			(xy 376.769643 -267.581411) (xy 376.770138 -267.606018) (xy 377.088649 -267.606018) (xy 377.092744 -267.55529)
			(xy 377.104923 -267.505876) (xy 377.124871 -267.459056) (xy 377.152072 -267.416042) (xy 377.18582 -267.377948)
			(xy 377.225242 -267.345761) (xy 377.269316 -267.320315) (xy 377.316902 -267.302268) (xy 377.366766 -267.292088)
			(xy 377.417618 -267.290039) (xy 377.468139 -267.296173) (xy 377.517023 -267.310333) (xy 377.563002 -267.33215)
			(xy 377.604886 -267.36106) (xy 377.64159 -267.396315) (xy 377.672163 -267.437001) (xy 377.695814 -267.482064)
			(xy 377.71193 -267.530338) (xy 377.720094 -267.580572) (xy 377.720606 -267.606018) (xy 378.039134 -267.606018)
			(xy 378.043094 -267.556964) (xy 378.054871 -267.50918) (xy 378.074162 -267.463904) (xy 378.100465 -267.422308)
			(xy 378.1331 -267.385471) (xy 378.171221 -267.354346) (xy 378.213842 -267.329739) (xy 378.259858 -267.312287)
			(xy 378.308077 -267.302443) (xy 378.357252 -267.300462) (xy 378.406107 -267.306394) (xy 378.453378 -267.320086)
			(xy 378.49784 -267.341184) (xy 378.538343 -267.36914) (xy 378.573836 -267.403232) (xy 378.603401 -267.442576)
			(xy 378.626272 -267.486153) (xy 378.641856 -267.532834) (xy 378.649751 -267.581411) (xy 378.650246 -267.606018)
			(xy 378.978934 -267.606018) (xy 378.982894 -267.556964) (xy 378.994671 -267.50918) (xy 379.013962 -267.463904)
			(xy 379.040265 -267.422308) (xy 379.0729 -267.385471) (xy 379.111021 -267.354346) (xy 379.153642 -267.329739)
			(xy 379.199658 -267.312287) (xy 379.247877 -267.302443) (xy 379.297052 -267.300462) (xy 379.345907 -267.306394)
			(xy 379.393178 -267.320086) (xy 379.43764 -267.341184) (xy 379.478143 -267.36914) (xy 379.513636 -267.403232)
			(xy 379.543201 -267.442576) (xy 379.566072 -267.486153) (xy 379.581656 -267.532834) (xy 379.589551 -267.581411)
			(xy 379.590046 -267.606018) (xy 379.918988 -267.606018) (xy 379.922948 -267.556964) (xy 379.934725 -267.50918)
			(xy 379.954016 -267.463904) (xy 379.980319 -267.422308) (xy 380.012954 -267.385471) (xy 380.051075 -267.354346)
			(xy 380.093696 -267.329739) (xy 380.139712 -267.312287) (xy 380.187931 -267.302443) (xy 380.237106 -267.300462)
			(xy 380.285961 -267.306394) (xy 380.333232 -267.320086) (xy 380.377694 -267.341184) (xy 380.418197 -267.36914)
			(xy 380.45369 -267.403232) (xy 380.483255 -267.442576) (xy 380.506126 -267.486153) (xy 380.52171 -267.532834)
			(xy 380.529605 -267.581411) (xy 380.5301 -267.606018) (xy 380.848611 -267.606018) (xy 380.852706 -267.55529)
			(xy 380.864885 -267.505876) (xy 380.884833 -267.459056) (xy 380.912034 -267.416042) (xy 380.945782 -267.377948)
			(xy 380.985204 -267.345761) (xy 381.029278 -267.320315) (xy 381.076864 -267.302268) (xy 381.126728 -267.292088)
			(xy 381.17758 -267.290039) (xy 381.228101 -267.296173) (xy 381.276985 -267.310333) (xy 381.322964 -267.33215)
			(xy 381.364848 -267.36106) (xy 381.401552 -267.396315) (xy 381.432125 -267.437001) (xy 381.455776 -267.482064)
			(xy 381.471892 -267.530338) (xy 381.480056 -267.580572) (xy 381.480568 -267.606018) (xy 381.799096 -267.606018)
			(xy 381.803056 -267.556964) (xy 381.814833 -267.50918) (xy 381.834124 -267.463904) (xy 381.860427 -267.422308)
			(xy 381.893062 -267.385471) (xy 381.931183 -267.354346) (xy 381.973804 -267.329739) (xy 382.01982 -267.312287)
			(xy 382.068039 -267.302443) (xy 382.117214 -267.300462) (xy 382.166069 -267.306394) (xy 382.21334 -267.320086)
			(xy 382.257802 -267.341184) (xy 382.298305 -267.36914) (xy 382.333798 -267.403232) (xy 382.363363 -267.442576)
			(xy 382.386234 -267.486153) (xy 382.401818 -267.532834) (xy 382.409713 -267.581411) (xy 382.410208 -267.606018)
			(xy 382.738896 -267.606018) (xy 382.742856 -267.556964) (xy 382.754633 -267.50918) (xy 382.773924 -267.463904)
			(xy 382.800227 -267.422308) (xy 382.832862 -267.385471) (xy 382.870983 -267.354346) (xy 382.913604 -267.329739)
			(xy 382.95962 -267.312287) (xy 383.007839 -267.302443) (xy 383.057014 -267.300462) (xy 383.105869 -267.306394)
			(xy 383.15314 -267.320086) (xy 383.197602 -267.341184) (xy 383.238105 -267.36914) (xy 383.273598 -267.403232)
			(xy 383.303163 -267.442576) (xy 383.326034 -267.486153) (xy 383.341618 -267.532834) (xy 383.349513 -267.581411)
			(xy 383.350008 -267.606018) (xy 383.668519 -267.606018) (xy 383.672614 -267.55529) (xy 383.684793 -267.505876)
			(xy 383.704741 -267.459056) (xy 383.731942 -267.416042) (xy 383.76569 -267.377948) (xy 383.805112 -267.345761)
			(xy 383.849186 -267.320315) (xy 383.896772 -267.302268) (xy 383.946636 -267.292088) (xy 383.997488 -267.290039)
			(xy 384.048009 -267.296173) (xy 384.096893 -267.310333) (xy 384.142872 -267.33215) (xy 384.184756 -267.36106)
			(xy 384.22146 -267.396315) (xy 384.252033 -267.437001) (xy 384.275684 -267.482064) (xy 384.2918 -267.530338)
			(xy 384.299964 -267.580572) (xy 384.300476 -267.606018) (xy 384.619004 -267.606018) (xy 384.622964 -267.556964)
			(xy 384.634741 -267.50918) (xy 384.654032 -267.463904) (xy 384.680335 -267.422308) (xy 384.71297 -267.385471)
			(xy 384.751091 -267.354346) (xy 384.793712 -267.329739) (xy 384.839728 -267.312287) (xy 384.887947 -267.302443)
			(xy 384.937122 -267.300462) (xy 384.985977 -267.306394) (xy 385.033248 -267.320086) (xy 385.07771 -267.341184)
			(xy 385.118213 -267.36914) (xy 385.153706 -267.403232) (xy 385.183271 -267.442576) (xy 385.206142 -267.486153)
			(xy 385.221726 -267.532834) (xy 385.229621 -267.581411) (xy 385.230116 -267.606018) (xy 385.559058 -267.606018)
			(xy 385.563018 -267.556964) (xy 385.574795 -267.50918) (xy 385.594086 -267.463904) (xy 385.620389 -267.422308)
			(xy 385.653024 -267.385471) (xy 385.691145 -267.354346) (xy 385.733766 -267.329739) (xy 385.779782 -267.312287)
			(xy 385.828001 -267.302443) (xy 385.877176 -267.300462) (xy 385.926031 -267.306394) (xy 385.973302 -267.320086)
			(xy 386.017764 -267.341184) (xy 386.058267 -267.36914) (xy 386.09376 -267.403232) (xy 386.123325 -267.442576)
			(xy 386.146196 -267.486153) (xy 386.16178 -267.532834) (xy 386.169675 -267.581411) (xy 386.17017 -267.606018)
			(xy 386.499112 -267.606018) (xy 386.503072 -267.556964) (xy 386.514849 -267.50918) (xy 386.53414 -267.463904)
			(xy 386.560443 -267.422308) (xy 386.593078 -267.385471) (xy 386.631199 -267.354346) (xy 386.67382 -267.329739)
			(xy 386.719836 -267.312287) (xy 386.768055 -267.302443) (xy 386.81723 -267.300462) (xy 386.866085 -267.306394)
			(xy 386.913356 -267.320086) (xy 386.957818 -267.341184) (xy 386.998321 -267.36914) (xy 387.033814 -267.403232)
			(xy 387.063379 -267.442576) (xy 387.08625 -267.486153) (xy 387.101834 -267.532834) (xy 387.109729 -267.581411)
			(xy 387.110224 -267.606018) (xy 387.428481 -267.606018) (xy 387.432576 -267.55529) (xy 387.444755 -267.505876)
			(xy 387.464703 -267.459056) (xy 387.491904 -267.416042) (xy 387.525652 -267.377948) (xy 387.565074 -267.345761)
			(xy 387.609148 -267.320315) (xy 387.656734 -267.302268) (xy 387.706598 -267.292088) (xy 387.75745 -267.290039)
			(xy 387.807971 -267.296173) (xy 387.856855 -267.310333) (xy 387.902834 -267.33215) (xy 387.944718 -267.36106)
			(xy 387.981422 -267.396315) (xy 388.011995 -267.437001) (xy 388.035646 -267.482064) (xy 388.051762 -267.530338)
			(xy 388.059926 -267.580572) (xy 388.060438 -267.606018) (xy 388.378966 -267.606018) (xy 388.382926 -267.556964)
			(xy 388.394703 -267.50918) (xy 388.413994 -267.463904) (xy 388.440297 -267.422308) (xy 388.472932 -267.385471)
			(xy 388.511053 -267.354346) (xy 388.553674 -267.329739) (xy 388.59969 -267.312287) (xy 388.647909 -267.302443)
			(xy 388.697084 -267.300462) (xy 388.745939 -267.306394) (xy 388.79321 -267.320086) (xy 388.837672 -267.341184)
			(xy 388.878175 -267.36914) (xy 388.913668 -267.403232) (xy 388.943233 -267.442576) (xy 388.966104 -267.486153)
			(xy 388.981688 -267.532834) (xy 388.989583 -267.581411) (xy 388.990078 -267.606018) (xy 389.31902 -267.606018)
			(xy 389.32298 -267.556964) (xy 389.334757 -267.50918) (xy 389.354048 -267.463904) (xy 389.380351 -267.422308)
			(xy 389.412986 -267.385471) (xy 389.451107 -267.354346) (xy 389.493728 -267.329739) (xy 389.539744 -267.312287)
			(xy 389.587963 -267.302443) (xy 389.637138 -267.300462) (xy 389.685993 -267.306394) (xy 389.733264 -267.320086)
			(xy 389.777726 -267.341184) (xy 389.818229 -267.36914) (xy 389.853722 -267.403232) (xy 389.883287 -267.442576)
			(xy 389.906158 -267.486153) (xy 389.921742 -267.532834) (xy 389.929637 -267.581411) (xy 389.930132 -267.606018)
			(xy 390.248643 -267.606018) (xy 390.252738 -267.55529) (xy 390.264917 -267.505876) (xy 390.284865 -267.459056)
			(xy 390.312066 -267.416042) (xy 390.345814 -267.377948) (xy 390.385236 -267.345761) (xy 390.42931 -267.320315)
			(xy 390.476896 -267.302268) (xy 390.52676 -267.292088) (xy 390.577612 -267.290039) (xy 390.628133 -267.296173)
			(xy 390.677017 -267.310333) (xy 390.722996 -267.33215) (xy 390.76488 -267.36106) (xy 390.801584 -267.396315)
			(xy 390.832157 -267.437001) (xy 390.855808 -267.482064) (xy 390.871924 -267.530338) (xy 390.880088 -267.580572)
			(xy 390.8806 -267.606018) (xy 391.198874 -267.606018) (xy 391.202834 -267.556964) (xy 391.214611 -267.50918)
			(xy 391.233902 -267.463904) (xy 391.260205 -267.422308) (xy 391.29284 -267.385471) (xy 391.330961 -267.354346)
			(xy 391.373582 -267.329739) (xy 391.419598 -267.312287) (xy 391.467817 -267.302443) (xy 391.516992 -267.300462)
			(xy 391.565847 -267.306394) (xy 391.613118 -267.320086) (xy 391.65758 -267.341184) (xy 391.698083 -267.36914)
			(xy 391.733576 -267.403232) (xy 391.763141 -267.442576) (xy 391.786012 -267.486153) (xy 391.801596 -267.532834)
			(xy 391.809491 -267.581411) (xy 391.809986 -267.606018) (xy 393.078982 -267.606018) (xy 393.082942 -267.556964)
			(xy 393.094719 -267.50918) (xy 393.11401 -267.463904) (xy 393.140313 -267.422308) (xy 393.172948 -267.385471)
			(xy 393.211069 -267.354346) (xy 393.25369 -267.329739) (xy 393.299706 -267.312287) (xy 393.347925 -267.302443)
			(xy 393.3971 -267.300462) (xy 393.445955 -267.306394) (xy 393.493226 -267.320086) (xy 393.537688 -267.341184)
			(xy 393.578191 -267.36914) (xy 393.613684 -267.403232) (xy 393.643249 -267.442576) (xy 393.66612 -267.486153)
			(xy 393.681704 -267.532834) (xy 393.689599 -267.581411) (xy 393.690094 -267.606018) (xy 393.689599 -267.630625)
			(xy 393.681704 -267.679202) (xy 393.66612 -267.725883) (xy 393.643249 -267.76946) (xy 393.613684 -267.808804)
			(xy 393.578191 -267.842896) (xy 393.537688 -267.870852) (xy 393.493226 -267.89195) (xy 393.445955 -267.905642)
			(xy 393.3971 -267.911574) (xy 393.347925 -267.909593) (xy 393.299706 -267.899749) (xy 393.25369 -267.882297)
			(xy 393.211069 -267.85769) (xy 393.172948 -267.826565) (xy 393.140313 -267.789728) (xy 393.11401 -267.748132)
			(xy 393.094719 -267.702856) (xy 393.082942 -267.655072) (xy 393.078982 -267.606018) (xy 391.809986 -267.606018)
			(xy 391.809491 -267.630625) (xy 391.801596 -267.679202) (xy 391.786012 -267.725883) (xy 391.763141 -267.76946)
			(xy 391.733576 -267.808804) (xy 391.698083 -267.842896) (xy 391.65758 -267.870852) (xy 391.613118 -267.89195)
			(xy 391.565847 -267.905642) (xy 391.516992 -267.911574) (xy 391.467817 -267.909593) (xy 391.419598 -267.899749)
			(xy 391.373582 -267.882297) (xy 391.330961 -267.85769) (xy 391.29284 -267.826565) (xy 391.260205 -267.789728)
			(xy 391.233902 -267.748132) (xy 391.214611 -267.702856) (xy 391.202834 -267.655072) (xy 391.198874 -267.606018)
			(xy 390.8806 -267.606018) (xy 390.880088 -267.631464) (xy 390.871924 -267.681698) (xy 390.855808 -267.729972)
			(xy 390.832157 -267.775035) (xy 390.801584 -267.815721) (xy 390.76488 -267.850976) (xy 390.722996 -267.879886)
			(xy 390.677017 -267.901703) (xy 390.628133 -267.915863) (xy 390.577612 -267.921997) (xy 390.52676 -267.919948)
			(xy 390.476896 -267.909768) (xy 390.42931 -267.891721) (xy 390.385236 -267.866275) (xy 390.345814 -267.834088)
			(xy 390.312066 -267.795994) (xy 390.284865 -267.75298) (xy 390.264917 -267.70616) (xy 390.252738 -267.656746)
			(xy 390.248643 -267.606018) (xy 389.930132 -267.606018) (xy 389.929637 -267.630625) (xy 389.921742 -267.679202)
			(xy 389.906158 -267.725883) (xy 389.883287 -267.76946) (xy 389.853722 -267.808804) (xy 389.818229 -267.842896)
			(xy 389.777726 -267.870852) (xy 389.733264 -267.89195) (xy 389.685993 -267.905642) (xy 389.637138 -267.911574)
			(xy 389.587963 -267.909593) (xy 389.539744 -267.899749) (xy 389.493728 -267.882297) (xy 389.451107 -267.85769)
			(xy 389.412986 -267.826565) (xy 389.380351 -267.789728) (xy 389.354048 -267.748132) (xy 389.334757 -267.702856)
			(xy 389.32298 -267.655072) (xy 389.31902 -267.606018) (xy 388.990078 -267.606018) (xy 388.989583 -267.630625)
			(xy 388.981688 -267.679202) (xy 388.966104 -267.725883) (xy 388.943233 -267.76946) (xy 388.913668 -267.808804)
			(xy 388.878175 -267.842896) (xy 388.837672 -267.870852) (xy 388.79321 -267.89195) (xy 388.745939 -267.905642)
			(xy 388.697084 -267.911574) (xy 388.647909 -267.909593) (xy 388.59969 -267.899749) (xy 388.553674 -267.882297)
			(xy 388.511053 -267.85769) (xy 388.472932 -267.826565) (xy 388.440297 -267.789728) (xy 388.413994 -267.748132)
			(xy 388.394703 -267.702856) (xy 388.382926 -267.655072) (xy 388.378966 -267.606018) (xy 388.060438 -267.606018)
			(xy 388.059926 -267.631464) (xy 388.051762 -267.681698) (xy 388.035646 -267.729972) (xy 388.011995 -267.775035)
			(xy 387.981422 -267.815721) (xy 387.944718 -267.850976) (xy 387.902834 -267.879886) (xy 387.856855 -267.901703)
			(xy 387.807971 -267.915863) (xy 387.75745 -267.921997) (xy 387.706598 -267.919948) (xy 387.656734 -267.909768)
			(xy 387.609148 -267.891721) (xy 387.565074 -267.866275) (xy 387.525652 -267.834088) (xy 387.491904 -267.795994)
			(xy 387.464703 -267.75298) (xy 387.444755 -267.70616) (xy 387.432576 -267.656746) (xy 387.428481 -267.606018)
			(xy 387.110224 -267.606018) (xy 387.109729 -267.630625) (xy 387.101834 -267.679202) (xy 387.08625 -267.725883)
			(xy 387.063379 -267.76946) (xy 387.033814 -267.808804) (xy 386.998321 -267.842896) (xy 386.957818 -267.870852)
			(xy 386.913356 -267.89195) (xy 386.866085 -267.905642) (xy 386.81723 -267.911574) (xy 386.768055 -267.909593)
			(xy 386.719836 -267.899749) (xy 386.67382 -267.882297) (xy 386.631199 -267.85769) (xy 386.593078 -267.826565)
			(xy 386.560443 -267.789728) (xy 386.53414 -267.748132) (xy 386.514849 -267.702856) (xy 386.503072 -267.655072)
			(xy 386.499112 -267.606018) (xy 386.17017 -267.606018) (xy 386.169675 -267.630625) (xy 386.16178 -267.679202)
			(xy 386.146196 -267.725883) (xy 386.123325 -267.76946) (xy 386.09376 -267.808804) (xy 386.058267 -267.842896)
			(xy 386.017764 -267.870852) (xy 385.973302 -267.89195) (xy 385.926031 -267.905642) (xy 385.877176 -267.911574)
			(xy 385.828001 -267.909593) (xy 385.779782 -267.899749) (xy 385.733766 -267.882297) (xy 385.691145 -267.85769)
			(xy 385.653024 -267.826565) (xy 385.620389 -267.789728) (xy 385.594086 -267.748132) (xy 385.574795 -267.702856)
			(xy 385.563018 -267.655072) (xy 385.559058 -267.606018) (xy 385.230116 -267.606018) (xy 385.229621 -267.630625)
			(xy 385.221726 -267.679202) (xy 385.206142 -267.725883) (xy 385.183271 -267.76946) (xy 385.153706 -267.808804)
			(xy 385.118213 -267.842896) (xy 385.07771 -267.870852) (xy 385.033248 -267.89195) (xy 384.985977 -267.905642)
			(xy 384.937122 -267.911574) (xy 384.887947 -267.909593) (xy 384.839728 -267.899749) (xy 384.793712 -267.882297)
			(xy 384.751091 -267.85769) (xy 384.71297 -267.826565) (xy 384.680335 -267.789728) (xy 384.654032 -267.748132)
			(xy 384.634741 -267.702856) (xy 384.622964 -267.655072) (xy 384.619004 -267.606018) (xy 384.300476 -267.606018)
			(xy 384.299964 -267.631464) (xy 384.2918 -267.681698) (xy 384.275684 -267.729972) (xy 384.252033 -267.775035)
			(xy 384.22146 -267.815721) (xy 384.184756 -267.850976) (xy 384.142872 -267.879886) (xy 384.096893 -267.901703)
			(xy 384.048009 -267.915863) (xy 383.997488 -267.921997) (xy 383.946636 -267.919948) (xy 383.896772 -267.909768)
			(xy 383.849186 -267.891721) (xy 383.805112 -267.866275) (xy 383.76569 -267.834088) (xy 383.731942 -267.795994)
			(xy 383.704741 -267.75298) (xy 383.684793 -267.70616) (xy 383.672614 -267.656746) (xy 383.668519 -267.606018)
			(xy 383.350008 -267.606018) (xy 383.349513 -267.630625) (xy 383.341618 -267.679202) (xy 383.326034 -267.725883)
			(xy 383.303163 -267.76946) (xy 383.273598 -267.808804) (xy 383.238105 -267.842896) (xy 383.197602 -267.870852)
			(xy 383.15314 -267.89195) (xy 383.105869 -267.905642) (xy 383.057014 -267.911574) (xy 383.007839 -267.909593)
			(xy 382.95962 -267.899749) (xy 382.913604 -267.882297) (xy 382.870983 -267.85769) (xy 382.832862 -267.826565)
			(xy 382.800227 -267.789728) (xy 382.773924 -267.748132) (xy 382.754633 -267.702856) (xy 382.742856 -267.655072)
			(xy 382.738896 -267.606018) (xy 382.410208 -267.606018) (xy 382.409713 -267.630625) (xy 382.401818 -267.679202)
			(xy 382.386234 -267.725883) (xy 382.363363 -267.76946) (xy 382.333798 -267.808804) (xy 382.298305 -267.842896)
			(xy 382.257802 -267.870852) (xy 382.21334 -267.89195) (xy 382.166069 -267.905642) (xy 382.117214 -267.911574)
			(xy 382.068039 -267.909593) (xy 382.01982 -267.899749) (xy 381.973804 -267.882297) (xy 381.931183 -267.85769)
			(xy 381.893062 -267.826565) (xy 381.860427 -267.789728) (xy 381.834124 -267.748132) (xy 381.814833 -267.702856)
			(xy 381.803056 -267.655072) (xy 381.799096 -267.606018) (xy 381.480568 -267.606018) (xy 381.480056 -267.631464)
			(xy 381.471892 -267.681698) (xy 381.455776 -267.729972) (xy 381.432125 -267.775035) (xy 381.401552 -267.815721)
			(xy 381.364848 -267.850976) (xy 381.322964 -267.879886) (xy 381.276985 -267.901703) (xy 381.228101 -267.915863)
			(xy 381.17758 -267.921997) (xy 381.126728 -267.919948) (xy 381.076864 -267.909768) (xy 381.029278 -267.891721)
			(xy 380.985204 -267.866275) (xy 380.945782 -267.834088) (xy 380.912034 -267.795994) (xy 380.884833 -267.75298)
			(xy 380.864885 -267.70616) (xy 380.852706 -267.656746) (xy 380.848611 -267.606018) (xy 380.5301 -267.606018)
			(xy 380.529605 -267.630625) (xy 380.52171 -267.679202) (xy 380.506126 -267.725883) (xy 380.483255 -267.76946)
			(xy 380.45369 -267.808804) (xy 380.418197 -267.842896) (xy 380.377694 -267.870852) (xy 380.333232 -267.89195)
			(xy 380.285961 -267.905642) (xy 380.237106 -267.911574) (xy 380.187931 -267.909593) (xy 380.139712 -267.899749)
			(xy 380.093696 -267.882297) (xy 380.051075 -267.85769) (xy 380.012954 -267.826565) (xy 379.980319 -267.789728)
			(xy 379.954016 -267.748132) (xy 379.934725 -267.702856) (xy 379.922948 -267.655072) (xy 379.918988 -267.606018)
			(xy 379.590046 -267.606018) (xy 379.589551 -267.630625) (xy 379.581656 -267.679202) (xy 379.566072 -267.725883)
			(xy 379.543201 -267.76946) (xy 379.513636 -267.808804) (xy 379.478143 -267.842896) (xy 379.43764 -267.870852)
			(xy 379.393178 -267.89195) (xy 379.345907 -267.905642) (xy 379.297052 -267.911574) (xy 379.247877 -267.909593)
			(xy 379.199658 -267.899749) (xy 379.153642 -267.882297) (xy 379.111021 -267.85769) (xy 379.0729 -267.826565)
			(xy 379.040265 -267.789728) (xy 379.013962 -267.748132) (xy 378.994671 -267.702856) (xy 378.982894 -267.655072)
			(xy 378.978934 -267.606018) (xy 378.650246 -267.606018) (xy 378.649751 -267.630625) (xy 378.641856 -267.679202)
			(xy 378.626272 -267.725883) (xy 378.603401 -267.76946) (xy 378.573836 -267.808804) (xy 378.538343 -267.842896)
			(xy 378.49784 -267.870852) (xy 378.453378 -267.89195) (xy 378.406107 -267.905642) (xy 378.357252 -267.911574)
			(xy 378.308077 -267.909593) (xy 378.259858 -267.899749) (xy 378.213842 -267.882297) (xy 378.171221 -267.85769)
			(xy 378.1331 -267.826565) (xy 378.100465 -267.789728) (xy 378.074162 -267.748132) (xy 378.054871 -267.702856)
			(xy 378.043094 -267.655072) (xy 378.039134 -267.606018) (xy 377.720606 -267.606018) (xy 377.720094 -267.631464)
			(xy 377.71193 -267.681698) (xy 377.695814 -267.729972) (xy 377.672163 -267.775035) (xy 377.64159 -267.815721)
			(xy 377.604886 -267.850976) (xy 377.563002 -267.879886) (xy 377.517023 -267.901703) (xy 377.468139 -267.915863)
			(xy 377.417618 -267.921997) (xy 377.366766 -267.919948) (xy 377.316902 -267.909768) (xy 377.269316 -267.891721)
			(xy 377.225242 -267.866275) (xy 377.18582 -267.834088) (xy 377.152072 -267.795994) (xy 377.124871 -267.75298)
			(xy 377.104923 -267.70616) (xy 377.092744 -267.656746) (xy 377.088649 -267.606018) (xy 376.770138 -267.606018)
			(xy 376.769643 -267.630625) (xy 376.761748 -267.679202) (xy 376.746164 -267.725883) (xy 376.723293 -267.76946)
			(xy 376.693728 -267.808804) (xy 376.658235 -267.842896) (xy 376.617732 -267.870852) (xy 376.57327 -267.89195)
			(xy 376.525999 -267.905642) (xy 376.477144 -267.911574) (xy 376.427969 -267.909593) (xy 376.37975 -267.899749)
			(xy 376.333734 -267.882297) (xy 376.291113 -267.85769) (xy 376.252992 -267.826565) (xy 376.220357 -267.789728)
			(xy 376.194054 -267.748132) (xy 376.174763 -267.702856) (xy 376.162986 -267.655072) (xy 376.159026 -267.606018)
			(xy 375.1961 -267.606018) (xy 375.1961 -268.11605) (xy 375.196371 -268.124581) (xy 375.201897 -268.14072)
			(xy 375.212445 -268.154126) (xy 375.219468 -268.158976) (xy 375.240664 -268.17314) (xy 375.278448 -268.20736)
			(xy 375.310018 -268.247383) (xy 375.334498 -268.292097) (xy 375.351205 -268.340257) (xy 375.359675 -268.390525)
			(xy 375.359674 -268.416024) (xy 375.689126 -268.416024) (xy 375.693086 -268.36697) (xy 375.704863 -268.319186)
			(xy 375.724154 -268.27391) (xy 375.750457 -268.232314) (xy 375.783092 -268.195477) (xy 375.821213 -268.164352)
			(xy 375.863834 -268.139745) (xy 375.90985 -268.122293) (xy 375.958069 -268.112449) (xy 376.007244 -268.110468)
			(xy 376.056099 -268.1164) (xy 376.10337 -268.130092) (xy 376.147832 -268.15119) (xy 376.188335 -268.179146)
			(xy 376.223828 -268.213238) (xy 376.253393 -268.252582) (xy 376.276264 -268.296159) (xy 376.291848 -268.34284)
			(xy 376.299743 -268.391417) (xy 376.300238 -268.416024) (xy 376.628926 -268.416024) (xy 376.632886 -268.36697)
			(xy 376.644663 -268.319186) (xy 376.663954 -268.27391) (xy 376.690257 -268.232314) (xy 376.722892 -268.195477)
			(xy 376.761013 -268.164352) (xy 376.803634 -268.139745) (xy 376.84965 -268.122293) (xy 376.897869 -268.112449)
			(xy 376.947044 -268.110468) (xy 376.995899 -268.1164) (xy 377.04317 -268.130092) (xy 377.087632 -268.15119)
			(xy 377.128135 -268.179146) (xy 377.163628 -268.213238) (xy 377.193193 -268.252582) (xy 377.216064 -268.296159)
			(xy 377.231648 -268.34284) (xy 377.239543 -268.391417) (xy 377.240038 -268.416024) (xy 377.56898 -268.416024)
			(xy 377.57294 -268.36697) (xy 377.584717 -268.319186) (xy 377.604008 -268.27391) (xy 377.630311 -268.232314)
			(xy 377.662946 -268.195477) (xy 377.701067 -268.164352) (xy 377.743688 -268.139745) (xy 377.789704 -268.122293)
			(xy 377.837923 -268.112449) (xy 377.887098 -268.110468) (xy 377.935953 -268.1164) (xy 377.983224 -268.130092)
			(xy 378.027686 -268.15119) (xy 378.068189 -268.179146) (xy 378.103682 -268.213238) (xy 378.133247 -268.252582)
			(xy 378.156118 -268.296159) (xy 378.171702 -268.34284) (xy 378.179597 -268.391417) (xy 378.180092 -268.416024)
			(xy 379.449088 -268.416024) (xy 379.453048 -268.36697) (xy 379.464825 -268.319186) (xy 379.484116 -268.27391)
			(xy 379.510419 -268.232314) (xy 379.543054 -268.195477) (xy 379.581175 -268.164352) (xy 379.623796 -268.139745)
			(xy 379.669812 -268.122293) (xy 379.718031 -268.112449) (xy 379.767206 -268.110468) (xy 379.816061 -268.1164)
			(xy 379.863332 -268.130092) (xy 379.907794 -268.15119) (xy 379.948297 -268.179146) (xy 379.98379 -268.213238)
			(xy 380.013355 -268.252582) (xy 380.036226 -268.296159) (xy 380.05181 -268.34284) (xy 380.059705 -268.391417)
			(xy 380.0602 -268.416024) (xy 380.388888 -268.416024) (xy 380.392848 -268.36697) (xy 380.404625 -268.319186)
			(xy 380.423916 -268.27391) (xy 380.450219 -268.232314) (xy 380.482854 -268.195477) (xy 380.520975 -268.164352)
			(xy 380.563596 -268.139745) (xy 380.609612 -268.122293) (xy 380.657831 -268.112449) (xy 380.707006 -268.110468)
			(xy 380.755861 -268.1164) (xy 380.803132 -268.130092) (xy 380.847594 -268.15119) (xy 380.888097 -268.179146)
			(xy 380.92359 -268.213238) (xy 380.953155 -268.252582) (xy 380.976026 -268.296159) (xy 380.99161 -268.34284)
			(xy 380.999505 -268.391417) (xy 381 -268.416024) (xy 381.328942 -268.416024) (xy 381.332902 -268.36697)
			(xy 381.344679 -268.319186) (xy 381.36397 -268.27391) (xy 381.390273 -268.232314) (xy 381.422908 -268.195477)
			(xy 381.461029 -268.164352) (xy 381.50365 -268.139745) (xy 381.549666 -268.122293) (xy 381.597885 -268.112449)
			(xy 381.64706 -268.110468) (xy 381.695915 -268.1164) (xy 381.743186 -268.130092) (xy 381.787648 -268.15119)
			(xy 381.828151 -268.179146) (xy 381.863644 -268.213238) (xy 381.893209 -268.252582) (xy 381.91608 -268.296159)
			(xy 381.931664 -268.34284) (xy 381.939559 -268.391417) (xy 381.940054 -268.416024) (xy 382.268996 -268.416024)
			(xy 382.272956 -268.36697) (xy 382.284733 -268.319186) (xy 382.304024 -268.27391) (xy 382.330327 -268.232314)
			(xy 382.362962 -268.195477) (xy 382.401083 -268.164352) (xy 382.443704 -268.139745) (xy 382.48972 -268.122293)
			(xy 382.537939 -268.112449) (xy 382.587114 -268.110468) (xy 382.635969 -268.1164) (xy 382.68324 -268.130092)
			(xy 382.727702 -268.15119) (xy 382.768205 -268.179146) (xy 382.803698 -268.213238) (xy 382.833263 -268.252582)
			(xy 382.856134 -268.296159) (xy 382.871718 -268.34284) (xy 382.879613 -268.391417) (xy 382.880108 -268.416024)
			(xy 383.20905 -268.416024) (xy 383.21301 -268.36697) (xy 383.224787 -268.319186) (xy 383.244078 -268.27391)
			(xy 383.270381 -268.232314) (xy 383.303016 -268.195477) (xy 383.341137 -268.164352) (xy 383.383758 -268.139745)
			(xy 383.429774 -268.122293) (xy 383.477993 -268.112449) (xy 383.527168 -268.110468) (xy 383.576023 -268.1164)
			(xy 383.623294 -268.130092) (xy 383.667756 -268.15119) (xy 383.708259 -268.179146) (xy 383.743752 -268.213238)
			(xy 383.773317 -268.252582) (xy 383.796188 -268.296159) (xy 383.811772 -268.34284) (xy 383.819667 -268.391417)
			(xy 383.820162 -268.416024) (xy 384.149104 -268.416024) (xy 384.153064 -268.36697) (xy 384.164841 -268.319186)
			(xy 384.184132 -268.27391) (xy 384.210435 -268.232314) (xy 384.24307 -268.195477) (xy 384.281191 -268.164352)
			(xy 384.323812 -268.139745) (xy 384.369828 -268.122293) (xy 384.418047 -268.112449) (xy 384.467222 -268.110468)
			(xy 384.516077 -268.1164) (xy 384.563348 -268.130092) (xy 384.60781 -268.15119) (xy 384.648313 -268.179146)
			(xy 384.683806 -268.213238) (xy 384.713371 -268.252582) (xy 384.736242 -268.296159) (xy 384.751826 -268.34284)
			(xy 384.759721 -268.391417) (xy 384.760216 -268.416024) (xy 386.028958 -268.416024) (xy 386.032918 -268.36697)
			(xy 386.044695 -268.319186) (xy 386.063986 -268.27391) (xy 386.090289 -268.232314) (xy 386.122924 -268.195477)
			(xy 386.161045 -268.164352) (xy 386.203666 -268.139745) (xy 386.249682 -268.122293) (xy 386.297901 -268.112449)
			(xy 386.347076 -268.110468) (xy 386.395931 -268.1164) (xy 386.443202 -268.130092) (xy 386.487664 -268.15119)
			(xy 386.528167 -268.179146) (xy 386.56366 -268.213238) (xy 386.593225 -268.252582) (xy 386.616096 -268.296159)
			(xy 386.63168 -268.34284) (xy 386.639575 -268.391417) (xy 386.64007 -268.416024) (xy 386.969012 -268.416024)
			(xy 386.972972 -268.36697) (xy 386.984749 -268.319186) (xy 387.00404 -268.27391) (xy 387.030343 -268.232314)
			(xy 387.062978 -268.195477) (xy 387.101099 -268.164352) (xy 387.14372 -268.139745) (xy 387.189736 -268.122293)
			(xy 387.237955 -268.112449) (xy 387.28713 -268.110468) (xy 387.335985 -268.1164) (xy 387.383256 -268.130092)
			(xy 387.427718 -268.15119) (xy 387.468221 -268.179146) (xy 387.503714 -268.213238) (xy 387.533279 -268.252582)
			(xy 387.55615 -268.296159) (xy 387.571734 -268.34284) (xy 387.579629 -268.391417) (xy 387.580124 -268.416024)
			(xy 387.909066 -268.416024) (xy 387.913026 -268.36697) (xy 387.924803 -268.319186) (xy 387.944094 -268.27391)
			(xy 387.970397 -268.232314) (xy 388.003032 -268.195477) (xy 388.041153 -268.164352) (xy 388.083774 -268.139745)
			(xy 388.12979 -268.122293) (xy 388.178009 -268.112449) (xy 388.227184 -268.110468) (xy 388.276039 -268.1164)
			(xy 388.32331 -268.130092) (xy 388.367772 -268.15119) (xy 388.408275 -268.179146) (xy 388.443768 -268.213238)
			(xy 388.473333 -268.252582) (xy 388.496204 -268.296159) (xy 388.511788 -268.34284) (xy 388.519683 -268.391417)
			(xy 388.520178 -268.416024) (xy 388.84912 -268.416024) (xy 388.85308 -268.36697) (xy 388.864857 -268.319186)
			(xy 388.884148 -268.27391) (xy 388.910451 -268.232314) (xy 388.943086 -268.195477) (xy 388.981207 -268.164352)
			(xy 389.023828 -268.139745) (xy 389.069844 -268.122293) (xy 389.118063 -268.112449) (xy 389.167238 -268.110468)
			(xy 389.216093 -268.1164) (xy 389.263364 -268.130092) (xy 389.307826 -268.15119) (xy 389.348329 -268.179146)
			(xy 389.383822 -268.213238) (xy 389.413387 -268.252582) (xy 389.436258 -268.296159) (xy 389.451842 -268.34284)
			(xy 389.459737 -268.391417) (xy 389.460232 -268.416024) (xy 389.78892 -268.416024) (xy 389.79288 -268.36697)
			(xy 389.804657 -268.319186) (xy 389.823948 -268.27391) (xy 389.850251 -268.232314) (xy 389.882886 -268.195477)
			(xy 389.921007 -268.164352) (xy 389.963628 -268.139745) (xy 390.009644 -268.122293) (xy 390.057863 -268.112449)
			(xy 390.107038 -268.110468) (xy 390.155893 -268.1164) (xy 390.203164 -268.130092) (xy 390.247626 -268.15119)
			(xy 390.288129 -268.179146) (xy 390.323622 -268.213238) (xy 390.353187 -268.252582) (xy 390.376058 -268.296159)
			(xy 390.391642 -268.34284) (xy 390.399537 -268.391417) (xy 390.400032 -268.416024) (xy 390.728974 -268.416024)
			(xy 390.732934 -268.36697) (xy 390.744711 -268.319186) (xy 390.764002 -268.27391) (xy 390.790305 -268.232314)
			(xy 390.82294 -268.195477) (xy 390.861061 -268.164352) (xy 390.903682 -268.139745) (xy 390.949698 -268.122293)
			(xy 390.997917 -268.112449) (xy 391.047092 -268.110468) (xy 391.095947 -268.1164) (xy 391.143218 -268.130092)
			(xy 391.18768 -268.15119) (xy 391.228183 -268.179146) (xy 391.263676 -268.213238) (xy 391.293241 -268.252582)
			(xy 391.316112 -268.296159) (xy 391.331696 -268.34284) (xy 391.339591 -268.391417) (xy 391.340086 -268.416024)
			(xy 392.609082 -268.416024) (xy 392.613042 -268.36697) (xy 392.624819 -268.319186) (xy 392.64411 -268.27391)
			(xy 392.670413 -268.232314) (xy 392.703048 -268.195477) (xy 392.741169 -268.164352) (xy 392.78379 -268.139745)
			(xy 392.829806 -268.122293) (xy 392.878025 -268.112449) (xy 392.9272 -268.110468) (xy 392.976055 -268.1164)
			(xy 393.023326 -268.130092) (xy 393.067788 -268.15119) (xy 393.108291 -268.179146) (xy 393.143784 -268.213238)
			(xy 393.173349 -268.252582) (xy 393.19622 -268.296159) (xy 393.211804 -268.34284) (xy 393.219699 -268.391417)
			(xy 393.220194 -268.416024) (xy 393.219699 -268.440631) (xy 393.211804 -268.489208) (xy 393.19622 -268.535889)
			(xy 393.173349 -268.579466) (xy 393.143784 -268.61881) (xy 393.108291 -268.652902) (xy 393.067788 -268.680858)
			(xy 393.023326 -268.701956) (xy 392.976055 -268.715648) (xy 392.9272 -268.72158) (xy 392.878025 -268.719599)
			(xy 392.829806 -268.709755) (xy 392.78379 -268.692303) (xy 392.741169 -268.667696) (xy 392.703048 -268.636571)
			(xy 392.670413 -268.599734) (xy 392.64411 -268.558138) (xy 392.624819 -268.512862) (xy 392.613042 -268.465078)
			(xy 392.609082 -268.416024) (xy 391.340086 -268.416024) (xy 391.339591 -268.440631) (xy 391.331696 -268.489208)
			(xy 391.316112 -268.535889) (xy 391.293241 -268.579466) (xy 391.263676 -268.61881) (xy 391.228183 -268.652902)
			(xy 391.18768 -268.680858) (xy 391.143218 -268.701956) (xy 391.095947 -268.715648) (xy 391.047092 -268.72158)
			(xy 390.997917 -268.719599) (xy 390.949698 -268.709755) (xy 390.903682 -268.692303) (xy 390.861061 -268.667696)
			(xy 390.82294 -268.636571) (xy 390.790305 -268.599734) (xy 390.764002 -268.558138) (xy 390.744711 -268.512862)
			(xy 390.732934 -268.465078) (xy 390.728974 -268.416024) (xy 390.400032 -268.416024) (xy 390.399537 -268.440631)
			(xy 390.391642 -268.489208) (xy 390.376058 -268.535889) (xy 390.353187 -268.579466) (xy 390.323622 -268.61881)
			(xy 390.288129 -268.652902) (xy 390.247626 -268.680858) (xy 390.203164 -268.701956) (xy 390.155893 -268.715648)
			(xy 390.107038 -268.72158) (xy 390.057863 -268.719599) (xy 390.009644 -268.709755) (xy 389.963628 -268.692303)
			(xy 389.921007 -268.667696) (xy 389.882886 -268.636571) (xy 389.850251 -268.599734) (xy 389.823948 -268.558138)
			(xy 389.804657 -268.512862) (xy 389.79288 -268.465078) (xy 389.78892 -268.416024) (xy 389.460232 -268.416024)
			(xy 389.459737 -268.440631) (xy 389.451842 -268.489208) (xy 389.436258 -268.535889) (xy 389.413387 -268.579466)
			(xy 389.383822 -268.61881) (xy 389.348329 -268.652902) (xy 389.307826 -268.680858) (xy 389.263364 -268.701956)
			(xy 389.216093 -268.715648) (xy 389.167238 -268.72158) (xy 389.118063 -268.719599) (xy 389.069844 -268.709755)
			(xy 389.023828 -268.692303) (xy 388.981207 -268.667696) (xy 388.943086 -268.636571) (xy 388.910451 -268.599734)
			(xy 388.884148 -268.558138) (xy 388.864857 -268.512862) (xy 388.85308 -268.465078) (xy 388.84912 -268.416024)
			(xy 388.520178 -268.416024) (xy 388.519683 -268.440631) (xy 388.511788 -268.489208) (xy 388.496204 -268.535889)
			(xy 388.473333 -268.579466) (xy 388.443768 -268.61881) (xy 388.408275 -268.652902) (xy 388.367772 -268.680858)
			(xy 388.32331 -268.701956) (xy 388.276039 -268.715648) (xy 388.227184 -268.72158) (xy 388.178009 -268.719599)
			(xy 388.12979 -268.709755) (xy 388.083774 -268.692303) (xy 388.041153 -268.667696) (xy 388.003032 -268.636571)
			(xy 387.970397 -268.599734) (xy 387.944094 -268.558138) (xy 387.924803 -268.512862) (xy 387.913026 -268.465078)
			(xy 387.909066 -268.416024) (xy 387.580124 -268.416024) (xy 387.579629 -268.440631) (xy 387.571734 -268.489208)
			(xy 387.55615 -268.535889) (xy 387.533279 -268.579466) (xy 387.503714 -268.61881) (xy 387.468221 -268.652902)
			(xy 387.427718 -268.680858) (xy 387.383256 -268.701956) (xy 387.335985 -268.715648) (xy 387.28713 -268.72158)
			(xy 387.237955 -268.719599) (xy 387.189736 -268.709755) (xy 387.14372 -268.692303) (xy 387.101099 -268.667696)
			(xy 387.062978 -268.636571) (xy 387.030343 -268.599734) (xy 387.00404 -268.558138) (xy 386.984749 -268.512862)
			(xy 386.972972 -268.465078) (xy 386.969012 -268.416024) (xy 386.64007 -268.416024) (xy 386.639575 -268.440631)
			(xy 386.63168 -268.489208) (xy 386.616096 -268.535889) (xy 386.593225 -268.579466) (xy 386.56366 -268.61881)
			(xy 386.528167 -268.652902) (xy 386.487664 -268.680858) (xy 386.443202 -268.701956) (xy 386.395931 -268.715648)
			(xy 386.347076 -268.72158) (xy 386.297901 -268.719599) (xy 386.249682 -268.709755) (xy 386.203666 -268.692303)
			(xy 386.161045 -268.667696) (xy 386.122924 -268.636571) (xy 386.090289 -268.599734) (xy 386.063986 -268.558138)
			(xy 386.044695 -268.512862) (xy 386.032918 -268.465078) (xy 386.028958 -268.416024) (xy 384.760216 -268.416024)
			(xy 384.759721 -268.440631) (xy 384.751826 -268.489208) (xy 384.736242 -268.535889) (xy 384.713371 -268.579466)
			(xy 384.683806 -268.61881) (xy 384.648313 -268.652902) (xy 384.60781 -268.680858) (xy 384.563348 -268.701956)
			(xy 384.516077 -268.715648) (xy 384.467222 -268.72158) (xy 384.418047 -268.719599) (xy 384.369828 -268.709755)
			(xy 384.323812 -268.692303) (xy 384.281191 -268.667696) (xy 384.24307 -268.636571) (xy 384.210435 -268.599734)
			(xy 384.184132 -268.558138) (xy 384.164841 -268.512862) (xy 384.153064 -268.465078) (xy 384.149104 -268.416024)
			(xy 383.820162 -268.416024) (xy 383.819667 -268.440631) (xy 383.811772 -268.489208) (xy 383.796188 -268.535889)
			(xy 383.773317 -268.579466) (xy 383.743752 -268.61881) (xy 383.708259 -268.652902) (xy 383.667756 -268.680858)
			(xy 383.623294 -268.701956) (xy 383.576023 -268.715648) (xy 383.527168 -268.72158) (xy 383.477993 -268.719599)
			(xy 383.429774 -268.709755) (xy 383.383758 -268.692303) (xy 383.341137 -268.667696) (xy 383.303016 -268.636571)
			(xy 383.270381 -268.599734) (xy 383.244078 -268.558138) (xy 383.224787 -268.512862) (xy 383.21301 -268.465078)
			(xy 383.20905 -268.416024) (xy 382.880108 -268.416024) (xy 382.879613 -268.440631) (xy 382.871718 -268.489208)
			(xy 382.856134 -268.535889) (xy 382.833263 -268.579466) (xy 382.803698 -268.61881) (xy 382.768205 -268.652902)
			(xy 382.727702 -268.680858) (xy 382.68324 -268.701956) (xy 382.635969 -268.715648) (xy 382.587114 -268.72158)
			(xy 382.537939 -268.719599) (xy 382.48972 -268.709755) (xy 382.443704 -268.692303) (xy 382.401083 -268.667696)
			(xy 382.362962 -268.636571) (xy 382.330327 -268.599734) (xy 382.304024 -268.558138) (xy 382.284733 -268.512862)
			(xy 382.272956 -268.465078) (xy 382.268996 -268.416024) (xy 381.940054 -268.416024) (xy 381.939559 -268.440631)
			(xy 381.931664 -268.489208) (xy 381.91608 -268.535889) (xy 381.893209 -268.579466) (xy 381.863644 -268.61881)
			(xy 381.828151 -268.652902) (xy 381.787648 -268.680858) (xy 381.743186 -268.701956) (xy 381.695915 -268.715648)
			(xy 381.64706 -268.72158) (xy 381.597885 -268.719599) (xy 381.549666 -268.709755) (xy 381.50365 -268.692303)
			(xy 381.461029 -268.667696) (xy 381.422908 -268.636571) (xy 381.390273 -268.599734) (xy 381.36397 -268.558138)
			(xy 381.344679 -268.512862) (xy 381.332902 -268.465078) (xy 381.328942 -268.416024) (xy 381 -268.416024)
			(xy 380.999505 -268.440631) (xy 380.99161 -268.489208) (xy 380.976026 -268.535889) (xy 380.953155 -268.579466)
			(xy 380.92359 -268.61881) (xy 380.888097 -268.652902) (xy 380.847594 -268.680858) (xy 380.803132 -268.701956)
			(xy 380.755861 -268.715648) (xy 380.707006 -268.72158) (xy 380.657831 -268.719599) (xy 380.609612 -268.709755)
			(xy 380.563596 -268.692303) (xy 380.520975 -268.667696) (xy 380.482854 -268.636571) (xy 380.450219 -268.599734)
			(xy 380.423916 -268.558138) (xy 380.404625 -268.512862) (xy 380.392848 -268.465078) (xy 380.388888 -268.416024)
			(xy 380.0602 -268.416024) (xy 380.059705 -268.440631) (xy 380.05181 -268.489208) (xy 380.036226 -268.535889)
			(xy 380.013355 -268.579466) (xy 379.98379 -268.61881) (xy 379.948297 -268.652902) (xy 379.907794 -268.680858)
			(xy 379.863332 -268.701956) (xy 379.816061 -268.715648) (xy 379.767206 -268.72158) (xy 379.718031 -268.719599)
			(xy 379.669812 -268.709755) (xy 379.623796 -268.692303) (xy 379.581175 -268.667696) (xy 379.543054 -268.636571)
			(xy 379.510419 -268.599734) (xy 379.484116 -268.558138) (xy 379.464825 -268.512862) (xy 379.453048 -268.465078)
			(xy 379.449088 -268.416024) (xy 378.180092 -268.416024) (xy 378.179597 -268.440631) (xy 378.171702 -268.489208)
			(xy 378.156118 -268.535889) (xy 378.133247 -268.579466) (xy 378.103682 -268.61881) (xy 378.068189 -268.652902)
			(xy 378.027686 -268.680858) (xy 377.983224 -268.701956) (xy 377.935953 -268.715648) (xy 377.887098 -268.72158)
			(xy 377.837923 -268.719599) (xy 377.789704 -268.709755) (xy 377.743688 -268.692303) (xy 377.701067 -268.667696)
			(xy 377.662946 -268.636571) (xy 377.630311 -268.599734) (xy 377.604008 -268.558138) (xy 377.584717 -268.512862)
			(xy 377.57294 -268.465078) (xy 377.56898 -268.416024) (xy 377.240038 -268.416024) (xy 377.239543 -268.440631)
			(xy 377.231648 -268.489208) (xy 377.216064 -268.535889) (xy 377.193193 -268.579466) (xy 377.163628 -268.61881)
			(xy 377.128135 -268.652902) (xy 377.087632 -268.680858) (xy 377.04317 -268.701956) (xy 376.995899 -268.715648)
			(xy 376.947044 -268.72158) (xy 376.897869 -268.719599) (xy 376.84965 -268.709755) (xy 376.803634 -268.692303)
			(xy 376.761013 -268.667696) (xy 376.722892 -268.636571) (xy 376.690257 -268.599734) (xy 376.663954 -268.558138)
			(xy 376.644663 -268.512862) (xy 376.632886 -268.465078) (xy 376.628926 -268.416024) (xy 376.300238 -268.416024)
			(xy 376.299743 -268.440631) (xy 376.291848 -268.489208) (xy 376.276264 -268.535889) (xy 376.253393 -268.579466)
			(xy 376.223828 -268.61881) (xy 376.188335 -268.652902) (xy 376.147832 -268.680858) (xy 376.10337 -268.701956)
			(xy 376.056099 -268.715648) (xy 376.007244 -268.72158) (xy 375.958069 -268.719599) (xy 375.90985 -268.709755)
			(xy 375.863834 -268.692303) (xy 375.821213 -268.667696) (xy 375.783092 -268.636571) (xy 375.750457 -268.599734)
			(xy 375.724154 -268.558138) (xy 375.704863 -268.512862) (xy 375.693086 -268.465078) (xy 375.689126 -268.416024)
			(xy 375.359674 -268.416024) (xy 375.359673 -268.441501) (xy 375.351198 -268.491768) (xy 375.334487 -268.539927)
			(xy 375.310004 -268.584639) (xy 375.27843 -268.624659) (xy 375.240644 -268.658876) (xy 375.219468 -268.673072)
			(xy 375.212483 -268.677958) (xy 375.201976 -268.691369) (xy 375.196434 -268.707479) (xy 375.1961 -268.715998)
			(xy 375.1961 -268.88821) (xy 375.196502 -268.897409) (xy 375.20299 -268.914626) (xy 375.215101 -268.928477)
			(xy 375.223024 -268.933168) (xy 375.314718 -268.98219) (xy 375.342404 -268.980666) (xy 375.354342 -268.972792)
			(xy 375.373328 -268.960493) (xy 375.414161 -268.941028) (xy 375.457421 -268.927803) (xy 375.502158 -268.921108)
			(xy 375.524776 -268.920722) (xy 375.550033 -268.921213) (xy 375.599857 -268.929523) (xy 375.647634 -268.945922)
			(xy 375.69206 -268.969961) (xy 375.731924 -269.000985) (xy 375.766137 -269.038147) (xy 375.793766 -269.080434)
			(xy 375.814058 -269.126692) (xy 375.826458 -269.17566) (xy 375.83063 -269.226) (xy 375.830628 -269.22603)
			(xy 376.159026 -269.22603) (xy 376.162986 -269.176976) (xy 376.174763 -269.129192) (xy 376.194054 -269.083916)
			(xy 376.220357 -269.04232) (xy 376.252992 -269.005483) (xy 376.291113 -268.974358) (xy 376.333734 -268.949751)
			(xy 376.37975 -268.932299) (xy 376.427969 -268.922455) (xy 376.477144 -268.920474) (xy 376.525999 -268.926406)
			(xy 376.57327 -268.940098) (xy 376.617732 -268.961196) (xy 376.658235 -268.989152) (xy 376.693728 -269.023244)
			(xy 376.723293 -269.062588) (xy 376.746164 -269.106165) (xy 376.761748 -269.152846) (xy 376.769643 -269.201423)
			(xy 376.770138 -269.22603) (xy 377.088649 -269.22603) (xy 377.092744 -269.175302) (xy 377.104923 -269.125888)
			(xy 377.124871 -269.079068) (xy 377.152072 -269.036054) (xy 377.18582 -268.99796) (xy 377.225242 -268.965773)
			(xy 377.269316 -268.940327) (xy 377.316902 -268.92228) (xy 377.366766 -268.9121) (xy 377.417618 -268.910051)
			(xy 377.468139 -268.916185) (xy 377.517023 -268.930345) (xy 377.563002 -268.952162) (xy 377.604886 -268.981072)
			(xy 377.64159 -269.016327) (xy 377.672163 -269.057013) (xy 377.695814 -269.102076) (xy 377.71193 -269.15035)
			(xy 377.720094 -269.200584) (xy 377.720606 -269.22603) (xy 378.039134 -269.22603) (xy 378.043094 -269.176976)
			(xy 378.054871 -269.129192) (xy 378.074162 -269.083916) (xy 378.100465 -269.04232) (xy 378.1331 -269.005483)
			(xy 378.171221 -268.974358) (xy 378.213842 -268.949751) (xy 378.259858 -268.932299) (xy 378.308077 -268.922455)
			(xy 378.357252 -268.920474) (xy 378.406107 -268.926406) (xy 378.453378 -268.940098) (xy 378.49784 -268.961196)
			(xy 378.538343 -268.989152) (xy 378.573836 -269.023244) (xy 378.603401 -269.062588) (xy 378.626272 -269.106165)
			(xy 378.641856 -269.152846) (xy 378.649751 -269.201423) (xy 378.650246 -269.22603) (xy 378.978934 -269.22603)
			(xy 378.982894 -269.176976) (xy 378.994671 -269.129192) (xy 379.013962 -269.083916) (xy 379.040265 -269.04232)
			(xy 379.0729 -269.005483) (xy 379.111021 -268.974358) (xy 379.153642 -268.949751) (xy 379.199658 -268.932299)
			(xy 379.247877 -268.922455) (xy 379.297052 -268.920474) (xy 379.345907 -268.926406) (xy 379.393178 -268.940098)
			(xy 379.43764 -268.961196) (xy 379.478143 -268.989152) (xy 379.513636 -269.023244) (xy 379.543201 -269.062588)
			(xy 379.566072 -269.106165) (xy 379.581656 -269.152846) (xy 379.589551 -269.201423) (xy 379.590046 -269.22603)
			(xy 379.918988 -269.22603) (xy 379.922948 -269.176976) (xy 379.934725 -269.129192) (xy 379.954016 -269.083916)
			(xy 379.980319 -269.04232) (xy 380.012954 -269.005483) (xy 380.051075 -268.974358) (xy 380.093696 -268.949751)
			(xy 380.139712 -268.932299) (xy 380.187931 -268.922455) (xy 380.237106 -268.920474) (xy 380.285961 -268.926406)
			(xy 380.333232 -268.940098) (xy 380.377694 -268.961196) (xy 380.418197 -268.989152) (xy 380.45369 -269.023244)
			(xy 380.483255 -269.062588) (xy 380.506126 -269.106165) (xy 380.52171 -269.152846) (xy 380.529605 -269.201423)
			(xy 380.5301 -269.22603) (xy 380.848611 -269.22603) (xy 380.852706 -269.175302) (xy 380.864885 -269.125888)
			(xy 380.884833 -269.079068) (xy 380.912034 -269.036054) (xy 380.945782 -268.99796) (xy 380.985204 -268.965773)
			(xy 381.029278 -268.940327) (xy 381.076864 -268.92228) (xy 381.126728 -268.9121) (xy 381.17758 -268.910051)
			(xy 381.228101 -268.916185) (xy 381.276985 -268.930345) (xy 381.322964 -268.952162) (xy 381.364848 -268.981072)
			(xy 381.401552 -269.016327) (xy 381.432125 -269.057013) (xy 381.455776 -269.102076) (xy 381.471892 -269.15035)
			(xy 381.480056 -269.200584) (xy 381.480568 -269.22603) (xy 381.799096 -269.22603) (xy 381.803056 -269.176976)
			(xy 381.814833 -269.129192) (xy 381.834124 -269.083916) (xy 381.860427 -269.04232) (xy 381.893062 -269.005483)
			(xy 381.931183 -268.974358) (xy 381.973804 -268.949751) (xy 382.01982 -268.932299) (xy 382.068039 -268.922455)
			(xy 382.117214 -268.920474) (xy 382.166069 -268.926406) (xy 382.21334 -268.940098) (xy 382.257802 -268.961196)
			(xy 382.298305 -268.989152) (xy 382.333798 -269.023244) (xy 382.363363 -269.062588) (xy 382.386234 -269.106165)
			(xy 382.401818 -269.152846) (xy 382.409713 -269.201423) (xy 382.410208 -269.22603) (xy 382.738896 -269.22603)
			(xy 382.742856 -269.176976) (xy 382.754633 -269.129192) (xy 382.773924 -269.083916) (xy 382.800227 -269.04232)
			(xy 382.832862 -269.005483) (xy 382.870983 -268.974358) (xy 382.913604 -268.949751) (xy 382.95962 -268.932299)
			(xy 383.007839 -268.922455) (xy 383.057014 -268.920474) (xy 383.105869 -268.926406) (xy 383.15314 -268.940098)
			(xy 383.197602 -268.961196) (xy 383.238105 -268.989152) (xy 383.273598 -269.023244) (xy 383.303163 -269.062588)
			(xy 383.326034 -269.106165) (xy 383.341618 -269.152846) (xy 383.349513 -269.201423) (xy 383.350008 -269.22603)
			(xy 383.668519 -269.22603) (xy 383.672614 -269.175302) (xy 383.684793 -269.125888) (xy 383.704741 -269.079068)
			(xy 383.731942 -269.036054) (xy 383.76569 -268.99796) (xy 383.805112 -268.965773) (xy 383.849186 -268.940327)
			(xy 383.896772 -268.92228) (xy 383.946636 -268.9121) (xy 383.997488 -268.910051) (xy 384.048009 -268.916185)
			(xy 384.096893 -268.930345) (xy 384.142872 -268.952162) (xy 384.184756 -268.981072) (xy 384.22146 -269.016327)
			(xy 384.252033 -269.057013) (xy 384.275684 -269.102076) (xy 384.2918 -269.15035) (xy 384.299964 -269.200584)
			(xy 384.300476 -269.22603) (xy 384.619004 -269.22603) (xy 384.622964 -269.176976) (xy 384.634741 -269.129192)
			(xy 384.654032 -269.083916) (xy 384.680335 -269.04232) (xy 384.71297 -269.005483) (xy 384.751091 -268.974358)
			(xy 384.793712 -268.949751) (xy 384.839728 -268.932299) (xy 384.887947 -268.922455) (xy 384.937122 -268.920474)
			(xy 384.985977 -268.926406) (xy 385.033248 -268.940098) (xy 385.07771 -268.961196) (xy 385.118213 -268.989152)
			(xy 385.153706 -269.023244) (xy 385.183271 -269.062588) (xy 385.206142 -269.106165) (xy 385.221726 -269.152846)
			(xy 385.229621 -269.201423) (xy 385.230116 -269.22603) (xy 385.559058 -269.22603) (xy 385.563018 -269.176976)
			(xy 385.574795 -269.129192) (xy 385.594086 -269.083916) (xy 385.620389 -269.04232) (xy 385.653024 -269.005483)
			(xy 385.691145 -268.974358) (xy 385.733766 -268.949751) (xy 385.779782 -268.932299) (xy 385.828001 -268.922455)
			(xy 385.877176 -268.920474) (xy 385.926031 -268.926406) (xy 385.973302 -268.940098) (xy 386.017764 -268.961196)
			(xy 386.058267 -268.989152) (xy 386.09376 -269.023244) (xy 386.123325 -269.062588) (xy 386.146196 -269.106165)
			(xy 386.16178 -269.152846) (xy 386.169675 -269.201423) (xy 386.17017 -269.22603) (xy 386.499112 -269.22603)
			(xy 386.503072 -269.176976) (xy 386.514849 -269.129192) (xy 386.53414 -269.083916) (xy 386.560443 -269.04232)
			(xy 386.593078 -269.005483) (xy 386.631199 -268.974358) (xy 386.67382 -268.949751) (xy 386.719836 -268.932299)
			(xy 386.768055 -268.922455) (xy 386.81723 -268.920474) (xy 386.866085 -268.926406) (xy 386.913356 -268.940098)
			(xy 386.957818 -268.961196) (xy 386.998321 -268.989152) (xy 387.033814 -269.023244) (xy 387.063379 -269.062588)
			(xy 387.08625 -269.106165) (xy 387.101834 -269.152846) (xy 387.109729 -269.201423) (xy 387.110224 -269.22603)
			(xy 387.428481 -269.22603) (xy 387.432576 -269.175302) (xy 387.444755 -269.125888) (xy 387.464703 -269.079068)
			(xy 387.491904 -269.036054) (xy 387.525652 -268.99796) (xy 387.565074 -268.965773) (xy 387.609148 -268.940327)
			(xy 387.656734 -268.92228) (xy 387.706598 -268.9121) (xy 387.75745 -268.910051) (xy 387.807971 -268.916185)
			(xy 387.856855 -268.930345) (xy 387.902834 -268.952162) (xy 387.944718 -268.981072) (xy 387.981422 -269.016327)
			(xy 388.011995 -269.057013) (xy 388.035646 -269.102076) (xy 388.051762 -269.15035) (xy 388.059926 -269.200584)
			(xy 388.060438 -269.22603) (xy 388.378966 -269.22603) (xy 388.382926 -269.176976) (xy 388.394703 -269.129192)
			(xy 388.413994 -269.083916) (xy 388.440297 -269.04232) (xy 388.472932 -269.005483) (xy 388.511053 -268.974358)
			(xy 388.553674 -268.949751) (xy 388.59969 -268.932299) (xy 388.647909 -268.922455) (xy 388.697084 -268.920474)
			(xy 388.745939 -268.926406) (xy 388.79321 -268.940098) (xy 388.837672 -268.961196) (xy 388.878175 -268.989152)
			(xy 388.913668 -269.023244) (xy 388.943233 -269.062588) (xy 388.966104 -269.106165) (xy 388.981688 -269.152846)
			(xy 388.989583 -269.201423) (xy 388.990078 -269.22603) (xy 389.31902 -269.22603) (xy 389.32298 -269.176976)
			(xy 389.334757 -269.129192) (xy 389.354048 -269.083916) (xy 389.380351 -269.04232) (xy 389.412986 -269.005483)
			(xy 389.451107 -268.974358) (xy 389.493728 -268.949751) (xy 389.539744 -268.932299) (xy 389.587963 -268.922455)
			(xy 389.637138 -268.920474) (xy 389.685993 -268.926406) (xy 389.733264 -268.940098) (xy 389.777726 -268.961196)
			(xy 389.818229 -268.989152) (xy 389.853722 -269.023244) (xy 389.883287 -269.062588) (xy 389.906158 -269.106165)
			(xy 389.921742 -269.152846) (xy 389.929637 -269.201423) (xy 389.930132 -269.22603) (xy 390.248643 -269.22603)
			(xy 390.252738 -269.175302) (xy 390.264917 -269.125888) (xy 390.284865 -269.079068) (xy 390.312066 -269.036054)
			(xy 390.345814 -268.99796) (xy 390.385236 -268.965773) (xy 390.42931 -268.940327) (xy 390.476896 -268.92228)
			(xy 390.52676 -268.9121) (xy 390.577612 -268.910051) (xy 390.628133 -268.916185) (xy 390.677017 -268.930345)
			(xy 390.722996 -268.952162) (xy 390.76488 -268.981072) (xy 390.801584 -269.016327) (xy 390.832157 -269.057013)
			(xy 390.855808 -269.102076) (xy 390.871924 -269.15035) (xy 390.880088 -269.200584) (xy 390.8806 -269.22603)
			(xy 391.198874 -269.22603) (xy 391.202834 -269.176976) (xy 391.214611 -269.129192) (xy 391.233902 -269.083916)
			(xy 391.260205 -269.04232) (xy 391.29284 -269.005483) (xy 391.330961 -268.974358) (xy 391.373582 -268.949751)
			(xy 391.419598 -268.932299) (xy 391.467817 -268.922455) (xy 391.516992 -268.920474) (xy 391.565847 -268.926406)
			(xy 391.613118 -268.940098) (xy 391.65758 -268.961196) (xy 391.698083 -268.989152) (xy 391.733576 -269.023244)
			(xy 391.763141 -269.062588) (xy 391.786012 -269.106165) (xy 391.801596 -269.152846) (xy 391.809491 -269.201423)
			(xy 391.809986 -269.22603) (xy 392.138928 -269.22603) (xy 392.142888 -269.176976) (xy 392.154665 -269.129192)
			(xy 392.173956 -269.083916) (xy 392.200259 -269.04232) (xy 392.232894 -269.005483) (xy 392.271015 -268.974358)
			(xy 392.313636 -268.949751) (xy 392.359652 -268.932299) (xy 392.407871 -268.922455) (xy 392.457046 -268.920474)
			(xy 392.505901 -268.926406) (xy 392.553172 -268.940098) (xy 392.597634 -268.961196) (xy 392.638137 -268.989152)
			(xy 392.67363 -269.023244) (xy 392.703195 -269.062588) (xy 392.726066 -269.106165) (xy 392.74165 -269.152846)
			(xy 392.749545 -269.201423) (xy 392.75004 -269.22603) (xy 393.078982 -269.22603) (xy 393.082942 -269.176976)
			(xy 393.094719 -269.129192) (xy 393.11401 -269.083916) (xy 393.140313 -269.04232) (xy 393.172948 -269.005483)
			(xy 393.211069 -268.974358) (xy 393.25369 -268.949751) (xy 393.299706 -268.932299) (xy 393.347925 -268.922455)
			(xy 393.3971 -268.920474) (xy 393.445955 -268.926406) (xy 393.493226 -268.940098) (xy 393.537688 -268.961196)
			(xy 393.578191 -268.989152) (xy 393.613684 -269.023244) (xy 393.643249 -269.062588) (xy 393.66612 -269.106165)
			(xy 393.681704 -269.152846) (xy 393.689599 -269.201423) (xy 393.690094 -269.22603) (xy 393.689599 -269.250637)
			(xy 393.681704 -269.299214) (xy 393.66612 -269.345895) (xy 393.643249 -269.389472) (xy 393.613684 -269.428816)
			(xy 393.578191 -269.462908) (xy 393.537688 -269.490864) (xy 393.493226 -269.511962) (xy 393.445955 -269.525654)
			(xy 393.3971 -269.531586) (xy 393.347925 -269.529605) (xy 393.299706 -269.519761) (xy 393.25369 -269.502309)
			(xy 393.211069 -269.477702) (xy 393.172948 -269.446577) (xy 393.140313 -269.40974) (xy 393.11401 -269.368144)
			(xy 393.094719 -269.322868) (xy 393.082942 -269.275084) (xy 393.078982 -269.22603) (xy 392.75004 -269.22603)
			(xy 392.749545 -269.250637) (xy 392.74165 -269.299214) (xy 392.726066 -269.345895) (xy 392.703195 -269.389472)
			(xy 392.67363 -269.428816) (xy 392.638137 -269.462908) (xy 392.597634 -269.490864) (xy 392.553172 -269.511962)
			(xy 392.505901 -269.525654) (xy 392.457046 -269.531586) (xy 392.407871 -269.529605) (xy 392.359652 -269.519761)
			(xy 392.313636 -269.502309) (xy 392.271015 -269.477702) (xy 392.232894 -269.446577) (xy 392.200259 -269.40974)
			(xy 392.173956 -269.368144) (xy 392.154665 -269.322868) (xy 392.142888 -269.275084) (xy 392.138928 -269.22603)
			(xy 391.809986 -269.22603) (xy 391.809491 -269.250637) (xy 391.801596 -269.299214) (xy 391.786012 -269.345895)
			(xy 391.763141 -269.389472) (xy 391.733576 -269.428816) (xy 391.698083 -269.462908) (xy 391.65758 -269.490864)
			(xy 391.613118 -269.511962) (xy 391.565847 -269.525654) (xy 391.516992 -269.531586) (xy 391.467817 -269.529605)
			(xy 391.419598 -269.519761) (xy 391.373582 -269.502309) (xy 391.330961 -269.477702) (xy 391.29284 -269.446577)
			(xy 391.260205 -269.40974) (xy 391.233902 -269.368144) (xy 391.214611 -269.322868) (xy 391.202834 -269.275084)
			(xy 391.198874 -269.22603) (xy 390.8806 -269.22603) (xy 390.880088 -269.251476) (xy 390.871924 -269.30171)
			(xy 390.855808 -269.349984) (xy 390.832157 -269.395047) (xy 390.801584 -269.435733) (xy 390.76488 -269.470988)
			(xy 390.722996 -269.499898) (xy 390.677017 -269.521715) (xy 390.628133 -269.535875) (xy 390.577612 -269.542009)
			(xy 390.52676 -269.53996) (xy 390.476896 -269.52978) (xy 390.42931 -269.511733) (xy 390.385236 -269.486287)
			(xy 390.345814 -269.4541) (xy 390.312066 -269.416006) (xy 390.284865 -269.372992) (xy 390.264917 -269.326172)
			(xy 390.252738 -269.276758) (xy 390.248643 -269.22603) (xy 389.930132 -269.22603) (xy 389.929637 -269.250637)
			(xy 389.921742 -269.299214) (xy 389.906158 -269.345895) (xy 389.883287 -269.389472) (xy 389.853722 -269.428816)
			(xy 389.818229 -269.462908) (xy 389.777726 -269.490864) (xy 389.733264 -269.511962) (xy 389.685993 -269.525654)
			(xy 389.637138 -269.531586) (xy 389.587963 -269.529605) (xy 389.539744 -269.519761) (xy 389.493728 -269.502309)
			(xy 389.451107 -269.477702) (xy 389.412986 -269.446577) (xy 389.380351 -269.40974) (xy 389.354048 -269.368144)
			(xy 389.334757 -269.322868) (xy 389.32298 -269.275084) (xy 389.31902 -269.22603) (xy 388.990078 -269.22603)
			(xy 388.989583 -269.250637) (xy 388.981688 -269.299214) (xy 388.966104 -269.345895) (xy 388.943233 -269.389472)
			(xy 388.913668 -269.428816) (xy 388.878175 -269.462908) (xy 388.837672 -269.490864) (xy 388.79321 -269.511962)
			(xy 388.745939 -269.525654) (xy 388.697084 -269.531586) (xy 388.647909 -269.529605) (xy 388.59969 -269.519761)
			(xy 388.553674 -269.502309) (xy 388.511053 -269.477702) (xy 388.472932 -269.446577) (xy 388.440297 -269.40974)
			(xy 388.413994 -269.368144) (xy 388.394703 -269.322868) (xy 388.382926 -269.275084) (xy 388.378966 -269.22603)
			(xy 388.060438 -269.22603) (xy 388.059926 -269.251476) (xy 388.051762 -269.30171) (xy 388.035646 -269.349984)
			(xy 388.011995 -269.395047) (xy 387.981422 -269.435733) (xy 387.944718 -269.470988) (xy 387.902834 -269.499898)
			(xy 387.856855 -269.521715) (xy 387.807971 -269.535875) (xy 387.75745 -269.542009) (xy 387.706598 -269.53996)
			(xy 387.656734 -269.52978) (xy 387.609148 -269.511733) (xy 387.565074 -269.486287) (xy 387.525652 -269.4541)
			(xy 387.491904 -269.416006) (xy 387.464703 -269.372992) (xy 387.444755 -269.326172) (xy 387.432576 -269.276758)
			(xy 387.428481 -269.22603) (xy 387.110224 -269.22603) (xy 387.109729 -269.250637) (xy 387.101834 -269.299214)
			(xy 387.08625 -269.345895) (xy 387.063379 -269.389472) (xy 387.033814 -269.428816) (xy 386.998321 -269.462908)
			(xy 386.957818 -269.490864) (xy 386.913356 -269.511962) (xy 386.866085 -269.525654) (xy 386.81723 -269.531586)
			(xy 386.768055 -269.529605) (xy 386.719836 -269.519761) (xy 386.67382 -269.502309) (xy 386.631199 -269.477702)
			(xy 386.593078 -269.446577) (xy 386.560443 -269.40974) (xy 386.53414 -269.368144) (xy 386.514849 -269.322868)
			(xy 386.503072 -269.275084) (xy 386.499112 -269.22603) (xy 386.17017 -269.22603) (xy 386.169675 -269.250637)
			(xy 386.16178 -269.299214) (xy 386.146196 -269.345895) (xy 386.123325 -269.389472) (xy 386.09376 -269.428816)
			(xy 386.058267 -269.462908) (xy 386.017764 -269.490864) (xy 385.973302 -269.511962) (xy 385.926031 -269.525654)
			(xy 385.877176 -269.531586) (xy 385.828001 -269.529605) (xy 385.779782 -269.519761) (xy 385.733766 -269.502309)
			(xy 385.691145 -269.477702) (xy 385.653024 -269.446577) (xy 385.620389 -269.40974) (xy 385.594086 -269.368144)
			(xy 385.574795 -269.322868) (xy 385.563018 -269.275084) (xy 385.559058 -269.22603) (xy 385.230116 -269.22603)
			(xy 385.229621 -269.250637) (xy 385.221726 -269.299214) (xy 385.206142 -269.345895) (xy 385.183271 -269.389472)
			(xy 385.153706 -269.428816) (xy 385.118213 -269.462908) (xy 385.07771 -269.490864) (xy 385.033248 -269.511962)
			(xy 384.985977 -269.525654) (xy 384.937122 -269.531586) (xy 384.887947 -269.529605) (xy 384.839728 -269.519761)
			(xy 384.793712 -269.502309) (xy 384.751091 -269.477702) (xy 384.71297 -269.446577) (xy 384.680335 -269.40974)
			(xy 384.654032 -269.368144) (xy 384.634741 -269.322868) (xy 384.622964 -269.275084) (xy 384.619004 -269.22603)
			(xy 384.300476 -269.22603) (xy 384.299964 -269.251476) (xy 384.2918 -269.30171) (xy 384.275684 -269.349984)
			(xy 384.252033 -269.395047) (xy 384.22146 -269.435733) (xy 384.184756 -269.470988) (xy 384.142872 -269.499898)
			(xy 384.096893 -269.521715) (xy 384.048009 -269.535875) (xy 383.997488 -269.542009) (xy 383.946636 -269.53996)
			(xy 383.896772 -269.52978) (xy 383.849186 -269.511733) (xy 383.805112 -269.486287) (xy 383.76569 -269.4541)
			(xy 383.731942 -269.416006) (xy 383.704741 -269.372992) (xy 383.684793 -269.326172) (xy 383.672614 -269.276758)
			(xy 383.668519 -269.22603) (xy 383.350008 -269.22603) (xy 383.349513 -269.250637) (xy 383.341618 -269.299214)
			(xy 383.326034 -269.345895) (xy 383.303163 -269.389472) (xy 383.273598 -269.428816) (xy 383.238105 -269.462908)
			(xy 383.197602 -269.490864) (xy 383.15314 -269.511962) (xy 383.105869 -269.525654) (xy 383.057014 -269.531586)
			(xy 383.007839 -269.529605) (xy 382.95962 -269.519761) (xy 382.913604 -269.502309) (xy 382.870983 -269.477702)
			(xy 382.832862 -269.446577) (xy 382.800227 -269.40974) (xy 382.773924 -269.368144) (xy 382.754633 -269.322868)
			(xy 382.742856 -269.275084) (xy 382.738896 -269.22603) (xy 382.410208 -269.22603) (xy 382.409713 -269.250637)
			(xy 382.401818 -269.299214) (xy 382.386234 -269.345895) (xy 382.363363 -269.389472) (xy 382.333798 -269.428816)
			(xy 382.298305 -269.462908) (xy 382.257802 -269.490864) (xy 382.21334 -269.511962) (xy 382.166069 -269.525654)
			(xy 382.117214 -269.531586) (xy 382.068039 -269.529605) (xy 382.01982 -269.519761) (xy 381.973804 -269.502309)
			(xy 381.931183 -269.477702) (xy 381.893062 -269.446577) (xy 381.860427 -269.40974) (xy 381.834124 -269.368144)
			(xy 381.814833 -269.322868) (xy 381.803056 -269.275084) (xy 381.799096 -269.22603) (xy 381.480568 -269.22603)
			(xy 381.480056 -269.251476) (xy 381.471892 -269.30171) (xy 381.455776 -269.349984) (xy 381.432125 -269.395047)
			(xy 381.401552 -269.435733) (xy 381.364848 -269.470988) (xy 381.322964 -269.499898) (xy 381.276985 -269.521715)
			(xy 381.228101 -269.535875) (xy 381.17758 -269.542009) (xy 381.126728 -269.53996) (xy 381.076864 -269.52978)
			(xy 381.029278 -269.511733) (xy 380.985204 -269.486287) (xy 380.945782 -269.4541) (xy 380.912034 -269.416006)
			(xy 380.884833 -269.372992) (xy 380.864885 -269.326172) (xy 380.852706 -269.276758) (xy 380.848611 -269.22603)
			(xy 380.5301 -269.22603) (xy 380.529605 -269.250637) (xy 380.52171 -269.299214) (xy 380.506126 -269.345895)
			(xy 380.483255 -269.389472) (xy 380.45369 -269.428816) (xy 380.418197 -269.462908) (xy 380.377694 -269.490864)
			(xy 380.333232 -269.511962) (xy 380.285961 -269.525654) (xy 380.237106 -269.531586) (xy 380.187931 -269.529605)
			(xy 380.139712 -269.519761) (xy 380.093696 -269.502309) (xy 380.051075 -269.477702) (xy 380.012954 -269.446577)
			(xy 379.980319 -269.40974) (xy 379.954016 -269.368144) (xy 379.934725 -269.322868) (xy 379.922948 -269.275084)
			(xy 379.918988 -269.22603) (xy 379.590046 -269.22603) (xy 379.589551 -269.250637) (xy 379.581656 -269.299214)
			(xy 379.566072 -269.345895) (xy 379.543201 -269.389472) (xy 379.513636 -269.428816) (xy 379.478143 -269.462908)
			(xy 379.43764 -269.490864) (xy 379.393178 -269.511962) (xy 379.345907 -269.525654) (xy 379.297052 -269.531586)
			(xy 379.247877 -269.529605) (xy 379.199658 -269.519761) (xy 379.153642 -269.502309) (xy 379.111021 -269.477702)
			(xy 379.0729 -269.446577) (xy 379.040265 -269.40974) (xy 379.013962 -269.368144) (xy 378.994671 -269.322868)
			(xy 378.982894 -269.275084) (xy 378.978934 -269.22603) (xy 378.650246 -269.22603) (xy 378.649751 -269.250637)
			(xy 378.641856 -269.299214) (xy 378.626272 -269.345895) (xy 378.603401 -269.389472) (xy 378.573836 -269.428816)
			(xy 378.538343 -269.462908) (xy 378.49784 -269.490864) (xy 378.453378 -269.511962) (xy 378.406107 -269.525654)
			(xy 378.357252 -269.531586) (xy 378.308077 -269.529605) (xy 378.259858 -269.519761) (xy 378.213842 -269.502309)
			(xy 378.171221 -269.477702) (xy 378.1331 -269.446577) (xy 378.100465 -269.40974) (xy 378.074162 -269.368144)
			(xy 378.054871 -269.322868) (xy 378.043094 -269.275084) (xy 378.039134 -269.22603) (xy 377.720606 -269.22603)
			(xy 377.720094 -269.251476) (xy 377.71193 -269.30171) (xy 377.695814 -269.349984) (xy 377.672163 -269.395047)
			(xy 377.64159 -269.435733) (xy 377.604886 -269.470988) (xy 377.563002 -269.499898) (xy 377.517023 -269.521715)
			(xy 377.468139 -269.535875) (xy 377.417618 -269.542009) (xy 377.366766 -269.53996) (xy 377.316902 -269.52978)
			(xy 377.269316 -269.511733) (xy 377.225242 -269.486287) (xy 377.18582 -269.4541) (xy 377.152072 -269.416006)
			(xy 377.124871 -269.372992) (xy 377.104923 -269.326172) (xy 377.092744 -269.276758) (xy 377.088649 -269.22603)
			(xy 376.770138 -269.22603) (xy 376.769643 -269.250637) (xy 376.761748 -269.299214) (xy 376.746164 -269.345895)
			(xy 376.723293 -269.389472) (xy 376.693728 -269.428816) (xy 376.658235 -269.462908) (xy 376.617732 -269.490864)
			(xy 376.57327 -269.511962) (xy 376.525999 -269.525654) (xy 376.477144 -269.531586) (xy 376.427969 -269.529605)
			(xy 376.37975 -269.519761) (xy 376.333734 -269.502309) (xy 376.291113 -269.477702) (xy 376.252992 -269.446577)
			(xy 376.220357 -269.40974) (xy 376.194054 -269.368144) (xy 376.174763 -269.322868) (xy 376.162986 -269.275084)
			(xy 376.159026 -269.22603) (xy 375.830628 -269.22603) (xy 375.826458 -269.27634) (xy 375.814058 -269.325308)
			(xy 375.793766 -269.371566) (xy 375.766137 -269.413853) (xy 375.731924 -269.451015) (xy 375.69206 -269.482039)
			(xy 375.647634 -269.506078) (xy 375.599857 -269.522477) (xy 375.550033 -269.530787) (xy 375.524776 -269.531338)
			(xy 375.502158 -269.530932) (xy 375.457416 -269.524258) (xy 375.414153 -269.511046) (xy 375.373316 -269.491585)
			(xy 375.354342 -269.479268) (xy 375.342404 -269.471394) (xy 375.314718 -269.46987) (xy 375.223024 -269.518892)
			(xy 375.215061 -269.523546) (xy 375.202881 -269.537376) (xy 375.196414 -269.554634) (xy 375.1961 -269.56385)
			(xy 375.1961 -269.736062) (xy 375.196373 -269.744592) (xy 375.201901 -269.760728) (xy 375.21245 -269.774131)
			(xy 375.219468 -269.778988) (xy 375.240663 -269.793152) (xy 375.278445 -269.827371) (xy 375.310013 -269.867394)
			(xy 375.334491 -269.912107) (xy 375.351197 -269.960266) (xy 375.359666 -270.010532) (xy 375.359664 -270.036036)
			(xy 375.678695 -270.036036) (xy 375.68279 -269.985308) (xy 375.694969 -269.935894) (xy 375.714917 -269.889074)
			(xy 375.742118 -269.84606) (xy 375.775866 -269.807966) (xy 375.815288 -269.775779) (xy 375.859362 -269.750333)
			(xy 375.906948 -269.732286) (xy 375.956812 -269.722106) (xy 376.007664 -269.720057) (xy 376.058185 -269.726191)
			(xy 376.107069 -269.740351) (xy 376.153048 -269.762168) (xy 376.194932 -269.791078) (xy 376.231636 -269.826333)
			(xy 376.262209 -269.867019) (xy 376.28586 -269.912082) (xy 376.301976 -269.960356) (xy 376.31014 -270.01059)
			(xy 376.310652 -270.036036) (xy 376.628926 -270.036036) (xy 376.632886 -269.986982) (xy 376.644663 -269.939198)
			(xy 376.663954 -269.893922) (xy 376.690257 -269.852326) (xy 376.722892 -269.815489) (xy 376.761013 -269.784364)
			(xy 376.803634 -269.759757) (xy 376.84965 -269.742305) (xy 376.897869 -269.732461) (xy 376.947044 -269.73048)
			(xy 376.995899 -269.736412) (xy 377.04317 -269.750104) (xy 377.087632 -269.771202) (xy 377.128135 -269.799158)
			(xy 377.163628 -269.83325) (xy 377.193193 -269.872594) (xy 377.216064 -269.916171) (xy 377.231648 -269.962852)
			(xy 377.239543 -270.011429) (xy 377.240038 -270.036036) (xy 377.558549 -270.036036) (xy 377.562644 -269.985308)
			(xy 377.574823 -269.935894) (xy 377.594771 -269.889074) (xy 377.621972 -269.84606) (xy 377.65572 -269.807966)
			(xy 377.695142 -269.775779) (xy 377.739216 -269.750333) (xy 377.786802 -269.732286) (xy 377.836666 -269.722106)
			(xy 377.887518 -269.720057) (xy 377.938039 -269.726191) (xy 377.986923 -269.740351) (xy 378.032902 -269.762168)
			(xy 378.074786 -269.791078) (xy 378.11149 -269.826333) (xy 378.142063 -269.867019) (xy 378.165714 -269.912082)
			(xy 378.18183 -269.960356) (xy 378.189994 -270.01059) (xy 378.190506 -270.036036) (xy 378.509034 -270.036036)
			(xy 378.512994 -269.986982) (xy 378.524771 -269.939198) (xy 378.544062 -269.893922) (xy 378.570365 -269.852326)
			(xy 378.603 -269.815489) (xy 378.641121 -269.784364) (xy 378.683742 -269.759757) (xy 378.729758 -269.742305)
			(xy 378.777977 -269.732461) (xy 378.827152 -269.73048) (xy 378.876007 -269.736412) (xy 378.923278 -269.750104)
			(xy 378.96774 -269.771202) (xy 379.008243 -269.799158) (xy 379.043736 -269.83325) (xy 379.073301 -269.872594)
			(xy 379.096172 -269.916171) (xy 379.111756 -269.962852) (xy 379.119651 -270.011429) (xy 379.120146 -270.036036)
			(xy 379.438657 -270.036036) (xy 379.442752 -269.985308) (xy 379.454931 -269.935894) (xy 379.474879 -269.889074)
			(xy 379.50208 -269.84606) (xy 379.535828 -269.807966) (xy 379.57525 -269.775779) (xy 379.619324 -269.750333)
			(xy 379.66691 -269.732286) (xy 379.716774 -269.722106) (xy 379.767626 -269.720057) (xy 379.818147 -269.726191)
			(xy 379.867031 -269.740351) (xy 379.91301 -269.762168) (xy 379.954894 -269.791078) (xy 379.991598 -269.826333)
			(xy 380.022171 -269.867019) (xy 380.045822 -269.912082) (xy 380.061938 -269.960356) (xy 380.070102 -270.01059)
			(xy 380.070614 -270.036036) (xy 380.378711 -270.036036) (xy 380.382806 -269.985308) (xy 380.394985 -269.935894)
			(xy 380.414933 -269.889074) (xy 380.442134 -269.84606) (xy 380.475882 -269.807966) (xy 380.515304 -269.775779)
			(xy 380.559378 -269.750333) (xy 380.606964 -269.732286) (xy 380.656828 -269.722106) (xy 380.70768 -269.720057)
			(xy 380.758201 -269.726191) (xy 380.807085 -269.740351) (xy 380.853064 -269.762168) (xy 380.894948 -269.791078)
			(xy 380.931652 -269.826333) (xy 380.962225 -269.867019) (xy 380.985876 -269.912082) (xy 381.001992 -269.960356)
			(xy 381.010156 -270.01059) (xy 381.010668 -270.036036) (xy 381.328942 -270.036036) (xy 381.332902 -269.986982)
			(xy 381.344679 -269.939198) (xy 381.36397 -269.893922) (xy 381.390273 -269.852326) (xy 381.422908 -269.815489)
			(xy 381.461029 -269.784364) (xy 381.50365 -269.759757) (xy 381.549666 -269.742305) (xy 381.597885 -269.732461)
			(xy 381.64706 -269.73048) (xy 381.695915 -269.736412) (xy 381.743186 -269.750104) (xy 381.787648 -269.771202)
			(xy 381.828151 -269.799158) (xy 381.863644 -269.83325) (xy 381.893209 -269.872594) (xy 381.91608 -269.916171)
			(xy 381.931664 -269.962852) (xy 381.939559 -270.011429) (xy 381.940054 -270.036036) (xy 382.258565 -270.036036)
			(xy 382.26266 -269.985308) (xy 382.274839 -269.935894) (xy 382.294787 -269.889074) (xy 382.321988 -269.84606)
			(xy 382.355736 -269.807966) (xy 382.395158 -269.775779) (xy 382.439232 -269.750333) (xy 382.486818 -269.732286)
			(xy 382.536682 -269.722106) (xy 382.587534 -269.720057) (xy 382.638055 -269.726191) (xy 382.686939 -269.740351)
			(xy 382.732918 -269.762168) (xy 382.774802 -269.791078) (xy 382.811506 -269.826333) (xy 382.842079 -269.867019)
			(xy 382.86573 -269.912082) (xy 382.881846 -269.960356) (xy 382.89001 -270.01059) (xy 382.890522 -270.036036)
			(xy 383.20905 -270.036036) (xy 383.21301 -269.986982) (xy 383.224787 -269.939198) (xy 383.244078 -269.893922)
			(xy 383.270381 -269.852326) (xy 383.303016 -269.815489) (xy 383.341137 -269.784364) (xy 383.383758 -269.759757)
			(xy 383.429774 -269.742305) (xy 383.477993 -269.732461) (xy 383.527168 -269.73048) (xy 383.576023 -269.736412)
			(xy 383.623294 -269.750104) (xy 383.667756 -269.771202) (xy 383.708259 -269.799158) (xy 383.743752 -269.83325)
			(xy 383.773317 -269.872594) (xy 383.796188 -269.916171) (xy 383.811772 -269.962852) (xy 383.819667 -270.011429)
			(xy 383.820162 -270.036036) (xy 384.138673 -270.036036) (xy 384.142768 -269.985308) (xy 384.154947 -269.935894)
			(xy 384.174895 -269.889074) (xy 384.202096 -269.84606) (xy 384.235844 -269.807966) (xy 384.275266 -269.775779)
			(xy 384.31934 -269.750333) (xy 384.366926 -269.732286) (xy 384.41679 -269.722106) (xy 384.467642 -269.720057)
			(xy 384.518163 -269.726191) (xy 384.567047 -269.740351) (xy 384.613026 -269.762168) (xy 384.65491 -269.791078)
			(xy 384.691614 -269.826333) (xy 384.722187 -269.867019) (xy 384.745838 -269.912082) (xy 384.761954 -269.960356)
			(xy 384.770118 -270.01059) (xy 384.77063 -270.036036) (xy 385.088904 -270.036036) (xy 385.092864 -269.986982)
			(xy 385.104641 -269.939198) (xy 385.123932 -269.893922) (xy 385.150235 -269.852326) (xy 385.18287 -269.815489)
			(xy 385.220991 -269.784364) (xy 385.263612 -269.759757) (xy 385.309628 -269.742305) (xy 385.357847 -269.732461)
			(xy 385.407022 -269.73048) (xy 385.455877 -269.736412) (xy 385.503148 -269.750104) (xy 385.54761 -269.771202)
			(xy 385.588113 -269.799158) (xy 385.623606 -269.83325) (xy 385.653171 -269.872594) (xy 385.676042 -269.916171)
			(xy 385.691626 -269.962852) (xy 385.699521 -270.011429) (xy 385.700016 -270.036036) (xy 386.018527 -270.036036)
			(xy 386.022622 -269.985308) (xy 386.034801 -269.935894) (xy 386.054749 -269.889074) (xy 386.08195 -269.84606)
			(xy 386.115698 -269.807966) (xy 386.15512 -269.775779) (xy 386.199194 -269.750333) (xy 386.24678 -269.732286)
			(xy 386.296644 -269.722106) (xy 386.347496 -269.720057) (xy 386.398017 -269.726191) (xy 386.446901 -269.740351)
			(xy 386.49288 -269.762168) (xy 386.534764 -269.791078) (xy 386.571468 -269.826333) (xy 386.602041 -269.867019)
			(xy 386.625692 -269.912082) (xy 386.641808 -269.960356) (xy 386.649972 -270.01059) (xy 386.650484 -270.036036)
			(xy 386.958581 -270.036036) (xy 386.962676 -269.985308) (xy 386.974855 -269.935894) (xy 386.994803 -269.889074)
			(xy 387.022004 -269.84606) (xy 387.055752 -269.807966) (xy 387.095174 -269.775779) (xy 387.139248 -269.750333)
			(xy 387.186834 -269.732286) (xy 387.236698 -269.722106) (xy 387.28755 -269.720057) (xy 387.338071 -269.726191)
			(xy 387.386955 -269.740351) (xy 387.432934 -269.762168) (xy 387.474818 -269.791078) (xy 387.511522 -269.826333)
			(xy 387.542095 -269.867019) (xy 387.565746 -269.912082) (xy 387.581862 -269.960356) (xy 387.590026 -270.01059)
			(xy 387.590538 -270.036036) (xy 387.909066 -270.036036) (xy 387.913026 -269.986982) (xy 387.924803 -269.939198)
			(xy 387.944094 -269.893922) (xy 387.970397 -269.852326) (xy 388.003032 -269.815489) (xy 388.041153 -269.784364)
			(xy 388.083774 -269.759757) (xy 388.12979 -269.742305) (xy 388.178009 -269.732461) (xy 388.227184 -269.73048)
			(xy 388.276039 -269.736412) (xy 388.32331 -269.750104) (xy 388.367772 -269.771202) (xy 388.408275 -269.799158)
			(xy 388.443768 -269.83325) (xy 388.473333 -269.872594) (xy 388.496204 -269.916171) (xy 388.511788 -269.962852)
			(xy 388.519683 -270.011429) (xy 388.520178 -270.036036) (xy 388.838689 -270.036036) (xy 388.842784 -269.985308)
			(xy 388.854963 -269.935894) (xy 388.874911 -269.889074) (xy 388.902112 -269.84606) (xy 388.93586 -269.807966)
			(xy 388.975282 -269.775779) (xy 389.019356 -269.750333) (xy 389.066942 -269.732286) (xy 389.116806 -269.722106)
			(xy 389.167658 -269.720057) (xy 389.218179 -269.726191) (xy 389.267063 -269.740351) (xy 389.313042 -269.762168)
			(xy 389.354926 -269.791078) (xy 389.39163 -269.826333) (xy 389.422203 -269.867019) (xy 389.445854 -269.912082)
			(xy 389.46197 -269.960356) (xy 389.470134 -270.01059) (xy 389.470646 -270.036036) (xy 389.78892 -270.036036)
			(xy 389.79288 -269.986982) (xy 389.804657 -269.939198) (xy 389.823948 -269.893922) (xy 389.850251 -269.852326)
			(xy 389.882886 -269.815489) (xy 389.921007 -269.784364) (xy 389.963628 -269.759757) (xy 390.009644 -269.742305)
			(xy 390.057863 -269.732461) (xy 390.107038 -269.73048) (xy 390.155893 -269.736412) (xy 390.203164 -269.750104)
			(xy 390.247626 -269.771202) (xy 390.288129 -269.799158) (xy 390.323622 -269.83325) (xy 390.353187 -269.872594)
			(xy 390.376058 -269.916171) (xy 390.391642 -269.962852) (xy 390.399537 -270.011429) (xy 390.400032 -270.036036)
			(xy 390.718543 -270.036036) (xy 390.722638 -269.985308) (xy 390.734817 -269.935894) (xy 390.754765 -269.889074)
			(xy 390.781966 -269.84606) (xy 390.815714 -269.807966) (xy 390.855136 -269.775779) (xy 390.89921 -269.750333)
			(xy 390.946796 -269.732286) (xy 390.99666 -269.722106) (xy 391.047512 -269.720057) (xy 391.098033 -269.726191)
			(xy 391.146917 -269.740351) (xy 391.192896 -269.762168) (xy 391.23478 -269.791078) (xy 391.271484 -269.826333)
			(xy 391.302057 -269.867019) (xy 391.325708 -269.912082) (xy 391.341824 -269.960356) (xy 391.349988 -270.01059)
			(xy 391.3505 -270.036036) (xy 391.669028 -270.036036) (xy 391.672988 -269.986982) (xy 391.684765 -269.939198)
			(xy 391.704056 -269.893922) (xy 391.730359 -269.852326) (xy 391.762994 -269.815489) (xy 391.801115 -269.784364)
			(xy 391.843736 -269.759757) (xy 391.889752 -269.742305) (xy 391.937971 -269.732461) (xy 391.987146 -269.73048)
			(xy 392.036001 -269.736412) (xy 392.083272 -269.750104) (xy 392.125407 -269.770098) (xy 394.67715 -269.770098)
			(xy 394.68111 -269.721044) (xy 394.692887 -269.67326) (xy 394.712178 -269.627984) (xy 394.738481 -269.586388)
			(xy 394.771116 -269.549551) (xy 394.809237 -269.518426) (xy 394.851858 -269.493819) (xy 394.897874 -269.476367)
			(xy 394.946093 -269.466523) (xy 394.995268 -269.464542) (xy 395.044123 -269.470474) (xy 395.091394 -269.484166)
			(xy 395.135856 -269.505264) (xy 395.176359 -269.53322) (xy 395.211852 -269.567312) (xy 395.241417 -269.606656)
			(xy 395.264288 -269.650233) (xy 395.279872 -269.696914) (xy 395.287767 -269.745491) (xy 395.288262 -269.770098)
			(xy 395.287767 -269.794705) (xy 395.279872 -269.843282) (xy 395.264288 -269.889963) (xy 395.241417 -269.93354)
			(xy 395.211852 -269.972884) (xy 395.176359 -270.006976) (xy 395.135856 -270.034932) (xy 395.091394 -270.05603)
			(xy 395.044123 -270.069722) (xy 394.995268 -270.075654) (xy 394.946093 -270.073673) (xy 394.897874 -270.063829)
			(xy 394.851858 -270.046377) (xy 394.809237 -270.02177) (xy 394.771116 -269.990645) (xy 394.738481 -269.953808)
			(xy 394.712178 -269.912212) (xy 394.692887 -269.866936) (xy 394.68111 -269.819152) (xy 394.67715 -269.770098)
			(xy 392.125407 -269.770098) (xy 392.127734 -269.771202) (xy 392.168237 -269.799158) (xy 392.20373 -269.83325)
			(xy 392.233295 -269.872594) (xy 392.256166 -269.916171) (xy 392.27175 -269.962852) (xy 392.279645 -270.011429)
			(xy 392.28014 -270.036036) (xy 392.279645 -270.060643) (xy 392.27175 -270.10922) (xy 392.256166 -270.155901)
			(xy 392.233295 -270.199478) (xy 392.20373 -270.238822) (xy 392.168237 -270.272914) (xy 392.127734 -270.30087)
			(xy 392.083272 -270.321968) (xy 392.036001 -270.33566) (xy 391.987146 -270.341592) (xy 391.937971 -270.339611)
			(xy 391.889752 -270.329767) (xy 391.843736 -270.312315) (xy 391.801115 -270.287708) (xy 391.762994 -270.256583)
			(xy 391.730359 -270.219746) (xy 391.704056 -270.17815) (xy 391.684765 -270.132874) (xy 391.672988 -270.08509)
			(xy 391.669028 -270.036036) (xy 391.3505 -270.036036) (xy 391.349988 -270.061482) (xy 391.341824 -270.111716)
			(xy 391.325708 -270.15999) (xy 391.302057 -270.205053) (xy 391.271484 -270.245739) (xy 391.23478 -270.280994)
			(xy 391.192896 -270.309904) (xy 391.146917 -270.331721) (xy 391.098033 -270.345881) (xy 391.047512 -270.352015)
			(xy 390.99666 -270.349966) (xy 390.946796 -270.339786) (xy 390.89921 -270.321739) (xy 390.855136 -270.296293)
			(xy 390.815714 -270.264106) (xy 390.781966 -270.226012) (xy 390.754765 -270.182998) (xy 390.734817 -270.136178)
			(xy 390.722638 -270.086764) (xy 390.718543 -270.036036) (xy 390.400032 -270.036036) (xy 390.399537 -270.060643)
			(xy 390.391642 -270.10922) (xy 390.376058 -270.155901) (xy 390.353187 -270.199478) (xy 390.323622 -270.238822)
			(xy 390.288129 -270.272914) (xy 390.247626 -270.30087) (xy 390.203164 -270.321968) (xy 390.155893 -270.33566)
			(xy 390.107038 -270.341592) (xy 390.057863 -270.339611) (xy 390.009644 -270.329767) (xy 389.963628 -270.312315)
			(xy 389.921007 -270.287708) (xy 389.882886 -270.256583) (xy 389.850251 -270.219746) (xy 389.823948 -270.17815)
			(xy 389.804657 -270.132874) (xy 389.79288 -270.08509) (xy 389.78892 -270.036036) (xy 389.470646 -270.036036)
			(xy 389.470134 -270.061482) (xy 389.46197 -270.111716) (xy 389.445854 -270.15999) (xy 389.422203 -270.205053)
			(xy 389.39163 -270.245739) (xy 389.354926 -270.280994) (xy 389.313042 -270.309904) (xy 389.267063 -270.331721)
			(xy 389.218179 -270.345881) (xy 389.167658 -270.352015) (xy 389.116806 -270.349966) (xy 389.066942 -270.339786)
			(xy 389.019356 -270.321739) (xy 388.975282 -270.296293) (xy 388.93586 -270.264106) (xy 388.902112 -270.226012)
			(xy 388.874911 -270.182998) (xy 388.854963 -270.136178) (xy 388.842784 -270.086764) (xy 388.838689 -270.036036)
			(xy 388.520178 -270.036036) (xy 388.519683 -270.060643) (xy 388.511788 -270.10922) (xy 388.496204 -270.155901)
			(xy 388.473333 -270.199478) (xy 388.443768 -270.238822) (xy 388.408275 -270.272914) (xy 388.367772 -270.30087)
			(xy 388.32331 -270.321968) (xy 388.276039 -270.33566) (xy 388.227184 -270.341592) (xy 388.178009 -270.339611)
			(xy 388.12979 -270.329767) (xy 388.083774 -270.312315) (xy 388.041153 -270.287708) (xy 388.003032 -270.256583)
			(xy 387.970397 -270.219746) (xy 387.944094 -270.17815) (xy 387.924803 -270.132874) (xy 387.913026 -270.08509)
			(xy 387.909066 -270.036036) (xy 387.590538 -270.036036) (xy 387.590026 -270.061482) (xy 387.581862 -270.111716)
			(xy 387.565746 -270.15999) (xy 387.542095 -270.205053) (xy 387.511522 -270.245739) (xy 387.474818 -270.280994)
			(xy 387.432934 -270.309904) (xy 387.386955 -270.331721) (xy 387.338071 -270.345881) (xy 387.28755 -270.352015)
			(xy 387.236698 -270.349966) (xy 387.186834 -270.339786) (xy 387.139248 -270.321739) (xy 387.095174 -270.296293)
			(xy 387.055752 -270.264106) (xy 387.022004 -270.226012) (xy 386.994803 -270.182998) (xy 386.974855 -270.136178)
			(xy 386.962676 -270.086764) (xy 386.958581 -270.036036) (xy 386.650484 -270.036036) (xy 386.649972 -270.061482)
			(xy 386.641808 -270.111716) (xy 386.625692 -270.15999) (xy 386.602041 -270.205053) (xy 386.571468 -270.245739)
			(xy 386.534764 -270.280994) (xy 386.49288 -270.309904) (xy 386.446901 -270.331721) (xy 386.398017 -270.345881)
			(xy 386.347496 -270.352015) (xy 386.296644 -270.349966) (xy 386.24678 -270.339786) (xy 386.199194 -270.321739)
			(xy 386.15512 -270.296293) (xy 386.115698 -270.264106) (xy 386.08195 -270.226012) (xy 386.054749 -270.182998)
			(xy 386.034801 -270.136178) (xy 386.022622 -270.086764) (xy 386.018527 -270.036036) (xy 385.700016 -270.036036)
			(xy 385.699521 -270.060643) (xy 385.691626 -270.10922) (xy 385.676042 -270.155901) (xy 385.653171 -270.199478)
			(xy 385.623606 -270.238822) (xy 385.588113 -270.272914) (xy 385.54761 -270.30087) (xy 385.503148 -270.321968)
			(xy 385.455877 -270.33566) (xy 385.407022 -270.341592) (xy 385.357847 -270.339611) (xy 385.309628 -270.329767)
			(xy 385.263612 -270.312315) (xy 385.220991 -270.287708) (xy 385.18287 -270.256583) (xy 385.150235 -270.219746)
			(xy 385.123932 -270.17815) (xy 385.104641 -270.132874) (xy 385.092864 -270.08509) (xy 385.088904 -270.036036)
			(xy 384.77063 -270.036036) (xy 384.770118 -270.061482) (xy 384.761954 -270.111716) (xy 384.745838 -270.15999)
			(xy 384.722187 -270.205053) (xy 384.691614 -270.245739) (xy 384.65491 -270.280994) (xy 384.613026 -270.309904)
			(xy 384.567047 -270.331721) (xy 384.518163 -270.345881) (xy 384.467642 -270.352015) (xy 384.41679 -270.349966)
			(xy 384.366926 -270.339786) (xy 384.31934 -270.321739) (xy 384.275266 -270.296293) (xy 384.235844 -270.264106)
			(xy 384.202096 -270.226012) (xy 384.174895 -270.182998) (xy 384.154947 -270.136178) (xy 384.142768 -270.086764)
			(xy 384.138673 -270.036036) (xy 383.820162 -270.036036) (xy 383.819667 -270.060643) (xy 383.811772 -270.10922)
			(xy 383.796188 -270.155901) (xy 383.773317 -270.199478) (xy 383.743752 -270.238822) (xy 383.708259 -270.272914)
			(xy 383.667756 -270.30087) (xy 383.623294 -270.321968) (xy 383.576023 -270.33566) (xy 383.527168 -270.341592)
			(xy 383.477993 -270.339611) (xy 383.429774 -270.329767) (xy 383.383758 -270.312315) (xy 383.341137 -270.287708)
			(xy 383.303016 -270.256583) (xy 383.270381 -270.219746) (xy 383.244078 -270.17815) (xy 383.224787 -270.132874)
			(xy 383.21301 -270.08509) (xy 383.20905 -270.036036) (xy 382.890522 -270.036036) (xy 382.89001 -270.061482)
			(xy 382.881846 -270.111716) (xy 382.86573 -270.15999) (xy 382.842079 -270.205053) (xy 382.811506 -270.245739)
			(xy 382.774802 -270.280994) (xy 382.732918 -270.309904) (xy 382.686939 -270.331721) (xy 382.638055 -270.345881)
			(xy 382.587534 -270.352015) (xy 382.536682 -270.349966) (xy 382.486818 -270.339786) (xy 382.439232 -270.321739)
			(xy 382.395158 -270.296293) (xy 382.355736 -270.264106) (xy 382.321988 -270.226012) (xy 382.294787 -270.182998)
			(xy 382.274839 -270.136178) (xy 382.26266 -270.086764) (xy 382.258565 -270.036036) (xy 381.940054 -270.036036)
			(xy 381.939559 -270.060643) (xy 381.931664 -270.10922) (xy 381.91608 -270.155901) (xy 381.893209 -270.199478)
			(xy 381.863644 -270.238822) (xy 381.828151 -270.272914) (xy 381.787648 -270.30087) (xy 381.743186 -270.321968)
			(xy 381.695915 -270.33566) (xy 381.64706 -270.341592) (xy 381.597885 -270.339611) (xy 381.549666 -270.329767)
			(xy 381.50365 -270.312315) (xy 381.461029 -270.287708) (xy 381.422908 -270.256583) (xy 381.390273 -270.219746)
			(xy 381.36397 -270.17815) (xy 381.344679 -270.132874) (xy 381.332902 -270.08509) (xy 381.328942 -270.036036)
			(xy 381.010668 -270.036036) (xy 381.010156 -270.061482) (xy 381.001992 -270.111716) (xy 380.985876 -270.15999)
			(xy 380.962225 -270.205053) (xy 380.931652 -270.245739) (xy 380.894948 -270.280994) (xy 380.853064 -270.309904)
			(xy 380.807085 -270.331721) (xy 380.758201 -270.345881) (xy 380.70768 -270.352015) (xy 380.656828 -270.349966)
			(xy 380.606964 -270.339786) (xy 380.559378 -270.321739) (xy 380.515304 -270.296293) (xy 380.475882 -270.264106)
			(xy 380.442134 -270.226012) (xy 380.414933 -270.182998) (xy 380.394985 -270.136178) (xy 380.382806 -270.086764)
			(xy 380.378711 -270.036036) (xy 380.070614 -270.036036) (xy 380.070102 -270.061482) (xy 380.061938 -270.111716)
			(xy 380.045822 -270.15999) (xy 380.022171 -270.205053) (xy 379.991598 -270.245739) (xy 379.954894 -270.280994)
			(xy 379.91301 -270.309904) (xy 379.867031 -270.331721) (xy 379.818147 -270.345881) (xy 379.767626 -270.352015)
			(xy 379.716774 -270.349966) (xy 379.66691 -270.339786) (xy 379.619324 -270.321739) (xy 379.57525 -270.296293)
			(xy 379.535828 -270.264106) (xy 379.50208 -270.226012) (xy 379.474879 -270.182998) (xy 379.454931 -270.136178)
			(xy 379.442752 -270.086764) (xy 379.438657 -270.036036) (xy 379.120146 -270.036036) (xy 379.119651 -270.060643)
			(xy 379.111756 -270.10922) (xy 379.096172 -270.155901) (xy 379.073301 -270.199478) (xy 379.043736 -270.238822)
			(xy 379.008243 -270.272914) (xy 378.96774 -270.30087) (xy 378.923278 -270.321968) (xy 378.876007 -270.33566)
			(xy 378.827152 -270.341592) (xy 378.777977 -270.339611) (xy 378.729758 -270.329767) (xy 378.683742 -270.312315)
			(xy 378.641121 -270.287708) (xy 378.603 -270.256583) (xy 378.570365 -270.219746) (xy 378.544062 -270.17815)
			(xy 378.524771 -270.132874) (xy 378.512994 -270.08509) (xy 378.509034 -270.036036) (xy 378.190506 -270.036036)
			(xy 378.189994 -270.061482) (xy 378.18183 -270.111716) (xy 378.165714 -270.15999) (xy 378.142063 -270.205053)
			(xy 378.11149 -270.245739) (xy 378.074786 -270.280994) (xy 378.032902 -270.309904) (xy 377.986923 -270.331721)
			(xy 377.938039 -270.345881) (xy 377.887518 -270.352015) (xy 377.836666 -270.349966) (xy 377.786802 -270.339786)
			(xy 377.739216 -270.321739) (xy 377.695142 -270.296293) (xy 377.65572 -270.264106) (xy 377.621972 -270.226012)
			(xy 377.594771 -270.182998) (xy 377.574823 -270.136178) (xy 377.562644 -270.086764) (xy 377.558549 -270.036036)
			(xy 377.240038 -270.036036) (xy 377.239543 -270.060643) (xy 377.231648 -270.10922) (xy 377.216064 -270.155901)
			(xy 377.193193 -270.199478) (xy 377.163628 -270.238822) (xy 377.128135 -270.272914) (xy 377.087632 -270.30087)
			(xy 377.04317 -270.321968) (xy 376.995899 -270.33566) (xy 376.947044 -270.341592) (xy 376.897869 -270.339611)
			(xy 376.84965 -270.329767) (xy 376.803634 -270.312315) (xy 376.761013 -270.287708) (xy 376.722892 -270.256583)
			(xy 376.690257 -270.219746) (xy 376.663954 -270.17815) (xy 376.644663 -270.132874) (xy 376.632886 -270.08509)
			(xy 376.628926 -270.036036) (xy 376.310652 -270.036036) (xy 376.31014 -270.061482) (xy 376.301976 -270.111716)
			(xy 376.28586 -270.15999) (xy 376.262209 -270.205053) (xy 376.231636 -270.245739) (xy 376.194932 -270.280994)
			(xy 376.153048 -270.309904) (xy 376.107069 -270.331721) (xy 376.058185 -270.345881) (xy 376.007664 -270.352015)
			(xy 375.956812 -270.349966) (xy 375.906948 -270.339786) (xy 375.859362 -270.321739) (xy 375.815288 -270.296293)
			(xy 375.775866 -270.264106) (xy 375.742118 -270.226012) (xy 375.714917 -270.182998) (xy 375.694969 -270.136178)
			(xy 375.68279 -270.086764) (xy 375.678695 -270.036036) (xy 375.359664 -270.036036) (xy 375.359662 -270.061507)
			(xy 375.351187 -270.111771) (xy 375.334475 -270.159929) (xy 375.309992 -270.204638) (xy 375.278418 -270.244657)
			(xy 375.240632 -270.278871) (xy 375.219468 -270.293084) (xy 375.212473 -270.297966) (xy 375.201943 -270.311373)
			(xy 375.196374 -270.327486) (xy 375.1961 -270.33601) (xy 375.1961 -270.846042) (xy 376.148595 -270.846042)
			(xy 376.15269 -270.795314) (xy 376.164869 -270.7459) (xy 376.184817 -270.69908) (xy 376.212018 -270.656066)
			(xy 376.245766 -270.617972) (xy 376.285188 -270.585785) (xy 376.329262 -270.560339) (xy 376.376848 -270.542292)
			(xy 376.426712 -270.532112) (xy 376.477564 -270.530063) (xy 376.528085 -270.536197) (xy 376.576969 -270.550357)
			(xy 376.622948 -270.572174) (xy 376.664832 -270.601084) (xy 376.701536 -270.636339) (xy 376.732109 -270.677025)
			(xy 376.75576 -270.722088) (xy 376.771876 -270.770362) (xy 376.78004 -270.820596) (xy 376.780552 -270.846042)
			(xy 377.088649 -270.846042) (xy 377.092744 -270.795314) (xy 377.104923 -270.7459) (xy 377.124871 -270.69908)
			(xy 377.152072 -270.656066) (xy 377.18582 -270.617972) (xy 377.225242 -270.585785) (xy 377.269316 -270.560339)
			(xy 377.316902 -270.542292) (xy 377.366766 -270.532112) (xy 377.417618 -270.530063) (xy 377.468139 -270.536197)
			(xy 377.517023 -270.550357) (xy 377.563002 -270.572174) (xy 377.604886 -270.601084) (xy 377.64159 -270.636339)
			(xy 377.672163 -270.677025) (xy 377.695814 -270.722088) (xy 377.71193 -270.770362) (xy 377.720094 -270.820596)
			(xy 377.720606 -270.846042) (xy 378.968503 -270.846042) (xy 378.972598 -270.795314) (xy 378.984777 -270.7459)
			(xy 379.004725 -270.69908) (xy 379.031926 -270.656066) (xy 379.065674 -270.617972) (xy 379.105096 -270.585785)
			(xy 379.14917 -270.560339) (xy 379.196756 -270.542292) (xy 379.24662 -270.532112) (xy 379.297472 -270.530063)
			(xy 379.347993 -270.536197) (xy 379.396877 -270.550357) (xy 379.442856 -270.572174) (xy 379.48474 -270.601084)
			(xy 379.521444 -270.636339) (xy 379.552017 -270.677025) (xy 379.575668 -270.722088) (xy 379.591784 -270.770362)
			(xy 379.599948 -270.820596) (xy 379.60046 -270.846042) (xy 379.918988 -270.846042) (xy 379.922948 -270.796988)
			(xy 379.934725 -270.749204) (xy 379.954016 -270.703928) (xy 379.980319 -270.662332) (xy 380.012954 -270.625495)
			(xy 380.051075 -270.59437) (xy 380.093696 -270.569763) (xy 380.139712 -270.552311) (xy 380.187931 -270.542467)
			(xy 380.237106 -270.540486) (xy 380.285961 -270.546418) (xy 380.333232 -270.56011) (xy 380.377694 -270.581208)
			(xy 380.418197 -270.609164) (xy 380.45369 -270.643256) (xy 380.483255 -270.6826) (xy 380.506126 -270.726177)
			(xy 380.52171 -270.772858) (xy 380.529605 -270.821435) (xy 380.5301 -270.846042) (xy 380.848611 -270.846042)
			(xy 380.852706 -270.795314) (xy 380.864885 -270.7459) (xy 380.884833 -270.69908) (xy 380.912034 -270.656066)
			(xy 380.945782 -270.617972) (xy 380.985204 -270.585785) (xy 381.029278 -270.560339) (xy 381.076864 -270.542292)
			(xy 381.126728 -270.532112) (xy 381.17758 -270.530063) (xy 381.228101 -270.536197) (xy 381.276985 -270.550357)
			(xy 381.322964 -270.572174) (xy 381.364848 -270.601084) (xy 381.401552 -270.636339) (xy 381.432125 -270.677025)
			(xy 381.455776 -270.722088) (xy 381.471892 -270.770362) (xy 381.480056 -270.820596) (xy 381.480568 -270.846042)
			(xy 381.799096 -270.846042) (xy 381.803056 -270.796988) (xy 381.814833 -270.749204) (xy 381.834124 -270.703928)
			(xy 381.860427 -270.662332) (xy 381.893062 -270.625495) (xy 381.931183 -270.59437) (xy 381.973804 -270.569763)
			(xy 382.01982 -270.552311) (xy 382.068039 -270.542467) (xy 382.117214 -270.540486) (xy 382.166069 -270.546418)
			(xy 382.21334 -270.56011) (xy 382.257802 -270.581208) (xy 382.298305 -270.609164) (xy 382.333798 -270.643256)
			(xy 382.363363 -270.6826) (xy 382.386234 -270.726177) (xy 382.401818 -270.772858) (xy 382.409713 -270.821435)
			(xy 382.410208 -270.846042) (xy 382.728465 -270.846042) (xy 382.73256 -270.795314) (xy 382.744739 -270.7459)
			(xy 382.764687 -270.69908) (xy 382.791888 -270.656066) (xy 382.825636 -270.617972) (xy 382.865058 -270.585785)
			(xy 382.909132 -270.560339) (xy 382.956718 -270.542292) (xy 383.006582 -270.532112) (xy 383.057434 -270.530063)
			(xy 383.107955 -270.536197) (xy 383.156839 -270.550357) (xy 383.202818 -270.572174) (xy 383.244702 -270.601084)
			(xy 383.281406 -270.636339) (xy 383.311979 -270.677025) (xy 383.33563 -270.722088) (xy 383.351746 -270.770362)
			(xy 383.35991 -270.820596) (xy 383.360422 -270.846042) (xy 383.668519 -270.846042) (xy 383.672614 -270.795314)
			(xy 383.684793 -270.7459) (xy 383.704741 -270.69908) (xy 383.731942 -270.656066) (xy 383.76569 -270.617972)
			(xy 383.805112 -270.585785) (xy 383.849186 -270.560339) (xy 383.896772 -270.542292) (xy 383.946636 -270.532112)
			(xy 383.997488 -270.530063) (xy 384.048009 -270.536197) (xy 384.096893 -270.550357) (xy 384.142872 -270.572174)
			(xy 384.184756 -270.601084) (xy 384.22146 -270.636339) (xy 384.252033 -270.677025) (xy 384.275684 -270.722088)
			(xy 384.2918 -270.770362) (xy 384.299964 -270.820596) (xy 384.300476 -270.846042) (xy 385.548627 -270.846042)
			(xy 385.552722 -270.795314) (xy 385.564901 -270.7459) (xy 385.584849 -270.69908) (xy 385.61205 -270.656066)
			(xy 385.645798 -270.617972) (xy 385.68522 -270.585785) (xy 385.729294 -270.560339) (xy 385.77688 -270.542292)
			(xy 385.826744 -270.532112) (xy 385.877596 -270.530063) (xy 385.928117 -270.536197) (xy 385.977001 -270.550357)
			(xy 386.02298 -270.572174) (xy 386.064864 -270.601084) (xy 386.101568 -270.636339) (xy 386.132141 -270.677025)
			(xy 386.155792 -270.722088) (xy 386.171908 -270.770362) (xy 386.180072 -270.820596) (xy 386.180584 -270.846042)
			(xy 386.499112 -270.846042) (xy 386.503072 -270.796988) (xy 386.514849 -270.749204) (xy 386.53414 -270.703928)
			(xy 386.560443 -270.662332) (xy 386.593078 -270.625495) (xy 386.631199 -270.59437) (xy 386.67382 -270.569763)
			(xy 386.719836 -270.552311) (xy 386.768055 -270.542467) (xy 386.81723 -270.540486) (xy 386.866085 -270.546418)
			(xy 386.913356 -270.56011) (xy 386.957818 -270.581208) (xy 386.998321 -270.609164) (xy 387.033814 -270.643256)
			(xy 387.063379 -270.6826) (xy 387.08625 -270.726177) (xy 387.101834 -270.772858) (xy 387.109729 -270.821435)
			(xy 387.110224 -270.846042) (xy 387.428481 -270.846042) (xy 387.432576 -270.795314) (xy 387.444755 -270.7459)
			(xy 387.464703 -270.69908) (xy 387.491904 -270.656066) (xy 387.525652 -270.617972) (xy 387.565074 -270.585785)
			(xy 387.609148 -270.560339) (xy 387.656734 -270.542292) (xy 387.706598 -270.532112) (xy 387.75745 -270.530063)
			(xy 387.807971 -270.536197) (xy 387.856855 -270.550357) (xy 387.902834 -270.572174) (xy 387.944718 -270.601084)
			(xy 387.981422 -270.636339) (xy 388.011995 -270.677025) (xy 388.035646 -270.722088) (xy 388.051762 -270.770362)
			(xy 388.059926 -270.820596) (xy 388.060438 -270.846042) (xy 388.378966 -270.846042) (xy 388.382926 -270.796988)
			(xy 388.394703 -270.749204) (xy 388.413994 -270.703928) (xy 388.440297 -270.662332) (xy 388.472932 -270.625495)
			(xy 388.511053 -270.59437) (xy 388.553674 -270.569763) (xy 388.59969 -270.552311) (xy 388.647909 -270.542467)
			(xy 388.697084 -270.540486) (xy 388.745939 -270.546418) (xy 388.79321 -270.56011) (xy 388.837672 -270.581208)
			(xy 388.878175 -270.609164) (xy 388.913668 -270.643256) (xy 388.943233 -270.6826) (xy 388.966104 -270.726177)
			(xy 388.981688 -270.772858) (xy 388.989583 -270.821435) (xy 388.990078 -270.846042) (xy 389.308589 -270.846042)
			(xy 389.312684 -270.795314) (xy 389.324863 -270.7459) (xy 389.344811 -270.69908) (xy 389.372012 -270.656066)
			(xy 389.40576 -270.617972) (xy 389.445182 -270.585785) (xy 389.489256 -270.560339) (xy 389.536842 -270.542292)
			(xy 389.586706 -270.532112) (xy 389.637558 -270.530063) (xy 389.688079 -270.536197) (xy 389.736963 -270.550357)
			(xy 389.782942 -270.572174) (xy 389.824826 -270.601084) (xy 389.86153 -270.636339) (xy 389.892103 -270.677025)
			(xy 389.915754 -270.722088) (xy 389.93187 -270.770362) (xy 389.940034 -270.820596) (xy 389.940546 -270.846042)
			(xy 390.248643 -270.846042) (xy 390.252738 -270.795314) (xy 390.264917 -270.7459) (xy 390.284865 -270.69908)
			(xy 390.312066 -270.656066) (xy 390.345814 -270.617972) (xy 390.385236 -270.585785) (xy 390.42931 -270.560339)
			(xy 390.476896 -270.542292) (xy 390.52676 -270.532112) (xy 390.577612 -270.530063) (xy 390.628133 -270.536197)
			(xy 390.677017 -270.550357) (xy 390.722996 -270.572174) (xy 390.76488 -270.601084) (xy 390.801584 -270.636339)
			(xy 390.832157 -270.677025) (xy 390.855808 -270.722088) (xy 390.871924 -270.770362) (xy 390.880088 -270.820596)
			(xy 390.8806 -270.846042) (xy 393.078982 -270.846042) (xy 393.082942 -270.796988) (xy 393.094719 -270.749204)
			(xy 393.11401 -270.703928) (xy 393.140313 -270.662332) (xy 393.172948 -270.625495) (xy 393.211069 -270.59437)
			(xy 393.25369 -270.569763) (xy 393.299706 -270.552311) (xy 393.347925 -270.542467) (xy 393.3971 -270.540486)
			(xy 393.445955 -270.546418) (xy 393.493226 -270.56011) (xy 393.537688 -270.581208) (xy 393.578191 -270.609164)
			(xy 393.613684 -270.643256) (xy 393.643249 -270.6826) (xy 393.66612 -270.726177) (xy 393.681704 -270.772858)
			(xy 393.689599 -270.821435) (xy 393.690094 -270.846042) (xy 393.689599 -270.870649) (xy 393.681704 -270.919226)
			(xy 393.66612 -270.965907) (xy 393.643249 -271.009484) (xy 393.613684 -271.048828) (xy 393.578191 -271.08292)
			(xy 393.537688 -271.110876) (xy 393.493226 -271.131974) (xy 393.445955 -271.145666) (xy 393.3971 -271.151598)
			(xy 393.347925 -271.149617) (xy 393.299706 -271.139773) (xy 393.25369 -271.122321) (xy 393.211069 -271.097714)
			(xy 393.172948 -271.066589) (xy 393.140313 -271.029752) (xy 393.11401 -270.988156) (xy 393.094719 -270.94288)
			(xy 393.082942 -270.895096) (xy 393.078982 -270.846042) (xy 390.8806 -270.846042) (xy 390.880088 -270.871488)
			(xy 390.871924 -270.921722) (xy 390.855808 -270.969996) (xy 390.832157 -271.015059) (xy 390.801584 -271.055745)
			(xy 390.76488 -271.091) (xy 390.722996 -271.11991) (xy 390.677017 -271.141727) (xy 390.628133 -271.155887)
			(xy 390.577612 -271.162021) (xy 390.52676 -271.159972) (xy 390.476896 -271.149792) (xy 390.42931 -271.131745)
			(xy 390.385236 -271.106299) (xy 390.345814 -271.074112) (xy 390.312066 -271.036018) (xy 390.284865 -270.993004)
			(xy 390.264917 -270.946184) (xy 390.252738 -270.89677) (xy 390.248643 -270.846042) (xy 389.940546 -270.846042)
			(xy 389.940034 -270.871488) (xy 389.93187 -270.921722) (xy 389.915754 -270.969996) (xy 389.892103 -271.015059)
			(xy 389.86153 -271.055745) (xy 389.824826 -271.091) (xy 389.782942 -271.11991) (xy 389.736963 -271.141727)
			(xy 389.688079 -271.155887) (xy 389.637558 -271.162021) (xy 389.586706 -271.159972) (xy 389.536842 -271.149792)
			(xy 389.489256 -271.131745) (xy 389.445182 -271.106299) (xy 389.40576 -271.074112) (xy 389.372012 -271.036018)
			(xy 389.344811 -270.993004) (xy 389.324863 -270.946184) (xy 389.312684 -270.89677) (xy 389.308589 -270.846042)
			(xy 388.990078 -270.846042) (xy 388.989583 -270.870649) (xy 388.981688 -270.919226) (xy 388.966104 -270.965907)
			(xy 388.943233 -271.009484) (xy 388.913668 -271.048828) (xy 388.878175 -271.08292) (xy 388.837672 -271.110876)
			(xy 388.79321 -271.131974) (xy 388.745939 -271.145666) (xy 388.697084 -271.151598) (xy 388.647909 -271.149617)
			(xy 388.59969 -271.139773) (xy 388.553674 -271.122321) (xy 388.511053 -271.097714) (xy 388.472932 -271.066589)
			(xy 388.440297 -271.029752) (xy 388.413994 -270.988156) (xy 388.394703 -270.94288) (xy 388.382926 -270.895096)
			(xy 388.378966 -270.846042) (xy 388.060438 -270.846042) (xy 388.059926 -270.871488) (xy 388.051762 -270.921722)
			(xy 388.035646 -270.969996) (xy 388.011995 -271.015059) (xy 387.981422 -271.055745) (xy 387.944718 -271.091)
			(xy 387.902834 -271.11991) (xy 387.856855 -271.141727) (xy 387.807971 -271.155887) (xy 387.75745 -271.162021)
			(xy 387.706598 -271.159972) (xy 387.656734 -271.149792) (xy 387.609148 -271.131745) (xy 387.565074 -271.106299)
			(xy 387.525652 -271.074112) (xy 387.491904 -271.036018) (xy 387.464703 -270.993004) (xy 387.444755 -270.946184)
			(xy 387.432576 -270.89677) (xy 387.428481 -270.846042) (xy 387.110224 -270.846042) (xy 387.109729 -270.870649)
			(xy 387.101834 -270.919226) (xy 387.08625 -270.965907) (xy 387.063379 -271.009484) (xy 387.033814 -271.048828)
			(xy 386.998321 -271.08292) (xy 386.957818 -271.110876) (xy 386.913356 -271.131974) (xy 386.866085 -271.145666)
			(xy 386.81723 -271.151598) (xy 386.768055 -271.149617) (xy 386.719836 -271.139773) (xy 386.67382 -271.122321)
			(xy 386.631199 -271.097714) (xy 386.593078 -271.066589) (xy 386.560443 -271.029752) (xy 386.53414 -270.988156)
			(xy 386.514849 -270.94288) (xy 386.503072 -270.895096) (xy 386.499112 -270.846042) (xy 386.180584 -270.846042)
			(xy 386.180072 -270.871488) (xy 386.171908 -270.921722) (xy 386.155792 -270.969996) (xy 386.132141 -271.015059)
			(xy 386.101568 -271.055745) (xy 386.064864 -271.091) (xy 386.02298 -271.11991) (xy 385.977001 -271.141727)
			(xy 385.928117 -271.155887) (xy 385.877596 -271.162021) (xy 385.826744 -271.159972) (xy 385.77688 -271.149792)
			(xy 385.729294 -271.131745) (xy 385.68522 -271.106299) (xy 385.645798 -271.074112) (xy 385.61205 -271.036018)
			(xy 385.584849 -270.993004) (xy 385.564901 -270.946184) (xy 385.552722 -270.89677) (xy 385.548627 -270.846042)
			(xy 384.300476 -270.846042) (xy 384.299964 -270.871488) (xy 384.2918 -270.921722) (xy 384.275684 -270.969996)
			(xy 384.252033 -271.015059) (xy 384.22146 -271.055745) (xy 384.184756 -271.091) (xy 384.142872 -271.11991)
			(xy 384.096893 -271.141727) (xy 384.048009 -271.155887) (xy 383.997488 -271.162021) (xy 383.946636 -271.159972)
			(xy 383.896772 -271.149792) (xy 383.849186 -271.131745) (xy 383.805112 -271.106299) (xy 383.76569 -271.074112)
			(xy 383.731942 -271.036018) (xy 383.704741 -270.993004) (xy 383.684793 -270.946184) (xy 383.672614 -270.89677)
			(xy 383.668519 -270.846042) (xy 383.360422 -270.846042) (xy 383.35991 -270.871488) (xy 383.351746 -270.921722)
			(xy 383.33563 -270.969996) (xy 383.311979 -271.015059) (xy 383.281406 -271.055745) (xy 383.244702 -271.091)
			(xy 383.202818 -271.11991) (xy 383.156839 -271.141727) (xy 383.107955 -271.155887) (xy 383.057434 -271.162021)
			(xy 383.006582 -271.159972) (xy 382.956718 -271.149792) (xy 382.909132 -271.131745) (xy 382.865058 -271.106299)
			(xy 382.825636 -271.074112) (xy 382.791888 -271.036018) (xy 382.764687 -270.993004) (xy 382.744739 -270.946184)
			(xy 382.73256 -270.89677) (xy 382.728465 -270.846042) (xy 382.410208 -270.846042) (xy 382.409713 -270.870649)
			(xy 382.401818 -270.919226) (xy 382.386234 -270.965907) (xy 382.363363 -271.009484) (xy 382.333798 -271.048828)
			(xy 382.298305 -271.08292) (xy 382.257802 -271.110876) (xy 382.21334 -271.131974) (xy 382.166069 -271.145666)
			(xy 382.117214 -271.151598) (xy 382.068039 -271.149617) (xy 382.01982 -271.139773) (xy 381.973804 -271.122321)
			(xy 381.931183 -271.097714) (xy 381.893062 -271.066589) (xy 381.860427 -271.029752) (xy 381.834124 -270.988156)
			(xy 381.814833 -270.94288) (xy 381.803056 -270.895096) (xy 381.799096 -270.846042) (xy 381.480568 -270.846042)
			(xy 381.480056 -270.871488) (xy 381.471892 -270.921722) (xy 381.455776 -270.969996) (xy 381.432125 -271.015059)
			(xy 381.401552 -271.055745) (xy 381.364848 -271.091) (xy 381.322964 -271.11991) (xy 381.276985 -271.141727)
			(xy 381.228101 -271.155887) (xy 381.17758 -271.162021) (xy 381.126728 -271.159972) (xy 381.076864 -271.149792)
			(xy 381.029278 -271.131745) (xy 380.985204 -271.106299) (xy 380.945782 -271.074112) (xy 380.912034 -271.036018)
			(xy 380.884833 -270.993004) (xy 380.864885 -270.946184) (xy 380.852706 -270.89677) (xy 380.848611 -270.846042)
			(xy 380.5301 -270.846042) (xy 380.529605 -270.870649) (xy 380.52171 -270.919226) (xy 380.506126 -270.965907)
			(xy 380.483255 -271.009484) (xy 380.45369 -271.048828) (xy 380.418197 -271.08292) (xy 380.377694 -271.110876)
			(xy 380.333232 -271.131974) (xy 380.285961 -271.145666) (xy 380.237106 -271.151598) (xy 380.187931 -271.149617)
			(xy 380.139712 -271.139773) (xy 380.093696 -271.122321) (xy 380.051075 -271.097714) (xy 380.012954 -271.066589)
			(xy 379.980319 -271.029752) (xy 379.954016 -270.988156) (xy 379.934725 -270.94288) (xy 379.922948 -270.895096)
			(xy 379.918988 -270.846042) (xy 379.60046 -270.846042) (xy 379.599948 -270.871488) (xy 379.591784 -270.921722)
			(xy 379.575668 -270.969996) (xy 379.552017 -271.015059) (xy 379.521444 -271.055745) (xy 379.48474 -271.091)
			(xy 379.442856 -271.11991) (xy 379.396877 -271.141727) (xy 379.347993 -271.155887) (xy 379.297472 -271.162021)
			(xy 379.24662 -271.159972) (xy 379.196756 -271.149792) (xy 379.14917 -271.131745) (xy 379.105096 -271.106299)
			(xy 379.065674 -271.074112) (xy 379.031926 -271.036018) (xy 379.004725 -270.993004) (xy 378.984777 -270.946184)
			(xy 378.972598 -270.89677) (xy 378.968503 -270.846042) (xy 377.720606 -270.846042) (xy 377.720094 -270.871488)
			(xy 377.71193 -270.921722) (xy 377.695814 -270.969996) (xy 377.672163 -271.015059) (xy 377.64159 -271.055745)
			(xy 377.604886 -271.091) (xy 377.563002 -271.11991) (xy 377.517023 -271.141727) (xy 377.468139 -271.155887)
			(xy 377.417618 -271.162021) (xy 377.366766 -271.159972) (xy 377.316902 -271.149792) (xy 377.269316 -271.131745)
			(xy 377.225242 -271.106299) (xy 377.18582 -271.074112) (xy 377.152072 -271.036018) (xy 377.124871 -270.993004)
			(xy 377.104923 -270.946184) (xy 377.092744 -270.89677) (xy 377.088649 -270.846042) (xy 376.780552 -270.846042)
			(xy 376.78004 -270.871488) (xy 376.771876 -270.921722) (xy 376.75576 -270.969996) (xy 376.732109 -271.015059)
			(xy 376.701536 -271.055745) (xy 376.664832 -271.091) (xy 376.622948 -271.11991) (xy 376.576969 -271.141727)
			(xy 376.528085 -271.155887) (xy 376.477564 -271.162021) (xy 376.426712 -271.159972) (xy 376.376848 -271.149792)
			(xy 376.329262 -271.131745) (xy 376.285188 -271.106299) (xy 376.245766 -271.074112) (xy 376.212018 -271.036018)
			(xy 376.184817 -270.993004) (xy 376.164869 -270.946184) (xy 376.15269 -270.89677) (xy 376.148595 -270.846042)
			(xy 375.1961 -270.846042) (xy 375.1961 -271.356074) (xy 375.196375 -271.364603) (xy 375.201906 -271.380736)
			(xy 375.212456 -271.394136) (xy 375.219468 -271.399) (xy 375.240662 -271.413164) (xy 375.278442 -271.447383)
			(xy 375.310009 -271.487405) (xy 375.334484 -271.532117) (xy 375.351188 -271.580275) (xy 375.359656 -271.630539)
			(xy 375.359654 -271.656048) (xy 375.678695 -271.656048) (xy 375.68279 -271.60532) (xy 375.694969 -271.555906)
			(xy 375.714917 -271.509086) (xy 375.742118 -271.466072) (xy 375.775866 -271.427978) (xy 375.815288 -271.395791)
			(xy 375.859362 -271.370345) (xy 375.906948 -271.352298) (xy 375.956812 -271.342118) (xy 376.007664 -271.340069)
			(xy 376.058185 -271.346203) (xy 376.107069 -271.360363) (xy 376.153048 -271.38218) (xy 376.194932 -271.41109)
			(xy 376.231636 -271.446345) (xy 376.262209 -271.487031) (xy 376.28586 -271.532094) (xy 376.301976 -271.580368)
			(xy 376.31014 -271.630602) (xy 376.310652 -271.656048) (xy 376.628926 -271.656048) (xy 376.632886 -271.606994)
			(xy 376.644663 -271.55921) (xy 376.663954 -271.513934) (xy 376.690257 -271.472338) (xy 376.722892 -271.435501)
			(xy 376.761013 -271.404376) (xy 376.803634 -271.379769) (xy 376.84965 -271.362317) (xy 376.897869 -271.352473)
			(xy 376.947044 -271.350492) (xy 376.995899 -271.356424) (xy 377.04317 -271.370116) (xy 377.087632 -271.391214)
			(xy 377.128135 -271.41917) (xy 377.163628 -271.453262) (xy 377.193193 -271.492606) (xy 377.216064 -271.536183)
			(xy 377.231648 -271.582864) (xy 377.239543 -271.631441) (xy 377.240038 -271.656048) (xy 377.558549 -271.656048)
			(xy 377.562644 -271.60532) (xy 377.574823 -271.555906) (xy 377.594771 -271.509086) (xy 377.621972 -271.466072)
			(xy 377.65572 -271.427978) (xy 377.695142 -271.395791) (xy 377.739216 -271.370345) (xy 377.786802 -271.352298)
			(xy 377.836666 -271.342118) (xy 377.887518 -271.340069) (xy 377.938039 -271.346203) (xy 377.986923 -271.360363)
			(xy 378.032902 -271.38218) (xy 378.074786 -271.41109) (xy 378.11149 -271.446345) (xy 378.142063 -271.487031)
			(xy 378.165714 -271.532094) (xy 378.18183 -271.580368) (xy 378.189994 -271.630602) (xy 378.190506 -271.656048)
			(xy 378.509034 -271.656048) (xy 378.512994 -271.606994) (xy 378.524771 -271.55921) (xy 378.544062 -271.513934)
			(xy 378.570365 -271.472338) (xy 378.603 -271.435501) (xy 378.641121 -271.404376) (xy 378.683742 -271.379769)
			(xy 378.729758 -271.362317) (xy 378.777977 -271.352473) (xy 378.827152 -271.350492) (xy 378.876007 -271.356424)
			(xy 378.923278 -271.370116) (xy 378.96774 -271.391214) (xy 379.008243 -271.41917) (xy 379.043736 -271.453262)
			(xy 379.073301 -271.492606) (xy 379.096172 -271.536183) (xy 379.111756 -271.582864) (xy 379.119651 -271.631441)
			(xy 379.120146 -271.656048) (xy 379.438657 -271.656048) (xy 379.442752 -271.60532) (xy 379.454931 -271.555906)
			(xy 379.474879 -271.509086) (xy 379.50208 -271.466072) (xy 379.535828 -271.427978) (xy 379.57525 -271.395791)
			(xy 379.619324 -271.370345) (xy 379.66691 -271.352298) (xy 379.716774 -271.342118) (xy 379.767626 -271.340069)
			(xy 379.818147 -271.346203) (xy 379.867031 -271.360363) (xy 379.91301 -271.38218) (xy 379.954894 -271.41109)
			(xy 379.991598 -271.446345) (xy 380.022171 -271.487031) (xy 380.045822 -271.532094) (xy 380.061938 -271.580368)
			(xy 380.070102 -271.630602) (xy 380.070614 -271.656048) (xy 380.378711 -271.656048) (xy 380.382806 -271.60532)
			(xy 380.394985 -271.555906) (xy 380.414933 -271.509086) (xy 380.442134 -271.466072) (xy 380.475882 -271.427978)
			(xy 380.515304 -271.395791) (xy 380.559378 -271.370345) (xy 380.606964 -271.352298) (xy 380.656828 -271.342118)
			(xy 380.70768 -271.340069) (xy 380.758201 -271.346203) (xy 380.807085 -271.360363) (xy 380.853064 -271.38218)
			(xy 380.894948 -271.41109) (xy 380.931652 -271.446345) (xy 380.962225 -271.487031) (xy 380.985876 -271.532094)
			(xy 381.001992 -271.580368) (xy 381.010156 -271.630602) (xy 381.010668 -271.656048) (xy 381.328942 -271.656048)
			(xy 381.332902 -271.606994) (xy 381.344679 -271.55921) (xy 381.36397 -271.513934) (xy 381.390273 -271.472338)
			(xy 381.422908 -271.435501) (xy 381.461029 -271.404376) (xy 381.50365 -271.379769) (xy 381.549666 -271.362317)
			(xy 381.597885 -271.352473) (xy 381.64706 -271.350492) (xy 381.695915 -271.356424) (xy 381.743186 -271.370116)
			(xy 381.787648 -271.391214) (xy 381.828151 -271.41917) (xy 381.863644 -271.453262) (xy 381.893209 -271.492606)
			(xy 381.91608 -271.536183) (xy 381.931664 -271.582864) (xy 381.939559 -271.631441) (xy 381.940054 -271.656048)
			(xy 382.258565 -271.656048) (xy 382.26266 -271.60532) (xy 382.274839 -271.555906) (xy 382.294787 -271.509086)
			(xy 382.321988 -271.466072) (xy 382.355736 -271.427978) (xy 382.395158 -271.395791) (xy 382.439232 -271.370345)
			(xy 382.486818 -271.352298) (xy 382.536682 -271.342118) (xy 382.587534 -271.340069) (xy 382.638055 -271.346203)
			(xy 382.686939 -271.360363) (xy 382.732918 -271.38218) (xy 382.774802 -271.41109) (xy 382.811506 -271.446345)
			(xy 382.842079 -271.487031) (xy 382.86573 -271.532094) (xy 382.881846 -271.580368) (xy 382.89001 -271.630602)
			(xy 382.890522 -271.656048) (xy 383.20905 -271.656048) (xy 383.21301 -271.606994) (xy 383.224787 -271.55921)
			(xy 383.244078 -271.513934) (xy 383.270381 -271.472338) (xy 383.303016 -271.435501) (xy 383.341137 -271.404376)
			(xy 383.383758 -271.379769) (xy 383.429774 -271.362317) (xy 383.477993 -271.352473) (xy 383.527168 -271.350492)
			(xy 383.576023 -271.356424) (xy 383.623294 -271.370116) (xy 383.667756 -271.391214) (xy 383.708259 -271.41917)
			(xy 383.743752 -271.453262) (xy 383.773317 -271.492606) (xy 383.796188 -271.536183) (xy 383.811772 -271.582864)
			(xy 383.819667 -271.631441) (xy 383.820162 -271.656048) (xy 384.138673 -271.656048) (xy 384.142768 -271.60532)
			(xy 384.154947 -271.555906) (xy 384.174895 -271.509086) (xy 384.202096 -271.466072) (xy 384.235844 -271.427978)
			(xy 384.275266 -271.395791) (xy 384.31934 -271.370345) (xy 384.366926 -271.352298) (xy 384.41679 -271.342118)
			(xy 384.467642 -271.340069) (xy 384.518163 -271.346203) (xy 384.567047 -271.360363) (xy 384.613026 -271.38218)
			(xy 384.65491 -271.41109) (xy 384.691614 -271.446345) (xy 384.722187 -271.487031) (xy 384.745838 -271.532094)
			(xy 384.761954 -271.580368) (xy 384.770118 -271.630602) (xy 384.77063 -271.656048) (xy 385.088904 -271.656048)
			(xy 385.092864 -271.606994) (xy 385.104641 -271.55921) (xy 385.123932 -271.513934) (xy 385.150235 -271.472338)
			(xy 385.18287 -271.435501) (xy 385.220991 -271.404376) (xy 385.263612 -271.379769) (xy 385.309628 -271.362317)
			(xy 385.357847 -271.352473) (xy 385.407022 -271.350492) (xy 385.455877 -271.356424) (xy 385.503148 -271.370116)
			(xy 385.54761 -271.391214) (xy 385.588113 -271.41917) (xy 385.623606 -271.453262) (xy 385.653171 -271.492606)
			(xy 385.676042 -271.536183) (xy 385.691626 -271.582864) (xy 385.699521 -271.631441) (xy 385.700016 -271.656048)
			(xy 386.018527 -271.656048) (xy 386.022622 -271.60532) (xy 386.034801 -271.555906) (xy 386.054749 -271.509086)
			(xy 386.08195 -271.466072) (xy 386.115698 -271.427978) (xy 386.15512 -271.395791) (xy 386.199194 -271.370345)
			(xy 386.24678 -271.352298) (xy 386.296644 -271.342118) (xy 386.347496 -271.340069) (xy 386.398017 -271.346203)
			(xy 386.446901 -271.360363) (xy 386.49288 -271.38218) (xy 386.534764 -271.41109) (xy 386.571468 -271.446345)
			(xy 386.602041 -271.487031) (xy 386.625692 -271.532094) (xy 386.641808 -271.580368) (xy 386.649972 -271.630602)
			(xy 386.650484 -271.656048) (xy 386.958581 -271.656048) (xy 386.962676 -271.60532) (xy 386.974855 -271.555906)
			(xy 386.994803 -271.509086) (xy 387.022004 -271.466072) (xy 387.055752 -271.427978) (xy 387.095174 -271.395791)
			(xy 387.139248 -271.370345) (xy 387.186834 -271.352298) (xy 387.236698 -271.342118) (xy 387.28755 -271.340069)
			(xy 387.338071 -271.346203) (xy 387.386955 -271.360363) (xy 387.432934 -271.38218) (xy 387.474818 -271.41109)
			(xy 387.511522 -271.446345) (xy 387.542095 -271.487031) (xy 387.565746 -271.532094) (xy 387.581862 -271.580368)
			(xy 387.590026 -271.630602) (xy 387.590538 -271.656048) (xy 387.909066 -271.656048) (xy 387.913026 -271.606994)
			(xy 387.924803 -271.55921) (xy 387.944094 -271.513934) (xy 387.970397 -271.472338) (xy 388.003032 -271.435501)
			(xy 388.041153 -271.404376) (xy 388.083774 -271.379769) (xy 388.12979 -271.362317) (xy 388.178009 -271.352473)
			(xy 388.227184 -271.350492) (xy 388.276039 -271.356424) (xy 388.32331 -271.370116) (xy 388.367772 -271.391214)
			(xy 388.408275 -271.41917) (xy 388.443768 -271.453262) (xy 388.473333 -271.492606) (xy 388.496204 -271.536183)
			(xy 388.511788 -271.582864) (xy 388.519683 -271.631441) (xy 388.520178 -271.656048) (xy 388.838689 -271.656048)
			(xy 388.842784 -271.60532) (xy 388.854963 -271.555906) (xy 388.874911 -271.509086) (xy 388.902112 -271.466072)
			(xy 388.93586 -271.427978) (xy 388.975282 -271.395791) (xy 389.019356 -271.370345) (xy 389.066942 -271.352298)
			(xy 389.116806 -271.342118) (xy 389.167658 -271.340069) (xy 389.218179 -271.346203) (xy 389.267063 -271.360363)
			(xy 389.313042 -271.38218) (xy 389.354926 -271.41109) (xy 389.39163 -271.446345) (xy 389.422203 -271.487031)
			(xy 389.445854 -271.532094) (xy 389.46197 -271.580368) (xy 389.470134 -271.630602) (xy 389.470646 -271.656048)
			(xy 389.78892 -271.656048) (xy 389.79288 -271.606994) (xy 389.804657 -271.55921) (xy 389.823948 -271.513934)
			(xy 389.850251 -271.472338) (xy 389.882886 -271.435501) (xy 389.921007 -271.404376) (xy 389.963628 -271.379769)
			(xy 390.009644 -271.362317) (xy 390.057863 -271.352473) (xy 390.107038 -271.350492) (xy 390.155893 -271.356424)
			(xy 390.203164 -271.370116) (xy 390.247626 -271.391214) (xy 390.288129 -271.41917) (xy 390.323622 -271.453262)
			(xy 390.353187 -271.492606) (xy 390.376058 -271.536183) (xy 390.391642 -271.582864) (xy 390.399537 -271.631441)
			(xy 390.400032 -271.656048) (xy 390.718543 -271.656048) (xy 390.722638 -271.60532) (xy 390.734817 -271.555906)
			(xy 390.754765 -271.509086) (xy 390.781966 -271.466072) (xy 390.815714 -271.427978) (xy 390.855136 -271.395791)
			(xy 390.89921 -271.370345) (xy 390.946796 -271.352298) (xy 390.99666 -271.342118) (xy 391.047512 -271.340069)
			(xy 391.098033 -271.346203) (xy 391.146917 -271.360363) (xy 391.192896 -271.38218) (xy 391.23478 -271.41109)
			(xy 391.271484 -271.446345) (xy 391.302057 -271.487031) (xy 391.325708 -271.532094) (xy 391.341824 -271.580368)
			(xy 391.349988 -271.630602) (xy 391.3505 -271.656048) (xy 391.669028 -271.656048) (xy 391.672988 -271.606994)
			(xy 391.684765 -271.55921) (xy 391.704056 -271.513934) (xy 391.730359 -271.472338) (xy 391.762994 -271.435501)
			(xy 391.801115 -271.404376) (xy 391.843736 -271.379769) (xy 391.889752 -271.362317) (xy 391.937971 -271.352473)
			(xy 391.987146 -271.350492) (xy 392.036001 -271.356424) (xy 392.083272 -271.370116) (xy 392.125407 -271.39011)
			(xy 394.67715 -271.39011) (xy 394.68111 -271.341056) (xy 394.692887 -271.293272) (xy 394.712178 -271.247996)
			(xy 394.738481 -271.2064) (xy 394.771116 -271.169563) (xy 394.809237 -271.138438) (xy 394.851858 -271.113831)
			(xy 394.897874 -271.096379) (xy 394.946093 -271.086535) (xy 394.995268 -271.084554) (xy 395.044123 -271.090486)
			(xy 395.091394 -271.104178) (xy 395.135856 -271.125276) (xy 395.176359 -271.153232) (xy 395.211852 -271.187324)
			(xy 395.241417 -271.226668) (xy 395.264288 -271.270245) (xy 395.279872 -271.316926) (xy 395.287767 -271.365503)
			(xy 395.288262 -271.39011) (xy 395.287767 -271.414717) (xy 395.279872 -271.463294) (xy 395.264288 -271.509975)
			(xy 395.241417 -271.553552) (xy 395.211852 -271.592896) (xy 395.176359 -271.626988) (xy 395.135856 -271.654944)
			(xy 395.091394 -271.676042) (xy 395.044123 -271.689734) (xy 394.995268 -271.695666) (xy 394.946093 -271.693685)
			(xy 394.897874 -271.683841) (xy 394.851858 -271.666389) (xy 394.809237 -271.641782) (xy 394.771116 -271.610657)
			(xy 394.738481 -271.57382) (xy 394.712178 -271.532224) (xy 394.692887 -271.486948) (xy 394.68111 -271.439164)
			(xy 394.67715 -271.39011) (xy 392.125407 -271.39011) (xy 392.127734 -271.391214) (xy 392.168237 -271.41917)
			(xy 392.20373 -271.453262) (xy 392.233295 -271.492606) (xy 392.256166 -271.536183) (xy 392.27175 -271.582864)
			(xy 392.279645 -271.631441) (xy 392.28014 -271.656048) (xy 392.279645 -271.680655) (xy 392.27175 -271.729232)
			(xy 392.256166 -271.775913) (xy 392.233295 -271.81949) (xy 392.20373 -271.858834) (xy 392.168237 -271.892926)
			(xy 392.127734 -271.920882) (xy 392.083272 -271.94198) (xy 392.036001 -271.955672) (xy 391.987146 -271.961604)
			(xy 391.937971 -271.959623) (xy 391.889752 -271.949779) (xy 391.843736 -271.932327) (xy 391.801115 -271.90772)
			(xy 391.762994 -271.876595) (xy 391.730359 -271.839758) (xy 391.704056 -271.798162) (xy 391.684765 -271.752886)
			(xy 391.672988 -271.705102) (xy 391.669028 -271.656048) (xy 391.3505 -271.656048) (xy 391.349988 -271.681494)
			(xy 391.341824 -271.731728) (xy 391.325708 -271.780002) (xy 391.302057 -271.825065) (xy 391.271484 -271.865751)
			(xy 391.23478 -271.901006) (xy 391.192896 -271.929916) (xy 391.146917 -271.951733) (xy 391.098033 -271.965893)
			(xy 391.047512 -271.972027) (xy 390.99666 -271.969978) (xy 390.946796 -271.959798) (xy 390.89921 -271.941751)
			(xy 390.855136 -271.916305) (xy 390.815714 -271.884118) (xy 390.781966 -271.846024) (xy 390.754765 -271.80301)
			(xy 390.734817 -271.75619) (xy 390.722638 -271.706776) (xy 390.718543 -271.656048) (xy 390.400032 -271.656048)
			(xy 390.399537 -271.680655) (xy 390.391642 -271.729232) (xy 390.376058 -271.775913) (xy 390.353187 -271.81949)
			(xy 390.323622 -271.858834) (xy 390.288129 -271.892926) (xy 390.247626 -271.920882) (xy 390.203164 -271.94198)
			(xy 390.155893 -271.955672) (xy 390.107038 -271.961604) (xy 390.057863 -271.959623) (xy 390.009644 -271.949779)
			(xy 389.963628 -271.932327) (xy 389.921007 -271.90772) (xy 389.882886 -271.876595) (xy 389.850251 -271.839758)
			(xy 389.823948 -271.798162) (xy 389.804657 -271.752886) (xy 389.79288 -271.705102) (xy 389.78892 -271.656048)
			(xy 389.470646 -271.656048) (xy 389.470134 -271.681494) (xy 389.46197 -271.731728) (xy 389.445854 -271.780002)
			(xy 389.422203 -271.825065) (xy 389.39163 -271.865751) (xy 389.354926 -271.901006) (xy 389.313042 -271.929916)
			(xy 389.267063 -271.951733) (xy 389.218179 -271.965893) (xy 389.167658 -271.972027) (xy 389.116806 -271.969978)
			(xy 389.066942 -271.959798) (xy 389.019356 -271.941751) (xy 388.975282 -271.916305) (xy 388.93586 -271.884118)
			(xy 388.902112 -271.846024) (xy 388.874911 -271.80301) (xy 388.854963 -271.75619) (xy 388.842784 -271.706776)
			(xy 388.838689 -271.656048) (xy 388.520178 -271.656048) (xy 388.519683 -271.680655) (xy 388.511788 -271.729232)
			(xy 388.496204 -271.775913) (xy 388.473333 -271.81949) (xy 388.443768 -271.858834) (xy 388.408275 -271.892926)
			(xy 388.367772 -271.920882) (xy 388.32331 -271.94198) (xy 388.276039 -271.955672) (xy 388.227184 -271.961604)
			(xy 388.178009 -271.959623) (xy 388.12979 -271.949779) (xy 388.083774 -271.932327) (xy 388.041153 -271.90772)
			(xy 388.003032 -271.876595) (xy 387.970397 -271.839758) (xy 387.944094 -271.798162) (xy 387.924803 -271.752886)
			(xy 387.913026 -271.705102) (xy 387.909066 -271.656048) (xy 387.590538 -271.656048) (xy 387.590026 -271.681494)
			(xy 387.581862 -271.731728) (xy 387.565746 -271.780002) (xy 387.542095 -271.825065) (xy 387.511522 -271.865751)
			(xy 387.474818 -271.901006) (xy 387.432934 -271.929916) (xy 387.386955 -271.951733) (xy 387.338071 -271.965893)
			(xy 387.28755 -271.972027) (xy 387.236698 -271.969978) (xy 387.186834 -271.959798) (xy 387.139248 -271.941751)
			(xy 387.095174 -271.916305) (xy 387.055752 -271.884118) (xy 387.022004 -271.846024) (xy 386.994803 -271.80301)
			(xy 386.974855 -271.75619) (xy 386.962676 -271.706776) (xy 386.958581 -271.656048) (xy 386.650484 -271.656048)
			(xy 386.649972 -271.681494) (xy 386.641808 -271.731728) (xy 386.625692 -271.780002) (xy 386.602041 -271.825065)
			(xy 386.571468 -271.865751) (xy 386.534764 -271.901006) (xy 386.49288 -271.929916) (xy 386.446901 -271.951733)
			(xy 386.398017 -271.965893) (xy 386.347496 -271.972027) (xy 386.296644 -271.969978) (xy 386.24678 -271.959798)
			(xy 386.199194 -271.941751) (xy 386.15512 -271.916305) (xy 386.115698 -271.884118) (xy 386.08195 -271.846024)
			(xy 386.054749 -271.80301) (xy 386.034801 -271.75619) (xy 386.022622 -271.706776) (xy 386.018527 -271.656048)
			(xy 385.700016 -271.656048) (xy 385.699521 -271.680655) (xy 385.691626 -271.729232) (xy 385.676042 -271.775913)
			(xy 385.653171 -271.81949) (xy 385.623606 -271.858834) (xy 385.588113 -271.892926) (xy 385.54761 -271.920882)
			(xy 385.503148 -271.94198) (xy 385.455877 -271.955672) (xy 385.407022 -271.961604) (xy 385.357847 -271.959623)
			(xy 385.309628 -271.949779) (xy 385.263612 -271.932327) (xy 385.220991 -271.90772) (xy 385.18287 -271.876595)
			(xy 385.150235 -271.839758) (xy 385.123932 -271.798162) (xy 385.104641 -271.752886) (xy 385.092864 -271.705102)
			(xy 385.088904 -271.656048) (xy 384.77063 -271.656048) (xy 384.770118 -271.681494) (xy 384.761954 -271.731728)
			(xy 384.745838 -271.780002) (xy 384.722187 -271.825065) (xy 384.691614 -271.865751) (xy 384.65491 -271.901006)
			(xy 384.613026 -271.929916) (xy 384.567047 -271.951733) (xy 384.518163 -271.965893) (xy 384.467642 -271.972027)
			(xy 384.41679 -271.969978) (xy 384.366926 -271.959798) (xy 384.31934 -271.941751) (xy 384.275266 -271.916305)
			(xy 384.235844 -271.884118) (xy 384.202096 -271.846024) (xy 384.174895 -271.80301) (xy 384.154947 -271.75619)
			(xy 384.142768 -271.706776) (xy 384.138673 -271.656048) (xy 383.820162 -271.656048) (xy 383.819667 -271.680655)
			(xy 383.811772 -271.729232) (xy 383.796188 -271.775913) (xy 383.773317 -271.81949) (xy 383.743752 -271.858834)
			(xy 383.708259 -271.892926) (xy 383.667756 -271.920882) (xy 383.623294 -271.94198) (xy 383.576023 -271.955672)
			(xy 383.527168 -271.961604) (xy 383.477993 -271.959623) (xy 383.429774 -271.949779) (xy 383.383758 -271.932327)
			(xy 383.341137 -271.90772) (xy 383.303016 -271.876595) (xy 383.270381 -271.839758) (xy 383.244078 -271.798162)
			(xy 383.224787 -271.752886) (xy 383.21301 -271.705102) (xy 383.20905 -271.656048) (xy 382.890522 -271.656048)
			(xy 382.89001 -271.681494) (xy 382.881846 -271.731728) (xy 382.86573 -271.780002) (xy 382.842079 -271.825065)
			(xy 382.811506 -271.865751) (xy 382.774802 -271.901006) (xy 382.732918 -271.929916) (xy 382.686939 -271.951733)
			(xy 382.638055 -271.965893) (xy 382.587534 -271.972027) (xy 382.536682 -271.969978) (xy 382.486818 -271.959798)
			(xy 382.439232 -271.941751) (xy 382.395158 -271.916305) (xy 382.355736 -271.884118) (xy 382.321988 -271.846024)
			(xy 382.294787 -271.80301) (xy 382.274839 -271.75619) (xy 382.26266 -271.706776) (xy 382.258565 -271.656048)
			(xy 381.940054 -271.656048) (xy 381.939559 -271.680655) (xy 381.931664 -271.729232) (xy 381.91608 -271.775913)
			(xy 381.893209 -271.81949) (xy 381.863644 -271.858834) (xy 381.828151 -271.892926) (xy 381.787648 -271.920882)
			(xy 381.743186 -271.94198) (xy 381.695915 -271.955672) (xy 381.64706 -271.961604) (xy 381.597885 -271.959623)
			(xy 381.549666 -271.949779) (xy 381.50365 -271.932327) (xy 381.461029 -271.90772) (xy 381.422908 -271.876595)
			(xy 381.390273 -271.839758) (xy 381.36397 -271.798162) (xy 381.344679 -271.752886) (xy 381.332902 -271.705102)
			(xy 381.328942 -271.656048) (xy 381.010668 -271.656048) (xy 381.010156 -271.681494) (xy 381.001992 -271.731728)
			(xy 380.985876 -271.780002) (xy 380.962225 -271.825065) (xy 380.931652 -271.865751) (xy 380.894948 -271.901006)
			(xy 380.853064 -271.929916) (xy 380.807085 -271.951733) (xy 380.758201 -271.965893) (xy 380.70768 -271.972027)
			(xy 380.656828 -271.969978) (xy 380.606964 -271.959798) (xy 380.559378 -271.941751) (xy 380.515304 -271.916305)
			(xy 380.475882 -271.884118) (xy 380.442134 -271.846024) (xy 380.414933 -271.80301) (xy 380.394985 -271.75619)
			(xy 380.382806 -271.706776) (xy 380.378711 -271.656048) (xy 380.070614 -271.656048) (xy 380.070102 -271.681494)
			(xy 380.061938 -271.731728) (xy 380.045822 -271.780002) (xy 380.022171 -271.825065) (xy 379.991598 -271.865751)
			(xy 379.954894 -271.901006) (xy 379.91301 -271.929916) (xy 379.867031 -271.951733) (xy 379.818147 -271.965893)
			(xy 379.767626 -271.972027) (xy 379.716774 -271.969978) (xy 379.66691 -271.959798) (xy 379.619324 -271.941751)
			(xy 379.57525 -271.916305) (xy 379.535828 -271.884118) (xy 379.50208 -271.846024) (xy 379.474879 -271.80301)
			(xy 379.454931 -271.75619) (xy 379.442752 -271.706776) (xy 379.438657 -271.656048) (xy 379.120146 -271.656048)
			(xy 379.119651 -271.680655) (xy 379.111756 -271.729232) (xy 379.096172 -271.775913) (xy 379.073301 -271.81949)
			(xy 379.043736 -271.858834) (xy 379.008243 -271.892926) (xy 378.96774 -271.920882) (xy 378.923278 -271.94198)
			(xy 378.876007 -271.955672) (xy 378.827152 -271.961604) (xy 378.777977 -271.959623) (xy 378.729758 -271.949779)
			(xy 378.683742 -271.932327) (xy 378.641121 -271.90772) (xy 378.603 -271.876595) (xy 378.570365 -271.839758)
			(xy 378.544062 -271.798162) (xy 378.524771 -271.752886) (xy 378.512994 -271.705102) (xy 378.509034 -271.656048)
			(xy 378.190506 -271.656048) (xy 378.189994 -271.681494) (xy 378.18183 -271.731728) (xy 378.165714 -271.780002)
			(xy 378.142063 -271.825065) (xy 378.11149 -271.865751) (xy 378.074786 -271.901006) (xy 378.032902 -271.929916)
			(xy 377.986923 -271.951733) (xy 377.938039 -271.965893) (xy 377.887518 -271.972027) (xy 377.836666 -271.969978)
			(xy 377.786802 -271.959798) (xy 377.739216 -271.941751) (xy 377.695142 -271.916305) (xy 377.65572 -271.884118)
			(xy 377.621972 -271.846024) (xy 377.594771 -271.80301) (xy 377.574823 -271.75619) (xy 377.562644 -271.706776)
			(xy 377.558549 -271.656048) (xy 377.240038 -271.656048) (xy 377.239543 -271.680655) (xy 377.231648 -271.729232)
			(xy 377.216064 -271.775913) (xy 377.193193 -271.81949) (xy 377.163628 -271.858834) (xy 377.128135 -271.892926)
			(xy 377.087632 -271.920882) (xy 377.04317 -271.94198) (xy 376.995899 -271.955672) (xy 376.947044 -271.961604)
			(xy 376.897869 -271.959623) (xy 376.84965 -271.949779) (xy 376.803634 -271.932327) (xy 376.761013 -271.90772)
			(xy 376.722892 -271.876595) (xy 376.690257 -271.839758) (xy 376.663954 -271.798162) (xy 376.644663 -271.752886)
			(xy 376.632886 -271.705102) (xy 376.628926 -271.656048) (xy 376.310652 -271.656048) (xy 376.31014 -271.681494)
			(xy 376.301976 -271.731728) (xy 376.28586 -271.780002) (xy 376.262209 -271.825065) (xy 376.231636 -271.865751)
			(xy 376.194932 -271.901006) (xy 376.153048 -271.929916) (xy 376.107069 -271.951733) (xy 376.058185 -271.965893)
			(xy 376.007664 -271.972027) (xy 375.956812 -271.969978) (xy 375.906948 -271.959798) (xy 375.859362 -271.941751)
			(xy 375.815288 -271.916305) (xy 375.775866 -271.884118) (xy 375.742118 -271.846024) (xy 375.714917 -271.80301)
			(xy 375.694969 -271.75619) (xy 375.68279 -271.706776) (xy 375.678695 -271.656048) (xy 375.359654 -271.656048)
			(xy 375.359652 -271.681512) (xy 375.351176 -271.731775) (xy 375.334463 -271.77993) (xy 375.30998 -271.824638)
			(xy 375.278406 -271.864655) (xy 375.240621 -271.898867) (xy 375.219468 -271.913096) (xy 375.212474 -271.917978)
			(xy 375.201947 -271.931386) (xy 375.196382 -271.947499) (xy 375.1961 -271.956022) (xy 375.1961 -272.128234)
			(xy 375.196506 -272.137431) (xy 375.202999 -272.154642) (xy 375.215112 -272.168486) (xy 375.223024 -272.173192)
			(xy 375.314718 -272.222214) (xy 375.342404 -272.22069) (xy 375.354342 -272.212816) (xy 375.373329 -272.20052)
			(xy 375.414163 -272.18106) (xy 375.457422 -272.167838) (xy 375.502159 -272.161145) (xy 375.524776 -272.160746)
			(xy 375.550039 -272.161237) (xy 375.599876 -272.16955) (xy 375.647665 -272.185952) (xy 375.692102 -272.209997)
			(xy 375.731975 -272.241029) (xy 375.766197 -272.278201) (xy 375.793833 -272.320498) (xy 375.81413 -272.366768)
			(xy 375.826533 -272.415747) (xy 375.830702 -272.466054) (xy 376.148595 -272.466054) (xy 376.15269 -272.415326)
			(xy 376.164869 -272.365912) (xy 376.184817 -272.319092) (xy 376.212018 -272.276078) (xy 376.245766 -272.237984)
			(xy 376.285188 -272.205797) (xy 376.329262 -272.180351) (xy 376.376848 -272.162304) (xy 376.426712 -272.152124)
			(xy 376.477564 -272.150075) (xy 376.528085 -272.156209) (xy 376.576969 -272.170369) (xy 376.622948 -272.192186)
			(xy 376.664832 -272.221096) (xy 376.701536 -272.256351) (xy 376.732109 -272.297037) (xy 376.75576 -272.3421)
			(xy 376.771876 -272.390374) (xy 376.78004 -272.440608) (xy 376.780552 -272.466054) (xy 377.088649 -272.466054)
			(xy 377.092744 -272.415326) (xy 377.104923 -272.365912) (xy 377.124871 -272.319092) (xy 377.152072 -272.276078)
			(xy 377.18582 -272.237984) (xy 377.225242 -272.205797) (xy 377.269316 -272.180351) (xy 377.316902 -272.162304)
			(xy 377.366766 -272.152124) (xy 377.417618 -272.150075) (xy 377.468139 -272.156209) (xy 377.517023 -272.170369)
			(xy 377.563002 -272.192186) (xy 377.604886 -272.221096) (xy 377.64159 -272.256351) (xy 377.672163 -272.297037)
			(xy 377.695814 -272.3421) (xy 377.71193 -272.390374) (xy 377.720094 -272.440608) (xy 377.720606 -272.466054)
			(xy 378.039134 -272.466054) (xy 378.043094 -272.417) (xy 378.054871 -272.369216) (xy 378.074162 -272.32394)
			(xy 378.100465 -272.282344) (xy 378.1331 -272.245507) (xy 378.171221 -272.214382) (xy 378.213842 -272.189775)
			(xy 378.259858 -272.172323) (xy 378.308077 -272.162479) (xy 378.357252 -272.160498) (xy 378.406107 -272.16643)
			(xy 378.453378 -272.180122) (xy 378.49784 -272.20122) (xy 378.538343 -272.229176) (xy 378.573836 -272.263268)
			(xy 378.603401 -272.302612) (xy 378.626272 -272.346189) (xy 378.641856 -272.39287) (xy 378.649751 -272.441447)
			(xy 378.650246 -272.466054) (xy 378.968503 -272.466054) (xy 378.972598 -272.415326) (xy 378.984777 -272.365912)
			(xy 379.004725 -272.319092) (xy 379.031926 -272.276078) (xy 379.065674 -272.237984) (xy 379.105096 -272.205797)
			(xy 379.14917 -272.180351) (xy 379.196756 -272.162304) (xy 379.24662 -272.152124) (xy 379.297472 -272.150075)
			(xy 379.347993 -272.156209) (xy 379.396877 -272.170369) (xy 379.442856 -272.192186) (xy 379.48474 -272.221096)
			(xy 379.521444 -272.256351) (xy 379.552017 -272.297037) (xy 379.575668 -272.3421) (xy 379.591784 -272.390374)
			(xy 379.599948 -272.440608) (xy 379.60046 -272.466054) (xy 379.918988 -272.466054) (xy 379.922948 -272.417)
			(xy 379.934725 -272.369216) (xy 379.954016 -272.32394) (xy 379.980319 -272.282344) (xy 380.012954 -272.245507)
			(xy 380.051075 -272.214382) (xy 380.093696 -272.189775) (xy 380.139712 -272.172323) (xy 380.187931 -272.162479)
			(xy 380.237106 -272.160498) (xy 380.285961 -272.16643) (xy 380.333232 -272.180122) (xy 380.377694 -272.20122)
			(xy 380.418197 -272.229176) (xy 380.45369 -272.263268) (xy 380.483255 -272.302612) (xy 380.506126 -272.346189)
			(xy 380.52171 -272.39287) (xy 380.529605 -272.441447) (xy 380.5301 -272.466054) (xy 380.848611 -272.466054)
			(xy 380.852706 -272.415326) (xy 380.864885 -272.365912) (xy 380.884833 -272.319092) (xy 380.912034 -272.276078)
			(xy 380.945782 -272.237984) (xy 380.985204 -272.205797) (xy 381.029278 -272.180351) (xy 381.076864 -272.162304)
			(xy 381.126728 -272.152124) (xy 381.17758 -272.150075) (xy 381.228101 -272.156209) (xy 381.276985 -272.170369)
			(xy 381.322964 -272.192186) (xy 381.364848 -272.221096) (xy 381.401552 -272.256351) (xy 381.432125 -272.297037)
			(xy 381.455776 -272.3421) (xy 381.471892 -272.390374) (xy 381.480056 -272.440608) (xy 381.480568 -272.466054)
			(xy 381.799096 -272.466054) (xy 381.803056 -272.417) (xy 381.814833 -272.369216) (xy 381.834124 -272.32394)
			(xy 381.860427 -272.282344) (xy 381.893062 -272.245507) (xy 381.931183 -272.214382) (xy 381.973804 -272.189775)
			(xy 382.01982 -272.172323) (xy 382.068039 -272.162479) (xy 382.117214 -272.160498) (xy 382.166069 -272.16643)
			(xy 382.21334 -272.180122) (xy 382.257802 -272.20122) (xy 382.298305 -272.229176) (xy 382.333798 -272.263268)
			(xy 382.363363 -272.302612) (xy 382.386234 -272.346189) (xy 382.401818 -272.39287) (xy 382.409713 -272.441447)
			(xy 382.410208 -272.466054) (xy 382.728465 -272.466054) (xy 382.73256 -272.415326) (xy 382.744739 -272.365912)
			(xy 382.764687 -272.319092) (xy 382.791888 -272.276078) (xy 382.825636 -272.237984) (xy 382.865058 -272.205797)
			(xy 382.909132 -272.180351) (xy 382.956718 -272.162304) (xy 383.006582 -272.152124) (xy 383.057434 -272.150075)
			(xy 383.107955 -272.156209) (xy 383.156839 -272.170369) (xy 383.202818 -272.192186) (xy 383.244702 -272.221096)
			(xy 383.281406 -272.256351) (xy 383.311979 -272.297037) (xy 383.33563 -272.3421) (xy 383.351746 -272.390374)
			(xy 383.35991 -272.440608) (xy 383.360422 -272.466054) (xy 383.668519 -272.466054) (xy 383.672614 -272.415326)
			(xy 383.684793 -272.365912) (xy 383.704741 -272.319092) (xy 383.731942 -272.276078) (xy 383.76569 -272.237984)
			(xy 383.805112 -272.205797) (xy 383.849186 -272.180351) (xy 383.896772 -272.162304) (xy 383.946636 -272.152124)
			(xy 383.997488 -272.150075) (xy 384.048009 -272.156209) (xy 384.096893 -272.170369) (xy 384.142872 -272.192186)
			(xy 384.184756 -272.221096) (xy 384.22146 -272.256351) (xy 384.252033 -272.297037) (xy 384.275684 -272.3421)
			(xy 384.2918 -272.390374) (xy 384.299964 -272.440608) (xy 384.300476 -272.466054) (xy 384.619004 -272.466054)
			(xy 384.622964 -272.417) (xy 384.634741 -272.369216) (xy 384.654032 -272.32394) (xy 384.680335 -272.282344)
			(xy 384.71297 -272.245507) (xy 384.751091 -272.214382) (xy 384.793712 -272.189775) (xy 384.839728 -272.172323)
			(xy 384.887947 -272.162479) (xy 384.937122 -272.160498) (xy 384.985977 -272.16643) (xy 385.033248 -272.180122)
			(xy 385.07771 -272.20122) (xy 385.118213 -272.229176) (xy 385.153706 -272.263268) (xy 385.183271 -272.302612)
			(xy 385.206142 -272.346189) (xy 385.221726 -272.39287) (xy 385.229621 -272.441447) (xy 385.230116 -272.466054)
			(xy 385.548627 -272.466054) (xy 385.552722 -272.415326) (xy 385.564901 -272.365912) (xy 385.584849 -272.319092)
			(xy 385.61205 -272.276078) (xy 385.645798 -272.237984) (xy 385.68522 -272.205797) (xy 385.729294 -272.180351)
			(xy 385.77688 -272.162304) (xy 385.826744 -272.152124) (xy 385.877596 -272.150075) (xy 385.928117 -272.156209)
			(xy 385.977001 -272.170369) (xy 386.02298 -272.192186) (xy 386.064864 -272.221096) (xy 386.101568 -272.256351)
			(xy 386.132141 -272.297037) (xy 386.155792 -272.3421) (xy 386.171908 -272.390374) (xy 386.180072 -272.440608)
			(xy 386.180584 -272.466054) (xy 386.499112 -272.466054) (xy 386.503072 -272.417) (xy 386.514849 -272.369216)
			(xy 386.53414 -272.32394) (xy 386.560443 -272.282344) (xy 386.593078 -272.245507) (xy 386.631199 -272.214382)
			(xy 386.67382 -272.189775) (xy 386.719836 -272.172323) (xy 386.768055 -272.162479) (xy 386.81723 -272.160498)
			(xy 386.866085 -272.16643) (xy 386.913356 -272.180122) (xy 386.957818 -272.20122) (xy 386.998321 -272.229176)
			(xy 387.033814 -272.263268) (xy 387.063379 -272.302612) (xy 387.08625 -272.346189) (xy 387.101834 -272.39287)
			(xy 387.109729 -272.441447) (xy 387.110224 -272.466054) (xy 387.428481 -272.466054) (xy 387.432576 -272.415326)
			(xy 387.444755 -272.365912) (xy 387.464703 -272.319092) (xy 387.491904 -272.276078) (xy 387.525652 -272.237984)
			(xy 387.565074 -272.205797) (xy 387.609148 -272.180351) (xy 387.656734 -272.162304) (xy 387.706598 -272.152124)
			(xy 387.75745 -272.150075) (xy 387.807971 -272.156209) (xy 387.856855 -272.170369) (xy 387.902834 -272.192186)
			(xy 387.944718 -272.221096) (xy 387.981422 -272.256351) (xy 388.011995 -272.297037) (xy 388.035646 -272.3421)
			(xy 388.051762 -272.390374) (xy 388.059926 -272.440608) (xy 388.060438 -272.466054) (xy 388.378966 -272.466054)
			(xy 388.382926 -272.417) (xy 388.394703 -272.369216) (xy 388.413994 -272.32394) (xy 388.440297 -272.282344)
			(xy 388.472932 -272.245507) (xy 388.511053 -272.214382) (xy 388.553674 -272.189775) (xy 388.59969 -272.172323)
			(xy 388.647909 -272.162479) (xy 388.697084 -272.160498) (xy 388.745939 -272.16643) (xy 388.79321 -272.180122)
			(xy 388.837672 -272.20122) (xy 388.878175 -272.229176) (xy 388.913668 -272.263268) (xy 388.943233 -272.302612)
			(xy 388.966104 -272.346189) (xy 388.981688 -272.39287) (xy 388.989583 -272.441447) (xy 388.990078 -272.466054)
			(xy 389.308589 -272.466054) (xy 389.312684 -272.415326) (xy 389.324863 -272.365912) (xy 389.344811 -272.319092)
			(xy 389.372012 -272.276078) (xy 389.40576 -272.237984) (xy 389.445182 -272.205797) (xy 389.489256 -272.180351)
			(xy 389.536842 -272.162304) (xy 389.586706 -272.152124) (xy 389.637558 -272.150075) (xy 389.688079 -272.156209)
			(xy 389.736963 -272.170369) (xy 389.782942 -272.192186) (xy 389.824826 -272.221096) (xy 389.86153 -272.256351)
			(xy 389.892103 -272.297037) (xy 389.915754 -272.3421) (xy 389.93187 -272.390374) (xy 389.940034 -272.440608)
			(xy 389.940546 -272.466054) (xy 390.248643 -272.466054) (xy 390.252738 -272.415326) (xy 390.264917 -272.365912)
			(xy 390.284865 -272.319092) (xy 390.312066 -272.276078) (xy 390.345814 -272.237984) (xy 390.385236 -272.205797)
			(xy 390.42931 -272.180351) (xy 390.476896 -272.162304) (xy 390.52676 -272.152124) (xy 390.577612 -272.150075)
			(xy 390.628133 -272.156209) (xy 390.677017 -272.170369) (xy 390.722996 -272.192186) (xy 390.76488 -272.221096)
			(xy 390.801584 -272.256351) (xy 390.832157 -272.297037) (xy 390.855808 -272.3421) (xy 390.871924 -272.390374)
			(xy 390.880088 -272.440608) (xy 390.8806 -272.466054) (xy 391.198874 -272.466054) (xy 391.202834 -272.417)
			(xy 391.214611 -272.369216) (xy 391.233902 -272.32394) (xy 391.260205 -272.282344) (xy 391.29284 -272.245507)
			(xy 391.330961 -272.214382) (xy 391.373582 -272.189775) (xy 391.419598 -272.172323) (xy 391.467817 -272.162479)
			(xy 391.516992 -272.160498) (xy 391.565847 -272.16643) (xy 391.613118 -272.180122) (xy 391.65758 -272.20122)
			(xy 391.698083 -272.229176) (xy 391.733576 -272.263268) (xy 391.763141 -272.302612) (xy 391.786012 -272.346189)
			(xy 391.801596 -272.39287) (xy 391.809491 -272.441447) (xy 391.809986 -272.466054) (xy 393.078982 -272.466054)
			(xy 393.082942 -272.417) (xy 393.094719 -272.369216) (xy 393.11401 -272.32394) (xy 393.140313 -272.282344)
			(xy 393.172948 -272.245507) (xy 393.211069 -272.214382) (xy 393.25369 -272.189775) (xy 393.299706 -272.172323)
			(xy 393.347925 -272.162479) (xy 393.3971 -272.160498) (xy 393.445955 -272.16643) (xy 393.493226 -272.180122)
			(xy 393.537688 -272.20122) (xy 393.578191 -272.229176) (xy 393.613684 -272.263268) (xy 393.643249 -272.302612)
			(xy 393.66612 -272.346189) (xy 393.681704 -272.39287) (xy 393.689599 -272.441447) (xy 393.690094 -272.466054)
			(xy 393.689599 -272.490661) (xy 393.681704 -272.539238) (xy 393.66612 -272.585919) (xy 393.643249 -272.629496)
			(xy 393.613684 -272.66884) (xy 393.578191 -272.702932) (xy 393.537688 -272.730888) (xy 393.493226 -272.751986)
			(xy 393.445955 -272.765678) (xy 393.3971 -272.77161) (xy 393.347925 -272.769629) (xy 393.299706 -272.759785)
			(xy 393.25369 -272.742333) (xy 393.211069 -272.717726) (xy 393.172948 -272.686601) (xy 393.140313 -272.649764)
			(xy 393.11401 -272.608168) (xy 393.094719 -272.562892) (xy 393.082942 -272.515108) (xy 393.078982 -272.466054)
			(xy 391.809986 -272.466054) (xy 391.809491 -272.490661) (xy 391.801596 -272.539238) (xy 391.786012 -272.585919)
			(xy 391.763141 -272.629496) (xy 391.733576 -272.66884) (xy 391.698083 -272.702932) (xy 391.65758 -272.730888)
			(xy 391.613118 -272.751986) (xy 391.565847 -272.765678) (xy 391.516992 -272.77161) (xy 391.467817 -272.769629)
			(xy 391.419598 -272.759785) (xy 391.373582 -272.742333) (xy 391.330961 -272.717726) (xy 391.29284 -272.686601)
			(xy 391.260205 -272.649764) (xy 391.233902 -272.608168) (xy 391.214611 -272.562892) (xy 391.202834 -272.515108)
			(xy 391.198874 -272.466054) (xy 390.8806 -272.466054) (xy 390.880088 -272.4915) (xy 390.871924 -272.541734)
			(xy 390.855808 -272.590008) (xy 390.832157 -272.635071) (xy 390.801584 -272.675757) (xy 390.76488 -272.711012)
			(xy 390.722996 -272.739922) (xy 390.677017 -272.761739) (xy 390.628133 -272.775899) (xy 390.577612 -272.782033)
			(xy 390.52676 -272.779984) (xy 390.476896 -272.769804) (xy 390.42931 -272.751757) (xy 390.385236 -272.726311)
			(xy 390.345814 -272.694124) (xy 390.312066 -272.65603) (xy 390.284865 -272.613016) (xy 390.264917 -272.566196)
			(xy 390.252738 -272.516782) (xy 390.248643 -272.466054) (xy 389.940546 -272.466054) (xy 389.940034 -272.4915)
			(xy 389.93187 -272.541734) (xy 389.915754 -272.590008) (xy 389.892103 -272.635071) (xy 389.86153 -272.675757)
			(xy 389.824826 -272.711012) (xy 389.782942 -272.739922) (xy 389.736963 -272.761739) (xy 389.688079 -272.775899)
			(xy 389.637558 -272.782033) (xy 389.586706 -272.779984) (xy 389.536842 -272.769804) (xy 389.489256 -272.751757)
			(xy 389.445182 -272.726311) (xy 389.40576 -272.694124) (xy 389.372012 -272.65603) (xy 389.344811 -272.613016)
			(xy 389.324863 -272.566196) (xy 389.312684 -272.516782) (xy 389.308589 -272.466054) (xy 388.990078 -272.466054)
			(xy 388.989583 -272.490661) (xy 388.981688 -272.539238) (xy 388.966104 -272.585919) (xy 388.943233 -272.629496)
			(xy 388.913668 -272.66884) (xy 388.878175 -272.702932) (xy 388.837672 -272.730888) (xy 388.79321 -272.751986)
			(xy 388.745939 -272.765678) (xy 388.697084 -272.77161) (xy 388.647909 -272.769629) (xy 388.59969 -272.759785)
			(xy 388.553674 -272.742333) (xy 388.511053 -272.717726) (xy 388.472932 -272.686601) (xy 388.440297 -272.649764)
			(xy 388.413994 -272.608168) (xy 388.394703 -272.562892) (xy 388.382926 -272.515108) (xy 388.378966 -272.466054)
			(xy 388.060438 -272.466054) (xy 388.059926 -272.4915) (xy 388.051762 -272.541734) (xy 388.035646 -272.590008)
			(xy 388.011995 -272.635071) (xy 387.981422 -272.675757) (xy 387.944718 -272.711012) (xy 387.902834 -272.739922)
			(xy 387.856855 -272.761739) (xy 387.807971 -272.775899) (xy 387.75745 -272.782033) (xy 387.706598 -272.779984)
			(xy 387.656734 -272.769804) (xy 387.609148 -272.751757) (xy 387.565074 -272.726311) (xy 387.525652 -272.694124)
			(xy 387.491904 -272.65603) (xy 387.464703 -272.613016) (xy 387.444755 -272.566196) (xy 387.432576 -272.516782)
			(xy 387.428481 -272.466054) (xy 387.110224 -272.466054) (xy 387.109729 -272.490661) (xy 387.101834 -272.539238)
			(xy 387.08625 -272.585919) (xy 387.063379 -272.629496) (xy 387.033814 -272.66884) (xy 386.998321 -272.702932)
			(xy 386.957818 -272.730888) (xy 386.913356 -272.751986) (xy 386.866085 -272.765678) (xy 386.81723 -272.77161)
			(xy 386.768055 -272.769629) (xy 386.719836 -272.759785) (xy 386.67382 -272.742333) (xy 386.631199 -272.717726)
			(xy 386.593078 -272.686601) (xy 386.560443 -272.649764) (xy 386.53414 -272.608168) (xy 386.514849 -272.562892)
			(xy 386.503072 -272.515108) (xy 386.499112 -272.466054) (xy 386.180584 -272.466054) (xy 386.180072 -272.4915)
			(xy 386.171908 -272.541734) (xy 386.155792 -272.590008) (xy 386.132141 -272.635071) (xy 386.101568 -272.675757)
			(xy 386.064864 -272.711012) (xy 386.02298 -272.739922) (xy 385.977001 -272.761739) (xy 385.928117 -272.775899)
			(xy 385.877596 -272.782033) (xy 385.826744 -272.779984) (xy 385.77688 -272.769804) (xy 385.729294 -272.751757)
			(xy 385.68522 -272.726311) (xy 385.645798 -272.694124) (xy 385.61205 -272.65603) (xy 385.584849 -272.613016)
			(xy 385.564901 -272.566196) (xy 385.552722 -272.516782) (xy 385.548627 -272.466054) (xy 385.230116 -272.466054)
			(xy 385.229621 -272.490661) (xy 385.221726 -272.539238) (xy 385.206142 -272.585919) (xy 385.183271 -272.629496)
			(xy 385.153706 -272.66884) (xy 385.118213 -272.702932) (xy 385.07771 -272.730888) (xy 385.033248 -272.751986)
			(xy 384.985977 -272.765678) (xy 384.937122 -272.77161) (xy 384.887947 -272.769629) (xy 384.839728 -272.759785)
			(xy 384.793712 -272.742333) (xy 384.751091 -272.717726) (xy 384.71297 -272.686601) (xy 384.680335 -272.649764)
			(xy 384.654032 -272.608168) (xy 384.634741 -272.562892) (xy 384.622964 -272.515108) (xy 384.619004 -272.466054)
			(xy 384.300476 -272.466054) (xy 384.299964 -272.4915) (xy 384.2918 -272.541734) (xy 384.275684 -272.590008)
			(xy 384.252033 -272.635071) (xy 384.22146 -272.675757) (xy 384.184756 -272.711012) (xy 384.142872 -272.739922)
			(xy 384.096893 -272.761739) (xy 384.048009 -272.775899) (xy 383.997488 -272.782033) (xy 383.946636 -272.779984)
			(xy 383.896772 -272.769804) (xy 383.849186 -272.751757) (xy 383.805112 -272.726311) (xy 383.76569 -272.694124)
			(xy 383.731942 -272.65603) (xy 383.704741 -272.613016) (xy 383.684793 -272.566196) (xy 383.672614 -272.516782)
			(xy 383.668519 -272.466054) (xy 383.360422 -272.466054) (xy 383.35991 -272.4915) (xy 383.351746 -272.541734)
			(xy 383.33563 -272.590008) (xy 383.311979 -272.635071) (xy 383.281406 -272.675757) (xy 383.244702 -272.711012)
			(xy 383.202818 -272.739922) (xy 383.156839 -272.761739) (xy 383.107955 -272.775899) (xy 383.057434 -272.782033)
			(xy 383.006582 -272.779984) (xy 382.956718 -272.769804) (xy 382.909132 -272.751757) (xy 382.865058 -272.726311)
			(xy 382.825636 -272.694124) (xy 382.791888 -272.65603) (xy 382.764687 -272.613016) (xy 382.744739 -272.566196)
			(xy 382.73256 -272.516782) (xy 382.728465 -272.466054) (xy 382.410208 -272.466054) (xy 382.409713 -272.490661)
			(xy 382.401818 -272.539238) (xy 382.386234 -272.585919) (xy 382.363363 -272.629496) (xy 382.333798 -272.66884)
			(xy 382.298305 -272.702932) (xy 382.257802 -272.730888) (xy 382.21334 -272.751986) (xy 382.166069 -272.765678)
			(xy 382.117214 -272.77161) (xy 382.068039 -272.769629) (xy 382.01982 -272.759785) (xy 381.973804 -272.742333)
			(xy 381.931183 -272.717726) (xy 381.893062 -272.686601) (xy 381.860427 -272.649764) (xy 381.834124 -272.608168)
			(xy 381.814833 -272.562892) (xy 381.803056 -272.515108) (xy 381.799096 -272.466054) (xy 381.480568 -272.466054)
			(xy 381.480056 -272.4915) (xy 381.471892 -272.541734) (xy 381.455776 -272.590008) (xy 381.432125 -272.635071)
			(xy 381.401552 -272.675757) (xy 381.364848 -272.711012) (xy 381.322964 -272.739922) (xy 381.276985 -272.761739)
			(xy 381.228101 -272.775899) (xy 381.17758 -272.782033) (xy 381.126728 -272.779984) (xy 381.076864 -272.769804)
			(xy 381.029278 -272.751757) (xy 380.985204 -272.726311) (xy 380.945782 -272.694124) (xy 380.912034 -272.65603)
			(xy 380.884833 -272.613016) (xy 380.864885 -272.566196) (xy 380.852706 -272.516782) (xy 380.848611 -272.466054)
			(xy 380.5301 -272.466054) (xy 380.529605 -272.490661) (xy 380.52171 -272.539238) (xy 380.506126 -272.585919)
			(xy 380.483255 -272.629496) (xy 380.45369 -272.66884) (xy 380.418197 -272.702932) (xy 380.377694 -272.730888)
			(xy 380.333232 -272.751986) (xy 380.285961 -272.765678) (xy 380.237106 -272.77161) (xy 380.187931 -272.769629)
			(xy 380.139712 -272.759785) (xy 380.093696 -272.742333) (xy 380.051075 -272.717726) (xy 380.012954 -272.686601)
			(xy 379.980319 -272.649764) (xy 379.954016 -272.608168) (xy 379.934725 -272.562892) (xy 379.922948 -272.515108)
			(xy 379.918988 -272.466054) (xy 379.60046 -272.466054) (xy 379.599948 -272.4915) (xy 379.591784 -272.541734)
			(xy 379.575668 -272.590008) (xy 379.552017 -272.635071) (xy 379.521444 -272.675757) (xy 379.48474 -272.711012)
			(xy 379.442856 -272.739922) (xy 379.396877 -272.761739) (xy 379.347993 -272.775899) (xy 379.297472 -272.782033)
			(xy 379.24662 -272.779984) (xy 379.196756 -272.769804) (xy 379.14917 -272.751757) (xy 379.105096 -272.726311)
			(xy 379.065674 -272.694124) (xy 379.031926 -272.65603) (xy 379.004725 -272.613016) (xy 378.984777 -272.566196)
			(xy 378.972598 -272.516782) (xy 378.968503 -272.466054) (xy 378.650246 -272.466054) (xy 378.649751 -272.490661)
			(xy 378.641856 -272.539238) (xy 378.626272 -272.585919) (xy 378.603401 -272.629496) (xy 378.573836 -272.66884)
			(xy 378.538343 -272.702932) (xy 378.49784 -272.730888) (xy 378.453378 -272.751986) (xy 378.406107 -272.765678)
			(xy 378.357252 -272.77161) (xy 378.308077 -272.769629) (xy 378.259858 -272.759785) (xy 378.213842 -272.742333)
			(xy 378.171221 -272.717726) (xy 378.1331 -272.686601) (xy 378.100465 -272.649764) (xy 378.074162 -272.608168)
			(xy 378.054871 -272.562892) (xy 378.043094 -272.515108) (xy 378.039134 -272.466054) (xy 377.720606 -272.466054)
			(xy 377.720094 -272.4915) (xy 377.71193 -272.541734) (xy 377.695814 -272.590008) (xy 377.672163 -272.635071)
			(xy 377.64159 -272.675757) (xy 377.604886 -272.711012) (xy 377.563002 -272.739922) (xy 377.517023 -272.761739)
			(xy 377.468139 -272.775899) (xy 377.417618 -272.782033) (xy 377.366766 -272.779984) (xy 377.316902 -272.769804)
			(xy 377.269316 -272.751757) (xy 377.225242 -272.726311) (xy 377.18582 -272.694124) (xy 377.152072 -272.65603)
			(xy 377.124871 -272.613016) (xy 377.104923 -272.566196) (xy 377.092744 -272.516782) (xy 377.088649 -272.466054)
			(xy 376.780552 -272.466054) (xy 376.78004 -272.4915) (xy 376.771876 -272.541734) (xy 376.75576 -272.590008)
			(xy 376.732109 -272.635071) (xy 376.701536 -272.675757) (xy 376.664832 -272.711012) (xy 376.622948 -272.739922)
			(xy 376.576969 -272.761739) (xy 376.528085 -272.775899) (xy 376.477564 -272.782033) (xy 376.426712 -272.779984)
			(xy 376.376848 -272.769804) (xy 376.329262 -272.751757) (xy 376.285188 -272.726311) (xy 376.245766 -272.694124)
			(xy 376.212018 -272.65603) (xy 376.184817 -272.613016) (xy 376.164869 -272.566196) (xy 376.15269 -272.516782)
			(xy 376.148595 -272.466054) (xy 375.830702 -272.466054) (xy 375.830706 -272.4661) (xy 375.826533 -272.516453)
			(xy 375.81413 -272.565432) (xy 375.793833 -272.611702) (xy 375.766197 -272.653999) (xy 375.731975 -272.691171)
			(xy 375.692102 -272.722203) (xy 375.647665 -272.746248) (xy 375.599876 -272.76265) (xy 375.550039 -272.770963)
			(xy 375.524776 -272.771362) (xy 375.502158 -272.770956) (xy 375.457416 -272.764283) (xy 375.414152 -272.751071)
			(xy 375.373315 -272.731612) (xy 375.354342 -272.719292) (xy 375.342404 -272.711418) (xy 375.314718 -272.709894)
			(xy 375.223024 -272.758916) (xy 375.215063 -272.763571) (xy 375.20289 -272.777403) (xy 375.196431 -272.794659)
			(xy 375.1961 -272.803874) (xy 375.1961 -272.976086) (xy 375.196377 -272.984614) (xy 375.20191 -273.000744)
			(xy 375.212461 -273.014141) (xy 375.219468 -273.019012) (xy 375.24067 -273.033176) (xy 375.278464 -273.067398)
			(xy 375.310044 -273.107424) (xy 375.334533 -273.152143) (xy 375.351248 -273.200311) (xy 375.359726 -273.250586)
			(xy 375.359728 -273.27606) (xy 375.678695 -273.27606) (xy 375.68279 -273.225332) (xy 375.694969 -273.175918)
			(xy 375.714917 -273.129098) (xy 375.742118 -273.086084) (xy 375.775866 -273.04799) (xy 375.815288 -273.015803)
			(xy 375.859362 -272.990357) (xy 375.906948 -272.97231) (xy 375.956812 -272.96213) (xy 376.007664 -272.960081)
			(xy 376.058185 -272.966215) (xy 376.107069 -272.980375) (xy 376.153048 -273.002192) (xy 376.194932 -273.031102)
			(xy 376.231636 -273.066357) (xy 376.262209 -273.107043) (xy 376.28586 -273.152106) (xy 376.301976 -273.20038)
			(xy 376.31014 -273.250614) (xy 376.310652 -273.27606) (xy 376.628926 -273.27606) (xy 376.632886 -273.227006)
			(xy 376.644663 -273.179222) (xy 376.663954 -273.133946) (xy 376.690257 -273.09235) (xy 376.722892 -273.055513)
			(xy 376.761013 -273.024388) (xy 376.803634 -272.999781) (xy 376.84965 -272.982329) (xy 376.897869 -272.972485)
			(xy 376.947044 -272.970504) (xy 376.995899 -272.976436) (xy 377.04317 -272.990128) (xy 377.087632 -273.011226)
			(xy 377.128135 -273.039182) (xy 377.163628 -273.073274) (xy 377.193193 -273.112618) (xy 377.216064 -273.156195)
			(xy 377.231648 -273.202876) (xy 377.239543 -273.251453) (xy 377.240038 -273.27606) (xy 377.558549 -273.27606)
			(xy 377.562644 -273.225332) (xy 377.574823 -273.175918) (xy 377.594771 -273.129098) (xy 377.621972 -273.086084)
			(xy 377.65572 -273.04799) (xy 377.695142 -273.015803) (xy 377.739216 -272.990357) (xy 377.786802 -272.97231)
			(xy 377.836666 -272.96213) (xy 377.887518 -272.960081) (xy 377.938039 -272.966215) (xy 377.986923 -272.980375)
			(xy 378.032902 -273.002192) (xy 378.074786 -273.031102) (xy 378.11149 -273.066357) (xy 378.142063 -273.107043)
			(xy 378.165714 -273.152106) (xy 378.18183 -273.20038) (xy 378.189994 -273.250614) (xy 378.190506 -273.27606)
			(xy 379.438657 -273.27606) (xy 379.442752 -273.225332) (xy 379.454931 -273.175918) (xy 379.474879 -273.129098)
			(xy 379.50208 -273.086084) (xy 379.535828 -273.04799) (xy 379.57525 -273.015803) (xy 379.619324 -272.990357)
			(xy 379.66691 -272.97231) (xy 379.716774 -272.96213) (xy 379.767626 -272.960081) (xy 379.818147 -272.966215)
			(xy 379.867031 -272.980375) (xy 379.91301 -273.002192) (xy 379.954894 -273.031102) (xy 379.991598 -273.066357)
			(xy 380.022171 -273.107043) (xy 380.045822 -273.152106) (xy 380.061938 -273.20038) (xy 380.070102 -273.250614)
			(xy 380.070614 -273.27606) (xy 380.378711 -273.27606) (xy 380.382806 -273.225332) (xy 380.394985 -273.175918)
			(xy 380.414933 -273.129098) (xy 380.442134 -273.086084) (xy 380.475882 -273.04799) (xy 380.515304 -273.015803)
			(xy 380.559378 -272.990357) (xy 380.606964 -272.97231) (xy 380.656828 -272.96213) (xy 380.70768 -272.960081)
			(xy 380.758201 -272.966215) (xy 380.807085 -272.980375) (xy 380.853064 -273.002192) (xy 380.894948 -273.031102)
			(xy 380.931652 -273.066357) (xy 380.962225 -273.107043) (xy 380.985876 -273.152106) (xy 381.001992 -273.20038)
			(xy 381.010156 -273.250614) (xy 381.010668 -273.27606) (xy 381.328942 -273.27606) (xy 381.332902 -273.227006)
			(xy 381.344679 -273.179222) (xy 381.36397 -273.133946) (xy 381.390273 -273.09235) (xy 381.422908 -273.055513)
			(xy 381.461029 -273.024388) (xy 381.50365 -272.999781) (xy 381.549666 -272.982329) (xy 381.597885 -272.972485)
			(xy 381.64706 -272.970504) (xy 381.695915 -272.976436) (xy 381.743186 -272.990128) (xy 381.787648 -273.011226)
			(xy 381.828151 -273.039182) (xy 381.863644 -273.073274) (xy 381.893209 -273.112618) (xy 381.91608 -273.156195)
			(xy 381.931664 -273.202876) (xy 381.939559 -273.251453) (xy 381.940054 -273.27606) (xy 382.258565 -273.27606)
			(xy 382.26266 -273.225332) (xy 382.274839 -273.175918) (xy 382.294787 -273.129098) (xy 382.321988 -273.086084)
			(xy 382.355736 -273.04799) (xy 382.395158 -273.015803) (xy 382.439232 -272.990357) (xy 382.486818 -272.97231)
			(xy 382.536682 -272.96213) (xy 382.587534 -272.960081) (xy 382.638055 -272.966215) (xy 382.686939 -272.980375)
			(xy 382.732918 -273.002192) (xy 382.774802 -273.031102) (xy 382.811506 -273.066357) (xy 382.842079 -273.107043)
			(xy 382.86573 -273.152106) (xy 382.881846 -273.20038) (xy 382.89001 -273.250614) (xy 382.890522 -273.27606)
			(xy 383.20905 -273.27606) (xy 383.21301 -273.227006) (xy 383.224787 -273.179222) (xy 383.244078 -273.133946)
			(xy 383.270381 -273.09235) (xy 383.303016 -273.055513) (xy 383.341137 -273.024388) (xy 383.383758 -272.999781)
			(xy 383.429774 -272.982329) (xy 383.477993 -272.972485) (xy 383.527168 -272.970504) (xy 383.576023 -272.976436)
			(xy 383.623294 -272.990128) (xy 383.667756 -273.011226) (xy 383.708259 -273.039182) (xy 383.743752 -273.073274)
			(xy 383.773317 -273.112618) (xy 383.796188 -273.156195) (xy 383.811772 -273.202876) (xy 383.819667 -273.251453)
			(xy 383.820162 -273.27606) (xy 384.138673 -273.27606) (xy 384.142768 -273.225332) (xy 384.154947 -273.175918)
			(xy 384.174895 -273.129098) (xy 384.202096 -273.086084) (xy 384.235844 -273.04799) (xy 384.275266 -273.015803)
			(xy 384.31934 -272.990357) (xy 384.366926 -272.97231) (xy 384.41679 -272.96213) (xy 384.467642 -272.960081)
			(xy 384.518163 -272.966215) (xy 384.567047 -272.980375) (xy 384.613026 -273.002192) (xy 384.65491 -273.031102)
			(xy 384.691614 -273.066357) (xy 384.722187 -273.107043) (xy 384.745838 -273.152106) (xy 384.761954 -273.20038)
			(xy 384.770118 -273.250614) (xy 384.77063 -273.27606) (xy 386.018527 -273.27606) (xy 386.022622 -273.225332)
			(xy 386.034801 -273.175918) (xy 386.054749 -273.129098) (xy 386.08195 -273.086084) (xy 386.115698 -273.04799)
			(xy 386.15512 -273.015803) (xy 386.199194 -272.990357) (xy 386.24678 -272.97231) (xy 386.296644 -272.96213)
			(xy 386.347496 -272.960081) (xy 386.398017 -272.966215) (xy 386.446901 -272.980375) (xy 386.49288 -273.002192)
			(xy 386.534764 -273.031102) (xy 386.571468 -273.066357) (xy 386.602041 -273.107043) (xy 386.625692 -273.152106)
			(xy 386.641808 -273.20038) (xy 386.649972 -273.250614) (xy 386.650484 -273.27606) (xy 386.958581 -273.27606)
			(xy 386.962676 -273.225332) (xy 386.974855 -273.175918) (xy 386.994803 -273.129098) (xy 387.022004 -273.086084)
			(xy 387.055752 -273.04799) (xy 387.095174 -273.015803) (xy 387.139248 -272.990357) (xy 387.186834 -272.97231)
			(xy 387.236698 -272.96213) (xy 387.28755 -272.960081) (xy 387.338071 -272.966215) (xy 387.386955 -272.980375)
			(xy 387.432934 -273.002192) (xy 387.474818 -273.031102) (xy 387.511522 -273.066357) (xy 387.542095 -273.107043)
			(xy 387.565746 -273.152106) (xy 387.581862 -273.20038) (xy 387.590026 -273.250614) (xy 387.590538 -273.27606)
			(xy 387.909066 -273.27606) (xy 387.913026 -273.227006) (xy 387.924803 -273.179222) (xy 387.944094 -273.133946)
			(xy 387.970397 -273.09235) (xy 388.003032 -273.055513) (xy 388.041153 -273.024388) (xy 388.083774 -272.999781)
			(xy 388.12979 -272.982329) (xy 388.178009 -272.972485) (xy 388.227184 -272.970504) (xy 388.276039 -272.976436)
			(xy 388.32331 -272.990128) (xy 388.367772 -273.011226) (xy 388.408275 -273.039182) (xy 388.443768 -273.073274)
			(xy 388.473333 -273.112618) (xy 388.496204 -273.156195) (xy 388.511788 -273.202876) (xy 388.519683 -273.251453)
			(xy 388.520178 -273.27606) (xy 388.838689 -273.27606) (xy 388.842784 -273.225332) (xy 388.854963 -273.175918)
			(xy 388.874911 -273.129098) (xy 388.902112 -273.086084) (xy 388.93586 -273.04799) (xy 388.975282 -273.015803)
			(xy 389.019356 -272.990357) (xy 389.066942 -272.97231) (xy 389.116806 -272.96213) (xy 389.167658 -272.960081)
			(xy 389.218179 -272.966215) (xy 389.267063 -272.980375) (xy 389.313042 -273.002192) (xy 389.354926 -273.031102)
			(xy 389.39163 -273.066357) (xy 389.422203 -273.107043) (xy 389.445854 -273.152106) (xy 389.46197 -273.20038)
			(xy 389.470134 -273.250614) (xy 389.470646 -273.27606) (xy 389.78892 -273.27606) (xy 389.79288 -273.227006)
			(xy 389.804657 -273.179222) (xy 389.823948 -273.133946) (xy 389.850251 -273.09235) (xy 389.882886 -273.055513)
			(xy 389.921007 -273.024388) (xy 389.963628 -272.999781) (xy 390.009644 -272.982329) (xy 390.057863 -272.972485)
			(xy 390.107038 -272.970504) (xy 390.155893 -272.976436) (xy 390.203164 -272.990128) (xy 390.247626 -273.011226)
			(xy 390.288129 -273.039182) (xy 390.323622 -273.073274) (xy 390.353187 -273.112618) (xy 390.376058 -273.156195)
			(xy 390.391642 -273.202876) (xy 390.399537 -273.251453) (xy 390.400032 -273.27606) (xy 390.718543 -273.27606)
			(xy 390.722638 -273.225332) (xy 390.734817 -273.175918) (xy 390.754765 -273.129098) (xy 390.781966 -273.086084)
			(xy 390.815714 -273.04799) (xy 390.855136 -273.015803) (xy 390.89921 -272.990357) (xy 390.946796 -272.97231)
			(xy 390.99666 -272.96213) (xy 391.047512 -272.960081) (xy 391.098033 -272.966215) (xy 391.146917 -272.980375)
			(xy 391.192896 -273.002192) (xy 391.204385 -273.010122) (xy 394.67715 -273.010122) (xy 394.68111 -272.961068)
			(xy 394.692887 -272.913284) (xy 394.712178 -272.868008) (xy 394.738481 -272.826412) (xy 394.771116 -272.789575)
			(xy 394.809237 -272.75845) (xy 394.851858 -272.733843) (xy 394.897874 -272.716391) (xy 394.946093 -272.706547)
			(xy 394.995268 -272.704566) (xy 395.044123 -272.710498) (xy 395.091394 -272.72419) (xy 395.135856 -272.745288)
			(xy 395.176359 -272.773244) (xy 395.211852 -272.807336) (xy 395.241417 -272.84668) (xy 395.264288 -272.890257)
			(xy 395.279872 -272.936938) (xy 395.287767 -272.985515) (xy 395.288262 -273.010122) (xy 395.287767 -273.034729)
			(xy 395.279872 -273.083306) (xy 395.264288 -273.129987) (xy 395.241417 -273.173564) (xy 395.211852 -273.212908)
			(xy 395.176359 -273.247) (xy 395.135856 -273.274956) (xy 395.091394 -273.296054) (xy 395.044123 -273.309746)
			(xy 394.995268 -273.315678) (xy 394.946093 -273.313697) (xy 394.897874 -273.303853) (xy 394.851858 -273.286401)
			(xy 394.809237 -273.261794) (xy 394.771116 -273.230669) (xy 394.738481 -273.193832) (xy 394.712178 -273.152236)
			(xy 394.692887 -273.10696) (xy 394.68111 -273.059176) (xy 394.67715 -273.010122) (xy 391.204385 -273.010122)
			(xy 391.23478 -273.031102) (xy 391.271484 -273.066357) (xy 391.302057 -273.107043) (xy 391.325708 -273.152106)
			(xy 391.341824 -273.20038) (xy 391.349988 -273.250614) (xy 391.3505 -273.27606) (xy 391.349988 -273.301506)
			(xy 391.341824 -273.35174) (xy 391.325708 -273.400014) (xy 391.302057 -273.445077) (xy 391.271484 -273.485763)
			(xy 391.23478 -273.521018) (xy 391.192896 -273.549928) (xy 391.146917 -273.571745) (xy 391.098033 -273.585905)
			(xy 391.047512 -273.592039) (xy 390.99666 -273.58999) (xy 390.946796 -273.57981) (xy 390.89921 -273.561763)
			(xy 390.855136 -273.536317) (xy 390.815714 -273.50413) (xy 390.781966 -273.466036) (xy 390.754765 -273.423022)
			(xy 390.734817 -273.376202) (xy 390.722638 -273.326788) (xy 390.718543 -273.27606) (xy 390.400032 -273.27606)
			(xy 390.399537 -273.300667) (xy 390.391642 -273.349244) (xy 390.376058 -273.395925) (xy 390.353187 -273.439502)
			(xy 390.323622 -273.478846) (xy 390.288129 -273.512938) (xy 390.247626 -273.540894) (xy 390.203164 -273.561992)
			(xy 390.155893 -273.575684) (xy 390.107038 -273.581616) (xy 390.057863 -273.579635) (xy 390.009644 -273.569791)
			(xy 389.963628 -273.552339) (xy 389.921007 -273.527732) (xy 389.882886 -273.496607) (xy 389.850251 -273.45977)
			(xy 389.823948 -273.418174) (xy 389.804657 -273.372898) (xy 389.79288 -273.325114) (xy 389.78892 -273.27606)
			(xy 389.470646 -273.27606) (xy 389.470134 -273.301506) (xy 389.46197 -273.35174) (xy 389.445854 -273.400014)
			(xy 389.422203 -273.445077) (xy 389.39163 -273.485763) (xy 389.354926 -273.521018) (xy 389.313042 -273.549928)
			(xy 389.267063 -273.571745) (xy 389.218179 -273.585905) (xy 389.167658 -273.592039) (xy 389.116806 -273.58999)
			(xy 389.066942 -273.57981) (xy 389.019356 -273.561763) (xy 388.975282 -273.536317) (xy 388.93586 -273.50413)
			(xy 388.902112 -273.466036) (xy 388.874911 -273.423022) (xy 388.854963 -273.376202) (xy 388.842784 -273.326788)
			(xy 388.838689 -273.27606) (xy 388.520178 -273.27606) (xy 388.519683 -273.300667) (xy 388.511788 -273.349244)
			(xy 388.496204 -273.395925) (xy 388.473333 -273.439502) (xy 388.443768 -273.478846) (xy 388.408275 -273.512938)
			(xy 388.367772 -273.540894) (xy 388.32331 -273.561992) (xy 388.276039 -273.575684) (xy 388.227184 -273.581616)
			(xy 388.178009 -273.579635) (xy 388.12979 -273.569791) (xy 388.083774 -273.552339) (xy 388.041153 -273.527732)
			(xy 388.003032 -273.496607) (xy 387.970397 -273.45977) (xy 387.944094 -273.418174) (xy 387.924803 -273.372898)
			(xy 387.913026 -273.325114) (xy 387.909066 -273.27606) (xy 387.590538 -273.27606) (xy 387.590026 -273.301506)
			(xy 387.581862 -273.35174) (xy 387.565746 -273.400014) (xy 387.542095 -273.445077) (xy 387.511522 -273.485763)
			(xy 387.474818 -273.521018) (xy 387.432934 -273.549928) (xy 387.386955 -273.571745) (xy 387.338071 -273.585905)
			(xy 387.28755 -273.592039) (xy 387.236698 -273.58999) (xy 387.186834 -273.57981) (xy 387.139248 -273.561763)
			(xy 387.095174 -273.536317) (xy 387.055752 -273.50413) (xy 387.022004 -273.466036) (xy 386.994803 -273.423022)
			(xy 386.974855 -273.376202) (xy 386.962676 -273.326788) (xy 386.958581 -273.27606) (xy 386.650484 -273.27606)
			(xy 386.649972 -273.301506) (xy 386.641808 -273.35174) (xy 386.625692 -273.400014) (xy 386.602041 -273.445077)
			(xy 386.571468 -273.485763) (xy 386.534764 -273.521018) (xy 386.49288 -273.549928) (xy 386.446901 -273.571745)
			(xy 386.398017 -273.585905) (xy 386.347496 -273.592039) (xy 386.296644 -273.58999) (xy 386.24678 -273.57981)
			(xy 386.199194 -273.561763) (xy 386.15512 -273.536317) (xy 386.115698 -273.50413) (xy 386.08195 -273.466036)
			(xy 386.054749 -273.423022) (xy 386.034801 -273.376202) (xy 386.022622 -273.326788) (xy 386.018527 -273.27606)
			(xy 384.77063 -273.27606) (xy 384.770118 -273.301506) (xy 384.761954 -273.35174) (xy 384.745838 -273.400014)
			(xy 384.722187 -273.445077) (xy 384.691614 -273.485763) (xy 384.65491 -273.521018) (xy 384.613026 -273.549928)
			(xy 384.567047 -273.571745) (xy 384.518163 -273.585905) (xy 384.467642 -273.592039) (xy 384.41679 -273.58999)
			(xy 384.366926 -273.57981) (xy 384.31934 -273.561763) (xy 384.275266 -273.536317) (xy 384.235844 -273.50413)
			(xy 384.202096 -273.466036) (xy 384.174895 -273.423022) (xy 384.154947 -273.376202) (xy 384.142768 -273.326788)
			(xy 384.138673 -273.27606) (xy 383.820162 -273.27606) (xy 383.819667 -273.300667) (xy 383.811772 -273.349244)
			(xy 383.796188 -273.395925) (xy 383.773317 -273.439502) (xy 383.743752 -273.478846) (xy 383.708259 -273.512938)
			(xy 383.667756 -273.540894) (xy 383.623294 -273.561992) (xy 383.576023 -273.575684) (xy 383.527168 -273.581616)
			(xy 383.477993 -273.579635) (xy 383.429774 -273.569791) (xy 383.383758 -273.552339) (xy 383.341137 -273.527732)
			(xy 383.303016 -273.496607) (xy 383.270381 -273.45977) (xy 383.244078 -273.418174) (xy 383.224787 -273.372898)
			(xy 383.21301 -273.325114) (xy 383.20905 -273.27606) (xy 382.890522 -273.27606) (xy 382.89001 -273.301506)
			(xy 382.881846 -273.35174) (xy 382.86573 -273.400014) (xy 382.842079 -273.445077) (xy 382.811506 -273.485763)
			(xy 382.774802 -273.521018) (xy 382.732918 -273.549928) (xy 382.686939 -273.571745) (xy 382.638055 -273.585905)
			(xy 382.587534 -273.592039) (xy 382.536682 -273.58999) (xy 382.486818 -273.57981) (xy 382.439232 -273.561763)
			(xy 382.395158 -273.536317) (xy 382.355736 -273.50413) (xy 382.321988 -273.466036) (xy 382.294787 -273.423022)
			(xy 382.274839 -273.376202) (xy 382.26266 -273.326788) (xy 382.258565 -273.27606) (xy 381.940054 -273.27606)
			(xy 381.939559 -273.300667) (xy 381.931664 -273.349244) (xy 381.91608 -273.395925) (xy 381.893209 -273.439502)
			(xy 381.863644 -273.478846) (xy 381.828151 -273.512938) (xy 381.787648 -273.540894) (xy 381.743186 -273.561992)
			(xy 381.695915 -273.575684) (xy 381.64706 -273.581616) (xy 381.597885 -273.579635) (xy 381.549666 -273.569791)
			(xy 381.50365 -273.552339) (xy 381.461029 -273.527732) (xy 381.422908 -273.496607) (xy 381.390273 -273.45977)
			(xy 381.36397 -273.418174) (xy 381.344679 -273.372898) (xy 381.332902 -273.325114) (xy 381.328942 -273.27606)
			(xy 381.010668 -273.27606) (xy 381.010156 -273.301506) (xy 381.001992 -273.35174) (xy 380.985876 -273.400014)
			(xy 380.962225 -273.445077) (xy 380.931652 -273.485763) (xy 380.894948 -273.521018) (xy 380.853064 -273.549928)
			(xy 380.807085 -273.571745) (xy 380.758201 -273.585905) (xy 380.70768 -273.592039) (xy 380.656828 -273.58999)
			(xy 380.606964 -273.57981) (xy 380.559378 -273.561763) (xy 380.515304 -273.536317) (xy 380.475882 -273.50413)
			(xy 380.442134 -273.466036) (xy 380.414933 -273.423022) (xy 380.394985 -273.376202) (xy 380.382806 -273.326788)
			(xy 380.378711 -273.27606) (xy 380.070614 -273.27606) (xy 380.070102 -273.301506) (xy 380.061938 -273.35174)
			(xy 380.045822 -273.400014) (xy 380.022171 -273.445077) (xy 379.991598 -273.485763) (xy 379.954894 -273.521018)
			(xy 379.91301 -273.549928) (xy 379.867031 -273.571745) (xy 379.818147 -273.585905) (xy 379.767626 -273.592039)
			(xy 379.716774 -273.58999) (xy 379.66691 -273.57981) (xy 379.619324 -273.561763) (xy 379.57525 -273.536317)
			(xy 379.535828 -273.50413) (xy 379.50208 -273.466036) (xy 379.474879 -273.423022) (xy 379.454931 -273.376202)
			(xy 379.442752 -273.326788) (xy 379.438657 -273.27606) (xy 378.190506 -273.27606) (xy 378.189994 -273.301506)
			(xy 378.18183 -273.35174) (xy 378.165714 -273.400014) (xy 378.142063 -273.445077) (xy 378.11149 -273.485763)
			(xy 378.074786 -273.521018) (xy 378.032902 -273.549928) (xy 377.986923 -273.571745) (xy 377.938039 -273.585905)
			(xy 377.887518 -273.592039) (xy 377.836666 -273.58999) (xy 377.786802 -273.57981) (xy 377.739216 -273.561763)
			(xy 377.695142 -273.536317) (xy 377.65572 -273.50413) (xy 377.621972 -273.466036) (xy 377.594771 -273.423022)
			(xy 377.574823 -273.376202) (xy 377.562644 -273.326788) (xy 377.558549 -273.27606) (xy 377.240038 -273.27606)
			(xy 377.239543 -273.300667) (xy 377.231648 -273.349244) (xy 377.216064 -273.395925) (xy 377.193193 -273.439502)
			(xy 377.163628 -273.478846) (xy 377.128135 -273.512938) (xy 377.087632 -273.540894) (xy 377.04317 -273.561992)
			(xy 376.995899 -273.575684) (xy 376.947044 -273.581616) (xy 376.897869 -273.579635) (xy 376.84965 -273.569791)
			(xy 376.803634 -273.552339) (xy 376.761013 -273.527732) (xy 376.722892 -273.496607) (xy 376.690257 -273.45977)
			(xy 376.663954 -273.418174) (xy 376.644663 -273.372898) (xy 376.632886 -273.325114) (xy 376.628926 -273.27606)
			(xy 376.310652 -273.27606) (xy 376.31014 -273.301506) (xy 376.301976 -273.35174) (xy 376.28586 -273.400014)
			(xy 376.262209 -273.445077) (xy 376.231636 -273.485763) (xy 376.194932 -273.521018) (xy 376.153048 -273.549928)
			(xy 376.107069 -273.571745) (xy 376.058185 -273.585905) (xy 376.007664 -273.592039) (xy 375.956812 -273.58999)
			(xy 375.906948 -273.57981) (xy 375.859362 -273.561763) (xy 375.815288 -273.536317) (xy 375.775866 -273.50413)
			(xy 375.742118 -273.466036) (xy 375.714917 -273.423022) (xy 375.694969 -273.376202) (xy 375.68279 -273.326788)
			(xy 375.678695 -273.27606) (xy 375.359728 -273.27606) (xy 375.35973 -273.301571) (xy 375.351259 -273.351848)
			(xy 375.33455 -273.400017) (xy 375.310068 -273.44474) (xy 375.278493 -273.484771) (xy 375.240704 -273.518997)
			(xy 375.219468 -273.533108) (xy 375.212476 -273.537991) (xy 375.201952 -273.551399) (xy 375.19639 -273.567511)
			(xy 375.1961 -273.576034) (xy 375.1961 -274.086066) (xy 376.148595 -274.086066) (xy 376.15269 -274.035338)
			(xy 376.164869 -273.985924) (xy 376.184817 -273.939104) (xy 376.212018 -273.89609) (xy 376.245766 -273.857996)
			(xy 376.285188 -273.825809) (xy 376.329262 -273.800363) (xy 376.376848 -273.782316) (xy 376.426712 -273.772136)
			(xy 376.477564 -273.770087) (xy 376.528085 -273.776221) (xy 376.576969 -273.790381) (xy 376.622948 -273.812198)
			(xy 376.664832 -273.841108) (xy 376.701536 -273.876363) (xy 376.732109 -273.917049) (xy 376.75576 -273.962112)
			(xy 376.771876 -274.010386) (xy 376.78004 -274.06062) (xy 376.780552 -274.086066) (xy 377.088649 -274.086066)
			(xy 377.092744 -274.035338) (xy 377.104923 -273.985924) (xy 377.124871 -273.939104) (xy 377.152072 -273.89609)
			(xy 377.18582 -273.857996) (xy 377.225242 -273.825809) (xy 377.269316 -273.800363) (xy 377.316902 -273.782316)
			(xy 377.366766 -273.772136) (xy 377.417618 -273.770087) (xy 377.468139 -273.776221) (xy 377.517023 -273.790381)
			(xy 377.563002 -273.812198) (xy 377.604886 -273.841108) (xy 377.64159 -273.876363) (xy 377.672163 -273.917049)
			(xy 377.695814 -273.962112) (xy 377.71193 -274.010386) (xy 377.720094 -274.06062) (xy 377.720606 -274.086066)
			(xy 378.039134 -274.086066) (xy 378.043094 -274.037012) (xy 378.054871 -273.989228) (xy 378.074162 -273.943952)
			(xy 378.100465 -273.902356) (xy 378.1331 -273.865519) (xy 378.171221 -273.834394) (xy 378.213842 -273.809787)
			(xy 378.259858 -273.792335) (xy 378.308077 -273.782491) (xy 378.357252 -273.78051) (xy 378.406107 -273.786442)
			(xy 378.453378 -273.800134) (xy 378.49784 -273.821232) (xy 378.538343 -273.849188) (xy 378.573836 -273.88328)
			(xy 378.603401 -273.922624) (xy 378.626272 -273.966201) (xy 378.641856 -274.012882) (xy 378.649751 -274.061459)
			(xy 378.650246 -274.086066) (xy 378.968503 -274.086066) (xy 378.972598 -274.035338) (xy 378.984777 -273.985924)
			(xy 379.004725 -273.939104) (xy 379.031926 -273.89609) (xy 379.065674 -273.857996) (xy 379.105096 -273.825809)
			(xy 379.14917 -273.800363) (xy 379.196756 -273.782316) (xy 379.24662 -273.772136) (xy 379.297472 -273.770087)
			(xy 379.347993 -273.776221) (xy 379.396877 -273.790381) (xy 379.442856 -273.812198) (xy 379.48474 -273.841108)
			(xy 379.521444 -273.876363) (xy 379.552017 -273.917049) (xy 379.575668 -273.962112) (xy 379.591784 -274.010386)
			(xy 379.599948 -274.06062) (xy 379.60046 -274.086066) (xy 379.918988 -274.086066) (xy 379.922948 -274.037012)
			(xy 379.934725 -273.989228) (xy 379.954016 -273.943952) (xy 379.980319 -273.902356) (xy 380.012954 -273.865519)
			(xy 380.051075 -273.834394) (xy 380.093696 -273.809787) (xy 380.139712 -273.792335) (xy 380.187931 -273.782491)
			(xy 380.237106 -273.78051) (xy 380.285961 -273.786442) (xy 380.333232 -273.800134) (xy 380.377694 -273.821232)
			(xy 380.418197 -273.849188) (xy 380.45369 -273.88328) (xy 380.483255 -273.922624) (xy 380.506126 -273.966201)
			(xy 380.52171 -274.012882) (xy 380.529605 -274.061459) (xy 380.5301 -274.086066) (xy 380.848611 -274.086066)
			(xy 380.852706 -274.035338) (xy 380.864885 -273.985924) (xy 380.884833 -273.939104) (xy 380.912034 -273.89609)
			(xy 380.945782 -273.857996) (xy 380.985204 -273.825809) (xy 381.029278 -273.800363) (xy 381.076864 -273.782316)
			(xy 381.126728 -273.772136) (xy 381.17758 -273.770087) (xy 381.228101 -273.776221) (xy 381.276985 -273.790381)
			(xy 381.322964 -273.812198) (xy 381.364848 -273.841108) (xy 381.401552 -273.876363) (xy 381.432125 -273.917049)
			(xy 381.455776 -273.962112) (xy 381.471892 -274.010386) (xy 381.480056 -274.06062) (xy 381.480568 -274.086066)
			(xy 381.799096 -274.086066) (xy 381.803056 -274.037012) (xy 381.814833 -273.989228) (xy 381.834124 -273.943952)
			(xy 381.860427 -273.902356) (xy 381.893062 -273.865519) (xy 381.931183 -273.834394) (xy 381.973804 -273.809787)
			(xy 382.01982 -273.792335) (xy 382.068039 -273.782491) (xy 382.117214 -273.78051) (xy 382.166069 -273.786442)
			(xy 382.21334 -273.800134) (xy 382.257802 -273.821232) (xy 382.298305 -273.849188) (xy 382.333798 -273.88328)
			(xy 382.363363 -273.922624) (xy 382.386234 -273.966201) (xy 382.401818 -274.012882) (xy 382.409713 -274.061459)
			(xy 382.410208 -274.086066) (xy 382.728465 -274.086066) (xy 382.73256 -274.035338) (xy 382.744739 -273.985924)
			(xy 382.764687 -273.939104) (xy 382.791888 -273.89609) (xy 382.825636 -273.857996) (xy 382.865058 -273.825809)
			(xy 382.909132 -273.800363) (xy 382.956718 -273.782316) (xy 383.006582 -273.772136) (xy 383.057434 -273.770087)
			(xy 383.107955 -273.776221) (xy 383.156839 -273.790381) (xy 383.202818 -273.812198) (xy 383.244702 -273.841108)
			(xy 383.281406 -273.876363) (xy 383.311979 -273.917049) (xy 383.33563 -273.962112) (xy 383.351746 -274.010386)
			(xy 383.35991 -274.06062) (xy 383.360422 -274.086066) (xy 383.668519 -274.086066) (xy 383.672614 -274.035338)
			(xy 383.684793 -273.985924) (xy 383.704741 -273.939104) (xy 383.731942 -273.89609) (xy 383.76569 -273.857996)
			(xy 383.805112 -273.825809) (xy 383.849186 -273.800363) (xy 383.896772 -273.782316) (xy 383.946636 -273.772136)
			(xy 383.997488 -273.770087) (xy 384.048009 -273.776221) (xy 384.096893 -273.790381) (xy 384.142872 -273.812198)
			(xy 384.184756 -273.841108) (xy 384.22146 -273.876363) (xy 384.252033 -273.917049) (xy 384.275684 -273.962112)
			(xy 384.2918 -274.010386) (xy 384.299964 -274.06062) (xy 384.300476 -274.086066) (xy 384.619004 -274.086066)
			(xy 384.622964 -274.037012) (xy 384.634741 -273.989228) (xy 384.654032 -273.943952) (xy 384.680335 -273.902356)
			(xy 384.71297 -273.865519) (xy 384.751091 -273.834394) (xy 384.793712 -273.809787) (xy 384.839728 -273.792335)
			(xy 384.887947 -273.782491) (xy 384.937122 -273.78051) (xy 384.985977 -273.786442) (xy 385.033248 -273.800134)
			(xy 385.07771 -273.821232) (xy 385.118213 -273.849188) (xy 385.153706 -273.88328) (xy 385.183271 -273.922624)
			(xy 385.206142 -273.966201) (xy 385.221726 -274.012882) (xy 385.229621 -274.061459) (xy 385.230116 -274.086066)
			(xy 385.548627 -274.086066) (xy 385.552722 -274.035338) (xy 385.564901 -273.985924) (xy 385.584849 -273.939104)
			(xy 385.61205 -273.89609) (xy 385.645798 -273.857996) (xy 385.68522 -273.825809) (xy 385.729294 -273.800363)
			(xy 385.77688 -273.782316) (xy 385.826744 -273.772136) (xy 385.877596 -273.770087) (xy 385.928117 -273.776221)
			(xy 385.977001 -273.790381) (xy 386.02298 -273.812198) (xy 386.064864 -273.841108) (xy 386.101568 -273.876363)
			(xy 386.132141 -273.917049) (xy 386.155792 -273.962112) (xy 386.171908 -274.010386) (xy 386.180072 -274.06062)
			(xy 386.180584 -274.086066) (xy 386.499112 -274.086066) (xy 386.503072 -274.037012) (xy 386.514849 -273.989228)
			(xy 386.53414 -273.943952) (xy 386.560443 -273.902356) (xy 386.593078 -273.865519) (xy 386.631199 -273.834394)
			(xy 386.67382 -273.809787) (xy 386.719836 -273.792335) (xy 386.768055 -273.782491) (xy 386.81723 -273.78051)
			(xy 386.866085 -273.786442) (xy 386.913356 -273.800134) (xy 386.957818 -273.821232) (xy 386.998321 -273.849188)
			(xy 387.033814 -273.88328) (xy 387.063379 -273.922624) (xy 387.08625 -273.966201) (xy 387.101834 -274.012882)
			(xy 387.109729 -274.061459) (xy 387.110224 -274.086066) (xy 387.428481 -274.086066) (xy 387.432576 -274.035338)
			(xy 387.444755 -273.985924) (xy 387.464703 -273.939104) (xy 387.491904 -273.89609) (xy 387.525652 -273.857996)
			(xy 387.565074 -273.825809) (xy 387.609148 -273.800363) (xy 387.656734 -273.782316) (xy 387.706598 -273.772136)
			(xy 387.75745 -273.770087) (xy 387.807971 -273.776221) (xy 387.856855 -273.790381) (xy 387.902834 -273.812198)
			(xy 387.944718 -273.841108) (xy 387.981422 -273.876363) (xy 388.011995 -273.917049) (xy 388.035646 -273.962112)
			(xy 388.051762 -274.010386) (xy 388.059926 -274.06062) (xy 388.060438 -274.086066) (xy 388.378966 -274.086066)
			(xy 388.382926 -274.037012) (xy 388.394703 -273.989228) (xy 388.413994 -273.943952) (xy 388.440297 -273.902356)
			(xy 388.472932 -273.865519) (xy 388.511053 -273.834394) (xy 388.553674 -273.809787) (xy 388.59969 -273.792335)
			(xy 388.647909 -273.782491) (xy 388.697084 -273.78051) (xy 388.745939 -273.786442) (xy 388.79321 -273.800134)
			(xy 388.837672 -273.821232) (xy 388.878175 -273.849188) (xy 388.913668 -273.88328) (xy 388.943233 -273.922624)
			(xy 388.966104 -273.966201) (xy 388.981688 -274.012882) (xy 388.989583 -274.061459) (xy 388.990078 -274.086066)
			(xy 389.308589 -274.086066) (xy 389.312684 -274.035338) (xy 389.324863 -273.985924) (xy 389.344811 -273.939104)
			(xy 389.372012 -273.89609) (xy 389.40576 -273.857996) (xy 389.445182 -273.825809) (xy 389.489256 -273.800363)
			(xy 389.536842 -273.782316) (xy 389.586706 -273.772136) (xy 389.637558 -273.770087) (xy 389.688079 -273.776221)
			(xy 389.736963 -273.790381) (xy 389.782942 -273.812198) (xy 389.824826 -273.841108) (xy 389.86153 -273.876363)
			(xy 389.892103 -273.917049) (xy 389.915754 -273.962112) (xy 389.93187 -274.010386) (xy 389.940034 -274.06062)
			(xy 389.940546 -274.086066) (xy 390.248643 -274.086066) (xy 390.252738 -274.035338) (xy 390.264917 -273.985924)
			(xy 390.284865 -273.939104) (xy 390.312066 -273.89609) (xy 390.345814 -273.857996) (xy 390.385236 -273.825809)
			(xy 390.42931 -273.800363) (xy 390.476896 -273.782316) (xy 390.52676 -273.772136) (xy 390.577612 -273.770087)
			(xy 390.628133 -273.776221) (xy 390.677017 -273.790381) (xy 390.722996 -273.812198) (xy 390.76488 -273.841108)
			(xy 390.801584 -273.876363) (xy 390.832157 -273.917049) (xy 390.855808 -273.962112) (xy 390.871924 -274.010386)
			(xy 390.880088 -274.06062) (xy 390.8806 -274.086066) (xy 391.198874 -274.086066) (xy 391.202834 -274.037012)
			(xy 391.214611 -273.989228) (xy 391.233902 -273.943952) (xy 391.260205 -273.902356) (xy 391.29284 -273.865519)
			(xy 391.330961 -273.834394) (xy 391.373582 -273.809787) (xy 391.419598 -273.792335) (xy 391.467817 -273.782491)
			(xy 391.516992 -273.78051) (xy 391.565847 -273.786442) (xy 391.613118 -273.800134) (xy 391.65758 -273.821232)
			(xy 391.698083 -273.849188) (xy 391.733576 -273.88328) (xy 391.763141 -273.922624) (xy 391.786012 -273.966201)
			(xy 391.801596 -274.012882) (xy 391.809491 -274.061459) (xy 391.809986 -274.086066) (xy 393.078982 -274.086066)
			(xy 393.082942 -274.037012) (xy 393.094719 -273.989228) (xy 393.11401 -273.943952) (xy 393.140313 -273.902356)
			(xy 393.172948 -273.865519) (xy 393.211069 -273.834394) (xy 393.25369 -273.809787) (xy 393.299706 -273.792335)
			(xy 393.347925 -273.782491) (xy 393.3971 -273.78051) (xy 393.445955 -273.786442) (xy 393.493226 -273.800134)
			(xy 393.537688 -273.821232) (xy 393.578191 -273.849188) (xy 393.613684 -273.88328) (xy 393.643249 -273.922624)
			(xy 393.66612 -273.966201) (xy 393.681704 -274.012882) (xy 393.689599 -274.061459) (xy 393.690094 -274.086066)
			(xy 393.689599 -274.110673) (xy 393.681704 -274.15925) (xy 393.66612 -274.205931) (xy 393.643249 -274.249508)
			(xy 393.613684 -274.288852) (xy 393.578191 -274.322944) (xy 393.537688 -274.3509) (xy 393.493226 -274.371998)
			(xy 393.445955 -274.38569) (xy 393.3971 -274.391622) (xy 393.347925 -274.389641) (xy 393.299706 -274.379797)
			(xy 393.25369 -274.362345) (xy 393.211069 -274.337738) (xy 393.172948 -274.306613) (xy 393.140313 -274.269776)
			(xy 393.11401 -274.22818) (xy 393.094719 -274.182904) (xy 393.082942 -274.13512) (xy 393.078982 -274.086066)
			(xy 391.809986 -274.086066) (xy 391.809491 -274.110673) (xy 391.801596 -274.15925) (xy 391.786012 -274.205931)
			(xy 391.763141 -274.249508) (xy 391.733576 -274.288852) (xy 391.698083 -274.322944) (xy 391.65758 -274.3509)
			(xy 391.613118 -274.371998) (xy 391.565847 -274.38569) (xy 391.516992 -274.391622) (xy 391.467817 -274.389641)
			(xy 391.419598 -274.379797) (xy 391.373582 -274.362345) (xy 391.330961 -274.337738) (xy 391.29284 -274.306613)
			(xy 391.260205 -274.269776) (xy 391.233902 -274.22818) (xy 391.214611 -274.182904) (xy 391.202834 -274.13512)
			(xy 391.198874 -274.086066) (xy 390.8806 -274.086066) (xy 390.880088 -274.111512) (xy 390.871924 -274.161746)
			(xy 390.855808 -274.21002) (xy 390.832157 -274.255083) (xy 390.801584 -274.295769) (xy 390.76488 -274.331024)
			(xy 390.722996 -274.359934) (xy 390.677017 -274.381751) (xy 390.628133 -274.395911) (xy 390.577612 -274.402045)
			(xy 390.52676 -274.399996) (xy 390.476896 -274.389816) (xy 390.42931 -274.371769) (xy 390.385236 -274.346323)
			(xy 390.345814 -274.314136) (xy 390.312066 -274.276042) (xy 390.284865 -274.233028) (xy 390.264917 -274.186208)
			(xy 390.252738 -274.136794) (xy 390.248643 -274.086066) (xy 389.940546 -274.086066) (xy 389.940034 -274.111512)
			(xy 389.93187 -274.161746) (xy 389.915754 -274.21002) (xy 389.892103 -274.255083) (xy 389.86153 -274.295769)
			(xy 389.824826 -274.331024) (xy 389.782942 -274.359934) (xy 389.736963 -274.381751) (xy 389.688079 -274.395911)
			(xy 389.637558 -274.402045) (xy 389.586706 -274.399996) (xy 389.536842 -274.389816) (xy 389.489256 -274.371769)
			(xy 389.445182 -274.346323) (xy 389.40576 -274.314136) (xy 389.372012 -274.276042) (xy 389.344811 -274.233028)
			(xy 389.324863 -274.186208) (xy 389.312684 -274.136794) (xy 389.308589 -274.086066) (xy 388.990078 -274.086066)
			(xy 388.989583 -274.110673) (xy 388.981688 -274.15925) (xy 388.966104 -274.205931) (xy 388.943233 -274.249508)
			(xy 388.913668 -274.288852) (xy 388.878175 -274.322944) (xy 388.837672 -274.3509) (xy 388.79321 -274.371998)
			(xy 388.745939 -274.38569) (xy 388.697084 -274.391622) (xy 388.647909 -274.389641) (xy 388.59969 -274.379797)
			(xy 388.553674 -274.362345) (xy 388.511053 -274.337738) (xy 388.472932 -274.306613) (xy 388.440297 -274.269776)
			(xy 388.413994 -274.22818) (xy 388.394703 -274.182904) (xy 388.382926 -274.13512) (xy 388.378966 -274.086066)
			(xy 388.060438 -274.086066) (xy 388.059926 -274.111512) (xy 388.051762 -274.161746) (xy 388.035646 -274.21002)
			(xy 388.011995 -274.255083) (xy 387.981422 -274.295769) (xy 387.944718 -274.331024) (xy 387.902834 -274.359934)
			(xy 387.856855 -274.381751) (xy 387.807971 -274.395911) (xy 387.75745 -274.402045) (xy 387.706598 -274.399996)
			(xy 387.656734 -274.389816) (xy 387.609148 -274.371769) (xy 387.565074 -274.346323) (xy 387.525652 -274.314136)
			(xy 387.491904 -274.276042) (xy 387.464703 -274.233028) (xy 387.444755 -274.186208) (xy 387.432576 -274.136794)
			(xy 387.428481 -274.086066) (xy 387.110224 -274.086066) (xy 387.109729 -274.110673) (xy 387.101834 -274.15925)
			(xy 387.08625 -274.205931) (xy 387.063379 -274.249508) (xy 387.033814 -274.288852) (xy 386.998321 -274.322944)
			(xy 386.957818 -274.3509) (xy 386.913356 -274.371998) (xy 386.866085 -274.38569) (xy 386.81723 -274.391622)
			(xy 386.768055 -274.389641) (xy 386.719836 -274.379797) (xy 386.67382 -274.362345) (xy 386.631199 -274.337738)
			(xy 386.593078 -274.306613) (xy 386.560443 -274.269776) (xy 386.53414 -274.22818) (xy 386.514849 -274.182904)
			(xy 386.503072 -274.13512) (xy 386.499112 -274.086066) (xy 386.180584 -274.086066) (xy 386.180072 -274.111512)
			(xy 386.171908 -274.161746) (xy 386.155792 -274.21002) (xy 386.132141 -274.255083) (xy 386.101568 -274.295769)
			(xy 386.064864 -274.331024) (xy 386.02298 -274.359934) (xy 385.977001 -274.381751) (xy 385.928117 -274.395911)
			(xy 385.877596 -274.402045) (xy 385.826744 -274.399996) (xy 385.77688 -274.389816) (xy 385.729294 -274.371769)
			(xy 385.68522 -274.346323) (xy 385.645798 -274.314136) (xy 385.61205 -274.276042) (xy 385.584849 -274.233028)
			(xy 385.564901 -274.186208) (xy 385.552722 -274.136794) (xy 385.548627 -274.086066) (xy 385.230116 -274.086066)
			(xy 385.229621 -274.110673) (xy 385.221726 -274.15925) (xy 385.206142 -274.205931) (xy 385.183271 -274.249508)
			(xy 385.153706 -274.288852) (xy 385.118213 -274.322944) (xy 385.07771 -274.3509) (xy 385.033248 -274.371998)
			(xy 384.985977 -274.38569) (xy 384.937122 -274.391622) (xy 384.887947 -274.389641) (xy 384.839728 -274.379797)
			(xy 384.793712 -274.362345) (xy 384.751091 -274.337738) (xy 384.71297 -274.306613) (xy 384.680335 -274.269776)
			(xy 384.654032 -274.22818) (xy 384.634741 -274.182904) (xy 384.622964 -274.13512) (xy 384.619004 -274.086066)
			(xy 384.300476 -274.086066) (xy 384.299964 -274.111512) (xy 384.2918 -274.161746) (xy 384.275684 -274.21002)
			(xy 384.252033 -274.255083) (xy 384.22146 -274.295769) (xy 384.184756 -274.331024) (xy 384.142872 -274.359934)
			(xy 384.096893 -274.381751) (xy 384.048009 -274.395911) (xy 383.997488 -274.402045) (xy 383.946636 -274.399996)
			(xy 383.896772 -274.389816) (xy 383.849186 -274.371769) (xy 383.805112 -274.346323) (xy 383.76569 -274.314136)
			(xy 383.731942 -274.276042) (xy 383.704741 -274.233028) (xy 383.684793 -274.186208) (xy 383.672614 -274.136794)
			(xy 383.668519 -274.086066) (xy 383.360422 -274.086066) (xy 383.35991 -274.111512) (xy 383.351746 -274.161746)
			(xy 383.33563 -274.21002) (xy 383.311979 -274.255083) (xy 383.281406 -274.295769) (xy 383.244702 -274.331024)
			(xy 383.202818 -274.359934) (xy 383.156839 -274.381751) (xy 383.107955 -274.395911) (xy 383.057434 -274.402045)
			(xy 383.006582 -274.399996) (xy 382.956718 -274.389816) (xy 382.909132 -274.371769) (xy 382.865058 -274.346323)
			(xy 382.825636 -274.314136) (xy 382.791888 -274.276042) (xy 382.764687 -274.233028) (xy 382.744739 -274.186208)
			(xy 382.73256 -274.136794) (xy 382.728465 -274.086066) (xy 382.410208 -274.086066) (xy 382.409713 -274.110673)
			(xy 382.401818 -274.15925) (xy 382.386234 -274.205931) (xy 382.363363 -274.249508) (xy 382.333798 -274.288852)
			(xy 382.298305 -274.322944) (xy 382.257802 -274.3509) (xy 382.21334 -274.371998) (xy 382.166069 -274.38569)
			(xy 382.117214 -274.391622) (xy 382.068039 -274.389641) (xy 382.01982 -274.379797) (xy 381.973804 -274.362345)
			(xy 381.931183 -274.337738) (xy 381.893062 -274.306613) (xy 381.860427 -274.269776) (xy 381.834124 -274.22818)
			(xy 381.814833 -274.182904) (xy 381.803056 -274.13512) (xy 381.799096 -274.086066) (xy 381.480568 -274.086066)
			(xy 381.480056 -274.111512) (xy 381.471892 -274.161746) (xy 381.455776 -274.21002) (xy 381.432125 -274.255083)
			(xy 381.401552 -274.295769) (xy 381.364848 -274.331024) (xy 381.322964 -274.359934) (xy 381.276985 -274.381751)
			(xy 381.228101 -274.395911) (xy 381.17758 -274.402045) (xy 381.126728 -274.399996) (xy 381.076864 -274.389816)
			(xy 381.029278 -274.371769) (xy 380.985204 -274.346323) (xy 380.945782 -274.314136) (xy 380.912034 -274.276042)
			(xy 380.884833 -274.233028) (xy 380.864885 -274.186208) (xy 380.852706 -274.136794) (xy 380.848611 -274.086066)
			(xy 380.5301 -274.086066) (xy 380.529605 -274.110673) (xy 380.52171 -274.15925) (xy 380.506126 -274.205931)
			(xy 380.483255 -274.249508) (xy 380.45369 -274.288852) (xy 380.418197 -274.322944) (xy 380.377694 -274.3509)
			(xy 380.333232 -274.371998) (xy 380.285961 -274.38569) (xy 380.237106 -274.391622) (xy 380.187931 -274.389641)
			(xy 380.139712 -274.379797) (xy 380.093696 -274.362345) (xy 380.051075 -274.337738) (xy 380.012954 -274.306613)
			(xy 379.980319 -274.269776) (xy 379.954016 -274.22818) (xy 379.934725 -274.182904) (xy 379.922948 -274.13512)
			(xy 379.918988 -274.086066) (xy 379.60046 -274.086066) (xy 379.599948 -274.111512) (xy 379.591784 -274.161746)
			(xy 379.575668 -274.21002) (xy 379.552017 -274.255083) (xy 379.521444 -274.295769) (xy 379.48474 -274.331024)
			(xy 379.442856 -274.359934) (xy 379.396877 -274.381751) (xy 379.347993 -274.395911) (xy 379.297472 -274.402045)
			(xy 379.24662 -274.399996) (xy 379.196756 -274.389816) (xy 379.14917 -274.371769) (xy 379.105096 -274.346323)
			(xy 379.065674 -274.314136) (xy 379.031926 -274.276042) (xy 379.004725 -274.233028) (xy 378.984777 -274.186208)
			(xy 378.972598 -274.136794) (xy 378.968503 -274.086066) (xy 378.650246 -274.086066) (xy 378.649751 -274.110673)
			(xy 378.641856 -274.15925) (xy 378.626272 -274.205931) (xy 378.603401 -274.249508) (xy 378.573836 -274.288852)
			(xy 378.538343 -274.322944) (xy 378.49784 -274.3509) (xy 378.453378 -274.371998) (xy 378.406107 -274.38569)
			(xy 378.357252 -274.391622) (xy 378.308077 -274.389641) (xy 378.259858 -274.379797) (xy 378.213842 -274.362345)
			(xy 378.171221 -274.337738) (xy 378.1331 -274.306613) (xy 378.100465 -274.269776) (xy 378.074162 -274.22818)
			(xy 378.054871 -274.182904) (xy 378.043094 -274.13512) (xy 378.039134 -274.086066) (xy 377.720606 -274.086066)
			(xy 377.720094 -274.111512) (xy 377.71193 -274.161746) (xy 377.695814 -274.21002) (xy 377.672163 -274.255083)
			(xy 377.64159 -274.295769) (xy 377.604886 -274.331024) (xy 377.563002 -274.359934) (xy 377.517023 -274.381751)
			(xy 377.468139 -274.395911) (xy 377.417618 -274.402045) (xy 377.366766 -274.399996) (xy 377.316902 -274.389816)
			(xy 377.269316 -274.371769) (xy 377.225242 -274.346323) (xy 377.18582 -274.314136) (xy 377.152072 -274.276042)
			(xy 377.124871 -274.233028) (xy 377.104923 -274.186208) (xy 377.092744 -274.136794) (xy 377.088649 -274.086066)
			(xy 376.780552 -274.086066) (xy 376.78004 -274.111512) (xy 376.771876 -274.161746) (xy 376.75576 -274.21002)
			(xy 376.732109 -274.255083) (xy 376.701536 -274.295769) (xy 376.664832 -274.331024) (xy 376.622948 -274.359934)
			(xy 376.576969 -274.381751) (xy 376.528085 -274.395911) (xy 376.477564 -274.402045) (xy 376.426712 -274.399996)
			(xy 376.376848 -274.389816) (xy 376.329262 -274.371769) (xy 376.285188 -274.346323) (xy 376.245766 -274.314136)
			(xy 376.212018 -274.276042) (xy 376.184817 -274.233028) (xy 376.164869 -274.186208) (xy 376.15269 -274.136794)
			(xy 376.148595 -274.086066) (xy 375.1961 -274.086066) (xy 375.1961 -274.596098) (xy 375.196379 -274.604625)
			(xy 375.201915 -274.620753) (xy 375.212467 -274.634146) (xy 375.219468 -274.639024) (xy 375.240669 -274.653188)
			(xy 375.278461 -274.687409) (xy 375.310039 -274.727435) (xy 375.334526 -274.772153) (xy 375.35124 -274.820319)
			(xy 375.359716 -274.870593) (xy 375.359717 -274.896072) (xy 375.678695 -274.896072) (xy 375.68279 -274.845344)
			(xy 375.694969 -274.79593) (xy 375.714917 -274.74911) (xy 375.742118 -274.706096) (xy 375.775866 -274.668002)
			(xy 375.815288 -274.635815) (xy 375.859362 -274.610369) (xy 375.906948 -274.592322) (xy 375.956812 -274.582142)
			(xy 376.007664 -274.580093) (xy 376.058185 -274.586227) (xy 376.107069 -274.600387) (xy 376.153048 -274.622204)
			(xy 376.194932 -274.651114) (xy 376.231636 -274.686369) (xy 376.262209 -274.727055) (xy 376.28586 -274.772118)
			(xy 376.301976 -274.820392) (xy 376.31014 -274.870626) (xy 376.310652 -274.896072) (xy 376.628926 -274.896072)
			(xy 376.632886 -274.847018) (xy 376.644663 -274.799234) (xy 376.663954 -274.753958) (xy 376.690257 -274.712362)
			(xy 376.722892 -274.675525) (xy 376.761013 -274.6444) (xy 376.803634 -274.619793) (xy 376.84965 -274.602341)
			(xy 376.897869 -274.592497) (xy 376.947044 -274.590516) (xy 376.995899 -274.596448) (xy 377.04317 -274.61014)
			(xy 377.087632 -274.631238) (xy 377.128135 -274.659194) (xy 377.163628 -274.693286) (xy 377.193193 -274.73263)
			(xy 377.216064 -274.776207) (xy 377.231648 -274.822888) (xy 377.239543 -274.871465) (xy 377.240038 -274.896072)
			(xy 377.558549 -274.896072) (xy 377.562644 -274.845344) (xy 377.574823 -274.79593) (xy 377.594771 -274.74911)
			(xy 377.621972 -274.706096) (xy 377.65572 -274.668002) (xy 377.695142 -274.635815) (xy 377.739216 -274.610369)
			(xy 377.786802 -274.592322) (xy 377.836666 -274.582142) (xy 377.887518 -274.580093) (xy 377.938039 -274.586227)
			(xy 377.986923 -274.600387) (xy 378.032902 -274.622204) (xy 378.074786 -274.651114) (xy 378.11149 -274.686369)
			(xy 378.142063 -274.727055) (xy 378.165714 -274.772118) (xy 378.18183 -274.820392) (xy 378.189994 -274.870626)
			(xy 378.190506 -274.896072) (xy 378.509034 -274.896072) (xy 378.512994 -274.847018) (xy 378.524771 -274.799234)
			(xy 378.544062 -274.753958) (xy 378.570365 -274.712362) (xy 378.603 -274.675525) (xy 378.641121 -274.6444)
			(xy 378.683742 -274.619793) (xy 378.729758 -274.602341) (xy 378.777977 -274.592497) (xy 378.827152 -274.590516)
			(xy 378.876007 -274.596448) (xy 378.923278 -274.61014) (xy 378.96774 -274.631238) (xy 379.008243 -274.659194)
			(xy 379.043736 -274.693286) (xy 379.073301 -274.73263) (xy 379.096172 -274.776207) (xy 379.111756 -274.822888)
			(xy 379.119651 -274.871465) (xy 379.120146 -274.896072) (xy 379.438657 -274.896072) (xy 379.442752 -274.845344)
			(xy 379.454931 -274.79593) (xy 379.474879 -274.74911) (xy 379.50208 -274.706096) (xy 379.535828 -274.668002)
			(xy 379.57525 -274.635815) (xy 379.619324 -274.610369) (xy 379.66691 -274.592322) (xy 379.716774 -274.582142)
			(xy 379.767626 -274.580093) (xy 379.818147 -274.586227) (xy 379.867031 -274.600387) (xy 379.91301 -274.622204)
			(xy 379.954894 -274.651114) (xy 379.991598 -274.686369) (xy 380.022171 -274.727055) (xy 380.045822 -274.772118)
			(xy 380.061938 -274.820392) (xy 380.070102 -274.870626) (xy 380.070614 -274.896072) (xy 380.378711 -274.896072)
			(xy 380.382806 -274.845344) (xy 380.394985 -274.79593) (xy 380.414933 -274.74911) (xy 380.442134 -274.706096)
			(xy 380.475882 -274.668002) (xy 380.515304 -274.635815) (xy 380.559378 -274.610369) (xy 380.606964 -274.592322)
			(xy 380.656828 -274.582142) (xy 380.70768 -274.580093) (xy 380.758201 -274.586227) (xy 380.807085 -274.600387)
			(xy 380.853064 -274.622204) (xy 380.894948 -274.651114) (xy 380.931652 -274.686369) (xy 380.962225 -274.727055)
			(xy 380.985876 -274.772118) (xy 381.001992 -274.820392) (xy 381.010156 -274.870626) (xy 381.010668 -274.896072)
			(xy 381.328942 -274.896072) (xy 381.332902 -274.847018) (xy 381.344679 -274.799234) (xy 381.36397 -274.753958)
			(xy 381.390273 -274.712362) (xy 381.422908 -274.675525) (xy 381.461029 -274.6444) (xy 381.50365 -274.619793)
			(xy 381.549666 -274.602341) (xy 381.597885 -274.592497) (xy 381.64706 -274.590516) (xy 381.695915 -274.596448)
			(xy 381.743186 -274.61014) (xy 381.787648 -274.631238) (xy 381.828151 -274.659194) (xy 381.863644 -274.693286)
			(xy 381.893209 -274.73263) (xy 381.91608 -274.776207) (xy 381.931664 -274.822888) (xy 381.939559 -274.871465)
			(xy 381.940054 -274.896072) (xy 382.258565 -274.896072) (xy 382.26266 -274.845344) (xy 382.274839 -274.79593)
			(xy 382.294787 -274.74911) (xy 382.321988 -274.706096) (xy 382.355736 -274.668002) (xy 382.395158 -274.635815)
			(xy 382.439232 -274.610369) (xy 382.486818 -274.592322) (xy 382.536682 -274.582142) (xy 382.587534 -274.580093)
			(xy 382.638055 -274.586227) (xy 382.686939 -274.600387) (xy 382.732918 -274.622204) (xy 382.774802 -274.651114)
			(xy 382.811506 -274.686369) (xy 382.842079 -274.727055) (xy 382.86573 -274.772118) (xy 382.881846 -274.820392)
			(xy 382.89001 -274.870626) (xy 382.890522 -274.896072) (xy 383.20905 -274.896072) (xy 383.21301 -274.847018)
			(xy 383.224787 -274.799234) (xy 383.244078 -274.753958) (xy 383.270381 -274.712362) (xy 383.303016 -274.675525)
			(xy 383.341137 -274.6444) (xy 383.383758 -274.619793) (xy 383.429774 -274.602341) (xy 383.477993 -274.592497)
			(xy 383.527168 -274.590516) (xy 383.576023 -274.596448) (xy 383.623294 -274.61014) (xy 383.667756 -274.631238)
			(xy 383.708259 -274.659194) (xy 383.743752 -274.693286) (xy 383.773317 -274.73263) (xy 383.796188 -274.776207)
			(xy 383.811772 -274.822888) (xy 383.819667 -274.871465) (xy 383.820162 -274.896072) (xy 384.138673 -274.896072)
			(xy 384.142768 -274.845344) (xy 384.154947 -274.79593) (xy 384.174895 -274.74911) (xy 384.202096 -274.706096)
			(xy 384.235844 -274.668002) (xy 384.275266 -274.635815) (xy 384.31934 -274.610369) (xy 384.366926 -274.592322)
			(xy 384.41679 -274.582142) (xy 384.467642 -274.580093) (xy 384.518163 -274.586227) (xy 384.567047 -274.600387)
			(xy 384.613026 -274.622204) (xy 384.65491 -274.651114) (xy 384.691614 -274.686369) (xy 384.722187 -274.727055)
			(xy 384.745838 -274.772118) (xy 384.761954 -274.820392) (xy 384.770118 -274.870626) (xy 384.77063 -274.896072)
			(xy 385.088904 -274.896072) (xy 385.092864 -274.847018) (xy 385.104641 -274.799234) (xy 385.123932 -274.753958)
			(xy 385.150235 -274.712362) (xy 385.18287 -274.675525) (xy 385.220991 -274.6444) (xy 385.263612 -274.619793)
			(xy 385.309628 -274.602341) (xy 385.357847 -274.592497) (xy 385.407022 -274.590516) (xy 385.455877 -274.596448)
			(xy 385.503148 -274.61014) (xy 385.54761 -274.631238) (xy 385.588113 -274.659194) (xy 385.623606 -274.693286)
			(xy 385.653171 -274.73263) (xy 385.676042 -274.776207) (xy 385.691626 -274.822888) (xy 385.699521 -274.871465)
			(xy 385.700016 -274.896072) (xy 386.018527 -274.896072) (xy 386.022622 -274.845344) (xy 386.034801 -274.79593)
			(xy 386.054749 -274.74911) (xy 386.08195 -274.706096) (xy 386.115698 -274.668002) (xy 386.15512 -274.635815)
			(xy 386.199194 -274.610369) (xy 386.24678 -274.592322) (xy 386.296644 -274.582142) (xy 386.347496 -274.580093)
			(xy 386.398017 -274.586227) (xy 386.446901 -274.600387) (xy 386.49288 -274.622204) (xy 386.534764 -274.651114)
			(xy 386.571468 -274.686369) (xy 386.602041 -274.727055) (xy 386.625692 -274.772118) (xy 386.641808 -274.820392)
			(xy 386.649972 -274.870626) (xy 386.650484 -274.896072) (xy 386.958581 -274.896072) (xy 386.962676 -274.845344)
			(xy 386.974855 -274.79593) (xy 386.994803 -274.74911) (xy 387.022004 -274.706096) (xy 387.055752 -274.668002)
			(xy 387.095174 -274.635815) (xy 387.139248 -274.610369) (xy 387.186834 -274.592322) (xy 387.236698 -274.582142)
			(xy 387.28755 -274.580093) (xy 387.338071 -274.586227) (xy 387.386955 -274.600387) (xy 387.432934 -274.622204)
			(xy 387.474818 -274.651114) (xy 387.511522 -274.686369) (xy 387.542095 -274.727055) (xy 387.565746 -274.772118)
			(xy 387.581862 -274.820392) (xy 387.590026 -274.870626) (xy 387.590538 -274.896072) (xy 387.909066 -274.896072)
			(xy 387.913026 -274.847018) (xy 387.924803 -274.799234) (xy 387.944094 -274.753958) (xy 387.970397 -274.712362)
			(xy 388.003032 -274.675525) (xy 388.041153 -274.6444) (xy 388.083774 -274.619793) (xy 388.12979 -274.602341)
			(xy 388.178009 -274.592497) (xy 388.227184 -274.590516) (xy 388.276039 -274.596448) (xy 388.32331 -274.61014)
			(xy 388.367772 -274.631238) (xy 388.408275 -274.659194) (xy 388.443768 -274.693286) (xy 388.473333 -274.73263)
			(xy 388.496204 -274.776207) (xy 388.511788 -274.822888) (xy 388.519683 -274.871465) (xy 388.520178 -274.896072)
			(xy 388.838689 -274.896072) (xy 388.842784 -274.845344) (xy 388.854963 -274.79593) (xy 388.874911 -274.74911)
			(xy 388.902112 -274.706096) (xy 388.93586 -274.668002) (xy 388.975282 -274.635815) (xy 389.019356 -274.610369)
			(xy 389.066942 -274.592322) (xy 389.116806 -274.582142) (xy 389.167658 -274.580093) (xy 389.218179 -274.586227)
			(xy 389.267063 -274.600387) (xy 389.313042 -274.622204) (xy 389.354926 -274.651114) (xy 389.39163 -274.686369)
			(xy 389.422203 -274.727055) (xy 389.445854 -274.772118) (xy 389.46197 -274.820392) (xy 389.470134 -274.870626)
			(xy 389.470646 -274.896072) (xy 389.78892 -274.896072) (xy 389.79288 -274.847018) (xy 389.804657 -274.799234)
			(xy 389.823948 -274.753958) (xy 389.850251 -274.712362) (xy 389.882886 -274.675525) (xy 389.921007 -274.6444)
			(xy 389.963628 -274.619793) (xy 390.009644 -274.602341) (xy 390.057863 -274.592497) (xy 390.107038 -274.590516)
			(xy 390.155893 -274.596448) (xy 390.203164 -274.61014) (xy 390.247626 -274.631238) (xy 390.288129 -274.659194)
			(xy 390.323622 -274.693286) (xy 390.353187 -274.73263) (xy 390.376058 -274.776207) (xy 390.391642 -274.822888)
			(xy 390.399537 -274.871465) (xy 390.400032 -274.896072) (xy 390.718543 -274.896072) (xy 390.722638 -274.845344)
			(xy 390.734817 -274.79593) (xy 390.754765 -274.74911) (xy 390.781966 -274.706096) (xy 390.815714 -274.668002)
			(xy 390.855136 -274.635815) (xy 390.89921 -274.610369) (xy 390.946796 -274.592322) (xy 390.99666 -274.582142)
			(xy 391.047512 -274.580093) (xy 391.098033 -274.586227) (xy 391.146917 -274.600387) (xy 391.192896 -274.622204)
			(xy 391.23478 -274.651114) (xy 391.271484 -274.686369) (xy 391.302057 -274.727055) (xy 391.325708 -274.772118)
			(xy 391.341824 -274.820392) (xy 391.349988 -274.870626) (xy 391.3505 -274.896072) (xy 391.669028 -274.896072)
			(xy 391.672988 -274.847018) (xy 391.684765 -274.799234) (xy 391.704056 -274.753958) (xy 391.730359 -274.712362)
			(xy 391.762994 -274.675525) (xy 391.801115 -274.6444) (xy 391.843736 -274.619793) (xy 391.889752 -274.602341)
			(xy 391.937971 -274.592497) (xy 391.987146 -274.590516) (xy 392.036001 -274.596448) (xy 392.083272 -274.61014)
			(xy 392.125407 -274.630134) (xy 394.67715 -274.630134) (xy 394.68111 -274.58108) (xy 394.692887 -274.533296)
			(xy 394.712178 -274.48802) (xy 394.738481 -274.446424) (xy 394.771116 -274.409587) (xy 394.809237 -274.378462)
			(xy 394.851858 -274.353855) (xy 394.897874 -274.336403) (xy 394.946093 -274.326559) (xy 394.995268 -274.324578)
			(xy 395.044123 -274.33051) (xy 395.091394 -274.344202) (xy 395.135856 -274.3653) (xy 395.176359 -274.393256)
			(xy 395.211852 -274.427348) (xy 395.241417 -274.466692) (xy 395.264288 -274.510269) (xy 395.279872 -274.55695)
			(xy 395.287767 -274.605527) (xy 395.288262 -274.630134) (xy 395.287767 -274.654741) (xy 395.279872 -274.703318)
			(xy 395.264288 -274.749999) (xy 395.241417 -274.793576) (xy 395.211852 -274.83292) (xy 395.176359 -274.867012)
			(xy 395.135856 -274.894968) (xy 395.091394 -274.916066) (xy 395.044123 -274.929758) (xy 394.995268 -274.93569)
			(xy 394.946093 -274.933709) (xy 394.897874 -274.923865) (xy 394.851858 -274.906413) (xy 394.809237 -274.881806)
			(xy 394.771116 -274.850681) (xy 394.738481 -274.813844) (xy 394.712178 -274.772248) (xy 394.692887 -274.726972)
			(xy 394.68111 -274.679188) (xy 394.67715 -274.630134) (xy 392.125407 -274.630134) (xy 392.127734 -274.631238)
			(xy 392.168237 -274.659194) (xy 392.20373 -274.693286) (xy 392.233295 -274.73263) (xy 392.256166 -274.776207)
			(xy 392.27175 -274.822888) (xy 392.279645 -274.871465) (xy 392.28014 -274.896072) (xy 392.279645 -274.920679)
			(xy 392.27175 -274.969256) (xy 392.256166 -275.015937) (xy 392.233295 -275.059514) (xy 392.20373 -275.098858)
			(xy 392.168237 -275.13295) (xy 392.127734 -275.160906) (xy 392.083272 -275.182004) (xy 392.036001 -275.195696)
			(xy 391.987146 -275.201628) (xy 391.937971 -275.199647) (xy 391.889752 -275.189803) (xy 391.843736 -275.172351)
			(xy 391.801115 -275.147744) (xy 391.762994 -275.116619) (xy 391.730359 -275.079782) (xy 391.704056 -275.038186)
			(xy 391.684765 -274.99291) (xy 391.672988 -274.945126) (xy 391.669028 -274.896072) (xy 391.3505 -274.896072)
			(xy 391.349988 -274.921518) (xy 391.341824 -274.971752) (xy 391.325708 -275.020026) (xy 391.302057 -275.065089)
			(xy 391.271484 -275.105775) (xy 391.23478 -275.14103) (xy 391.192896 -275.16994) (xy 391.146917 -275.191757)
			(xy 391.098033 -275.205917) (xy 391.047512 -275.212051) (xy 390.99666 -275.210002) (xy 390.946796 -275.199822)
			(xy 390.89921 -275.181775) (xy 390.855136 -275.156329) (xy 390.815714 -275.124142) (xy 390.781966 -275.086048)
			(xy 390.754765 -275.043034) (xy 390.734817 -274.996214) (xy 390.722638 -274.9468) (xy 390.718543 -274.896072)
			(xy 390.400032 -274.896072) (xy 390.399537 -274.920679) (xy 390.391642 -274.969256) (xy 390.376058 -275.015937)
			(xy 390.353187 -275.059514) (xy 390.323622 -275.098858) (xy 390.288129 -275.13295) (xy 390.247626 -275.160906)
			(xy 390.203164 -275.182004) (xy 390.155893 -275.195696) (xy 390.107038 -275.201628) (xy 390.057863 -275.199647)
			(xy 390.009644 -275.189803) (xy 389.963628 -275.172351) (xy 389.921007 -275.147744) (xy 389.882886 -275.116619)
			(xy 389.850251 -275.079782) (xy 389.823948 -275.038186) (xy 389.804657 -274.99291) (xy 389.79288 -274.945126)
			(xy 389.78892 -274.896072) (xy 389.470646 -274.896072) (xy 389.470134 -274.921518) (xy 389.46197 -274.971752)
			(xy 389.445854 -275.020026) (xy 389.422203 -275.065089) (xy 389.39163 -275.105775) (xy 389.354926 -275.14103)
			(xy 389.313042 -275.16994) (xy 389.267063 -275.191757) (xy 389.218179 -275.205917) (xy 389.167658 -275.212051)
			(xy 389.116806 -275.210002) (xy 389.066942 -275.199822) (xy 389.019356 -275.181775) (xy 388.975282 -275.156329)
			(xy 388.93586 -275.124142) (xy 388.902112 -275.086048) (xy 388.874911 -275.043034) (xy 388.854963 -274.996214)
			(xy 388.842784 -274.9468) (xy 388.838689 -274.896072) (xy 388.520178 -274.896072) (xy 388.519683 -274.920679)
			(xy 388.511788 -274.969256) (xy 388.496204 -275.015937) (xy 388.473333 -275.059514) (xy 388.443768 -275.098858)
			(xy 388.408275 -275.13295) (xy 388.367772 -275.160906) (xy 388.32331 -275.182004) (xy 388.276039 -275.195696)
			(xy 388.227184 -275.201628) (xy 388.178009 -275.199647) (xy 388.12979 -275.189803) (xy 388.083774 -275.172351)
			(xy 388.041153 -275.147744) (xy 388.003032 -275.116619) (xy 387.970397 -275.079782) (xy 387.944094 -275.038186)
			(xy 387.924803 -274.99291) (xy 387.913026 -274.945126) (xy 387.909066 -274.896072) (xy 387.590538 -274.896072)
			(xy 387.590026 -274.921518) (xy 387.581862 -274.971752) (xy 387.565746 -275.020026) (xy 387.542095 -275.065089)
			(xy 387.511522 -275.105775) (xy 387.474818 -275.14103) (xy 387.432934 -275.16994) (xy 387.386955 -275.191757)
			(xy 387.338071 -275.205917) (xy 387.28755 -275.212051) (xy 387.236698 -275.210002) (xy 387.186834 -275.199822)
			(xy 387.139248 -275.181775) (xy 387.095174 -275.156329) (xy 387.055752 -275.124142) (xy 387.022004 -275.086048)
			(xy 386.994803 -275.043034) (xy 386.974855 -274.996214) (xy 386.962676 -274.9468) (xy 386.958581 -274.896072)
			(xy 386.650484 -274.896072) (xy 386.649972 -274.921518) (xy 386.641808 -274.971752) (xy 386.625692 -275.020026)
			(xy 386.602041 -275.065089) (xy 386.571468 -275.105775) (xy 386.534764 -275.14103) (xy 386.49288 -275.16994)
			(xy 386.446901 -275.191757) (xy 386.398017 -275.205917) (xy 386.347496 -275.212051) (xy 386.296644 -275.210002)
			(xy 386.24678 -275.199822) (xy 386.199194 -275.181775) (xy 386.15512 -275.156329) (xy 386.115698 -275.124142)
			(xy 386.08195 -275.086048) (xy 386.054749 -275.043034) (xy 386.034801 -274.996214) (xy 386.022622 -274.9468)
			(xy 386.018527 -274.896072) (xy 385.700016 -274.896072) (xy 385.699521 -274.920679) (xy 385.691626 -274.969256)
			(xy 385.676042 -275.015937) (xy 385.653171 -275.059514) (xy 385.623606 -275.098858) (xy 385.588113 -275.13295)
			(xy 385.54761 -275.160906) (xy 385.503148 -275.182004) (xy 385.455877 -275.195696) (xy 385.407022 -275.201628)
			(xy 385.357847 -275.199647) (xy 385.309628 -275.189803) (xy 385.263612 -275.172351) (xy 385.220991 -275.147744)
			(xy 385.18287 -275.116619) (xy 385.150235 -275.079782) (xy 385.123932 -275.038186) (xy 385.104641 -274.99291)
			(xy 385.092864 -274.945126) (xy 385.088904 -274.896072) (xy 384.77063 -274.896072) (xy 384.770118 -274.921518)
			(xy 384.761954 -274.971752) (xy 384.745838 -275.020026) (xy 384.722187 -275.065089) (xy 384.691614 -275.105775)
			(xy 384.65491 -275.14103) (xy 384.613026 -275.16994) (xy 384.567047 -275.191757) (xy 384.518163 -275.205917)
			(xy 384.467642 -275.212051) (xy 384.41679 -275.210002) (xy 384.366926 -275.199822) (xy 384.31934 -275.181775)
			(xy 384.275266 -275.156329) (xy 384.235844 -275.124142) (xy 384.202096 -275.086048) (xy 384.174895 -275.043034)
			(xy 384.154947 -274.996214) (xy 384.142768 -274.9468) (xy 384.138673 -274.896072) (xy 383.820162 -274.896072)
			(xy 383.819667 -274.920679) (xy 383.811772 -274.969256) (xy 383.796188 -275.015937) (xy 383.773317 -275.059514)
			(xy 383.743752 -275.098858) (xy 383.708259 -275.13295) (xy 383.667756 -275.160906) (xy 383.623294 -275.182004)
			(xy 383.576023 -275.195696) (xy 383.527168 -275.201628) (xy 383.477993 -275.199647) (xy 383.429774 -275.189803)
			(xy 383.383758 -275.172351) (xy 383.341137 -275.147744) (xy 383.303016 -275.116619) (xy 383.270381 -275.079782)
			(xy 383.244078 -275.038186) (xy 383.224787 -274.99291) (xy 383.21301 -274.945126) (xy 383.20905 -274.896072)
			(xy 382.890522 -274.896072) (xy 382.89001 -274.921518) (xy 382.881846 -274.971752) (xy 382.86573 -275.020026)
			(xy 382.842079 -275.065089) (xy 382.811506 -275.105775) (xy 382.774802 -275.14103) (xy 382.732918 -275.16994)
			(xy 382.686939 -275.191757) (xy 382.638055 -275.205917) (xy 382.587534 -275.212051) (xy 382.536682 -275.210002)
			(xy 382.486818 -275.199822) (xy 382.439232 -275.181775) (xy 382.395158 -275.156329) (xy 382.355736 -275.124142)
			(xy 382.321988 -275.086048) (xy 382.294787 -275.043034) (xy 382.274839 -274.996214) (xy 382.26266 -274.9468)
			(xy 382.258565 -274.896072) (xy 381.940054 -274.896072) (xy 381.939559 -274.920679) (xy 381.931664 -274.969256)
			(xy 381.91608 -275.015937) (xy 381.893209 -275.059514) (xy 381.863644 -275.098858) (xy 381.828151 -275.13295)
			(xy 381.787648 -275.160906) (xy 381.743186 -275.182004) (xy 381.695915 -275.195696) (xy 381.64706 -275.201628)
			(xy 381.597885 -275.199647) (xy 381.549666 -275.189803) (xy 381.50365 -275.172351) (xy 381.461029 -275.147744)
			(xy 381.422908 -275.116619) (xy 381.390273 -275.079782) (xy 381.36397 -275.038186) (xy 381.344679 -274.99291)
			(xy 381.332902 -274.945126) (xy 381.328942 -274.896072) (xy 381.010668 -274.896072) (xy 381.010156 -274.921518)
			(xy 381.001992 -274.971752) (xy 380.985876 -275.020026) (xy 380.962225 -275.065089) (xy 380.931652 -275.105775)
			(xy 380.894948 -275.14103) (xy 380.853064 -275.16994) (xy 380.807085 -275.191757) (xy 380.758201 -275.205917)
			(xy 380.70768 -275.212051) (xy 380.656828 -275.210002) (xy 380.606964 -275.199822) (xy 380.559378 -275.181775)
			(xy 380.515304 -275.156329) (xy 380.475882 -275.124142) (xy 380.442134 -275.086048) (xy 380.414933 -275.043034)
			(xy 380.394985 -274.996214) (xy 380.382806 -274.9468) (xy 380.378711 -274.896072) (xy 380.070614 -274.896072)
			(xy 380.070102 -274.921518) (xy 380.061938 -274.971752) (xy 380.045822 -275.020026) (xy 380.022171 -275.065089)
			(xy 379.991598 -275.105775) (xy 379.954894 -275.14103) (xy 379.91301 -275.16994) (xy 379.867031 -275.191757)
			(xy 379.818147 -275.205917) (xy 379.767626 -275.212051) (xy 379.716774 -275.210002) (xy 379.66691 -275.199822)
			(xy 379.619324 -275.181775) (xy 379.57525 -275.156329) (xy 379.535828 -275.124142) (xy 379.50208 -275.086048)
			(xy 379.474879 -275.043034) (xy 379.454931 -274.996214) (xy 379.442752 -274.9468) (xy 379.438657 -274.896072)
			(xy 379.120146 -274.896072) (xy 379.119651 -274.920679) (xy 379.111756 -274.969256) (xy 379.096172 -275.015937)
			(xy 379.073301 -275.059514) (xy 379.043736 -275.098858) (xy 379.008243 -275.13295) (xy 378.96774 -275.160906)
			(xy 378.923278 -275.182004) (xy 378.876007 -275.195696) (xy 378.827152 -275.201628) (xy 378.777977 -275.199647)
			(xy 378.729758 -275.189803) (xy 378.683742 -275.172351) (xy 378.641121 -275.147744) (xy 378.603 -275.116619)
			(xy 378.570365 -275.079782) (xy 378.544062 -275.038186) (xy 378.524771 -274.99291) (xy 378.512994 -274.945126)
			(xy 378.509034 -274.896072) (xy 378.190506 -274.896072) (xy 378.189994 -274.921518) (xy 378.18183 -274.971752)
			(xy 378.165714 -275.020026) (xy 378.142063 -275.065089) (xy 378.11149 -275.105775) (xy 378.074786 -275.14103)
			(xy 378.032902 -275.16994) (xy 377.986923 -275.191757) (xy 377.938039 -275.205917) (xy 377.887518 -275.212051)
			(xy 377.836666 -275.210002) (xy 377.786802 -275.199822) (xy 377.739216 -275.181775) (xy 377.695142 -275.156329)
			(xy 377.65572 -275.124142) (xy 377.621972 -275.086048) (xy 377.594771 -275.043034) (xy 377.574823 -274.996214)
			(xy 377.562644 -274.9468) (xy 377.558549 -274.896072) (xy 377.240038 -274.896072) (xy 377.239543 -274.920679)
			(xy 377.231648 -274.969256) (xy 377.216064 -275.015937) (xy 377.193193 -275.059514) (xy 377.163628 -275.098858)
			(xy 377.128135 -275.13295) (xy 377.087632 -275.160906) (xy 377.04317 -275.182004) (xy 376.995899 -275.195696)
			(xy 376.947044 -275.201628) (xy 376.897869 -275.199647) (xy 376.84965 -275.189803) (xy 376.803634 -275.172351)
			(xy 376.761013 -275.147744) (xy 376.722892 -275.116619) (xy 376.690257 -275.079782) (xy 376.663954 -275.038186)
			(xy 376.644663 -274.99291) (xy 376.632886 -274.945126) (xy 376.628926 -274.896072) (xy 376.310652 -274.896072)
			(xy 376.31014 -274.921518) (xy 376.301976 -274.971752) (xy 376.28586 -275.020026) (xy 376.262209 -275.065089)
			(xy 376.231636 -275.105775) (xy 376.194932 -275.14103) (xy 376.153048 -275.16994) (xy 376.107069 -275.191757)
			(xy 376.058185 -275.205917) (xy 376.007664 -275.212051) (xy 375.956812 -275.210002) (xy 375.906948 -275.199822)
			(xy 375.859362 -275.181775) (xy 375.815288 -275.156329) (xy 375.775866 -275.124142) (xy 375.742118 -275.086048)
			(xy 375.714917 -275.043034) (xy 375.694969 -274.996214) (xy 375.68279 -274.9468) (xy 375.678695 -274.896072)
			(xy 375.359717 -274.896072) (xy 375.359719 -274.921577) (xy 375.351248 -274.971851) (xy 375.334538 -275.020019)
			(xy 375.310056 -275.064739) (xy 375.278481 -275.104769) (xy 375.240693 -275.138993) (xy 375.219468 -275.15312)
			(xy 375.212477 -275.158003) (xy 375.201956 -275.171412) (xy 375.196398 -275.187524) (xy 375.1961 -275.196046)
			(xy 375.1961 -275.368258) (xy 375.196494 -275.377462) (xy 375.20297 -275.394693) (xy 375.215078 -275.408559)
			(xy 375.223024 -275.413216) (xy 375.314718 -275.462238) (xy 375.342404 -275.460714) (xy 375.354342 -275.45284)
			(xy 375.373329 -275.440543) (xy 375.414163 -275.421081) (xy 375.457422 -275.407859) (xy 375.502159 -275.401165)
			(xy 375.524776 -275.40077) (xy 375.550037 -275.401261) (xy 375.59987 -275.409573) (xy 375.647655 -275.425974)
			(xy 375.692089 -275.450018) (xy 375.731959 -275.481047) (xy 375.766178 -275.518215) (xy 375.793812 -275.56051)
			(xy 375.814107 -275.606775) (xy 375.82651 -275.655751) (xy 375.83068 -275.706078) (xy 376.148595 -275.706078)
			(xy 376.15269 -275.65535) (xy 376.164869 -275.605936) (xy 376.184817 -275.559116) (xy 376.212018 -275.516102)
			(xy 376.245766 -275.478008) (xy 376.285188 -275.445821) (xy 376.329262 -275.420375) (xy 376.376848 -275.402328)
			(xy 376.426712 -275.392148) (xy 376.477564 -275.390099) (xy 376.528085 -275.396233) (xy 376.576969 -275.410393)
			(xy 376.622948 -275.43221) (xy 376.664832 -275.46112) (xy 376.701536 -275.496375) (xy 376.732109 -275.537061)
			(xy 376.75576 -275.582124) (xy 376.771876 -275.630398) (xy 376.78004 -275.680632) (xy 376.780552 -275.706078)
			(xy 377.088649 -275.706078) (xy 377.092744 -275.65535) (xy 377.104923 -275.605936) (xy 377.124871 -275.559116)
			(xy 377.152072 -275.516102) (xy 377.18582 -275.478008) (xy 377.225242 -275.445821) (xy 377.269316 -275.420375)
			(xy 377.316902 -275.402328) (xy 377.366766 -275.392148) (xy 377.417618 -275.390099) (xy 377.468139 -275.396233)
			(xy 377.517023 -275.410393) (xy 377.563002 -275.43221) (xy 377.604886 -275.46112) (xy 377.64159 -275.496375)
			(xy 377.672163 -275.537061) (xy 377.695814 -275.582124) (xy 377.71193 -275.630398) (xy 377.720094 -275.680632)
			(xy 377.720606 -275.706078) (xy 378.968503 -275.706078) (xy 378.972598 -275.65535) (xy 378.984777 -275.605936)
			(xy 379.004725 -275.559116) (xy 379.031926 -275.516102) (xy 379.065674 -275.478008) (xy 379.105096 -275.445821)
			(xy 379.14917 -275.420375) (xy 379.196756 -275.402328) (xy 379.24662 -275.392148) (xy 379.297472 -275.390099)
			(xy 379.347993 -275.396233) (xy 379.396877 -275.410393) (xy 379.442856 -275.43221) (xy 379.48474 -275.46112)
			(xy 379.521444 -275.496375) (xy 379.552017 -275.537061) (xy 379.575668 -275.582124) (xy 379.591784 -275.630398)
			(xy 379.599948 -275.680632) (xy 379.60046 -275.706078) (xy 379.918988 -275.706078) (xy 379.922948 -275.657024)
			(xy 379.934725 -275.60924) (xy 379.954016 -275.563964) (xy 379.980319 -275.522368) (xy 380.012954 -275.485531)
			(xy 380.051075 -275.454406) (xy 380.093696 -275.429799) (xy 380.139712 -275.412347) (xy 380.187931 -275.402503)
			(xy 380.237106 -275.400522) (xy 380.285961 -275.406454) (xy 380.333232 -275.420146) (xy 380.377694 -275.441244)
			(xy 380.418197 -275.4692) (xy 380.45369 -275.503292) (xy 380.483255 -275.542636) (xy 380.506126 -275.586213)
			(xy 380.52171 -275.632894) (xy 380.529605 -275.681471) (xy 380.5301 -275.706078) (xy 380.848611 -275.706078)
			(xy 380.852706 -275.65535) (xy 380.864885 -275.605936) (xy 380.884833 -275.559116) (xy 380.912034 -275.516102)
			(xy 380.945782 -275.478008) (xy 380.985204 -275.445821) (xy 381.029278 -275.420375) (xy 381.076864 -275.402328)
			(xy 381.126728 -275.392148) (xy 381.17758 -275.390099) (xy 381.228101 -275.396233) (xy 381.276985 -275.410393)
			(xy 381.322964 -275.43221) (xy 381.364848 -275.46112) (xy 381.401552 -275.496375) (xy 381.432125 -275.537061)
			(xy 381.455776 -275.582124) (xy 381.471892 -275.630398) (xy 381.480056 -275.680632) (xy 381.480568 -275.706078)
			(xy 381.799096 -275.706078) (xy 381.803056 -275.657024) (xy 381.814833 -275.60924) (xy 381.834124 -275.563964)
			(xy 381.860427 -275.522368) (xy 381.893062 -275.485531) (xy 381.931183 -275.454406) (xy 381.973804 -275.429799)
			(xy 382.01982 -275.412347) (xy 382.068039 -275.402503) (xy 382.117214 -275.400522) (xy 382.166069 -275.406454)
			(xy 382.21334 -275.420146) (xy 382.257802 -275.441244) (xy 382.298305 -275.4692) (xy 382.333798 -275.503292)
			(xy 382.363363 -275.542636) (xy 382.386234 -275.586213) (xy 382.401818 -275.632894) (xy 382.409713 -275.681471)
			(xy 382.410208 -275.706078) (xy 382.728465 -275.706078) (xy 382.73256 -275.65535) (xy 382.744739 -275.605936)
			(xy 382.764687 -275.559116) (xy 382.791888 -275.516102) (xy 382.825636 -275.478008) (xy 382.865058 -275.445821)
			(xy 382.909132 -275.420375) (xy 382.956718 -275.402328) (xy 383.006582 -275.392148) (xy 383.057434 -275.390099)
			(xy 383.107955 -275.396233) (xy 383.156839 -275.410393) (xy 383.202818 -275.43221) (xy 383.244702 -275.46112)
			(xy 383.281406 -275.496375) (xy 383.311979 -275.537061) (xy 383.33563 -275.582124) (xy 383.351746 -275.630398)
			(xy 383.35991 -275.680632) (xy 383.360422 -275.706078) (xy 383.668519 -275.706078) (xy 383.672614 -275.65535)
			(xy 383.684793 -275.605936) (xy 383.704741 -275.559116) (xy 383.731942 -275.516102) (xy 383.76569 -275.478008)
			(xy 383.805112 -275.445821) (xy 383.849186 -275.420375) (xy 383.896772 -275.402328) (xy 383.946636 -275.392148)
			(xy 383.997488 -275.390099) (xy 384.048009 -275.396233) (xy 384.096893 -275.410393) (xy 384.142872 -275.43221)
			(xy 384.184756 -275.46112) (xy 384.22146 -275.496375) (xy 384.252033 -275.537061) (xy 384.275684 -275.582124)
			(xy 384.2918 -275.630398) (xy 384.299964 -275.680632) (xy 384.300476 -275.706078) (xy 385.548627 -275.706078)
			(xy 385.552722 -275.65535) (xy 385.564901 -275.605936) (xy 385.584849 -275.559116) (xy 385.61205 -275.516102)
			(xy 385.645798 -275.478008) (xy 385.68522 -275.445821) (xy 385.729294 -275.420375) (xy 385.77688 -275.402328)
			(xy 385.826744 -275.392148) (xy 385.877596 -275.390099) (xy 385.928117 -275.396233) (xy 385.977001 -275.410393)
			(xy 386.02298 -275.43221) (xy 386.064864 -275.46112) (xy 386.101568 -275.496375) (xy 386.132141 -275.537061)
			(xy 386.155792 -275.582124) (xy 386.171908 -275.630398) (xy 386.180072 -275.680632) (xy 386.180584 -275.706078)
			(xy 386.499112 -275.706078) (xy 386.503072 -275.657024) (xy 386.514849 -275.60924) (xy 386.53414 -275.563964)
			(xy 386.560443 -275.522368) (xy 386.593078 -275.485531) (xy 386.631199 -275.454406) (xy 386.67382 -275.429799)
			(xy 386.719836 -275.412347) (xy 386.768055 -275.402503) (xy 386.81723 -275.400522) (xy 386.866085 -275.406454)
			(xy 386.913356 -275.420146) (xy 386.957818 -275.441244) (xy 386.998321 -275.4692) (xy 387.033814 -275.503292)
			(xy 387.063379 -275.542636) (xy 387.08625 -275.586213) (xy 387.101834 -275.632894) (xy 387.109729 -275.681471)
			(xy 387.110224 -275.706078) (xy 387.428481 -275.706078) (xy 387.432576 -275.65535) (xy 387.444755 -275.605936)
			(xy 387.464703 -275.559116) (xy 387.491904 -275.516102) (xy 387.525652 -275.478008) (xy 387.565074 -275.445821)
			(xy 387.609148 -275.420375) (xy 387.656734 -275.402328) (xy 387.706598 -275.392148) (xy 387.75745 -275.390099)
			(xy 387.807971 -275.396233) (xy 387.856855 -275.410393) (xy 387.902834 -275.43221) (xy 387.944718 -275.46112)
			(xy 387.981422 -275.496375) (xy 388.011995 -275.537061) (xy 388.035646 -275.582124) (xy 388.051762 -275.630398)
			(xy 388.059926 -275.680632) (xy 388.060438 -275.706078) (xy 388.378966 -275.706078) (xy 388.382926 -275.657024)
			(xy 388.394703 -275.60924) (xy 388.413994 -275.563964) (xy 388.440297 -275.522368) (xy 388.472932 -275.485531)
			(xy 388.511053 -275.454406) (xy 388.553674 -275.429799) (xy 388.59969 -275.412347) (xy 388.647909 -275.402503)
			(xy 388.697084 -275.400522) (xy 388.745939 -275.406454) (xy 388.79321 -275.420146) (xy 388.837672 -275.441244)
			(xy 388.878175 -275.4692) (xy 388.913668 -275.503292) (xy 388.943233 -275.542636) (xy 388.966104 -275.586213)
			(xy 388.981688 -275.632894) (xy 388.989583 -275.681471) (xy 388.990078 -275.706078) (xy 389.308589 -275.706078)
			(xy 389.312684 -275.65535) (xy 389.324863 -275.605936) (xy 389.344811 -275.559116) (xy 389.372012 -275.516102)
			(xy 389.40576 -275.478008) (xy 389.445182 -275.445821) (xy 389.489256 -275.420375) (xy 389.536842 -275.402328)
			(xy 389.586706 -275.392148) (xy 389.637558 -275.390099) (xy 389.688079 -275.396233) (xy 389.736963 -275.410393)
			(xy 389.782942 -275.43221) (xy 389.824826 -275.46112) (xy 389.86153 -275.496375) (xy 389.892103 -275.537061)
			(xy 389.915754 -275.582124) (xy 389.93187 -275.630398) (xy 389.940034 -275.680632) (xy 389.940546 -275.706078)
			(xy 390.248643 -275.706078) (xy 390.252738 -275.65535) (xy 390.264917 -275.605936) (xy 390.284865 -275.559116)
			(xy 390.312066 -275.516102) (xy 390.345814 -275.478008) (xy 390.385236 -275.445821) (xy 390.42931 -275.420375)
			(xy 390.476896 -275.402328) (xy 390.52676 -275.392148) (xy 390.577612 -275.390099) (xy 390.628133 -275.396233)
			(xy 390.677017 -275.410393) (xy 390.722996 -275.43221) (xy 390.76488 -275.46112) (xy 390.801584 -275.496375)
			(xy 390.832157 -275.537061) (xy 390.855808 -275.582124) (xy 390.871924 -275.630398) (xy 390.880088 -275.680632)
			(xy 390.8806 -275.706078) (xy 393.078982 -275.706078) (xy 393.082942 -275.657024) (xy 393.094719 -275.60924)
			(xy 393.11401 -275.563964) (xy 393.140313 -275.522368) (xy 393.172948 -275.485531) (xy 393.211069 -275.454406)
			(xy 393.25369 -275.429799) (xy 393.299706 -275.412347) (xy 393.347925 -275.402503) (xy 393.3971 -275.400522)
			(xy 393.445955 -275.406454) (xy 393.493226 -275.420146) (xy 393.537688 -275.441244) (xy 393.578191 -275.4692)
			(xy 393.613684 -275.503292) (xy 393.643249 -275.542636) (xy 393.66612 -275.586213) (xy 393.681704 -275.632894)
			(xy 393.689599 -275.681471) (xy 393.690094 -275.706078) (xy 393.689599 -275.730685) (xy 393.681704 -275.779262)
			(xy 393.66612 -275.825943) (xy 393.643249 -275.86952) (xy 393.613684 -275.908864) (xy 393.578191 -275.942956)
			(xy 393.537688 -275.970912) (xy 393.493226 -275.99201) (xy 393.445955 -276.005702) (xy 393.3971 -276.011634)
			(xy 393.347925 -276.009653) (xy 393.299706 -275.999809) (xy 393.25369 -275.982357) (xy 393.211069 -275.95775)
			(xy 393.172948 -275.926625) (xy 393.140313 -275.889788) (xy 393.11401 -275.848192) (xy 393.094719 -275.802916)
			(xy 393.082942 -275.755132) (xy 393.078982 -275.706078) (xy 390.8806 -275.706078) (xy 390.880088 -275.731524)
			(xy 390.871924 -275.781758) (xy 390.855808 -275.830032) (xy 390.832157 -275.875095) (xy 390.801584 -275.915781)
			(xy 390.76488 -275.951036) (xy 390.722996 -275.979946) (xy 390.677017 -276.001763) (xy 390.628133 -276.015923)
			(xy 390.577612 -276.022057) (xy 390.52676 -276.020008) (xy 390.476896 -276.009828) (xy 390.42931 -275.991781)
			(xy 390.385236 -275.966335) (xy 390.345814 -275.934148) (xy 390.312066 -275.896054) (xy 390.284865 -275.85304)
			(xy 390.264917 -275.80622) (xy 390.252738 -275.756806) (xy 390.248643 -275.706078) (xy 389.940546 -275.706078)
			(xy 389.940034 -275.731524) (xy 389.93187 -275.781758) (xy 389.915754 -275.830032) (xy 389.892103 -275.875095)
			(xy 389.86153 -275.915781) (xy 389.824826 -275.951036) (xy 389.782942 -275.979946) (xy 389.736963 -276.001763)
			(xy 389.688079 -276.015923) (xy 389.637558 -276.022057) (xy 389.586706 -276.020008) (xy 389.536842 -276.009828)
			(xy 389.489256 -275.991781) (xy 389.445182 -275.966335) (xy 389.40576 -275.934148) (xy 389.372012 -275.896054)
			(xy 389.344811 -275.85304) (xy 389.324863 -275.80622) (xy 389.312684 -275.756806) (xy 389.308589 -275.706078)
			(xy 388.990078 -275.706078) (xy 388.989583 -275.730685) (xy 388.981688 -275.779262) (xy 388.966104 -275.825943)
			(xy 388.943233 -275.86952) (xy 388.913668 -275.908864) (xy 388.878175 -275.942956) (xy 388.837672 -275.970912)
			(xy 388.79321 -275.99201) (xy 388.745939 -276.005702) (xy 388.697084 -276.011634) (xy 388.647909 -276.009653)
			(xy 388.59969 -275.999809) (xy 388.553674 -275.982357) (xy 388.511053 -275.95775) (xy 388.472932 -275.926625)
			(xy 388.440297 -275.889788) (xy 388.413994 -275.848192) (xy 388.394703 -275.802916) (xy 388.382926 -275.755132)
			(xy 388.378966 -275.706078) (xy 388.060438 -275.706078) (xy 388.059926 -275.731524) (xy 388.051762 -275.781758)
			(xy 388.035646 -275.830032) (xy 388.011995 -275.875095) (xy 387.981422 -275.915781) (xy 387.944718 -275.951036)
			(xy 387.902834 -275.979946) (xy 387.856855 -276.001763) (xy 387.807971 -276.015923) (xy 387.75745 -276.022057)
			(xy 387.706598 -276.020008) (xy 387.656734 -276.009828) (xy 387.609148 -275.991781) (xy 387.565074 -275.966335)
			(xy 387.525652 -275.934148) (xy 387.491904 -275.896054) (xy 387.464703 -275.85304) (xy 387.444755 -275.80622)
			(xy 387.432576 -275.756806) (xy 387.428481 -275.706078) (xy 387.110224 -275.706078) (xy 387.109729 -275.730685)
			(xy 387.101834 -275.779262) (xy 387.08625 -275.825943) (xy 387.063379 -275.86952) (xy 387.033814 -275.908864)
			(xy 386.998321 -275.942956) (xy 386.957818 -275.970912) (xy 386.913356 -275.99201) (xy 386.866085 -276.005702)
			(xy 386.81723 -276.011634) (xy 386.768055 -276.009653) (xy 386.719836 -275.999809) (xy 386.67382 -275.982357)
			(xy 386.631199 -275.95775) (xy 386.593078 -275.926625) (xy 386.560443 -275.889788) (xy 386.53414 -275.848192)
			(xy 386.514849 -275.802916) (xy 386.503072 -275.755132) (xy 386.499112 -275.706078) (xy 386.180584 -275.706078)
			(xy 386.180072 -275.731524) (xy 386.171908 -275.781758) (xy 386.155792 -275.830032) (xy 386.132141 -275.875095)
			(xy 386.101568 -275.915781) (xy 386.064864 -275.951036) (xy 386.02298 -275.979946) (xy 385.977001 -276.001763)
			(xy 385.928117 -276.015923) (xy 385.877596 -276.022057) (xy 385.826744 -276.020008) (xy 385.77688 -276.009828)
			(xy 385.729294 -275.991781) (xy 385.68522 -275.966335) (xy 385.645798 -275.934148) (xy 385.61205 -275.896054)
			(xy 385.584849 -275.85304) (xy 385.564901 -275.80622) (xy 385.552722 -275.756806) (xy 385.548627 -275.706078)
			(xy 384.300476 -275.706078) (xy 384.299964 -275.731524) (xy 384.2918 -275.781758) (xy 384.275684 -275.830032)
			(xy 384.252033 -275.875095) (xy 384.22146 -275.915781) (xy 384.184756 -275.951036) (xy 384.142872 -275.979946)
			(xy 384.096893 -276.001763) (xy 384.048009 -276.015923) (xy 383.997488 -276.022057) (xy 383.946636 -276.020008)
			(xy 383.896772 -276.009828) (xy 383.849186 -275.991781) (xy 383.805112 -275.966335) (xy 383.76569 -275.934148)
			(xy 383.731942 -275.896054) (xy 383.704741 -275.85304) (xy 383.684793 -275.80622) (xy 383.672614 -275.756806)
			(xy 383.668519 -275.706078) (xy 383.360422 -275.706078) (xy 383.35991 -275.731524) (xy 383.351746 -275.781758)
			(xy 383.33563 -275.830032) (xy 383.311979 -275.875095) (xy 383.281406 -275.915781) (xy 383.244702 -275.951036)
			(xy 383.202818 -275.979946) (xy 383.156839 -276.001763) (xy 383.107955 -276.015923) (xy 383.057434 -276.022057)
			(xy 383.006582 -276.020008) (xy 382.956718 -276.009828) (xy 382.909132 -275.991781) (xy 382.865058 -275.966335)
			(xy 382.825636 -275.934148) (xy 382.791888 -275.896054) (xy 382.764687 -275.85304) (xy 382.744739 -275.80622)
			(xy 382.73256 -275.756806) (xy 382.728465 -275.706078) (xy 382.410208 -275.706078) (xy 382.409713 -275.730685)
			(xy 382.401818 -275.779262) (xy 382.386234 -275.825943) (xy 382.363363 -275.86952) (xy 382.333798 -275.908864)
			(xy 382.298305 -275.942956) (xy 382.257802 -275.970912) (xy 382.21334 -275.99201) (xy 382.166069 -276.005702)
			(xy 382.117214 -276.011634) (xy 382.068039 -276.009653) (xy 382.01982 -275.999809) (xy 381.973804 -275.982357)
			(xy 381.931183 -275.95775) (xy 381.893062 -275.926625) (xy 381.860427 -275.889788) (xy 381.834124 -275.848192)
			(xy 381.814833 -275.802916) (xy 381.803056 -275.755132) (xy 381.799096 -275.706078) (xy 381.480568 -275.706078)
			(xy 381.480056 -275.731524) (xy 381.471892 -275.781758) (xy 381.455776 -275.830032) (xy 381.432125 -275.875095)
			(xy 381.401552 -275.915781) (xy 381.364848 -275.951036) (xy 381.322964 -275.979946) (xy 381.276985 -276.001763)
			(xy 381.228101 -276.015923) (xy 381.17758 -276.022057) (xy 381.126728 -276.020008) (xy 381.076864 -276.009828)
			(xy 381.029278 -275.991781) (xy 380.985204 -275.966335) (xy 380.945782 -275.934148) (xy 380.912034 -275.896054)
			(xy 380.884833 -275.85304) (xy 380.864885 -275.80622) (xy 380.852706 -275.756806) (xy 380.848611 -275.706078)
			(xy 380.5301 -275.706078) (xy 380.529605 -275.730685) (xy 380.52171 -275.779262) (xy 380.506126 -275.825943)
			(xy 380.483255 -275.86952) (xy 380.45369 -275.908864) (xy 380.418197 -275.942956) (xy 380.377694 -275.970912)
			(xy 380.333232 -275.99201) (xy 380.285961 -276.005702) (xy 380.237106 -276.011634) (xy 380.187931 -276.009653)
			(xy 380.139712 -275.999809) (xy 380.093696 -275.982357) (xy 380.051075 -275.95775) (xy 380.012954 -275.926625)
			(xy 379.980319 -275.889788) (xy 379.954016 -275.848192) (xy 379.934725 -275.802916) (xy 379.922948 -275.755132)
			(xy 379.918988 -275.706078) (xy 379.60046 -275.706078) (xy 379.599948 -275.731524) (xy 379.591784 -275.781758)
			(xy 379.575668 -275.830032) (xy 379.552017 -275.875095) (xy 379.521444 -275.915781) (xy 379.48474 -275.951036)
			(xy 379.442856 -275.979946) (xy 379.396877 -276.001763) (xy 379.347993 -276.015923) (xy 379.297472 -276.022057)
			(xy 379.24662 -276.020008) (xy 379.196756 -276.009828) (xy 379.14917 -275.991781) (xy 379.105096 -275.966335)
			(xy 379.065674 -275.934148) (xy 379.031926 -275.896054) (xy 379.004725 -275.85304) (xy 378.984777 -275.80622)
			(xy 378.972598 -275.756806) (xy 378.968503 -275.706078) (xy 377.720606 -275.706078) (xy 377.720094 -275.731524)
			(xy 377.71193 -275.781758) (xy 377.695814 -275.830032) (xy 377.672163 -275.875095) (xy 377.64159 -275.915781)
			(xy 377.604886 -275.951036) (xy 377.563002 -275.979946) (xy 377.517023 -276.001763) (xy 377.468139 -276.015923)
			(xy 377.417618 -276.022057) (xy 377.366766 -276.020008) (xy 377.316902 -276.009828) (xy 377.269316 -275.991781)
			(xy 377.225242 -275.966335) (xy 377.18582 -275.934148) (xy 377.152072 -275.896054) (xy 377.124871 -275.85304)
			(xy 377.104923 -275.80622) (xy 377.092744 -275.756806) (xy 377.088649 -275.706078) (xy 376.780552 -275.706078)
			(xy 376.78004 -275.731524) (xy 376.771876 -275.781758) (xy 376.75576 -275.830032) (xy 376.732109 -275.875095)
			(xy 376.701536 -275.915781) (xy 376.664832 -275.951036) (xy 376.622948 -275.979946) (xy 376.576969 -276.001763)
			(xy 376.528085 -276.015923) (xy 376.477564 -276.022057) (xy 376.426712 -276.020008) (xy 376.376848 -276.009828)
			(xy 376.329262 -275.991781) (xy 376.285188 -275.966335) (xy 376.245766 -275.934148) (xy 376.212018 -275.896054)
			(xy 376.184817 -275.85304) (xy 376.164869 -275.80622) (xy 376.15269 -275.756806) (xy 376.148595 -275.706078)
			(xy 375.83068 -275.706078) (xy 375.830682 -275.7061) (xy 375.82651 -275.756449) (xy 375.814107 -275.805425)
			(xy 375.793812 -275.85169) (xy 375.766178 -275.893985) (xy 375.731959 -275.931153) (xy 375.692089 -275.962182)
			(xy 375.647655 -275.986226) (xy 375.59987 -276.002627) (xy 375.550037 -276.010939) (xy 375.524776 -276.011386)
			(xy 375.502158 -276.01098) (xy 375.457416 -276.004307) (xy 375.414151 -275.991097) (xy 375.373313 -275.971638)
			(xy 375.354342 -275.959316) (xy 375.342404 -275.951442) (xy 375.314718 -275.949918) (xy 375.223024 -275.99894)
			(xy 375.215066 -276.003596) (xy 375.202899 -276.017429) (xy 375.196448 -276.034685) (xy 375.1961 -276.043898)
			(xy 375.1961 -276.21611) (xy 375.196381 -276.224636) (xy 375.201919 -276.240761) (xy 375.212472 -276.254151)
			(xy 375.219468 -276.259036) (xy 375.240668 -276.2732) (xy 375.278458 -276.307421) (xy 375.310034 -276.347446)
			(xy 375.33452 -276.392163) (xy 375.351232 -276.440328) (xy 375.359707 -276.490601) (xy 375.359707 -276.516084)
			(xy 375.678695 -276.516084) (xy 375.68279 -276.465356) (xy 375.694969 -276.415942) (xy 375.714917 -276.369122)
			(xy 375.742118 -276.326108) (xy 375.775866 -276.288014) (xy 375.815288 -276.255827) (xy 375.859362 -276.230381)
			(xy 375.906948 -276.212334) (xy 375.956812 -276.202154) (xy 376.007664 -276.200105) (xy 376.058185 -276.206239)
			(xy 376.107069 -276.220399) (xy 376.153048 -276.242216) (xy 376.194932 -276.271126) (xy 376.231636 -276.306381)
			(xy 376.262209 -276.347067) (xy 376.28586 -276.39213) (xy 376.301976 -276.440404) (xy 376.31014 -276.490638)
			(xy 376.310652 -276.516084) (xy 376.628926 -276.516084) (xy 376.632886 -276.46703) (xy 376.644663 -276.419246)
			(xy 376.663954 -276.37397) (xy 376.690257 -276.332374) (xy 376.722892 -276.295537) (xy 376.761013 -276.264412)
			(xy 376.803634 -276.239805) (xy 376.84965 -276.222353) (xy 376.897869 -276.212509) (xy 376.947044 -276.210528)
			(xy 376.995899 -276.21646) (xy 377.04317 -276.230152) (xy 377.087632 -276.25125) (xy 377.128135 -276.279206)
			(xy 377.163628 -276.313298) (xy 377.193193 -276.352642) (xy 377.216064 -276.396219) (xy 377.231648 -276.4429)
			(xy 377.239543 -276.491477) (xy 377.240038 -276.516084) (xy 377.558549 -276.516084) (xy 377.562644 -276.465356)
			(xy 377.574823 -276.415942) (xy 377.594771 -276.369122) (xy 377.621972 -276.326108) (xy 377.65572 -276.288014)
			(xy 377.695142 -276.255827) (xy 377.739216 -276.230381) (xy 377.786802 -276.212334) (xy 377.836666 -276.202154)
			(xy 377.887518 -276.200105) (xy 377.938039 -276.206239) (xy 377.986923 -276.220399) (xy 378.032902 -276.242216)
			(xy 378.074786 -276.271126) (xy 378.11149 -276.306381) (xy 378.142063 -276.347067) (xy 378.165714 -276.39213)
			(xy 378.18183 -276.440404) (xy 378.189994 -276.490638) (xy 378.190506 -276.516084) (xy 378.509034 -276.516084)
			(xy 378.512994 -276.46703) (xy 378.524771 -276.419246) (xy 378.544062 -276.37397) (xy 378.570365 -276.332374)
			(xy 378.603 -276.295537) (xy 378.641121 -276.264412) (xy 378.683742 -276.239805) (xy 378.729758 -276.222353)
			(xy 378.777977 -276.212509) (xy 378.827152 -276.210528) (xy 378.876007 -276.21646) (xy 378.923278 -276.230152)
			(xy 378.96774 -276.25125) (xy 379.008243 -276.279206) (xy 379.043736 -276.313298) (xy 379.073301 -276.352642)
			(xy 379.096172 -276.396219) (xy 379.111756 -276.4429) (xy 379.119651 -276.491477) (xy 379.120146 -276.516084)
			(xy 379.438657 -276.516084) (xy 379.442752 -276.465356) (xy 379.454931 -276.415942) (xy 379.474879 -276.369122)
			(xy 379.50208 -276.326108) (xy 379.535828 -276.288014) (xy 379.57525 -276.255827) (xy 379.619324 -276.230381)
			(xy 379.66691 -276.212334) (xy 379.716774 -276.202154) (xy 379.767626 -276.200105) (xy 379.818147 -276.206239)
			(xy 379.867031 -276.220399) (xy 379.91301 -276.242216) (xy 379.954894 -276.271126) (xy 379.991598 -276.306381)
			(xy 380.022171 -276.347067) (xy 380.045822 -276.39213) (xy 380.061938 -276.440404) (xy 380.070102 -276.490638)
			(xy 380.070614 -276.516084) (xy 380.378711 -276.516084) (xy 380.382806 -276.465356) (xy 380.394985 -276.415942)
			(xy 380.414933 -276.369122) (xy 380.442134 -276.326108) (xy 380.475882 -276.288014) (xy 380.515304 -276.255827)
			(xy 380.559378 -276.230381) (xy 380.606964 -276.212334) (xy 380.656828 -276.202154) (xy 380.70768 -276.200105)
			(xy 380.758201 -276.206239) (xy 380.807085 -276.220399) (xy 380.853064 -276.242216) (xy 380.894948 -276.271126)
			(xy 380.931652 -276.306381) (xy 380.962225 -276.347067) (xy 380.985876 -276.39213) (xy 381.001992 -276.440404)
			(xy 381.010156 -276.490638) (xy 381.010668 -276.516084) (xy 381.328942 -276.516084) (xy 381.332902 -276.46703)
			(xy 381.344679 -276.419246) (xy 381.36397 -276.37397) (xy 381.390273 -276.332374) (xy 381.422908 -276.295537)
			(xy 381.461029 -276.264412) (xy 381.50365 -276.239805) (xy 381.549666 -276.222353) (xy 381.597885 -276.212509)
			(xy 381.64706 -276.210528) (xy 381.695915 -276.21646) (xy 381.743186 -276.230152) (xy 381.787648 -276.25125)
			(xy 381.828151 -276.279206) (xy 381.863644 -276.313298) (xy 381.893209 -276.352642) (xy 381.91608 -276.396219)
			(xy 381.931664 -276.4429) (xy 381.939559 -276.491477) (xy 381.940054 -276.516084) (xy 382.258565 -276.516084)
			(xy 382.26266 -276.465356) (xy 382.274839 -276.415942) (xy 382.294787 -276.369122) (xy 382.321988 -276.326108)
			(xy 382.355736 -276.288014) (xy 382.395158 -276.255827) (xy 382.439232 -276.230381) (xy 382.486818 -276.212334)
			(xy 382.536682 -276.202154) (xy 382.587534 -276.200105) (xy 382.638055 -276.206239) (xy 382.686939 -276.220399)
			(xy 382.732918 -276.242216) (xy 382.774802 -276.271126) (xy 382.811506 -276.306381) (xy 382.842079 -276.347067)
			(xy 382.86573 -276.39213) (xy 382.881846 -276.440404) (xy 382.89001 -276.490638) (xy 382.890522 -276.516084)
			(xy 383.20905 -276.516084) (xy 383.21301 -276.46703) (xy 383.224787 -276.419246) (xy 383.244078 -276.37397)
			(xy 383.270381 -276.332374) (xy 383.303016 -276.295537) (xy 383.341137 -276.264412) (xy 383.383758 -276.239805)
			(xy 383.429774 -276.222353) (xy 383.477993 -276.212509) (xy 383.527168 -276.210528) (xy 383.576023 -276.21646)
			(xy 383.623294 -276.230152) (xy 383.667756 -276.25125) (xy 383.708259 -276.279206) (xy 383.743752 -276.313298)
			(xy 383.773317 -276.352642) (xy 383.796188 -276.396219) (xy 383.811772 -276.4429) (xy 383.819667 -276.491477)
			(xy 383.820162 -276.516084) (xy 384.138673 -276.516084) (xy 384.142768 -276.465356) (xy 384.154947 -276.415942)
			(xy 384.174895 -276.369122) (xy 384.202096 -276.326108) (xy 384.235844 -276.288014) (xy 384.275266 -276.255827)
			(xy 384.31934 -276.230381) (xy 384.366926 -276.212334) (xy 384.41679 -276.202154) (xy 384.467642 -276.200105)
			(xy 384.518163 -276.206239) (xy 384.567047 -276.220399) (xy 384.613026 -276.242216) (xy 384.65491 -276.271126)
			(xy 384.691614 -276.306381) (xy 384.722187 -276.347067) (xy 384.745838 -276.39213) (xy 384.761954 -276.440404)
			(xy 384.770118 -276.490638) (xy 384.77063 -276.516084) (xy 385.088904 -276.516084) (xy 385.092864 -276.46703)
			(xy 385.104641 -276.419246) (xy 385.123932 -276.37397) (xy 385.150235 -276.332374) (xy 385.18287 -276.295537)
			(xy 385.220991 -276.264412) (xy 385.263612 -276.239805) (xy 385.309628 -276.222353) (xy 385.357847 -276.212509)
			(xy 385.407022 -276.210528) (xy 385.455877 -276.21646) (xy 385.503148 -276.230152) (xy 385.54761 -276.25125)
			(xy 385.588113 -276.279206) (xy 385.623606 -276.313298) (xy 385.653171 -276.352642) (xy 385.676042 -276.396219)
			(xy 385.691626 -276.4429) (xy 385.699521 -276.491477) (xy 385.700016 -276.516084) (xy 386.018527 -276.516084)
			(xy 386.022622 -276.465356) (xy 386.034801 -276.415942) (xy 386.054749 -276.369122) (xy 386.08195 -276.326108)
			(xy 386.115698 -276.288014) (xy 386.15512 -276.255827) (xy 386.199194 -276.230381) (xy 386.24678 -276.212334)
			(xy 386.296644 -276.202154) (xy 386.347496 -276.200105) (xy 386.398017 -276.206239) (xy 386.446901 -276.220399)
			(xy 386.49288 -276.242216) (xy 386.534764 -276.271126) (xy 386.571468 -276.306381) (xy 386.602041 -276.347067)
			(xy 386.625692 -276.39213) (xy 386.641808 -276.440404) (xy 386.649972 -276.490638) (xy 386.650484 -276.516084)
			(xy 386.958581 -276.516084) (xy 386.962676 -276.465356) (xy 386.974855 -276.415942) (xy 386.994803 -276.369122)
			(xy 387.022004 -276.326108) (xy 387.055752 -276.288014) (xy 387.095174 -276.255827) (xy 387.139248 -276.230381)
			(xy 387.186834 -276.212334) (xy 387.236698 -276.202154) (xy 387.28755 -276.200105) (xy 387.338071 -276.206239)
			(xy 387.386955 -276.220399) (xy 387.432934 -276.242216) (xy 387.474818 -276.271126) (xy 387.511522 -276.306381)
			(xy 387.542095 -276.347067) (xy 387.565746 -276.39213) (xy 387.581862 -276.440404) (xy 387.590026 -276.490638)
			(xy 387.590538 -276.516084) (xy 387.909066 -276.516084) (xy 387.913026 -276.46703) (xy 387.924803 -276.419246)
			(xy 387.944094 -276.37397) (xy 387.970397 -276.332374) (xy 388.003032 -276.295537) (xy 388.041153 -276.264412)
			(xy 388.083774 -276.239805) (xy 388.12979 -276.222353) (xy 388.178009 -276.212509) (xy 388.227184 -276.210528)
			(xy 388.276039 -276.21646) (xy 388.32331 -276.230152) (xy 388.367772 -276.25125) (xy 388.408275 -276.279206)
			(xy 388.443768 -276.313298) (xy 388.473333 -276.352642) (xy 388.496204 -276.396219) (xy 388.511788 -276.4429)
			(xy 388.519683 -276.491477) (xy 388.520178 -276.516084) (xy 388.838689 -276.516084) (xy 388.842784 -276.465356)
			(xy 388.854963 -276.415942) (xy 388.874911 -276.369122) (xy 388.902112 -276.326108) (xy 388.93586 -276.288014)
			(xy 388.975282 -276.255827) (xy 389.019356 -276.230381) (xy 389.066942 -276.212334) (xy 389.116806 -276.202154)
			(xy 389.167658 -276.200105) (xy 389.218179 -276.206239) (xy 389.267063 -276.220399) (xy 389.313042 -276.242216)
			(xy 389.354926 -276.271126) (xy 389.39163 -276.306381) (xy 389.422203 -276.347067) (xy 389.445854 -276.39213)
			(xy 389.46197 -276.440404) (xy 389.470134 -276.490638) (xy 389.470646 -276.516084) (xy 389.78892 -276.516084)
			(xy 389.79288 -276.46703) (xy 389.804657 -276.419246) (xy 389.823948 -276.37397) (xy 389.850251 -276.332374)
			(xy 389.882886 -276.295537) (xy 389.921007 -276.264412) (xy 389.963628 -276.239805) (xy 390.009644 -276.222353)
			(xy 390.057863 -276.212509) (xy 390.107038 -276.210528) (xy 390.155893 -276.21646) (xy 390.203164 -276.230152)
			(xy 390.247626 -276.25125) (xy 390.288129 -276.279206) (xy 390.323622 -276.313298) (xy 390.353187 -276.352642)
			(xy 390.376058 -276.396219) (xy 390.391642 -276.4429) (xy 390.399537 -276.491477) (xy 390.400032 -276.516084)
			(xy 390.718543 -276.516084) (xy 390.722638 -276.465356) (xy 390.734817 -276.415942) (xy 390.754765 -276.369122)
			(xy 390.781966 -276.326108) (xy 390.815714 -276.288014) (xy 390.855136 -276.255827) (xy 390.89921 -276.230381)
			(xy 390.946796 -276.212334) (xy 390.99666 -276.202154) (xy 391.047512 -276.200105) (xy 391.098033 -276.206239)
			(xy 391.146917 -276.220399) (xy 391.192896 -276.242216) (xy 391.23478 -276.271126) (xy 391.271484 -276.306381)
			(xy 391.302057 -276.347067) (xy 391.325708 -276.39213) (xy 391.341824 -276.440404) (xy 391.349988 -276.490638)
			(xy 391.3505 -276.516084) (xy 391.669028 -276.516084) (xy 391.672988 -276.46703) (xy 391.684765 -276.419246)
			(xy 391.704056 -276.37397) (xy 391.730359 -276.332374) (xy 391.762994 -276.295537) (xy 391.801115 -276.264412)
			(xy 391.843736 -276.239805) (xy 391.889752 -276.222353) (xy 391.937971 -276.212509) (xy 391.987146 -276.210528)
			(xy 392.036001 -276.21646) (xy 392.083272 -276.230152) (xy 392.125407 -276.250146) (xy 394.67715 -276.250146)
			(xy 394.68111 -276.201092) (xy 394.692887 -276.153308) (xy 394.712178 -276.108032) (xy 394.738481 -276.066436)
			(xy 394.771116 -276.029599) (xy 394.809237 -275.998474) (xy 394.851858 -275.973867) (xy 394.897874 -275.956415)
			(xy 394.946093 -275.946571) (xy 394.995268 -275.94459) (xy 395.044123 -275.950522) (xy 395.091394 -275.964214)
			(xy 395.135856 -275.985312) (xy 395.176359 -276.013268) (xy 395.211852 -276.04736) (xy 395.241417 -276.086704)
			(xy 395.264288 -276.130281) (xy 395.279872 -276.176962) (xy 395.287767 -276.225539) (xy 395.288262 -276.250146)
			(xy 395.287767 -276.274753) (xy 395.279872 -276.32333) (xy 395.264288 -276.370011) (xy 395.241417 -276.413588)
			(xy 395.211852 -276.452932) (xy 395.176359 -276.487024) (xy 395.135856 -276.51498) (xy 395.091394 -276.536078)
			(xy 395.044123 -276.54977) (xy 394.995268 -276.555702) (xy 394.946093 -276.553721) (xy 394.897874 -276.543877)
			(xy 394.851858 -276.526425) (xy 394.809237 -276.501818) (xy 394.771116 -276.470693) (xy 394.738481 -276.433856)
			(xy 394.712178 -276.39226) (xy 394.692887 -276.346984) (xy 394.68111 -276.2992) (xy 394.67715 -276.250146)
			(xy 392.125407 -276.250146) (xy 392.127734 -276.25125) (xy 392.168237 -276.279206) (xy 392.20373 -276.313298)
			(xy 392.233295 -276.352642) (xy 392.256166 -276.396219) (xy 392.27175 -276.4429) (xy 392.279645 -276.491477)
			(xy 392.28014 -276.516084) (xy 392.279645 -276.540691) (xy 392.27175 -276.589268) (xy 392.256166 -276.635949)
			(xy 392.233295 -276.679526) (xy 392.20373 -276.71887) (xy 392.168237 -276.752962) (xy 392.127734 -276.780918)
			(xy 392.083272 -276.802016) (xy 392.036001 -276.815708) (xy 391.987146 -276.82164) (xy 391.937971 -276.819659)
			(xy 391.889752 -276.809815) (xy 391.843736 -276.792363) (xy 391.801115 -276.767756) (xy 391.762994 -276.736631)
			(xy 391.730359 -276.699794) (xy 391.704056 -276.658198) (xy 391.684765 -276.612922) (xy 391.672988 -276.565138)
			(xy 391.669028 -276.516084) (xy 391.3505 -276.516084) (xy 391.349988 -276.54153) (xy 391.341824 -276.591764)
			(xy 391.325708 -276.640038) (xy 391.302057 -276.685101) (xy 391.271484 -276.725787) (xy 391.23478 -276.761042)
			(xy 391.192896 -276.789952) (xy 391.146917 -276.811769) (xy 391.098033 -276.825929) (xy 391.047512 -276.832063)
			(xy 390.99666 -276.830014) (xy 390.946796 -276.819834) (xy 390.89921 -276.801787) (xy 390.855136 -276.776341)
			(xy 390.815714 -276.744154) (xy 390.781966 -276.70606) (xy 390.754765 -276.663046) (xy 390.734817 -276.616226)
			(xy 390.722638 -276.566812) (xy 390.718543 -276.516084) (xy 390.400032 -276.516084) (xy 390.399537 -276.540691)
			(xy 390.391642 -276.589268) (xy 390.376058 -276.635949) (xy 390.353187 -276.679526) (xy 390.323622 -276.71887)
			(xy 390.288129 -276.752962) (xy 390.247626 -276.780918) (xy 390.203164 -276.802016) (xy 390.155893 -276.815708)
			(xy 390.107038 -276.82164) (xy 390.057863 -276.819659) (xy 390.009644 -276.809815) (xy 389.963628 -276.792363)
			(xy 389.921007 -276.767756) (xy 389.882886 -276.736631) (xy 389.850251 -276.699794) (xy 389.823948 -276.658198)
			(xy 389.804657 -276.612922) (xy 389.79288 -276.565138) (xy 389.78892 -276.516084) (xy 389.470646 -276.516084)
			(xy 389.470134 -276.54153) (xy 389.46197 -276.591764) (xy 389.445854 -276.640038) (xy 389.422203 -276.685101)
			(xy 389.39163 -276.725787) (xy 389.354926 -276.761042) (xy 389.313042 -276.789952) (xy 389.267063 -276.811769)
			(xy 389.218179 -276.825929) (xy 389.167658 -276.832063) (xy 389.116806 -276.830014) (xy 389.066942 -276.819834)
			(xy 389.019356 -276.801787) (xy 388.975282 -276.776341) (xy 388.93586 -276.744154) (xy 388.902112 -276.70606)
			(xy 388.874911 -276.663046) (xy 388.854963 -276.616226) (xy 388.842784 -276.566812) (xy 388.838689 -276.516084)
			(xy 388.520178 -276.516084) (xy 388.519683 -276.540691) (xy 388.511788 -276.589268) (xy 388.496204 -276.635949)
			(xy 388.473333 -276.679526) (xy 388.443768 -276.71887) (xy 388.408275 -276.752962) (xy 388.367772 -276.780918)
			(xy 388.32331 -276.802016) (xy 388.276039 -276.815708) (xy 388.227184 -276.82164) (xy 388.178009 -276.819659)
			(xy 388.12979 -276.809815) (xy 388.083774 -276.792363) (xy 388.041153 -276.767756) (xy 388.003032 -276.736631)
			(xy 387.970397 -276.699794) (xy 387.944094 -276.658198) (xy 387.924803 -276.612922) (xy 387.913026 -276.565138)
			(xy 387.909066 -276.516084) (xy 387.590538 -276.516084) (xy 387.590026 -276.54153) (xy 387.581862 -276.591764)
			(xy 387.565746 -276.640038) (xy 387.542095 -276.685101) (xy 387.511522 -276.725787) (xy 387.474818 -276.761042)
			(xy 387.432934 -276.789952) (xy 387.386955 -276.811769) (xy 387.338071 -276.825929) (xy 387.28755 -276.832063)
			(xy 387.236698 -276.830014) (xy 387.186834 -276.819834) (xy 387.139248 -276.801787) (xy 387.095174 -276.776341)
			(xy 387.055752 -276.744154) (xy 387.022004 -276.70606) (xy 386.994803 -276.663046) (xy 386.974855 -276.616226)
			(xy 386.962676 -276.566812) (xy 386.958581 -276.516084) (xy 386.650484 -276.516084) (xy 386.649972 -276.54153)
			(xy 386.641808 -276.591764) (xy 386.625692 -276.640038) (xy 386.602041 -276.685101) (xy 386.571468 -276.725787)
			(xy 386.534764 -276.761042) (xy 386.49288 -276.789952) (xy 386.446901 -276.811769) (xy 386.398017 -276.825929)
			(xy 386.347496 -276.832063) (xy 386.296644 -276.830014) (xy 386.24678 -276.819834) (xy 386.199194 -276.801787)
			(xy 386.15512 -276.776341) (xy 386.115698 -276.744154) (xy 386.08195 -276.70606) (xy 386.054749 -276.663046)
			(xy 386.034801 -276.616226) (xy 386.022622 -276.566812) (xy 386.018527 -276.516084) (xy 385.700016 -276.516084)
			(xy 385.699521 -276.540691) (xy 385.691626 -276.589268) (xy 385.676042 -276.635949) (xy 385.653171 -276.679526)
			(xy 385.623606 -276.71887) (xy 385.588113 -276.752962) (xy 385.54761 -276.780918) (xy 385.503148 -276.802016)
			(xy 385.455877 -276.815708) (xy 385.407022 -276.82164) (xy 385.357847 -276.819659) (xy 385.309628 -276.809815)
			(xy 385.263612 -276.792363) (xy 385.220991 -276.767756) (xy 385.18287 -276.736631) (xy 385.150235 -276.699794)
			(xy 385.123932 -276.658198) (xy 385.104641 -276.612922) (xy 385.092864 -276.565138) (xy 385.088904 -276.516084)
			(xy 384.77063 -276.516084) (xy 384.770118 -276.54153) (xy 384.761954 -276.591764) (xy 384.745838 -276.640038)
			(xy 384.722187 -276.685101) (xy 384.691614 -276.725787) (xy 384.65491 -276.761042) (xy 384.613026 -276.789952)
			(xy 384.567047 -276.811769) (xy 384.518163 -276.825929) (xy 384.467642 -276.832063) (xy 384.41679 -276.830014)
			(xy 384.366926 -276.819834) (xy 384.31934 -276.801787) (xy 384.275266 -276.776341) (xy 384.235844 -276.744154)
			(xy 384.202096 -276.70606) (xy 384.174895 -276.663046) (xy 384.154947 -276.616226) (xy 384.142768 -276.566812)
			(xy 384.138673 -276.516084) (xy 383.820162 -276.516084) (xy 383.819667 -276.540691) (xy 383.811772 -276.589268)
			(xy 383.796188 -276.635949) (xy 383.773317 -276.679526) (xy 383.743752 -276.71887) (xy 383.708259 -276.752962)
			(xy 383.667756 -276.780918) (xy 383.623294 -276.802016) (xy 383.576023 -276.815708) (xy 383.527168 -276.82164)
			(xy 383.477993 -276.819659) (xy 383.429774 -276.809815) (xy 383.383758 -276.792363) (xy 383.341137 -276.767756)
			(xy 383.303016 -276.736631) (xy 383.270381 -276.699794) (xy 383.244078 -276.658198) (xy 383.224787 -276.612922)
			(xy 383.21301 -276.565138) (xy 383.20905 -276.516084) (xy 382.890522 -276.516084) (xy 382.89001 -276.54153)
			(xy 382.881846 -276.591764) (xy 382.86573 -276.640038) (xy 382.842079 -276.685101) (xy 382.811506 -276.725787)
			(xy 382.774802 -276.761042) (xy 382.732918 -276.789952) (xy 382.686939 -276.811769) (xy 382.638055 -276.825929)
			(xy 382.587534 -276.832063) (xy 382.536682 -276.830014) (xy 382.486818 -276.819834) (xy 382.439232 -276.801787)
			(xy 382.395158 -276.776341) (xy 382.355736 -276.744154) (xy 382.321988 -276.70606) (xy 382.294787 -276.663046)
			(xy 382.274839 -276.616226) (xy 382.26266 -276.566812) (xy 382.258565 -276.516084) (xy 381.940054 -276.516084)
			(xy 381.939559 -276.540691) (xy 381.931664 -276.589268) (xy 381.91608 -276.635949) (xy 381.893209 -276.679526)
			(xy 381.863644 -276.71887) (xy 381.828151 -276.752962) (xy 381.787648 -276.780918) (xy 381.743186 -276.802016)
			(xy 381.695915 -276.815708) (xy 381.64706 -276.82164) (xy 381.597885 -276.819659) (xy 381.549666 -276.809815)
			(xy 381.50365 -276.792363) (xy 381.461029 -276.767756) (xy 381.422908 -276.736631) (xy 381.390273 -276.699794)
			(xy 381.36397 -276.658198) (xy 381.344679 -276.612922) (xy 381.332902 -276.565138) (xy 381.328942 -276.516084)
			(xy 381.010668 -276.516084) (xy 381.010156 -276.54153) (xy 381.001992 -276.591764) (xy 380.985876 -276.640038)
			(xy 380.962225 -276.685101) (xy 380.931652 -276.725787) (xy 380.894948 -276.761042) (xy 380.853064 -276.789952)
			(xy 380.807085 -276.811769) (xy 380.758201 -276.825929) (xy 380.70768 -276.832063) (xy 380.656828 -276.830014)
			(xy 380.606964 -276.819834) (xy 380.559378 -276.801787) (xy 380.515304 -276.776341) (xy 380.475882 -276.744154)
			(xy 380.442134 -276.70606) (xy 380.414933 -276.663046) (xy 380.394985 -276.616226) (xy 380.382806 -276.566812)
			(xy 380.378711 -276.516084) (xy 380.070614 -276.516084) (xy 380.070102 -276.54153) (xy 380.061938 -276.591764)
			(xy 380.045822 -276.640038) (xy 380.022171 -276.685101) (xy 379.991598 -276.725787) (xy 379.954894 -276.761042)
			(xy 379.91301 -276.789952) (xy 379.867031 -276.811769) (xy 379.818147 -276.825929) (xy 379.767626 -276.832063)
			(xy 379.716774 -276.830014) (xy 379.66691 -276.819834) (xy 379.619324 -276.801787) (xy 379.57525 -276.776341)
			(xy 379.535828 -276.744154) (xy 379.50208 -276.70606) (xy 379.474879 -276.663046) (xy 379.454931 -276.616226)
			(xy 379.442752 -276.566812) (xy 379.438657 -276.516084) (xy 379.120146 -276.516084) (xy 379.119651 -276.540691)
			(xy 379.111756 -276.589268) (xy 379.096172 -276.635949) (xy 379.073301 -276.679526) (xy 379.043736 -276.71887)
			(xy 379.008243 -276.752962) (xy 378.96774 -276.780918) (xy 378.923278 -276.802016) (xy 378.876007 -276.815708)
			(xy 378.827152 -276.82164) (xy 378.777977 -276.819659) (xy 378.729758 -276.809815) (xy 378.683742 -276.792363)
			(xy 378.641121 -276.767756) (xy 378.603 -276.736631) (xy 378.570365 -276.699794) (xy 378.544062 -276.658198)
			(xy 378.524771 -276.612922) (xy 378.512994 -276.565138) (xy 378.509034 -276.516084) (xy 378.190506 -276.516084)
			(xy 378.189994 -276.54153) (xy 378.18183 -276.591764) (xy 378.165714 -276.640038) (xy 378.142063 -276.685101)
			(xy 378.11149 -276.725787) (xy 378.074786 -276.761042) (xy 378.032902 -276.789952) (xy 377.986923 -276.811769)
			(xy 377.938039 -276.825929) (xy 377.887518 -276.832063) (xy 377.836666 -276.830014) (xy 377.786802 -276.819834)
			(xy 377.739216 -276.801787) (xy 377.695142 -276.776341) (xy 377.65572 -276.744154) (xy 377.621972 -276.70606)
			(xy 377.594771 -276.663046) (xy 377.574823 -276.616226) (xy 377.562644 -276.566812) (xy 377.558549 -276.516084)
			(xy 377.240038 -276.516084) (xy 377.239543 -276.540691) (xy 377.231648 -276.589268) (xy 377.216064 -276.635949)
			(xy 377.193193 -276.679526) (xy 377.163628 -276.71887) (xy 377.128135 -276.752962) (xy 377.087632 -276.780918)
			(xy 377.04317 -276.802016) (xy 376.995899 -276.815708) (xy 376.947044 -276.82164) (xy 376.897869 -276.819659)
			(xy 376.84965 -276.809815) (xy 376.803634 -276.792363) (xy 376.761013 -276.767756) (xy 376.722892 -276.736631)
			(xy 376.690257 -276.699794) (xy 376.663954 -276.658198) (xy 376.644663 -276.612922) (xy 376.632886 -276.565138)
			(xy 376.628926 -276.516084) (xy 376.310652 -276.516084) (xy 376.31014 -276.54153) (xy 376.301976 -276.591764)
			(xy 376.28586 -276.640038) (xy 376.262209 -276.685101) (xy 376.231636 -276.725787) (xy 376.194932 -276.761042)
			(xy 376.153048 -276.789952) (xy 376.107069 -276.811769) (xy 376.058185 -276.825929) (xy 376.007664 -276.832063)
			(xy 375.956812 -276.830014) (xy 375.906948 -276.819834) (xy 375.859362 -276.801787) (xy 375.815288 -276.776341)
			(xy 375.775866 -276.744154) (xy 375.742118 -276.70606) (xy 375.714917 -276.663046) (xy 375.694969 -276.616226)
			(xy 375.68279 -276.566812) (xy 375.678695 -276.516084) (xy 375.359707 -276.516084) (xy 375.359708 -276.541582)
			(xy 375.351236 -276.591855) (xy 375.334527 -276.640021) (xy 375.310044 -276.684739) (xy 375.278469 -276.724766)
			(xy 375.240681 -276.758989) (xy 375.219468 -276.773132) (xy 375.212478 -276.778016) (xy 375.201961 -276.791425)
			(xy 375.196406 -276.807537) (xy 375.1961 -276.816058) (xy 375.1961 -277.32609) (xy 376.148595 -277.32609)
			(xy 376.15269 -277.275362) (xy 376.164869 -277.225948) (xy 376.184817 -277.179128) (xy 376.212018 -277.136114)
			(xy 376.245766 -277.09802) (xy 376.285188 -277.065833) (xy 376.329262 -277.040387) (xy 376.376848 -277.02234)
			(xy 376.426712 -277.01216) (xy 376.477564 -277.010111) (xy 376.528085 -277.016245) (xy 376.576969 -277.030405)
			(xy 376.622948 -277.052222) (xy 376.664832 -277.081132) (xy 376.701536 -277.116387) (xy 376.732109 -277.157073)
			(xy 376.75576 -277.202136) (xy 376.771876 -277.25041) (xy 376.78004 -277.300644) (xy 376.780552 -277.32609)
			(xy 377.088649 -277.32609) (xy 377.092744 -277.275362) (xy 377.104923 -277.225948) (xy 377.124871 -277.179128)
			(xy 377.152072 -277.136114) (xy 377.18582 -277.09802) (xy 377.225242 -277.065833) (xy 377.269316 -277.040387)
			(xy 377.316902 -277.02234) (xy 377.366766 -277.01216) (xy 377.417618 -277.010111) (xy 377.468139 -277.016245)
			(xy 377.517023 -277.030405) (xy 377.563002 -277.052222) (xy 377.604886 -277.081132) (xy 377.64159 -277.116387)
			(xy 377.672163 -277.157073) (xy 377.695814 -277.202136) (xy 377.71193 -277.25041) (xy 377.720094 -277.300644)
			(xy 377.720606 -277.32609) (xy 378.039134 -277.32609) (xy 378.043094 -277.277036) (xy 378.054871 -277.229252)
			(xy 378.074162 -277.183976) (xy 378.100465 -277.14238) (xy 378.1331 -277.105543) (xy 378.171221 -277.074418)
			(xy 378.213842 -277.049811) (xy 378.259858 -277.032359) (xy 378.308077 -277.022515) (xy 378.357252 -277.020534)
			(xy 378.406107 -277.026466) (xy 378.453378 -277.040158) (xy 378.49784 -277.061256) (xy 378.538343 -277.089212)
			(xy 378.573836 -277.123304) (xy 378.603401 -277.162648) (xy 378.626272 -277.206225) (xy 378.641856 -277.252906)
			(xy 378.649751 -277.301483) (xy 378.650246 -277.32609) (xy 378.968503 -277.32609) (xy 378.972598 -277.275362)
			(xy 378.984777 -277.225948) (xy 379.004725 -277.179128) (xy 379.031926 -277.136114) (xy 379.065674 -277.09802)
			(xy 379.105096 -277.065833) (xy 379.14917 -277.040387) (xy 379.196756 -277.02234) (xy 379.24662 -277.01216)
			(xy 379.297472 -277.010111) (xy 379.347993 -277.016245) (xy 379.396877 -277.030405) (xy 379.442856 -277.052222)
			(xy 379.48474 -277.081132) (xy 379.521444 -277.116387) (xy 379.552017 -277.157073) (xy 379.575668 -277.202136)
			(xy 379.591784 -277.25041) (xy 379.599948 -277.300644) (xy 379.60046 -277.32609) (xy 379.918988 -277.32609)
			(xy 379.922948 -277.277036) (xy 379.934725 -277.229252) (xy 379.954016 -277.183976) (xy 379.980319 -277.14238)
			(xy 380.012954 -277.105543) (xy 380.051075 -277.074418) (xy 380.093696 -277.049811) (xy 380.139712 -277.032359)
			(xy 380.187931 -277.022515) (xy 380.237106 -277.020534) (xy 380.285961 -277.026466) (xy 380.333232 -277.040158)
			(xy 380.377694 -277.061256) (xy 380.418197 -277.089212) (xy 380.45369 -277.123304) (xy 380.483255 -277.162648)
			(xy 380.506126 -277.206225) (xy 380.52171 -277.252906) (xy 380.529605 -277.301483) (xy 380.5301 -277.32609)
			(xy 380.848611 -277.32609) (xy 380.852706 -277.275362) (xy 380.864885 -277.225948) (xy 380.884833 -277.179128)
			(xy 380.912034 -277.136114) (xy 380.945782 -277.09802) (xy 380.985204 -277.065833) (xy 381.029278 -277.040387)
			(xy 381.076864 -277.02234) (xy 381.126728 -277.01216) (xy 381.17758 -277.010111) (xy 381.228101 -277.016245)
			(xy 381.276985 -277.030405) (xy 381.322964 -277.052222) (xy 381.364848 -277.081132) (xy 381.401552 -277.116387)
			(xy 381.432125 -277.157073) (xy 381.455776 -277.202136) (xy 381.471892 -277.25041) (xy 381.480056 -277.300644)
			(xy 381.480568 -277.32609) (xy 381.799096 -277.32609) (xy 381.803056 -277.277036) (xy 381.814833 -277.229252)
			(xy 381.834124 -277.183976) (xy 381.860427 -277.14238) (xy 381.893062 -277.105543) (xy 381.931183 -277.074418)
			(xy 381.973804 -277.049811) (xy 382.01982 -277.032359) (xy 382.068039 -277.022515) (xy 382.117214 -277.020534)
			(xy 382.166069 -277.026466) (xy 382.21334 -277.040158) (xy 382.257802 -277.061256) (xy 382.298305 -277.089212)
			(xy 382.333798 -277.123304) (xy 382.363363 -277.162648) (xy 382.386234 -277.206225) (xy 382.401818 -277.252906)
			(xy 382.409713 -277.301483) (xy 382.410208 -277.32609) (xy 382.728465 -277.32609) (xy 382.73256 -277.275362)
			(xy 382.744739 -277.225948) (xy 382.764687 -277.179128) (xy 382.791888 -277.136114) (xy 382.825636 -277.09802)
			(xy 382.865058 -277.065833) (xy 382.909132 -277.040387) (xy 382.956718 -277.02234) (xy 383.006582 -277.01216)
			(xy 383.057434 -277.010111) (xy 383.107955 -277.016245) (xy 383.156839 -277.030405) (xy 383.202818 -277.052222)
			(xy 383.244702 -277.081132) (xy 383.281406 -277.116387) (xy 383.311979 -277.157073) (xy 383.33563 -277.202136)
			(xy 383.351746 -277.25041) (xy 383.35991 -277.300644) (xy 383.360422 -277.32609) (xy 383.668519 -277.32609)
			(xy 383.672614 -277.275362) (xy 383.684793 -277.225948) (xy 383.704741 -277.179128) (xy 383.731942 -277.136114)
			(xy 383.76569 -277.09802) (xy 383.805112 -277.065833) (xy 383.849186 -277.040387) (xy 383.896772 -277.02234)
			(xy 383.946636 -277.01216) (xy 383.997488 -277.010111) (xy 384.048009 -277.016245) (xy 384.096893 -277.030405)
			(xy 384.142872 -277.052222) (xy 384.184756 -277.081132) (xy 384.22146 -277.116387) (xy 384.252033 -277.157073)
			(xy 384.275684 -277.202136) (xy 384.2918 -277.25041) (xy 384.299964 -277.300644) (xy 384.300476 -277.32609)
			(xy 384.619004 -277.32609) (xy 384.622964 -277.277036) (xy 384.634741 -277.229252) (xy 384.654032 -277.183976)
			(xy 384.680335 -277.14238) (xy 384.71297 -277.105543) (xy 384.751091 -277.074418) (xy 384.793712 -277.049811)
			(xy 384.839728 -277.032359) (xy 384.887947 -277.022515) (xy 384.937122 -277.020534) (xy 384.985977 -277.026466)
			(xy 385.033248 -277.040158) (xy 385.07771 -277.061256) (xy 385.118213 -277.089212) (xy 385.153706 -277.123304)
			(xy 385.183271 -277.162648) (xy 385.206142 -277.206225) (xy 385.221726 -277.252906) (xy 385.229621 -277.301483)
			(xy 385.230116 -277.32609) (xy 385.548627 -277.32609) (xy 385.552722 -277.275362) (xy 385.564901 -277.225948)
			(xy 385.584849 -277.179128) (xy 385.61205 -277.136114) (xy 385.645798 -277.09802) (xy 385.68522 -277.065833)
			(xy 385.729294 -277.040387) (xy 385.77688 -277.02234) (xy 385.826744 -277.01216) (xy 385.877596 -277.010111)
			(xy 385.928117 -277.016245) (xy 385.977001 -277.030405) (xy 386.02298 -277.052222) (xy 386.064864 -277.081132)
			(xy 386.101568 -277.116387) (xy 386.132141 -277.157073) (xy 386.155792 -277.202136) (xy 386.171908 -277.25041)
			(xy 386.180072 -277.300644) (xy 386.180584 -277.32609) (xy 386.499112 -277.32609) (xy 386.503072 -277.277036)
			(xy 386.514849 -277.229252) (xy 386.53414 -277.183976) (xy 386.560443 -277.14238) (xy 386.593078 -277.105543)
			(xy 386.631199 -277.074418) (xy 386.67382 -277.049811) (xy 386.719836 -277.032359) (xy 386.768055 -277.022515)
			(xy 386.81723 -277.020534) (xy 386.866085 -277.026466) (xy 386.913356 -277.040158) (xy 386.957818 -277.061256)
			(xy 386.998321 -277.089212) (xy 387.033814 -277.123304) (xy 387.063379 -277.162648) (xy 387.08625 -277.206225)
			(xy 387.101834 -277.252906) (xy 387.109729 -277.301483) (xy 387.110224 -277.32609) (xy 387.428481 -277.32609)
			(xy 387.432576 -277.275362) (xy 387.444755 -277.225948) (xy 387.464703 -277.179128) (xy 387.491904 -277.136114)
			(xy 387.525652 -277.09802) (xy 387.565074 -277.065833) (xy 387.609148 -277.040387) (xy 387.656734 -277.02234)
			(xy 387.706598 -277.01216) (xy 387.75745 -277.010111) (xy 387.807971 -277.016245) (xy 387.856855 -277.030405)
			(xy 387.902834 -277.052222) (xy 387.944718 -277.081132) (xy 387.981422 -277.116387) (xy 388.011995 -277.157073)
			(xy 388.035646 -277.202136) (xy 388.051762 -277.25041) (xy 388.059926 -277.300644) (xy 388.060438 -277.32609)
			(xy 388.378966 -277.32609) (xy 388.382926 -277.277036) (xy 388.394703 -277.229252) (xy 388.413994 -277.183976)
			(xy 388.440297 -277.14238) (xy 388.472932 -277.105543) (xy 388.511053 -277.074418) (xy 388.553674 -277.049811)
			(xy 388.59969 -277.032359) (xy 388.647909 -277.022515) (xy 388.697084 -277.020534) (xy 388.745939 -277.026466)
			(xy 388.79321 -277.040158) (xy 388.837672 -277.061256) (xy 388.878175 -277.089212) (xy 388.913668 -277.123304)
			(xy 388.943233 -277.162648) (xy 388.966104 -277.206225) (xy 388.981688 -277.252906) (xy 388.989583 -277.301483)
			(xy 388.990078 -277.32609) (xy 389.308589 -277.32609) (xy 389.312684 -277.275362) (xy 389.324863 -277.225948)
			(xy 389.344811 -277.179128) (xy 389.372012 -277.136114) (xy 389.40576 -277.09802) (xy 389.445182 -277.065833)
			(xy 389.489256 -277.040387) (xy 389.536842 -277.02234) (xy 389.586706 -277.01216) (xy 389.637558 -277.010111)
			(xy 389.688079 -277.016245) (xy 389.736963 -277.030405) (xy 389.782942 -277.052222) (xy 389.824826 -277.081132)
			(xy 389.86153 -277.116387) (xy 389.892103 -277.157073) (xy 389.915754 -277.202136) (xy 389.93187 -277.25041)
			(xy 389.940034 -277.300644) (xy 389.940546 -277.32609) (xy 390.248643 -277.32609) (xy 390.252738 -277.275362)
			(xy 390.264917 -277.225948) (xy 390.284865 -277.179128) (xy 390.312066 -277.136114) (xy 390.345814 -277.09802)
			(xy 390.385236 -277.065833) (xy 390.42931 -277.040387) (xy 390.476896 -277.02234) (xy 390.52676 -277.01216)
			(xy 390.577612 -277.010111) (xy 390.628133 -277.016245) (xy 390.677017 -277.030405) (xy 390.722996 -277.052222)
			(xy 390.76488 -277.081132) (xy 390.801584 -277.116387) (xy 390.832157 -277.157073) (xy 390.855808 -277.202136)
			(xy 390.871924 -277.25041) (xy 390.880088 -277.300644) (xy 390.8806 -277.32609) (xy 391.198874 -277.32609)
			(xy 391.202834 -277.277036) (xy 391.214611 -277.229252) (xy 391.233902 -277.183976) (xy 391.260205 -277.14238)
			(xy 391.29284 -277.105543) (xy 391.330961 -277.074418) (xy 391.373582 -277.049811) (xy 391.419598 -277.032359)
			(xy 391.467817 -277.022515) (xy 391.516992 -277.020534) (xy 391.565847 -277.026466) (xy 391.613118 -277.040158)
			(xy 391.65758 -277.061256) (xy 391.698083 -277.089212) (xy 391.733576 -277.123304) (xy 391.763141 -277.162648)
			(xy 391.786012 -277.206225) (xy 391.801596 -277.252906) (xy 391.809491 -277.301483) (xy 391.809986 -277.32609)
			(xy 393.078982 -277.32609) (xy 393.082942 -277.277036) (xy 393.094719 -277.229252) (xy 393.11401 -277.183976)
			(xy 393.140313 -277.14238) (xy 393.172948 -277.105543) (xy 393.211069 -277.074418) (xy 393.25369 -277.049811)
			(xy 393.299706 -277.032359) (xy 393.347925 -277.022515) (xy 393.3971 -277.020534) (xy 393.445955 -277.026466)
			(xy 393.493226 -277.040158) (xy 393.537688 -277.061256) (xy 393.578191 -277.089212) (xy 393.613684 -277.123304)
			(xy 393.643249 -277.162648) (xy 393.66612 -277.206225) (xy 393.681704 -277.252906) (xy 393.689599 -277.301483)
			(xy 393.690094 -277.32609) (xy 393.689599 -277.350697) (xy 393.681704 -277.399274) (xy 393.66612 -277.445955)
			(xy 393.643249 -277.489532) (xy 393.613684 -277.528876) (xy 393.578191 -277.562968) (xy 393.537688 -277.590924)
			(xy 393.493226 -277.612022) (xy 393.445955 -277.625714) (xy 393.3971 -277.631646) (xy 393.347925 -277.629665)
			(xy 393.299706 -277.619821) (xy 393.25369 -277.602369) (xy 393.211069 -277.577762) (xy 393.172948 -277.546637)
			(xy 393.140313 -277.5098) (xy 393.11401 -277.468204) (xy 393.094719 -277.422928) (xy 393.082942 -277.375144)
			(xy 393.078982 -277.32609) (xy 391.809986 -277.32609) (xy 391.809491 -277.350697) (xy 391.801596 -277.399274)
			(xy 391.786012 -277.445955) (xy 391.763141 -277.489532) (xy 391.733576 -277.528876) (xy 391.698083 -277.562968)
			(xy 391.65758 -277.590924) (xy 391.613118 -277.612022) (xy 391.565847 -277.625714) (xy 391.516992 -277.631646)
			(xy 391.467817 -277.629665) (xy 391.419598 -277.619821) (xy 391.373582 -277.602369) (xy 391.330961 -277.577762)
			(xy 391.29284 -277.546637) (xy 391.260205 -277.5098) (xy 391.233902 -277.468204) (xy 391.214611 -277.422928)
			(xy 391.202834 -277.375144) (xy 391.198874 -277.32609) (xy 390.8806 -277.32609) (xy 390.880088 -277.351536)
			(xy 390.871924 -277.40177) (xy 390.855808 -277.450044) (xy 390.832157 -277.495107) (xy 390.801584 -277.535793)
			(xy 390.76488 -277.571048) (xy 390.722996 -277.599958) (xy 390.677017 -277.621775) (xy 390.628133 -277.635935)
			(xy 390.577612 -277.642069) (xy 390.52676 -277.64002) (xy 390.476896 -277.62984) (xy 390.42931 -277.611793)
			(xy 390.385236 -277.586347) (xy 390.345814 -277.55416) (xy 390.312066 -277.516066) (xy 390.284865 -277.473052)
			(xy 390.264917 -277.426232) (xy 390.252738 -277.376818) (xy 390.248643 -277.32609) (xy 389.940546 -277.32609)
			(xy 389.940034 -277.351536) (xy 389.93187 -277.40177) (xy 389.915754 -277.450044) (xy 389.892103 -277.495107)
			(xy 389.86153 -277.535793) (xy 389.824826 -277.571048) (xy 389.782942 -277.599958) (xy 389.736963 -277.621775)
			(xy 389.688079 -277.635935) (xy 389.637558 -277.642069) (xy 389.586706 -277.64002) (xy 389.536842 -277.62984)
			(xy 389.489256 -277.611793) (xy 389.445182 -277.586347) (xy 389.40576 -277.55416) (xy 389.372012 -277.516066)
			(xy 389.344811 -277.473052) (xy 389.324863 -277.426232) (xy 389.312684 -277.376818) (xy 389.308589 -277.32609)
			(xy 388.990078 -277.32609) (xy 388.989583 -277.350697) (xy 388.981688 -277.399274) (xy 388.966104 -277.445955)
			(xy 388.943233 -277.489532) (xy 388.913668 -277.528876) (xy 388.878175 -277.562968) (xy 388.837672 -277.590924)
			(xy 388.79321 -277.612022) (xy 388.745939 -277.625714) (xy 388.697084 -277.631646) (xy 388.647909 -277.629665)
			(xy 388.59969 -277.619821) (xy 388.553674 -277.602369) (xy 388.511053 -277.577762) (xy 388.472932 -277.546637)
			(xy 388.440297 -277.5098) (xy 388.413994 -277.468204) (xy 388.394703 -277.422928) (xy 388.382926 -277.375144)
			(xy 388.378966 -277.32609) (xy 388.060438 -277.32609) (xy 388.059926 -277.351536) (xy 388.051762 -277.40177)
			(xy 388.035646 -277.450044) (xy 388.011995 -277.495107) (xy 387.981422 -277.535793) (xy 387.944718 -277.571048)
			(xy 387.902834 -277.599958) (xy 387.856855 -277.621775) (xy 387.807971 -277.635935) (xy 387.75745 -277.642069)
			(xy 387.706598 -277.64002) (xy 387.656734 -277.62984) (xy 387.609148 -277.611793) (xy 387.565074 -277.586347)
			(xy 387.525652 -277.55416) (xy 387.491904 -277.516066) (xy 387.464703 -277.473052) (xy 387.444755 -277.426232)
			(xy 387.432576 -277.376818) (xy 387.428481 -277.32609) (xy 387.110224 -277.32609) (xy 387.109729 -277.350697)
			(xy 387.101834 -277.399274) (xy 387.08625 -277.445955) (xy 387.063379 -277.489532) (xy 387.033814 -277.528876)
			(xy 386.998321 -277.562968) (xy 386.957818 -277.590924) (xy 386.913356 -277.612022) (xy 386.866085 -277.625714)
			(xy 386.81723 -277.631646) (xy 386.768055 -277.629665) (xy 386.719836 -277.619821) (xy 386.67382 -277.602369)
			(xy 386.631199 -277.577762) (xy 386.593078 -277.546637) (xy 386.560443 -277.5098) (xy 386.53414 -277.468204)
			(xy 386.514849 -277.422928) (xy 386.503072 -277.375144) (xy 386.499112 -277.32609) (xy 386.180584 -277.32609)
			(xy 386.180072 -277.351536) (xy 386.171908 -277.40177) (xy 386.155792 -277.450044) (xy 386.132141 -277.495107)
			(xy 386.101568 -277.535793) (xy 386.064864 -277.571048) (xy 386.02298 -277.599958) (xy 385.977001 -277.621775)
			(xy 385.928117 -277.635935) (xy 385.877596 -277.642069) (xy 385.826744 -277.64002) (xy 385.77688 -277.62984)
			(xy 385.729294 -277.611793) (xy 385.68522 -277.586347) (xy 385.645798 -277.55416) (xy 385.61205 -277.516066)
			(xy 385.584849 -277.473052) (xy 385.564901 -277.426232) (xy 385.552722 -277.376818) (xy 385.548627 -277.32609)
			(xy 385.230116 -277.32609) (xy 385.229621 -277.350697) (xy 385.221726 -277.399274) (xy 385.206142 -277.445955)
			(xy 385.183271 -277.489532) (xy 385.153706 -277.528876) (xy 385.118213 -277.562968) (xy 385.07771 -277.590924)
			(xy 385.033248 -277.612022) (xy 384.985977 -277.625714) (xy 384.937122 -277.631646) (xy 384.887947 -277.629665)
			(xy 384.839728 -277.619821) (xy 384.793712 -277.602369) (xy 384.751091 -277.577762) (xy 384.71297 -277.546637)
			(xy 384.680335 -277.5098) (xy 384.654032 -277.468204) (xy 384.634741 -277.422928) (xy 384.622964 -277.375144)
			(xy 384.619004 -277.32609) (xy 384.300476 -277.32609) (xy 384.299964 -277.351536) (xy 384.2918 -277.40177)
			(xy 384.275684 -277.450044) (xy 384.252033 -277.495107) (xy 384.22146 -277.535793) (xy 384.184756 -277.571048)
			(xy 384.142872 -277.599958) (xy 384.096893 -277.621775) (xy 384.048009 -277.635935) (xy 383.997488 -277.642069)
			(xy 383.946636 -277.64002) (xy 383.896772 -277.62984) (xy 383.849186 -277.611793) (xy 383.805112 -277.586347)
			(xy 383.76569 -277.55416) (xy 383.731942 -277.516066) (xy 383.704741 -277.473052) (xy 383.684793 -277.426232)
			(xy 383.672614 -277.376818) (xy 383.668519 -277.32609) (xy 383.360422 -277.32609) (xy 383.35991 -277.351536)
			(xy 383.351746 -277.40177) (xy 383.33563 -277.450044) (xy 383.311979 -277.495107) (xy 383.281406 -277.535793)
			(xy 383.244702 -277.571048) (xy 383.202818 -277.599958) (xy 383.156839 -277.621775) (xy 383.107955 -277.635935)
			(xy 383.057434 -277.642069) (xy 383.006582 -277.64002) (xy 382.956718 -277.62984) (xy 382.909132 -277.611793)
			(xy 382.865058 -277.586347) (xy 382.825636 -277.55416) (xy 382.791888 -277.516066) (xy 382.764687 -277.473052)
			(xy 382.744739 -277.426232) (xy 382.73256 -277.376818) (xy 382.728465 -277.32609) (xy 382.410208 -277.32609)
			(xy 382.409713 -277.350697) (xy 382.401818 -277.399274) (xy 382.386234 -277.445955) (xy 382.363363 -277.489532)
			(xy 382.333798 -277.528876) (xy 382.298305 -277.562968) (xy 382.257802 -277.590924) (xy 382.21334 -277.612022)
			(xy 382.166069 -277.625714) (xy 382.117214 -277.631646) (xy 382.068039 -277.629665) (xy 382.01982 -277.619821)
			(xy 381.973804 -277.602369) (xy 381.931183 -277.577762) (xy 381.893062 -277.546637) (xy 381.860427 -277.5098)
			(xy 381.834124 -277.468204) (xy 381.814833 -277.422928) (xy 381.803056 -277.375144) (xy 381.799096 -277.32609)
			(xy 381.480568 -277.32609) (xy 381.480056 -277.351536) (xy 381.471892 -277.40177) (xy 381.455776 -277.450044)
			(xy 381.432125 -277.495107) (xy 381.401552 -277.535793) (xy 381.364848 -277.571048) (xy 381.322964 -277.599958)
			(xy 381.276985 -277.621775) (xy 381.228101 -277.635935) (xy 381.17758 -277.642069) (xy 381.126728 -277.64002)
			(xy 381.076864 -277.62984) (xy 381.029278 -277.611793) (xy 380.985204 -277.586347) (xy 380.945782 -277.55416)
			(xy 380.912034 -277.516066) (xy 380.884833 -277.473052) (xy 380.864885 -277.426232) (xy 380.852706 -277.376818)
			(xy 380.848611 -277.32609) (xy 380.5301 -277.32609) (xy 380.529605 -277.350697) (xy 380.52171 -277.399274)
			(xy 380.506126 -277.445955) (xy 380.483255 -277.489532) (xy 380.45369 -277.528876) (xy 380.418197 -277.562968)
			(xy 380.377694 -277.590924) (xy 380.333232 -277.612022) (xy 380.285961 -277.625714) (xy 380.237106 -277.631646)
			(xy 380.187931 -277.629665) (xy 380.139712 -277.619821) (xy 380.093696 -277.602369) (xy 380.051075 -277.577762)
			(xy 380.012954 -277.546637) (xy 379.980319 -277.5098) (xy 379.954016 -277.468204) (xy 379.934725 -277.422928)
			(xy 379.922948 -277.375144) (xy 379.918988 -277.32609) (xy 379.60046 -277.32609) (xy 379.599948 -277.351536)
			(xy 379.591784 -277.40177) (xy 379.575668 -277.450044) (xy 379.552017 -277.495107) (xy 379.521444 -277.535793)
			(xy 379.48474 -277.571048) (xy 379.442856 -277.599958) (xy 379.396877 -277.621775) (xy 379.347993 -277.635935)
			(xy 379.297472 -277.642069) (xy 379.24662 -277.64002) (xy 379.196756 -277.62984) (xy 379.14917 -277.611793)
			(xy 379.105096 -277.586347) (xy 379.065674 -277.55416) (xy 379.031926 -277.516066) (xy 379.004725 -277.473052)
			(xy 378.984777 -277.426232) (xy 378.972598 -277.376818) (xy 378.968503 -277.32609) (xy 378.650246 -277.32609)
			(xy 378.649751 -277.350697) (xy 378.641856 -277.399274) (xy 378.626272 -277.445955) (xy 378.603401 -277.489532)
			(xy 378.573836 -277.528876) (xy 378.538343 -277.562968) (xy 378.49784 -277.590924) (xy 378.453378 -277.612022)
			(xy 378.406107 -277.625714) (xy 378.357252 -277.631646) (xy 378.308077 -277.629665) (xy 378.259858 -277.619821)
			(xy 378.213842 -277.602369) (xy 378.171221 -277.577762) (xy 378.1331 -277.546637) (xy 378.100465 -277.5098)
			(xy 378.074162 -277.468204) (xy 378.054871 -277.422928) (xy 378.043094 -277.375144) (xy 378.039134 -277.32609)
			(xy 377.720606 -277.32609) (xy 377.720094 -277.351536) (xy 377.71193 -277.40177) (xy 377.695814 -277.450044)
			(xy 377.672163 -277.495107) (xy 377.64159 -277.535793) (xy 377.604886 -277.571048) (xy 377.563002 -277.599958)
			(xy 377.517023 -277.621775) (xy 377.468139 -277.635935) (xy 377.417618 -277.642069) (xy 377.366766 -277.64002)
			(xy 377.316902 -277.62984) (xy 377.269316 -277.611793) (xy 377.225242 -277.586347) (xy 377.18582 -277.55416)
			(xy 377.152072 -277.516066) (xy 377.124871 -277.473052) (xy 377.104923 -277.426232) (xy 377.092744 -277.376818)
			(xy 377.088649 -277.32609) (xy 376.780552 -277.32609) (xy 376.78004 -277.351536) (xy 376.771876 -277.40177)
			(xy 376.75576 -277.450044) (xy 376.732109 -277.495107) (xy 376.701536 -277.535793) (xy 376.664832 -277.571048)
			(xy 376.622948 -277.599958) (xy 376.576969 -277.621775) (xy 376.528085 -277.635935) (xy 376.477564 -277.642069)
			(xy 376.426712 -277.64002) (xy 376.376848 -277.62984) (xy 376.329262 -277.611793) (xy 376.285188 -277.586347)
			(xy 376.245766 -277.55416) (xy 376.212018 -277.516066) (xy 376.184817 -277.473052) (xy 376.164869 -277.426232)
			(xy 376.15269 -277.376818) (xy 376.148595 -277.32609) (xy 375.1961 -277.32609) (xy 375.1961 -277.836122)
			(xy 375.196382 -277.844647) (xy 375.201924 -277.860769) (xy 375.212478 -277.874156) (xy 375.219468 -277.879048)
			(xy 375.240667 -277.893212) (xy 375.278455 -277.927433) (xy 375.31003 -277.967457) (xy 375.334513 -278.012173)
			(xy 375.351224 -278.060337) (xy 375.359697 -278.110608) (xy 375.359697 -278.136096) (xy 375.678695 -278.136096)
			(xy 375.68279 -278.085368) (xy 375.694969 -278.035954) (xy 375.714917 -277.989134) (xy 375.742118 -277.94612)
			(xy 375.775866 -277.908026) (xy 375.815288 -277.875839) (xy 375.859362 -277.850393) (xy 375.906948 -277.832346)
			(xy 375.956812 -277.822166) (xy 376.007664 -277.820117) (xy 376.058185 -277.826251) (xy 376.107069 -277.840411)
			(xy 376.153048 -277.862228) (xy 376.194932 -277.891138) (xy 376.231636 -277.926393) (xy 376.262209 -277.967079)
			(xy 376.28586 -278.012142) (xy 376.301976 -278.060416) (xy 376.31014 -278.11065) (xy 376.310652 -278.136096)
			(xy 376.628926 -278.136096) (xy 376.632886 -278.087042) (xy 376.644663 -278.039258) (xy 376.663954 -277.993982)
			(xy 376.690257 -277.952386) (xy 376.722892 -277.915549) (xy 376.761013 -277.884424) (xy 376.803634 -277.859817)
			(xy 376.84965 -277.842365) (xy 376.897869 -277.832521) (xy 376.947044 -277.83054) (xy 376.995899 -277.836472)
			(xy 377.04317 -277.850164) (xy 377.087632 -277.871262) (xy 377.128135 -277.899218) (xy 377.163628 -277.93331)
			(xy 377.193193 -277.972654) (xy 377.216064 -278.016231) (xy 377.231648 -278.062912) (xy 377.239543 -278.111489)
			(xy 377.240038 -278.136096) (xy 377.558549 -278.136096) (xy 377.562644 -278.085368) (xy 377.574823 -278.035954)
			(xy 377.594771 -277.989134) (xy 377.621972 -277.94612) (xy 377.65572 -277.908026) (xy 377.695142 -277.875839)
			(xy 377.739216 -277.850393) (xy 377.786802 -277.832346) (xy 377.836666 -277.822166) (xy 377.887518 -277.820117)
			(xy 377.938039 -277.826251) (xy 377.986923 -277.840411) (xy 378.032902 -277.862228) (xy 378.074786 -277.891138)
			(xy 378.11149 -277.926393) (xy 378.142063 -277.967079) (xy 378.165714 -278.012142) (xy 378.18183 -278.060416)
			(xy 378.189994 -278.11065) (xy 378.190506 -278.136096) (xy 379.438657 -278.136096) (xy 379.442752 -278.085368)
			(xy 379.454931 -278.035954) (xy 379.474879 -277.989134) (xy 379.50208 -277.94612) (xy 379.535828 -277.908026)
			(xy 379.57525 -277.875839) (xy 379.619324 -277.850393) (xy 379.66691 -277.832346) (xy 379.716774 -277.822166)
			(xy 379.767626 -277.820117) (xy 379.818147 -277.826251) (xy 379.867031 -277.840411) (xy 379.91301 -277.862228)
			(xy 379.954894 -277.891138) (xy 379.991598 -277.926393) (xy 380.022171 -277.967079) (xy 380.045822 -278.012142)
			(xy 380.061938 -278.060416) (xy 380.070102 -278.11065) (xy 380.070614 -278.136096) (xy 380.378711 -278.136096)
			(xy 380.382806 -278.085368) (xy 380.394985 -278.035954) (xy 380.414933 -277.989134) (xy 380.442134 -277.94612)
			(xy 380.475882 -277.908026) (xy 380.515304 -277.875839) (xy 380.559378 -277.850393) (xy 380.606964 -277.832346)
			(xy 380.656828 -277.822166) (xy 380.70768 -277.820117) (xy 380.758201 -277.826251) (xy 380.807085 -277.840411)
			(xy 380.853064 -277.862228) (xy 380.894948 -277.891138) (xy 380.931652 -277.926393) (xy 380.962225 -277.967079)
			(xy 380.985876 -278.012142) (xy 381.001992 -278.060416) (xy 381.010156 -278.11065) (xy 381.010668 -278.136096)
			(xy 381.328942 -278.136096) (xy 381.332902 -278.087042) (xy 381.344679 -278.039258) (xy 381.36397 -277.993982)
			(xy 381.390273 -277.952386) (xy 381.422908 -277.915549) (xy 381.461029 -277.884424) (xy 381.50365 -277.859817)
			(xy 381.549666 -277.842365) (xy 381.597885 -277.832521) (xy 381.64706 -277.83054) (xy 381.695915 -277.836472)
			(xy 381.743186 -277.850164) (xy 381.787648 -277.871262) (xy 381.828151 -277.899218) (xy 381.863644 -277.93331)
			(xy 381.893209 -277.972654) (xy 381.91608 -278.016231) (xy 381.931664 -278.062912) (xy 381.939559 -278.111489)
			(xy 381.940054 -278.136096) (xy 382.258565 -278.136096) (xy 382.26266 -278.085368) (xy 382.274839 -278.035954)
			(xy 382.294787 -277.989134) (xy 382.321988 -277.94612) (xy 382.355736 -277.908026) (xy 382.395158 -277.875839)
			(xy 382.439232 -277.850393) (xy 382.486818 -277.832346) (xy 382.536682 -277.822166) (xy 382.587534 -277.820117)
			(xy 382.638055 -277.826251) (xy 382.686939 -277.840411) (xy 382.732918 -277.862228) (xy 382.774802 -277.891138)
			(xy 382.811506 -277.926393) (xy 382.842079 -277.967079) (xy 382.86573 -278.012142) (xy 382.881846 -278.060416)
			(xy 382.89001 -278.11065) (xy 382.890522 -278.136096) (xy 383.20905 -278.136096) (xy 383.21301 -278.087042)
			(xy 383.224787 -278.039258) (xy 383.244078 -277.993982) (xy 383.270381 -277.952386) (xy 383.303016 -277.915549)
			(xy 383.341137 -277.884424) (xy 383.383758 -277.859817) (xy 383.429774 -277.842365) (xy 383.477993 -277.832521)
			(xy 383.527168 -277.83054) (xy 383.576023 -277.836472) (xy 383.623294 -277.850164) (xy 383.667756 -277.871262)
			(xy 383.708259 -277.899218) (xy 383.743752 -277.93331) (xy 383.773317 -277.972654) (xy 383.796188 -278.016231)
			(xy 383.811772 -278.062912) (xy 383.819667 -278.111489) (xy 383.820162 -278.136096) (xy 384.138673 -278.136096)
			(xy 384.142768 -278.085368) (xy 384.154947 -278.035954) (xy 384.174895 -277.989134) (xy 384.202096 -277.94612)
			(xy 384.235844 -277.908026) (xy 384.275266 -277.875839) (xy 384.31934 -277.850393) (xy 384.366926 -277.832346)
			(xy 384.41679 -277.822166) (xy 384.467642 -277.820117) (xy 384.518163 -277.826251) (xy 384.567047 -277.840411)
			(xy 384.613026 -277.862228) (xy 384.65491 -277.891138) (xy 384.691614 -277.926393) (xy 384.722187 -277.967079)
			(xy 384.745838 -278.012142) (xy 384.761954 -278.060416) (xy 384.770118 -278.11065) (xy 384.77063 -278.136096)
			(xy 386.018527 -278.136096) (xy 386.022622 -278.085368) (xy 386.034801 -278.035954) (xy 386.054749 -277.989134)
			(xy 386.08195 -277.94612) (xy 386.115698 -277.908026) (xy 386.15512 -277.875839) (xy 386.199194 -277.850393)
			(xy 386.24678 -277.832346) (xy 386.296644 -277.822166) (xy 386.347496 -277.820117) (xy 386.398017 -277.826251)
			(xy 386.446901 -277.840411) (xy 386.49288 -277.862228) (xy 386.534764 -277.891138) (xy 386.571468 -277.926393)
			(xy 386.602041 -277.967079) (xy 386.625692 -278.012142) (xy 386.641808 -278.060416) (xy 386.649972 -278.11065)
			(xy 386.650484 -278.136096) (xy 386.958581 -278.136096) (xy 386.962676 -278.085368) (xy 386.974855 -278.035954)
			(xy 386.994803 -277.989134) (xy 387.022004 -277.94612) (xy 387.055752 -277.908026) (xy 387.095174 -277.875839)
			(xy 387.139248 -277.850393) (xy 387.186834 -277.832346) (xy 387.236698 -277.822166) (xy 387.28755 -277.820117)
			(xy 387.338071 -277.826251) (xy 387.386955 -277.840411) (xy 387.432934 -277.862228) (xy 387.474818 -277.891138)
			(xy 387.511522 -277.926393) (xy 387.542095 -277.967079) (xy 387.565746 -278.012142) (xy 387.581862 -278.060416)
			(xy 387.590026 -278.11065) (xy 387.590538 -278.136096) (xy 387.909066 -278.136096) (xy 387.913026 -278.087042)
			(xy 387.924803 -278.039258) (xy 387.944094 -277.993982) (xy 387.970397 -277.952386) (xy 388.003032 -277.915549)
			(xy 388.041153 -277.884424) (xy 388.083774 -277.859817) (xy 388.12979 -277.842365) (xy 388.178009 -277.832521)
			(xy 388.227184 -277.83054) (xy 388.276039 -277.836472) (xy 388.32331 -277.850164) (xy 388.367772 -277.871262)
			(xy 388.408275 -277.899218) (xy 388.443768 -277.93331) (xy 388.473333 -277.972654) (xy 388.496204 -278.016231)
			(xy 388.511788 -278.062912) (xy 388.519683 -278.111489) (xy 388.520178 -278.136096) (xy 388.838689 -278.136096)
			(xy 388.842784 -278.085368) (xy 388.854963 -278.035954) (xy 388.874911 -277.989134) (xy 388.902112 -277.94612)
			(xy 388.93586 -277.908026) (xy 388.975282 -277.875839) (xy 389.019356 -277.850393) (xy 389.066942 -277.832346)
			(xy 389.116806 -277.822166) (xy 389.167658 -277.820117) (xy 389.218179 -277.826251) (xy 389.267063 -277.840411)
			(xy 389.313042 -277.862228) (xy 389.354926 -277.891138) (xy 389.39163 -277.926393) (xy 389.422203 -277.967079)
			(xy 389.445854 -278.012142) (xy 389.46197 -278.060416) (xy 389.470134 -278.11065) (xy 389.470646 -278.136096)
			(xy 389.78892 -278.136096) (xy 389.79288 -278.087042) (xy 389.804657 -278.039258) (xy 389.823948 -277.993982)
			(xy 389.850251 -277.952386) (xy 389.882886 -277.915549) (xy 389.921007 -277.884424) (xy 389.963628 -277.859817)
			(xy 390.009644 -277.842365) (xy 390.057863 -277.832521) (xy 390.107038 -277.83054) (xy 390.155893 -277.836472)
			(xy 390.203164 -277.850164) (xy 390.247626 -277.871262) (xy 390.288129 -277.899218) (xy 390.323622 -277.93331)
			(xy 390.353187 -277.972654) (xy 390.376058 -278.016231) (xy 390.391642 -278.062912) (xy 390.399537 -278.111489)
			(xy 390.400032 -278.136096) (xy 390.718543 -278.136096) (xy 390.722638 -278.085368) (xy 390.734817 -278.035954)
			(xy 390.754765 -277.989134) (xy 390.781966 -277.94612) (xy 390.815714 -277.908026) (xy 390.855136 -277.875839)
			(xy 390.89921 -277.850393) (xy 390.946796 -277.832346) (xy 390.99666 -277.822166) (xy 391.047512 -277.820117)
			(xy 391.098033 -277.826251) (xy 391.146917 -277.840411) (xy 391.192896 -277.862228) (xy 391.204385 -277.870158)
			(xy 394.67715 -277.870158) (xy 394.68111 -277.821104) (xy 394.692887 -277.77332) (xy 394.712178 -277.728044)
			(xy 394.738481 -277.686448) (xy 394.771116 -277.649611) (xy 394.809237 -277.618486) (xy 394.851858 -277.593879)
			(xy 394.897874 -277.576427) (xy 394.946093 -277.566583) (xy 394.995268 -277.564602) (xy 395.044123 -277.570534)
			(xy 395.091394 -277.584226) (xy 395.135856 -277.605324) (xy 395.176359 -277.63328) (xy 395.211852 -277.667372)
			(xy 395.241417 -277.706716) (xy 395.264288 -277.750293) (xy 395.279872 -277.796974) (xy 395.287767 -277.845551)
			(xy 395.288262 -277.870158) (xy 395.287767 -277.894765) (xy 395.279872 -277.943342) (xy 395.264288 -277.990023)
			(xy 395.241417 -278.0336) (xy 395.211852 -278.072944) (xy 395.176359 -278.107036) (xy 395.135856 -278.134992)
			(xy 395.091394 -278.15609) (xy 395.044123 -278.169782) (xy 394.995268 -278.175714) (xy 394.946093 -278.173733)
			(xy 394.897874 -278.163889) (xy 394.851858 -278.146437) (xy 394.809237 -278.12183) (xy 394.771116 -278.090705)
			(xy 394.738481 -278.053868) (xy 394.712178 -278.012272) (xy 394.692887 -277.966996) (xy 394.68111 -277.919212)
			(xy 394.67715 -277.870158) (xy 391.204385 -277.870158) (xy 391.23478 -277.891138) (xy 391.271484 -277.926393)
			(xy 391.302057 -277.967079) (xy 391.325708 -278.012142) (xy 391.341824 -278.060416) (xy 391.349988 -278.11065)
			(xy 391.3505 -278.136096) (xy 391.349988 -278.161542) (xy 391.341824 -278.211776) (xy 391.325708 -278.26005)
			(xy 391.302057 -278.305113) (xy 391.271484 -278.345799) (xy 391.23478 -278.381054) (xy 391.192896 -278.409964)
			(xy 391.146917 -278.431781) (xy 391.098033 -278.445941) (xy 391.047512 -278.452075) (xy 390.99666 -278.450026)
			(xy 390.946796 -278.439846) (xy 390.89921 -278.421799) (xy 390.855136 -278.396353) (xy 390.815714 -278.364166)
			(xy 390.781966 -278.326072) (xy 390.754765 -278.283058) (xy 390.734817 -278.236238) (xy 390.722638 -278.186824)
			(xy 390.718543 -278.136096) (xy 390.400032 -278.136096) (xy 390.399537 -278.160703) (xy 390.391642 -278.20928)
			(xy 390.376058 -278.255961) (xy 390.353187 -278.299538) (xy 390.323622 -278.338882) (xy 390.288129 -278.372974)
			(xy 390.247626 -278.40093) (xy 390.203164 -278.422028) (xy 390.155893 -278.43572) (xy 390.107038 -278.441652)
			(xy 390.057863 -278.439671) (xy 390.009644 -278.429827) (xy 389.963628 -278.412375) (xy 389.921007 -278.387768)
			(xy 389.882886 -278.356643) (xy 389.850251 -278.319806) (xy 389.823948 -278.27821) (xy 389.804657 -278.232934)
			(xy 389.79288 -278.18515) (xy 389.78892 -278.136096) (xy 389.470646 -278.136096) (xy 389.470134 -278.161542)
			(xy 389.46197 -278.211776) (xy 389.445854 -278.26005) (xy 389.422203 -278.305113) (xy 389.39163 -278.345799)
			(xy 389.354926 -278.381054) (xy 389.313042 -278.409964) (xy 389.267063 -278.431781) (xy 389.218179 -278.445941)
			(xy 389.167658 -278.452075) (xy 389.116806 -278.450026) (xy 389.066942 -278.439846) (xy 389.019356 -278.421799)
			(xy 388.975282 -278.396353) (xy 388.93586 -278.364166) (xy 388.902112 -278.326072) (xy 388.874911 -278.283058)
			(xy 388.854963 -278.236238) (xy 388.842784 -278.186824) (xy 388.838689 -278.136096) (xy 388.520178 -278.136096)
			(xy 388.519683 -278.160703) (xy 388.511788 -278.20928) (xy 388.496204 -278.255961) (xy 388.473333 -278.299538)
			(xy 388.443768 -278.338882) (xy 388.408275 -278.372974) (xy 388.367772 -278.40093) (xy 388.32331 -278.422028)
			(xy 388.276039 -278.43572) (xy 388.227184 -278.441652) (xy 388.178009 -278.439671) (xy 388.12979 -278.429827)
			(xy 388.083774 -278.412375) (xy 388.041153 -278.387768) (xy 388.003032 -278.356643) (xy 387.970397 -278.319806)
			(xy 387.944094 -278.27821) (xy 387.924803 -278.232934) (xy 387.913026 -278.18515) (xy 387.909066 -278.136096)
			(xy 387.590538 -278.136096) (xy 387.590026 -278.161542) (xy 387.581862 -278.211776) (xy 387.565746 -278.26005)
			(xy 387.542095 -278.305113) (xy 387.511522 -278.345799) (xy 387.474818 -278.381054) (xy 387.432934 -278.409964)
			(xy 387.386955 -278.431781) (xy 387.338071 -278.445941) (xy 387.28755 -278.452075) (xy 387.236698 -278.450026)
			(xy 387.186834 -278.439846) (xy 387.139248 -278.421799) (xy 387.095174 -278.396353) (xy 387.055752 -278.364166)
			(xy 387.022004 -278.326072) (xy 386.994803 -278.283058) (xy 386.974855 -278.236238) (xy 386.962676 -278.186824)
			(xy 386.958581 -278.136096) (xy 386.650484 -278.136096) (xy 386.649972 -278.161542) (xy 386.641808 -278.211776)
			(xy 386.625692 -278.26005) (xy 386.602041 -278.305113) (xy 386.571468 -278.345799) (xy 386.534764 -278.381054)
			(xy 386.49288 -278.409964) (xy 386.446901 -278.431781) (xy 386.398017 -278.445941) (xy 386.347496 -278.452075)
			(xy 386.296644 -278.450026) (xy 386.24678 -278.439846) (xy 386.199194 -278.421799) (xy 386.15512 -278.396353)
			(xy 386.115698 -278.364166) (xy 386.08195 -278.326072) (xy 386.054749 -278.283058) (xy 386.034801 -278.236238)
			(xy 386.022622 -278.186824) (xy 386.018527 -278.136096) (xy 384.77063 -278.136096) (xy 384.770118 -278.161542)
			(xy 384.761954 -278.211776) (xy 384.745838 -278.26005) (xy 384.722187 -278.305113) (xy 384.691614 -278.345799)
			(xy 384.65491 -278.381054) (xy 384.613026 -278.409964) (xy 384.567047 -278.431781) (xy 384.518163 -278.445941)
			(xy 384.467642 -278.452075) (xy 384.41679 -278.450026) (xy 384.366926 -278.439846) (xy 384.31934 -278.421799)
			(xy 384.275266 -278.396353) (xy 384.235844 -278.364166) (xy 384.202096 -278.326072) (xy 384.174895 -278.283058)
			(xy 384.154947 -278.236238) (xy 384.142768 -278.186824) (xy 384.138673 -278.136096) (xy 383.820162 -278.136096)
			(xy 383.819667 -278.160703) (xy 383.811772 -278.20928) (xy 383.796188 -278.255961) (xy 383.773317 -278.299538)
			(xy 383.743752 -278.338882) (xy 383.708259 -278.372974) (xy 383.667756 -278.40093) (xy 383.623294 -278.422028)
			(xy 383.576023 -278.43572) (xy 383.527168 -278.441652) (xy 383.477993 -278.439671) (xy 383.429774 -278.429827)
			(xy 383.383758 -278.412375) (xy 383.341137 -278.387768) (xy 383.303016 -278.356643) (xy 383.270381 -278.319806)
			(xy 383.244078 -278.27821) (xy 383.224787 -278.232934) (xy 383.21301 -278.18515) (xy 383.20905 -278.136096)
			(xy 382.890522 -278.136096) (xy 382.89001 -278.161542) (xy 382.881846 -278.211776) (xy 382.86573 -278.26005)
			(xy 382.842079 -278.305113) (xy 382.811506 -278.345799) (xy 382.774802 -278.381054) (xy 382.732918 -278.409964)
			(xy 382.686939 -278.431781) (xy 382.638055 -278.445941) (xy 382.587534 -278.452075) (xy 382.536682 -278.450026)
			(xy 382.486818 -278.439846) (xy 382.439232 -278.421799) (xy 382.395158 -278.396353) (xy 382.355736 -278.364166)
			(xy 382.321988 -278.326072) (xy 382.294787 -278.283058) (xy 382.274839 -278.236238) (xy 382.26266 -278.186824)
			(xy 382.258565 -278.136096) (xy 381.940054 -278.136096) (xy 381.939559 -278.160703) (xy 381.931664 -278.20928)
			(xy 381.91608 -278.255961) (xy 381.893209 -278.299538) (xy 381.863644 -278.338882) (xy 381.828151 -278.372974)
			(xy 381.787648 -278.40093) (xy 381.743186 -278.422028) (xy 381.695915 -278.43572) (xy 381.64706 -278.441652)
			(xy 381.597885 -278.439671) (xy 381.549666 -278.429827) (xy 381.50365 -278.412375) (xy 381.461029 -278.387768)
			(xy 381.422908 -278.356643) (xy 381.390273 -278.319806) (xy 381.36397 -278.27821) (xy 381.344679 -278.232934)
			(xy 381.332902 -278.18515) (xy 381.328942 -278.136096) (xy 381.010668 -278.136096) (xy 381.010156 -278.161542)
			(xy 381.001992 -278.211776) (xy 380.985876 -278.26005) (xy 380.962225 -278.305113) (xy 380.931652 -278.345799)
			(xy 380.894948 -278.381054) (xy 380.853064 -278.409964) (xy 380.807085 -278.431781) (xy 380.758201 -278.445941)
			(xy 380.70768 -278.452075) (xy 380.656828 -278.450026) (xy 380.606964 -278.439846) (xy 380.559378 -278.421799)
			(xy 380.515304 -278.396353) (xy 380.475882 -278.364166) (xy 380.442134 -278.326072) (xy 380.414933 -278.283058)
			(xy 380.394985 -278.236238) (xy 380.382806 -278.186824) (xy 380.378711 -278.136096) (xy 380.070614 -278.136096)
			(xy 380.070102 -278.161542) (xy 380.061938 -278.211776) (xy 380.045822 -278.26005) (xy 380.022171 -278.305113)
			(xy 379.991598 -278.345799) (xy 379.954894 -278.381054) (xy 379.91301 -278.409964) (xy 379.867031 -278.431781)
			(xy 379.818147 -278.445941) (xy 379.767626 -278.452075) (xy 379.716774 -278.450026) (xy 379.66691 -278.439846)
			(xy 379.619324 -278.421799) (xy 379.57525 -278.396353) (xy 379.535828 -278.364166) (xy 379.50208 -278.326072)
			(xy 379.474879 -278.283058) (xy 379.454931 -278.236238) (xy 379.442752 -278.186824) (xy 379.438657 -278.136096)
			(xy 378.190506 -278.136096) (xy 378.189994 -278.161542) (xy 378.18183 -278.211776) (xy 378.165714 -278.26005)
			(xy 378.142063 -278.305113) (xy 378.11149 -278.345799) (xy 378.074786 -278.381054) (xy 378.032902 -278.409964)
			(xy 377.986923 -278.431781) (xy 377.938039 -278.445941) (xy 377.887518 -278.452075) (xy 377.836666 -278.450026)
			(xy 377.786802 -278.439846) (xy 377.739216 -278.421799) (xy 377.695142 -278.396353) (xy 377.65572 -278.364166)
			(xy 377.621972 -278.326072) (xy 377.594771 -278.283058) (xy 377.574823 -278.236238) (xy 377.562644 -278.186824)
			(xy 377.558549 -278.136096) (xy 377.240038 -278.136096) (xy 377.239543 -278.160703) (xy 377.231648 -278.20928)
			(xy 377.216064 -278.255961) (xy 377.193193 -278.299538) (xy 377.163628 -278.338882) (xy 377.128135 -278.372974)
			(xy 377.087632 -278.40093) (xy 377.04317 -278.422028) (xy 376.995899 -278.43572) (xy 376.947044 -278.441652)
			(xy 376.897869 -278.439671) (xy 376.84965 -278.429827) (xy 376.803634 -278.412375) (xy 376.761013 -278.387768)
			(xy 376.722892 -278.356643) (xy 376.690257 -278.319806) (xy 376.663954 -278.27821) (xy 376.644663 -278.232934)
			(xy 376.632886 -278.18515) (xy 376.628926 -278.136096) (xy 376.310652 -278.136096) (xy 376.31014 -278.161542)
			(xy 376.301976 -278.211776) (xy 376.28586 -278.26005) (xy 376.262209 -278.305113) (xy 376.231636 -278.345799)
			(xy 376.194932 -278.381054) (xy 376.153048 -278.409964) (xy 376.107069 -278.431781) (xy 376.058185 -278.445941)
			(xy 376.007664 -278.452075) (xy 375.956812 -278.450026) (xy 375.906948 -278.439846) (xy 375.859362 -278.421799)
			(xy 375.815288 -278.396353) (xy 375.775866 -278.364166) (xy 375.742118 -278.326072) (xy 375.714917 -278.283058)
			(xy 375.694969 -278.236238) (xy 375.68279 -278.186824) (xy 375.678695 -278.136096) (xy 375.359697 -278.136096)
			(xy 375.359698 -278.161588) (xy 375.351225 -278.211859) (xy 375.334515 -278.260023) (xy 375.310032 -278.304739)
			(xy 375.278458 -278.344764) (xy 375.24067 -278.378985) (xy 375.219468 -278.393144) (xy 375.212479 -278.398028)
			(xy 375.201965 -278.411438) (xy 375.196414 -278.427549) (xy 375.1961 -278.43607) (xy 375.1961 -278.608282)
			(xy 375.196498 -278.617483) (xy 375.202979 -278.634709) (xy 375.215089 -278.648567) (xy 375.223024 -278.65324)
			(xy 375.314718 -278.702262) (xy 375.342404 -278.700738) (xy 375.354342 -278.692864) (xy 375.373328 -278.680566)
			(xy 375.414162 -278.661103) (xy 375.457421 -278.647879) (xy 375.502159 -278.641185) (xy 375.524776 -278.640794)
			(xy 375.550035 -278.641285) (xy 375.599864 -278.649596) (xy 375.647646 -278.665996) (xy 375.692076 -278.690038)
			(xy 375.731943 -278.721064) (xy 375.766159 -278.75823) (xy 375.79379 -278.800521) (xy 375.814084 -278.846783)
			(xy 375.826486 -278.895755) (xy 375.830658 -278.9461) (xy 375.830658 -278.946102) (xy 376.148595 -278.946102)
			(xy 376.15269 -278.895374) (xy 376.164869 -278.84596) (xy 376.184817 -278.79914) (xy 376.212018 -278.756126)
			(xy 376.245766 -278.718032) (xy 376.285188 -278.685845) (xy 376.329262 -278.660399) (xy 376.376848 -278.642352)
			(xy 376.426712 -278.632172) (xy 376.477564 -278.630123) (xy 376.528085 -278.636257) (xy 376.576969 -278.650417)
			(xy 376.622948 -278.672234) (xy 376.664832 -278.701144) (xy 376.701536 -278.736399) (xy 376.732109 -278.777085)
			(xy 376.75576 -278.822148) (xy 376.771876 -278.870422) (xy 376.78004 -278.920656) (xy 376.780552 -278.946102)
			(xy 377.088649 -278.946102) (xy 377.092744 -278.895374) (xy 377.104923 -278.84596) (xy 377.124871 -278.79914)
			(xy 377.152072 -278.756126) (xy 377.18582 -278.718032) (xy 377.225242 -278.685845) (xy 377.269316 -278.660399)
			(xy 377.316902 -278.642352) (xy 377.366766 -278.632172) (xy 377.417618 -278.630123) (xy 377.468139 -278.636257)
			(xy 377.517023 -278.650417) (xy 377.563002 -278.672234) (xy 377.604886 -278.701144) (xy 377.64159 -278.736399)
			(xy 377.672163 -278.777085) (xy 377.695814 -278.822148) (xy 377.71193 -278.870422) (xy 377.720094 -278.920656)
			(xy 377.720606 -278.946102) (xy 378.039134 -278.946102) (xy 378.043094 -278.897048) (xy 378.054871 -278.849264)
			(xy 378.074162 -278.803988) (xy 378.100465 -278.762392) (xy 378.1331 -278.725555) (xy 378.171221 -278.69443)
			(xy 378.213842 -278.669823) (xy 378.259858 -278.652371) (xy 378.308077 -278.642527) (xy 378.357252 -278.640546)
			(xy 378.406107 -278.646478) (xy 378.453378 -278.66017) (xy 378.49784 -278.681268) (xy 378.538343 -278.709224)
			(xy 378.573836 -278.743316) (xy 378.603401 -278.78266) (xy 378.626272 -278.826237) (xy 378.641856 -278.872918)
			(xy 378.649751 -278.921495) (xy 378.650246 -278.946102) (xy 378.968503 -278.946102) (xy 378.972598 -278.895374)
			(xy 378.984777 -278.84596) (xy 379.004725 -278.79914) (xy 379.031926 -278.756126) (xy 379.065674 -278.718032)
			(xy 379.105096 -278.685845) (xy 379.14917 -278.660399) (xy 379.196756 -278.642352) (xy 379.24662 -278.632172)
			(xy 379.297472 -278.630123) (xy 379.347993 -278.636257) (xy 379.396877 -278.650417) (xy 379.442856 -278.672234)
			(xy 379.48474 -278.701144) (xy 379.521444 -278.736399) (xy 379.552017 -278.777085) (xy 379.575668 -278.822148)
			(xy 379.591784 -278.870422) (xy 379.599948 -278.920656) (xy 379.60046 -278.946102) (xy 379.918988 -278.946102)
			(xy 379.922948 -278.897048) (xy 379.934725 -278.849264) (xy 379.954016 -278.803988) (xy 379.980319 -278.762392)
			(xy 380.012954 -278.725555) (xy 380.051075 -278.69443) (xy 380.093696 -278.669823) (xy 380.139712 -278.652371)
			(xy 380.187931 -278.642527) (xy 380.237106 -278.640546) (xy 380.285961 -278.646478) (xy 380.333232 -278.66017)
			(xy 380.377694 -278.681268) (xy 380.418197 -278.709224) (xy 380.45369 -278.743316) (xy 380.483255 -278.78266)
			(xy 380.506126 -278.826237) (xy 380.52171 -278.872918) (xy 380.529605 -278.921495) (xy 380.5301 -278.946102)
			(xy 380.848611 -278.946102) (xy 380.852706 -278.895374) (xy 380.864885 -278.84596) (xy 380.884833 -278.79914)
			(xy 380.912034 -278.756126) (xy 380.945782 -278.718032) (xy 380.985204 -278.685845) (xy 381.029278 -278.660399)
			(xy 381.076864 -278.642352) (xy 381.126728 -278.632172) (xy 381.17758 -278.630123) (xy 381.228101 -278.636257)
			(xy 381.276985 -278.650417) (xy 381.322964 -278.672234) (xy 381.364848 -278.701144) (xy 381.401552 -278.736399)
			(xy 381.432125 -278.777085) (xy 381.455776 -278.822148) (xy 381.471892 -278.870422) (xy 381.480056 -278.920656)
			(xy 381.480568 -278.946102) (xy 381.799096 -278.946102) (xy 381.803056 -278.897048) (xy 381.814833 -278.849264)
			(xy 381.834124 -278.803988) (xy 381.860427 -278.762392) (xy 381.893062 -278.725555) (xy 381.931183 -278.69443)
			(xy 381.973804 -278.669823) (xy 382.01982 -278.652371) (xy 382.068039 -278.642527) (xy 382.117214 -278.640546)
			(xy 382.166069 -278.646478) (xy 382.21334 -278.66017) (xy 382.257802 -278.681268) (xy 382.298305 -278.709224)
			(xy 382.333798 -278.743316) (xy 382.363363 -278.78266) (xy 382.386234 -278.826237) (xy 382.401818 -278.872918)
			(xy 382.409713 -278.921495) (xy 382.410208 -278.946102) (xy 382.728465 -278.946102) (xy 382.73256 -278.895374)
			(xy 382.744739 -278.84596) (xy 382.764687 -278.79914) (xy 382.791888 -278.756126) (xy 382.825636 -278.718032)
			(xy 382.865058 -278.685845) (xy 382.909132 -278.660399) (xy 382.956718 -278.642352) (xy 383.006582 -278.632172)
			(xy 383.057434 -278.630123) (xy 383.107955 -278.636257) (xy 383.156839 -278.650417) (xy 383.202818 -278.672234)
			(xy 383.244702 -278.701144) (xy 383.281406 -278.736399) (xy 383.311979 -278.777085) (xy 383.33563 -278.822148)
			(xy 383.351746 -278.870422) (xy 383.35991 -278.920656) (xy 383.360422 -278.946102) (xy 383.668519 -278.946102)
			(xy 383.672614 -278.895374) (xy 383.684793 -278.84596) (xy 383.704741 -278.79914) (xy 383.731942 -278.756126)
			(xy 383.76569 -278.718032) (xy 383.805112 -278.685845) (xy 383.849186 -278.660399) (xy 383.896772 -278.642352)
			(xy 383.946636 -278.632172) (xy 383.997488 -278.630123) (xy 384.048009 -278.636257) (xy 384.096893 -278.650417)
			(xy 384.142872 -278.672234) (xy 384.184756 -278.701144) (xy 384.22146 -278.736399) (xy 384.252033 -278.777085)
			(xy 384.275684 -278.822148) (xy 384.2918 -278.870422) (xy 384.299964 -278.920656) (xy 384.300476 -278.946102)
			(xy 384.619004 -278.946102) (xy 384.622964 -278.897048) (xy 384.634741 -278.849264) (xy 384.654032 -278.803988)
			(xy 384.680335 -278.762392) (xy 384.71297 -278.725555) (xy 384.751091 -278.69443) (xy 384.793712 -278.669823)
			(xy 384.839728 -278.652371) (xy 384.887947 -278.642527) (xy 384.937122 -278.640546) (xy 384.985977 -278.646478)
			(xy 385.033248 -278.66017) (xy 385.07771 -278.681268) (xy 385.118213 -278.709224) (xy 385.153706 -278.743316)
			(xy 385.183271 -278.78266) (xy 385.206142 -278.826237) (xy 385.221726 -278.872918) (xy 385.229621 -278.921495)
			(xy 385.230116 -278.946102) (xy 385.548627 -278.946102) (xy 385.552722 -278.895374) (xy 385.564901 -278.84596)
			(xy 385.584849 -278.79914) (xy 385.61205 -278.756126) (xy 385.645798 -278.718032) (xy 385.68522 -278.685845)
			(xy 385.729294 -278.660399) (xy 385.77688 -278.642352) (xy 385.826744 -278.632172) (xy 385.877596 -278.630123)
			(xy 385.928117 -278.636257) (xy 385.977001 -278.650417) (xy 386.02298 -278.672234) (xy 386.064864 -278.701144)
			(xy 386.101568 -278.736399) (xy 386.132141 -278.777085) (xy 386.155792 -278.822148) (xy 386.171908 -278.870422)
			(xy 386.180072 -278.920656) (xy 386.180584 -278.946102) (xy 386.499112 -278.946102) (xy 386.503072 -278.897048)
			(xy 386.514849 -278.849264) (xy 386.53414 -278.803988) (xy 386.560443 -278.762392) (xy 386.593078 -278.725555)
			(xy 386.631199 -278.69443) (xy 386.67382 -278.669823) (xy 386.719836 -278.652371) (xy 386.768055 -278.642527)
			(xy 386.81723 -278.640546) (xy 386.866085 -278.646478) (xy 386.913356 -278.66017) (xy 386.957818 -278.681268)
			(xy 386.998321 -278.709224) (xy 387.033814 -278.743316) (xy 387.063379 -278.78266) (xy 387.08625 -278.826237)
			(xy 387.101834 -278.872918) (xy 387.109729 -278.921495) (xy 387.110224 -278.946102) (xy 387.428481 -278.946102)
			(xy 387.432576 -278.895374) (xy 387.444755 -278.84596) (xy 387.464703 -278.79914) (xy 387.491904 -278.756126)
			(xy 387.525652 -278.718032) (xy 387.565074 -278.685845) (xy 387.609148 -278.660399) (xy 387.656734 -278.642352)
			(xy 387.706598 -278.632172) (xy 387.75745 -278.630123) (xy 387.807971 -278.636257) (xy 387.856855 -278.650417)
			(xy 387.902834 -278.672234) (xy 387.944718 -278.701144) (xy 387.981422 -278.736399) (xy 388.011995 -278.777085)
			(xy 388.035646 -278.822148) (xy 388.051762 -278.870422) (xy 388.059926 -278.920656) (xy 388.060438 -278.946102)
			(xy 388.378966 -278.946102) (xy 388.382926 -278.897048) (xy 388.394703 -278.849264) (xy 388.413994 -278.803988)
			(xy 388.440297 -278.762392) (xy 388.472932 -278.725555) (xy 388.511053 -278.69443) (xy 388.553674 -278.669823)
			(xy 388.59969 -278.652371) (xy 388.647909 -278.642527) (xy 388.697084 -278.640546) (xy 388.745939 -278.646478)
			(xy 388.79321 -278.66017) (xy 388.837672 -278.681268) (xy 388.878175 -278.709224) (xy 388.913668 -278.743316)
			(xy 388.943233 -278.78266) (xy 388.966104 -278.826237) (xy 388.981688 -278.872918) (xy 388.989583 -278.921495)
			(xy 388.990078 -278.946102) (xy 389.308589 -278.946102) (xy 389.312684 -278.895374) (xy 389.324863 -278.84596)
			(xy 389.344811 -278.79914) (xy 389.372012 -278.756126) (xy 389.40576 -278.718032) (xy 389.445182 -278.685845)
			(xy 389.489256 -278.660399) (xy 389.536842 -278.642352) (xy 389.586706 -278.632172) (xy 389.637558 -278.630123)
			(xy 389.688079 -278.636257) (xy 389.736963 -278.650417) (xy 389.782942 -278.672234) (xy 389.824826 -278.701144)
			(xy 389.86153 -278.736399) (xy 389.892103 -278.777085) (xy 389.915754 -278.822148) (xy 389.93187 -278.870422)
			(xy 389.940034 -278.920656) (xy 389.940546 -278.946102) (xy 390.248643 -278.946102) (xy 390.252738 -278.895374)
			(xy 390.264917 -278.84596) (xy 390.284865 -278.79914) (xy 390.312066 -278.756126) (xy 390.345814 -278.718032)
			(xy 390.385236 -278.685845) (xy 390.42931 -278.660399) (xy 390.476896 -278.642352) (xy 390.52676 -278.632172)
			(xy 390.577612 -278.630123) (xy 390.628133 -278.636257) (xy 390.677017 -278.650417) (xy 390.722996 -278.672234)
			(xy 390.76488 -278.701144) (xy 390.801584 -278.736399) (xy 390.832157 -278.777085) (xy 390.855808 -278.822148)
			(xy 390.871924 -278.870422) (xy 390.880088 -278.920656) (xy 390.8806 -278.946102) (xy 391.198874 -278.946102)
			(xy 391.202834 -278.897048) (xy 391.214611 -278.849264) (xy 391.233902 -278.803988) (xy 391.260205 -278.762392)
			(xy 391.29284 -278.725555) (xy 391.330961 -278.69443) (xy 391.373582 -278.669823) (xy 391.419598 -278.652371)
			(xy 391.467817 -278.642527) (xy 391.516992 -278.640546) (xy 391.565847 -278.646478) (xy 391.613118 -278.66017)
			(xy 391.65758 -278.681268) (xy 391.698083 -278.709224) (xy 391.733576 -278.743316) (xy 391.763141 -278.78266)
			(xy 391.786012 -278.826237) (xy 391.801596 -278.872918) (xy 391.809491 -278.921495) (xy 391.809986 -278.946102)
			(xy 393.078982 -278.946102) (xy 393.082942 -278.897048) (xy 393.094719 -278.849264) (xy 393.11401 -278.803988)
			(xy 393.140313 -278.762392) (xy 393.172948 -278.725555) (xy 393.211069 -278.69443) (xy 393.25369 -278.669823)
			(xy 393.299706 -278.652371) (xy 393.347925 -278.642527) (xy 393.3971 -278.640546) (xy 393.445955 -278.646478)
			(xy 393.493226 -278.66017) (xy 393.537688 -278.681268) (xy 393.578191 -278.709224) (xy 393.613684 -278.743316)
			(xy 393.643249 -278.78266) (xy 393.66612 -278.826237) (xy 393.681704 -278.872918) (xy 393.689599 -278.921495)
			(xy 393.690094 -278.946102) (xy 393.689599 -278.970709) (xy 393.681704 -279.019286) (xy 393.66612 -279.065967)
			(xy 393.643249 -279.109544) (xy 393.613684 -279.148888) (xy 393.578191 -279.18298) (xy 393.537688 -279.210936)
			(xy 393.493226 -279.232034) (xy 393.445955 -279.245726) (xy 393.3971 -279.251658) (xy 393.347925 -279.249677)
			(xy 393.299706 -279.239833) (xy 393.25369 -279.222381) (xy 393.211069 -279.197774) (xy 393.172948 -279.166649)
			(xy 393.140313 -279.129812) (xy 393.11401 -279.088216) (xy 393.094719 -279.04294) (xy 393.082942 -278.995156)
			(xy 393.078982 -278.946102) (xy 391.809986 -278.946102) (xy 391.809491 -278.970709) (xy 391.801596 -279.019286)
			(xy 391.786012 -279.065967) (xy 391.763141 -279.109544) (xy 391.733576 -279.148888) (xy 391.698083 -279.18298)
			(xy 391.65758 -279.210936) (xy 391.613118 -279.232034) (xy 391.565847 -279.245726) (xy 391.516992 -279.251658)
			(xy 391.467817 -279.249677) (xy 391.419598 -279.239833) (xy 391.373582 -279.222381) (xy 391.330961 -279.197774)
			(xy 391.29284 -279.166649) (xy 391.260205 -279.129812) (xy 391.233902 -279.088216) (xy 391.214611 -279.04294)
			(xy 391.202834 -278.995156) (xy 391.198874 -278.946102) (xy 390.8806 -278.946102) (xy 390.880088 -278.971548)
			(xy 390.871924 -279.021782) (xy 390.855808 -279.070056) (xy 390.832157 -279.115119) (xy 390.801584 -279.155805)
			(xy 390.76488 -279.19106) (xy 390.722996 -279.21997) (xy 390.677017 -279.241787) (xy 390.628133 -279.255947)
			(xy 390.577612 -279.262081) (xy 390.52676 -279.260032) (xy 390.476896 -279.249852) (xy 390.42931 -279.231805)
			(xy 390.385236 -279.206359) (xy 390.345814 -279.174172) (xy 390.312066 -279.136078) (xy 390.284865 -279.093064)
			(xy 390.264917 -279.046244) (xy 390.252738 -278.99683) (xy 390.248643 -278.946102) (xy 389.940546 -278.946102)
			(xy 389.940034 -278.971548) (xy 389.93187 -279.021782) (xy 389.915754 -279.070056) (xy 389.892103 -279.115119)
			(xy 389.86153 -279.155805) (xy 389.824826 -279.19106) (xy 389.782942 -279.21997) (xy 389.736963 -279.241787)
			(xy 389.688079 -279.255947) (xy 389.637558 -279.262081) (xy 389.586706 -279.260032) (xy 389.536842 -279.249852)
			(xy 389.489256 -279.231805) (xy 389.445182 -279.206359) (xy 389.40576 -279.174172) (xy 389.372012 -279.136078)
			(xy 389.344811 -279.093064) (xy 389.324863 -279.046244) (xy 389.312684 -278.99683) (xy 389.308589 -278.946102)
			(xy 388.990078 -278.946102) (xy 388.989583 -278.970709) (xy 388.981688 -279.019286) (xy 388.966104 -279.065967)
			(xy 388.943233 -279.109544) (xy 388.913668 -279.148888) (xy 388.878175 -279.18298) (xy 388.837672 -279.210936)
			(xy 388.79321 -279.232034) (xy 388.745939 -279.245726) (xy 388.697084 -279.251658) (xy 388.647909 -279.249677)
			(xy 388.59969 -279.239833) (xy 388.553674 -279.222381) (xy 388.511053 -279.197774) (xy 388.472932 -279.166649)
			(xy 388.440297 -279.129812) (xy 388.413994 -279.088216) (xy 388.394703 -279.04294) (xy 388.382926 -278.995156)
			(xy 388.378966 -278.946102) (xy 388.060438 -278.946102) (xy 388.059926 -278.971548) (xy 388.051762 -279.021782)
			(xy 388.035646 -279.070056) (xy 388.011995 -279.115119) (xy 387.981422 -279.155805) (xy 387.944718 -279.19106)
			(xy 387.902834 -279.21997) (xy 387.856855 -279.241787) (xy 387.807971 -279.255947) (xy 387.75745 -279.262081)
			(xy 387.706598 -279.260032) (xy 387.656734 -279.249852) (xy 387.609148 -279.231805) (xy 387.565074 -279.206359)
			(xy 387.525652 -279.174172) (xy 387.491904 -279.136078) (xy 387.464703 -279.093064) (xy 387.444755 -279.046244)
			(xy 387.432576 -278.99683) (xy 387.428481 -278.946102) (xy 387.110224 -278.946102) (xy 387.109729 -278.970709)
			(xy 387.101834 -279.019286) (xy 387.08625 -279.065967) (xy 387.063379 -279.109544) (xy 387.033814 -279.148888)
			(xy 386.998321 -279.18298) (xy 386.957818 -279.210936) (xy 386.913356 -279.232034) (xy 386.866085 -279.245726)
			(xy 386.81723 -279.251658) (xy 386.768055 -279.249677) (xy 386.719836 -279.239833) (xy 386.67382 -279.222381)
			(xy 386.631199 -279.197774) (xy 386.593078 -279.166649) (xy 386.560443 -279.129812) (xy 386.53414 -279.088216)
			(xy 386.514849 -279.04294) (xy 386.503072 -278.995156) (xy 386.499112 -278.946102) (xy 386.180584 -278.946102)
			(xy 386.180072 -278.971548) (xy 386.171908 -279.021782) (xy 386.155792 -279.070056) (xy 386.132141 -279.115119)
			(xy 386.101568 -279.155805) (xy 386.064864 -279.19106) (xy 386.02298 -279.21997) (xy 385.977001 -279.241787)
			(xy 385.928117 -279.255947) (xy 385.877596 -279.262081) (xy 385.826744 -279.260032) (xy 385.77688 -279.249852)
			(xy 385.729294 -279.231805) (xy 385.68522 -279.206359) (xy 385.645798 -279.174172) (xy 385.61205 -279.136078)
			(xy 385.584849 -279.093064) (xy 385.564901 -279.046244) (xy 385.552722 -278.99683) (xy 385.548627 -278.946102)
			(xy 385.230116 -278.946102) (xy 385.229621 -278.970709) (xy 385.221726 -279.019286) (xy 385.206142 -279.065967)
			(xy 385.183271 -279.109544) (xy 385.153706 -279.148888) (xy 385.118213 -279.18298) (xy 385.07771 -279.210936)
			(xy 385.033248 -279.232034) (xy 384.985977 -279.245726) (xy 384.937122 -279.251658) (xy 384.887947 -279.249677)
			(xy 384.839728 -279.239833) (xy 384.793712 -279.222381) (xy 384.751091 -279.197774) (xy 384.71297 -279.166649)
			(xy 384.680335 -279.129812) (xy 384.654032 -279.088216) (xy 384.634741 -279.04294) (xy 384.622964 -278.995156)
			(xy 384.619004 -278.946102) (xy 384.300476 -278.946102) (xy 384.299964 -278.971548) (xy 384.2918 -279.021782)
			(xy 384.275684 -279.070056) (xy 384.252033 -279.115119) (xy 384.22146 -279.155805) (xy 384.184756 -279.19106)
			(xy 384.142872 -279.21997) (xy 384.096893 -279.241787) (xy 384.048009 -279.255947) (xy 383.997488 -279.262081)
			(xy 383.946636 -279.260032) (xy 383.896772 -279.249852) (xy 383.849186 -279.231805) (xy 383.805112 -279.206359)
			(xy 383.76569 -279.174172) (xy 383.731942 -279.136078) (xy 383.704741 -279.093064) (xy 383.684793 -279.046244)
			(xy 383.672614 -278.99683) (xy 383.668519 -278.946102) (xy 383.360422 -278.946102) (xy 383.35991 -278.971548)
			(xy 383.351746 -279.021782) (xy 383.33563 -279.070056) (xy 383.311979 -279.115119) (xy 383.281406 -279.155805)
			(xy 383.244702 -279.19106) (xy 383.202818 -279.21997) (xy 383.156839 -279.241787) (xy 383.107955 -279.255947)
			(xy 383.057434 -279.262081) (xy 383.006582 -279.260032) (xy 382.956718 -279.249852) (xy 382.909132 -279.231805)
			(xy 382.865058 -279.206359) (xy 382.825636 -279.174172) (xy 382.791888 -279.136078) (xy 382.764687 -279.093064)
			(xy 382.744739 -279.046244) (xy 382.73256 -278.99683) (xy 382.728465 -278.946102) (xy 382.410208 -278.946102)
			(xy 382.409713 -278.970709) (xy 382.401818 -279.019286) (xy 382.386234 -279.065967) (xy 382.363363 -279.109544)
			(xy 382.333798 -279.148888) (xy 382.298305 -279.18298) (xy 382.257802 -279.210936) (xy 382.21334 -279.232034)
			(xy 382.166069 -279.245726) (xy 382.117214 -279.251658) (xy 382.068039 -279.249677) (xy 382.01982 -279.239833)
			(xy 381.973804 -279.222381) (xy 381.931183 -279.197774) (xy 381.893062 -279.166649) (xy 381.860427 -279.129812)
			(xy 381.834124 -279.088216) (xy 381.814833 -279.04294) (xy 381.803056 -278.995156) (xy 381.799096 -278.946102)
			(xy 381.480568 -278.946102) (xy 381.480056 -278.971548) (xy 381.471892 -279.021782) (xy 381.455776 -279.070056)
			(xy 381.432125 -279.115119) (xy 381.401552 -279.155805) (xy 381.364848 -279.19106) (xy 381.322964 -279.21997)
			(xy 381.276985 -279.241787) (xy 381.228101 -279.255947) (xy 381.17758 -279.262081) (xy 381.126728 -279.260032)
			(xy 381.076864 -279.249852) (xy 381.029278 -279.231805) (xy 380.985204 -279.206359) (xy 380.945782 -279.174172)
			(xy 380.912034 -279.136078) (xy 380.884833 -279.093064) (xy 380.864885 -279.046244) (xy 380.852706 -278.99683)
			(xy 380.848611 -278.946102) (xy 380.5301 -278.946102) (xy 380.529605 -278.970709) (xy 380.52171 -279.019286)
			(xy 380.506126 -279.065967) (xy 380.483255 -279.109544) (xy 380.45369 -279.148888) (xy 380.418197 -279.18298)
			(xy 380.377694 -279.210936) (xy 380.333232 -279.232034) (xy 380.285961 -279.245726) (xy 380.237106 -279.251658)
			(xy 380.187931 -279.249677) (xy 380.139712 -279.239833) (xy 380.093696 -279.222381) (xy 380.051075 -279.197774)
			(xy 380.012954 -279.166649) (xy 379.980319 -279.129812) (xy 379.954016 -279.088216) (xy 379.934725 -279.04294)
			(xy 379.922948 -278.995156) (xy 379.918988 -278.946102) (xy 379.60046 -278.946102) (xy 379.599948 -278.971548)
			(xy 379.591784 -279.021782) (xy 379.575668 -279.070056) (xy 379.552017 -279.115119) (xy 379.521444 -279.155805)
			(xy 379.48474 -279.19106) (xy 379.442856 -279.21997) (xy 379.396877 -279.241787) (xy 379.347993 -279.255947)
			(xy 379.297472 -279.262081) (xy 379.24662 -279.260032) (xy 379.196756 -279.249852) (xy 379.14917 -279.231805)
			(xy 379.105096 -279.206359) (xy 379.065674 -279.174172) (xy 379.031926 -279.136078) (xy 379.004725 -279.093064)
			(xy 378.984777 -279.046244) (xy 378.972598 -278.99683) (xy 378.968503 -278.946102) (xy 378.650246 -278.946102)
			(xy 378.649751 -278.970709) (xy 378.641856 -279.019286) (xy 378.626272 -279.065967) (xy 378.603401 -279.109544)
			(xy 378.573836 -279.148888) (xy 378.538343 -279.18298) (xy 378.49784 -279.210936) (xy 378.453378 -279.232034)
			(xy 378.406107 -279.245726) (xy 378.357252 -279.251658) (xy 378.308077 -279.249677) (xy 378.259858 -279.239833)
			(xy 378.213842 -279.222381) (xy 378.171221 -279.197774) (xy 378.1331 -279.166649) (xy 378.100465 -279.129812)
			(xy 378.074162 -279.088216) (xy 378.054871 -279.04294) (xy 378.043094 -278.995156) (xy 378.039134 -278.946102)
			(xy 377.720606 -278.946102) (xy 377.720094 -278.971548) (xy 377.71193 -279.021782) (xy 377.695814 -279.070056)
			(xy 377.672163 -279.115119) (xy 377.64159 -279.155805) (xy 377.604886 -279.19106) (xy 377.563002 -279.21997)
			(xy 377.517023 -279.241787) (xy 377.468139 -279.255947) (xy 377.417618 -279.262081) (xy 377.366766 -279.260032)
			(xy 377.316902 -279.249852) (xy 377.269316 -279.231805) (xy 377.225242 -279.206359) (xy 377.18582 -279.174172)
			(xy 377.152072 -279.136078) (xy 377.124871 -279.093064) (xy 377.104923 -279.046244) (xy 377.092744 -278.99683)
			(xy 377.088649 -278.946102) (xy 376.780552 -278.946102) (xy 376.78004 -278.971548) (xy 376.771876 -279.021782)
			(xy 376.75576 -279.070056) (xy 376.732109 -279.115119) (xy 376.701536 -279.155805) (xy 376.664832 -279.19106)
			(xy 376.622948 -279.21997) (xy 376.576969 -279.241787) (xy 376.528085 -279.255947) (xy 376.477564 -279.262081)
			(xy 376.426712 -279.260032) (xy 376.376848 -279.249852) (xy 376.329262 -279.231805) (xy 376.285188 -279.206359)
			(xy 376.245766 -279.174172) (xy 376.212018 -279.136078) (xy 376.184817 -279.093064) (xy 376.164869 -279.046244)
			(xy 376.15269 -278.99683) (xy 376.148595 -278.946102) (xy 375.830658 -278.946102) (xy 375.826486 -278.996445)
			(xy 375.814084 -279.045417) (xy 375.79379 -279.091679) (xy 375.766159 -279.13397) (xy 375.731943 -279.171136)
			(xy 375.692076 -279.202162) (xy 375.647646 -279.226204) (xy 375.599864 -279.242604) (xy 375.550035 -279.250915)
			(xy 375.524776 -279.25141) (xy 375.502157 -279.251004) (xy 375.457415 -279.244332) (xy 375.41415 -279.231122)
			(xy 375.373311 -279.211665) (xy 375.354342 -279.19934) (xy 375.342404 -279.191466) (xy 375.314718 -279.189942)
			(xy 375.223024 -279.238964) (xy 375.215069 -279.243621) (xy 375.202908 -279.257455) (xy 375.196465 -279.27471)
			(xy 375.1961 -279.283922) (xy 375.1961 -279.426416) (xy 375.196492 -279.435264) (xy 375.202521 -279.451902)
			(xy 375.213828 -279.465517) (xy 375.221246 -279.470358) (xy 375.243932 -279.484176) (xy 375.284972 -279.517893)
			(xy 375.320094 -279.557738) (xy 375.348395 -279.602685) (xy 375.369146 -279.651578) (xy 375.381814 -279.70316)
			(xy 375.386073 -279.756104) (xy 375.386073 -279.756108) (xy 375.678695 -279.756108) (xy 375.68279 -279.70538)
			(xy 375.694969 -279.655966) (xy 375.714917 -279.609146) (xy 375.742118 -279.566132) (xy 375.775866 -279.528038)
			(xy 375.815288 -279.495851) (xy 375.859362 -279.470405) (xy 375.906948 -279.452358) (xy 375.956812 -279.442178)
			(xy 376.007664 -279.440129) (xy 376.058185 -279.446263) (xy 376.107069 -279.460423) (xy 376.153048 -279.48224)
			(xy 376.194932 -279.51115) (xy 376.231636 -279.546405) (xy 376.262209 -279.587091) (xy 376.28586 -279.632154)
			(xy 376.301976 -279.680428) (xy 376.31014 -279.730662) (xy 376.310652 -279.756108) (xy 376.628926 -279.756108)
			(xy 376.632886 -279.707054) (xy 376.644663 -279.65927) (xy 376.663954 -279.613994) (xy 376.690257 -279.572398)
			(xy 376.722892 -279.535561) (xy 376.761013 -279.504436) (xy 376.803634 -279.479829) (xy 376.84965 -279.462377)
			(xy 376.897869 -279.452533) (xy 376.947044 -279.450552) (xy 376.995899 -279.456484) (xy 377.04317 -279.470176)
			(xy 377.087632 -279.491274) (xy 377.128135 -279.51923) (xy 377.163628 -279.553322) (xy 377.193193 -279.592666)
			(xy 377.216064 -279.636243) (xy 377.231648 -279.682924) (xy 377.239543 -279.731501) (xy 377.240038 -279.756108)
			(xy 377.558549 -279.756108) (xy 377.562644 -279.70538) (xy 377.574823 -279.655966) (xy 377.594771 -279.609146)
			(xy 377.621972 -279.566132) (xy 377.65572 -279.528038) (xy 377.695142 -279.495851) (xy 377.739216 -279.470405)
			(xy 377.786802 -279.452358) (xy 377.836666 -279.442178) (xy 377.887518 -279.440129) (xy 377.938039 -279.446263)
			(xy 377.986923 -279.460423) (xy 378.032902 -279.48224) (xy 378.074786 -279.51115) (xy 378.11149 -279.546405)
			(xy 378.142063 -279.587091) (xy 378.165714 -279.632154) (xy 378.18183 -279.680428) (xy 378.189994 -279.730662)
			(xy 378.190506 -279.756108) (xy 378.509034 -279.756108) (xy 378.512994 -279.707054) (xy 378.524771 -279.65927)
			(xy 378.544062 -279.613994) (xy 378.570365 -279.572398) (xy 378.603 -279.535561) (xy 378.641121 -279.504436)
			(xy 378.683742 -279.479829) (xy 378.729758 -279.462377) (xy 378.777977 -279.452533) (xy 378.827152 -279.450552)
			(xy 378.876007 -279.456484) (xy 378.923278 -279.470176) (xy 378.96774 -279.491274) (xy 379.008243 -279.51923)
			(xy 379.043736 -279.553322) (xy 379.073301 -279.592666) (xy 379.096172 -279.636243) (xy 379.111756 -279.682924)
			(xy 379.119651 -279.731501) (xy 379.120146 -279.756108) (xy 379.438657 -279.756108) (xy 379.442752 -279.70538)
			(xy 379.454931 -279.655966) (xy 379.474879 -279.609146) (xy 379.50208 -279.566132) (xy 379.535828 -279.528038)
			(xy 379.57525 -279.495851) (xy 379.619324 -279.470405) (xy 379.66691 -279.452358) (xy 379.716774 -279.442178)
			(xy 379.767626 -279.440129) (xy 379.818147 -279.446263) (xy 379.867031 -279.460423) (xy 379.91301 -279.48224)
			(xy 379.954894 -279.51115) (xy 379.991598 -279.546405) (xy 380.022171 -279.587091) (xy 380.045822 -279.632154)
			(xy 380.061938 -279.680428) (xy 380.070102 -279.730662) (xy 380.070614 -279.756108) (xy 380.378711 -279.756108)
			(xy 380.382806 -279.70538) (xy 380.394985 -279.655966) (xy 380.414933 -279.609146) (xy 380.442134 -279.566132)
			(xy 380.475882 -279.528038) (xy 380.515304 -279.495851) (xy 380.559378 -279.470405) (xy 380.606964 -279.452358)
			(xy 380.656828 -279.442178) (xy 380.70768 -279.440129) (xy 380.758201 -279.446263) (xy 380.807085 -279.460423)
			(xy 380.853064 -279.48224) (xy 380.894948 -279.51115) (xy 380.931652 -279.546405) (xy 380.962225 -279.587091)
			(xy 380.985876 -279.632154) (xy 381.001992 -279.680428) (xy 381.010156 -279.730662) (xy 381.010668 -279.756108)
			(xy 381.328942 -279.756108) (xy 381.332902 -279.707054) (xy 381.344679 -279.65927) (xy 381.36397 -279.613994)
			(xy 381.390273 -279.572398) (xy 381.422908 -279.535561) (xy 381.461029 -279.504436) (xy 381.50365 -279.479829)
			(xy 381.549666 -279.462377) (xy 381.597885 -279.452533) (xy 381.64706 -279.450552) (xy 381.695915 -279.456484)
			(xy 381.743186 -279.470176) (xy 381.787648 -279.491274) (xy 381.828151 -279.51923) (xy 381.863644 -279.553322)
			(xy 381.893209 -279.592666) (xy 381.91608 -279.636243) (xy 381.931664 -279.682924) (xy 381.939559 -279.731501)
			(xy 381.940054 -279.756108) (xy 382.258565 -279.756108) (xy 382.26266 -279.70538) (xy 382.274839 -279.655966)
			(xy 382.294787 -279.609146) (xy 382.321988 -279.566132) (xy 382.355736 -279.528038) (xy 382.395158 -279.495851)
			(xy 382.439232 -279.470405) (xy 382.486818 -279.452358) (xy 382.536682 -279.442178) (xy 382.587534 -279.440129)
			(xy 382.638055 -279.446263) (xy 382.686939 -279.460423) (xy 382.732918 -279.48224) (xy 382.774802 -279.51115)
			(xy 382.811506 -279.546405) (xy 382.842079 -279.587091) (xy 382.86573 -279.632154) (xy 382.881846 -279.680428)
			(xy 382.89001 -279.730662) (xy 382.890522 -279.756108) (xy 383.20905 -279.756108) (xy 383.21301 -279.707054)
			(xy 383.224787 -279.65927) (xy 383.244078 -279.613994) (xy 383.270381 -279.572398) (xy 383.303016 -279.535561)
			(xy 383.341137 -279.504436) (xy 383.383758 -279.479829) (xy 383.429774 -279.462377) (xy 383.477993 -279.452533)
			(xy 383.527168 -279.450552) (xy 383.576023 -279.456484) (xy 383.623294 -279.470176) (xy 383.667756 -279.491274)
			(xy 383.708259 -279.51923) (xy 383.743752 -279.553322) (xy 383.773317 -279.592666) (xy 383.796188 -279.636243)
			(xy 383.811772 -279.682924) (xy 383.819667 -279.731501) (xy 383.820162 -279.756108) (xy 384.138673 -279.756108)
			(xy 384.142768 -279.70538) (xy 384.154947 -279.655966) (xy 384.174895 -279.609146) (xy 384.202096 -279.566132)
			(xy 384.235844 -279.528038) (xy 384.275266 -279.495851) (xy 384.31934 -279.470405) (xy 384.366926 -279.452358)
			(xy 384.41679 -279.442178) (xy 384.467642 -279.440129) (xy 384.518163 -279.446263) (xy 384.567047 -279.460423)
			(xy 384.613026 -279.48224) (xy 384.65491 -279.51115) (xy 384.691614 -279.546405) (xy 384.722187 -279.587091)
			(xy 384.745838 -279.632154) (xy 384.761954 -279.680428) (xy 384.770118 -279.730662) (xy 384.77063 -279.756108)
			(xy 385.088904 -279.756108) (xy 385.092864 -279.707054) (xy 385.104641 -279.65927) (xy 385.123932 -279.613994)
			(xy 385.150235 -279.572398) (xy 385.18287 -279.535561) (xy 385.220991 -279.504436) (xy 385.263612 -279.479829)
			(xy 385.309628 -279.462377) (xy 385.357847 -279.452533) (xy 385.407022 -279.450552) (xy 385.455877 -279.456484)
			(xy 385.503148 -279.470176) (xy 385.54761 -279.491274) (xy 385.588113 -279.51923) (xy 385.623606 -279.553322)
			(xy 385.653171 -279.592666) (xy 385.676042 -279.636243) (xy 385.691626 -279.682924) (xy 385.699521 -279.731501)
			(xy 385.700016 -279.756108) (xy 386.018527 -279.756108) (xy 386.022622 -279.70538) (xy 386.034801 -279.655966)
			(xy 386.054749 -279.609146) (xy 386.08195 -279.566132) (xy 386.115698 -279.528038) (xy 386.15512 -279.495851)
			(xy 386.199194 -279.470405) (xy 386.24678 -279.452358) (xy 386.296644 -279.442178) (xy 386.347496 -279.440129)
			(xy 386.398017 -279.446263) (xy 386.446901 -279.460423) (xy 386.49288 -279.48224) (xy 386.534764 -279.51115)
			(xy 386.571468 -279.546405) (xy 386.602041 -279.587091) (xy 386.625692 -279.632154) (xy 386.641808 -279.680428)
			(xy 386.649972 -279.730662) (xy 386.650484 -279.756108) (xy 386.958581 -279.756108) (xy 386.962676 -279.70538)
			(xy 386.974855 -279.655966) (xy 386.994803 -279.609146) (xy 387.022004 -279.566132) (xy 387.055752 -279.528038)
			(xy 387.095174 -279.495851) (xy 387.139248 -279.470405) (xy 387.186834 -279.452358) (xy 387.236698 -279.442178)
			(xy 387.28755 -279.440129) (xy 387.338071 -279.446263) (xy 387.386955 -279.460423) (xy 387.432934 -279.48224)
			(xy 387.474818 -279.51115) (xy 387.511522 -279.546405) (xy 387.542095 -279.587091) (xy 387.565746 -279.632154)
			(xy 387.581862 -279.680428) (xy 387.590026 -279.730662) (xy 387.590538 -279.756108) (xy 387.909066 -279.756108)
			(xy 387.913026 -279.707054) (xy 387.924803 -279.65927) (xy 387.944094 -279.613994) (xy 387.970397 -279.572398)
			(xy 388.003032 -279.535561) (xy 388.041153 -279.504436) (xy 388.083774 -279.479829) (xy 388.12979 -279.462377)
			(xy 388.178009 -279.452533) (xy 388.227184 -279.450552) (xy 388.276039 -279.456484) (xy 388.32331 -279.470176)
			(xy 388.367772 -279.491274) (xy 388.408275 -279.51923) (xy 388.443768 -279.553322) (xy 388.473333 -279.592666)
			(xy 388.496204 -279.636243) (xy 388.511788 -279.682924) (xy 388.519683 -279.731501) (xy 388.520178 -279.756108)
			(xy 388.838689 -279.756108) (xy 388.842784 -279.70538) (xy 388.854963 -279.655966) (xy 388.874911 -279.609146)
			(xy 388.902112 -279.566132) (xy 388.93586 -279.528038) (xy 388.975282 -279.495851) (xy 389.019356 -279.470405)
			(xy 389.066942 -279.452358) (xy 389.116806 -279.442178) (xy 389.167658 -279.440129) (xy 389.218179 -279.446263)
			(xy 389.267063 -279.460423) (xy 389.313042 -279.48224) (xy 389.354926 -279.51115) (xy 389.39163 -279.546405)
			(xy 389.422203 -279.587091) (xy 389.445854 -279.632154) (xy 389.46197 -279.680428) (xy 389.470134 -279.730662)
			(xy 389.470646 -279.756108) (xy 389.78892 -279.756108) (xy 389.79288 -279.707054) (xy 389.804657 -279.65927)
			(xy 389.823948 -279.613994) (xy 389.850251 -279.572398) (xy 389.882886 -279.535561) (xy 389.921007 -279.504436)
			(xy 389.963628 -279.479829) (xy 390.009644 -279.462377) (xy 390.057863 -279.452533) (xy 390.107038 -279.450552)
			(xy 390.155893 -279.456484) (xy 390.203164 -279.470176) (xy 390.247626 -279.491274) (xy 390.288129 -279.51923)
			(xy 390.323622 -279.553322) (xy 390.353187 -279.592666) (xy 390.376058 -279.636243) (xy 390.391642 -279.682924)
			(xy 390.399537 -279.731501) (xy 390.400032 -279.756108) (xy 390.718543 -279.756108) (xy 390.722638 -279.70538)
			(xy 390.734817 -279.655966) (xy 390.754765 -279.609146) (xy 390.781966 -279.566132) (xy 390.815714 -279.528038)
			(xy 390.855136 -279.495851) (xy 390.89921 -279.470405) (xy 390.946796 -279.452358) (xy 390.99666 -279.442178)
			(xy 391.047512 -279.440129) (xy 391.098033 -279.446263) (xy 391.146917 -279.460423) (xy 391.192896 -279.48224)
			(xy 391.23478 -279.51115) (xy 391.271484 -279.546405) (xy 391.302057 -279.587091) (xy 391.325708 -279.632154)
			(xy 391.341824 -279.680428) (xy 391.349988 -279.730662) (xy 391.3505 -279.756108) (xy 391.669028 -279.756108)
			(xy 391.672988 -279.707054) (xy 391.684765 -279.65927) (xy 391.704056 -279.613994) (xy 391.730359 -279.572398)
			(xy 391.762994 -279.535561) (xy 391.801115 -279.504436) (xy 391.843736 -279.479829) (xy 391.889752 -279.462377)
			(xy 391.937971 -279.452533) (xy 391.987146 -279.450552) (xy 392.036001 -279.456484) (xy 392.083272 -279.470176)
			(xy 392.125407 -279.49017) (xy 394.67715 -279.49017) (xy 394.68111 -279.441116) (xy 394.692887 -279.393332)
			(xy 394.712178 -279.348056) (xy 394.738481 -279.30646) (xy 394.771116 -279.269623) (xy 394.809237 -279.238498)
			(xy 394.851858 -279.213891) (xy 394.897874 -279.196439) (xy 394.946093 -279.186595) (xy 394.995268 -279.184614)
			(xy 395.044123 -279.190546) (xy 395.091394 -279.204238) (xy 395.135856 -279.225336) (xy 395.176359 -279.253292)
			(xy 395.211852 -279.287384) (xy 395.241417 -279.326728) (xy 395.264288 -279.370305) (xy 395.279872 -279.416986)
			(xy 395.287767 -279.465563) (xy 395.288262 -279.49017) (xy 395.287767 -279.514777) (xy 395.279872 -279.563354)
			(xy 395.264288 -279.610035) (xy 395.241417 -279.653612) (xy 395.211852 -279.692956) (xy 395.176359 -279.727048)
			(xy 395.135856 -279.755004) (xy 395.091394 -279.776102) (xy 395.044123 -279.789794) (xy 394.995268 -279.795726)
			(xy 394.946093 -279.793745) (xy 394.897874 -279.783901) (xy 394.851858 -279.766449) (xy 394.809237 -279.741842)
			(xy 394.771116 -279.710717) (xy 394.738481 -279.67388) (xy 394.712178 -279.632284) (xy 394.692887 -279.587008)
			(xy 394.68111 -279.539224) (xy 394.67715 -279.49017) (xy 392.125407 -279.49017) (xy 392.127734 -279.491274)
			(xy 392.168237 -279.51923) (xy 392.20373 -279.553322) (xy 392.233295 -279.592666) (xy 392.256166 -279.636243)
			(xy 392.27175 -279.682924) (xy 392.279645 -279.731501) (xy 392.28014 -279.756108) (xy 392.279645 -279.780715)
			(xy 392.27175 -279.829292) (xy 392.256166 -279.875973) (xy 392.233295 -279.91955) (xy 392.20373 -279.958894)
			(xy 392.168237 -279.992986) (xy 392.127734 -280.020942) (xy 392.083272 -280.04204) (xy 392.036001 -280.055732)
			(xy 391.987146 -280.061664) (xy 391.937971 -280.059683) (xy 391.889752 -280.049839) (xy 391.843736 -280.032387)
			(xy 391.801115 -280.00778) (xy 391.762994 -279.976655) (xy 391.730359 -279.939818) (xy 391.704056 -279.898222)
			(xy 391.684765 -279.852946) (xy 391.672988 -279.805162) (xy 391.669028 -279.756108) (xy 391.3505 -279.756108)
			(xy 391.349988 -279.781554) (xy 391.341824 -279.831788) (xy 391.325708 -279.880062) (xy 391.302057 -279.925125)
			(xy 391.271484 -279.965811) (xy 391.23478 -280.001066) (xy 391.192896 -280.029976) (xy 391.146917 -280.051793)
			(xy 391.098033 -280.065953) (xy 391.047512 -280.072087) (xy 390.99666 -280.070038) (xy 390.946796 -280.059858)
			(xy 390.89921 -280.041811) (xy 390.855136 -280.016365) (xy 390.815714 -279.984178) (xy 390.781966 -279.946084)
			(xy 390.754765 -279.90307) (xy 390.734817 -279.85625) (xy 390.722638 -279.806836) (xy 390.718543 -279.756108)
			(xy 390.400032 -279.756108) (xy 390.399537 -279.780715) (xy 390.391642 -279.829292) (xy 390.376058 -279.875973)
			(xy 390.353187 -279.91955) (xy 390.323622 -279.958894) (xy 390.288129 -279.992986) (xy 390.247626 -280.020942)
			(xy 390.203164 -280.04204) (xy 390.155893 -280.055732) (xy 390.107038 -280.061664) (xy 390.057863 -280.059683)
			(xy 390.009644 -280.049839) (xy 389.963628 -280.032387) (xy 389.921007 -280.00778) (xy 389.882886 -279.976655)
			(xy 389.850251 -279.939818) (xy 389.823948 -279.898222) (xy 389.804657 -279.852946) (xy 389.79288 -279.805162)
			(xy 389.78892 -279.756108) (xy 389.470646 -279.756108) (xy 389.470134 -279.781554) (xy 389.46197 -279.831788)
			(xy 389.445854 -279.880062) (xy 389.422203 -279.925125) (xy 389.39163 -279.965811) (xy 389.354926 -280.001066)
			(xy 389.313042 -280.029976) (xy 389.267063 -280.051793) (xy 389.218179 -280.065953) (xy 389.167658 -280.072087)
			(xy 389.116806 -280.070038) (xy 389.066942 -280.059858) (xy 389.019356 -280.041811) (xy 388.975282 -280.016365)
			(xy 388.93586 -279.984178) (xy 388.902112 -279.946084) (xy 388.874911 -279.90307) (xy 388.854963 -279.85625)
			(xy 388.842784 -279.806836) (xy 388.838689 -279.756108) (xy 388.520178 -279.756108) (xy 388.519683 -279.780715)
			(xy 388.511788 -279.829292) (xy 388.496204 -279.875973) (xy 388.473333 -279.91955) (xy 388.443768 -279.958894)
			(xy 388.408275 -279.992986) (xy 388.367772 -280.020942) (xy 388.32331 -280.04204) (xy 388.276039 -280.055732)
			(xy 388.227184 -280.061664) (xy 388.178009 -280.059683) (xy 388.12979 -280.049839) (xy 388.083774 -280.032387)
			(xy 388.041153 -280.00778) (xy 388.003032 -279.976655) (xy 387.970397 -279.939818) (xy 387.944094 -279.898222)
			(xy 387.924803 -279.852946) (xy 387.913026 -279.805162) (xy 387.909066 -279.756108) (xy 387.590538 -279.756108)
			(xy 387.590026 -279.781554) (xy 387.581862 -279.831788) (xy 387.565746 -279.880062) (xy 387.542095 -279.925125)
			(xy 387.511522 -279.965811) (xy 387.474818 -280.001066) (xy 387.432934 -280.029976) (xy 387.386955 -280.051793)
			(xy 387.338071 -280.065953) (xy 387.28755 -280.072087) (xy 387.236698 -280.070038) (xy 387.186834 -280.059858)
			(xy 387.139248 -280.041811) (xy 387.095174 -280.016365) (xy 387.055752 -279.984178) (xy 387.022004 -279.946084)
			(xy 386.994803 -279.90307) (xy 386.974855 -279.85625) (xy 386.962676 -279.806836) (xy 386.958581 -279.756108)
			(xy 386.650484 -279.756108) (xy 386.649972 -279.781554) (xy 386.641808 -279.831788) (xy 386.625692 -279.880062)
			(xy 386.602041 -279.925125) (xy 386.571468 -279.965811) (xy 386.534764 -280.001066) (xy 386.49288 -280.029976)
			(xy 386.446901 -280.051793) (xy 386.398017 -280.065953) (xy 386.347496 -280.072087) (xy 386.296644 -280.070038)
			(xy 386.24678 -280.059858) (xy 386.199194 -280.041811) (xy 386.15512 -280.016365) (xy 386.115698 -279.984178)
			(xy 386.08195 -279.946084) (xy 386.054749 -279.90307) (xy 386.034801 -279.85625) (xy 386.022622 -279.806836)
			(xy 386.018527 -279.756108) (xy 385.700016 -279.756108) (xy 385.699521 -279.780715) (xy 385.691626 -279.829292)
			(xy 385.676042 -279.875973) (xy 385.653171 -279.91955) (xy 385.623606 -279.958894) (xy 385.588113 -279.992986)
			(xy 385.54761 -280.020942) (xy 385.503148 -280.04204) (xy 385.455877 -280.055732) (xy 385.407022 -280.061664)
			(xy 385.357847 -280.059683) (xy 385.309628 -280.049839) (xy 385.263612 -280.032387) (xy 385.220991 -280.00778)
			(xy 385.18287 -279.976655) (xy 385.150235 -279.939818) (xy 385.123932 -279.898222) (xy 385.104641 -279.852946)
			(xy 385.092864 -279.805162) (xy 385.088904 -279.756108) (xy 384.77063 -279.756108) (xy 384.770118 -279.781554)
			(xy 384.761954 -279.831788) (xy 384.745838 -279.880062) (xy 384.722187 -279.925125) (xy 384.691614 -279.965811)
			(xy 384.65491 -280.001066) (xy 384.613026 -280.029976) (xy 384.567047 -280.051793) (xy 384.518163 -280.065953)
			(xy 384.467642 -280.072087) (xy 384.41679 -280.070038) (xy 384.366926 -280.059858) (xy 384.31934 -280.041811)
			(xy 384.275266 -280.016365) (xy 384.235844 -279.984178) (xy 384.202096 -279.946084) (xy 384.174895 -279.90307)
			(xy 384.154947 -279.85625) (xy 384.142768 -279.806836) (xy 384.138673 -279.756108) (xy 383.820162 -279.756108)
			(xy 383.819667 -279.780715) (xy 383.811772 -279.829292) (xy 383.796188 -279.875973) (xy 383.773317 -279.91955)
			(xy 383.743752 -279.958894) (xy 383.708259 -279.992986) (xy 383.667756 -280.020942) (xy 383.623294 -280.04204)
			(xy 383.576023 -280.055732) (xy 383.527168 -280.061664) (xy 383.477993 -280.059683) (xy 383.429774 -280.049839)
			(xy 383.383758 -280.032387) (xy 383.341137 -280.00778) (xy 383.303016 -279.976655) (xy 383.270381 -279.939818)
			(xy 383.244078 -279.898222) (xy 383.224787 -279.852946) (xy 383.21301 -279.805162) (xy 383.20905 -279.756108)
			(xy 382.890522 -279.756108) (xy 382.89001 -279.781554) (xy 382.881846 -279.831788) (xy 382.86573 -279.880062)
			(xy 382.842079 -279.925125) (xy 382.811506 -279.965811) (xy 382.774802 -280.001066) (xy 382.732918 -280.029976)
			(xy 382.686939 -280.051793) (xy 382.638055 -280.065953) (xy 382.587534 -280.072087) (xy 382.536682 -280.070038)
			(xy 382.486818 -280.059858) (xy 382.439232 -280.041811) (xy 382.395158 -280.016365) (xy 382.355736 -279.984178)
			(xy 382.321988 -279.946084) (xy 382.294787 -279.90307) (xy 382.274839 -279.85625) (xy 382.26266 -279.806836)
			(xy 382.258565 -279.756108) (xy 381.940054 -279.756108) (xy 381.939559 -279.780715) (xy 381.931664 -279.829292)
			(xy 381.91608 -279.875973) (xy 381.893209 -279.91955) (xy 381.863644 -279.958894) (xy 381.828151 -279.992986)
			(xy 381.787648 -280.020942) (xy 381.743186 -280.04204) (xy 381.695915 -280.055732) (xy 381.64706 -280.061664)
			(xy 381.597885 -280.059683) (xy 381.549666 -280.049839) (xy 381.50365 -280.032387) (xy 381.461029 -280.00778)
			(xy 381.422908 -279.976655) (xy 381.390273 -279.939818) (xy 381.36397 -279.898222) (xy 381.344679 -279.852946)
			(xy 381.332902 -279.805162) (xy 381.328942 -279.756108) (xy 381.010668 -279.756108) (xy 381.010156 -279.781554)
			(xy 381.001992 -279.831788) (xy 380.985876 -279.880062) (xy 380.962225 -279.925125) (xy 380.931652 -279.965811)
			(xy 380.894948 -280.001066) (xy 380.853064 -280.029976) (xy 380.807085 -280.051793) (xy 380.758201 -280.065953)
			(xy 380.70768 -280.072087) (xy 380.656828 -280.070038) (xy 380.606964 -280.059858) (xy 380.559378 -280.041811)
			(xy 380.515304 -280.016365) (xy 380.475882 -279.984178) (xy 380.442134 -279.946084) (xy 380.414933 -279.90307)
			(xy 380.394985 -279.85625) (xy 380.382806 -279.806836) (xy 380.378711 -279.756108) (xy 380.070614 -279.756108)
			(xy 380.070102 -279.781554) (xy 380.061938 -279.831788) (xy 380.045822 -279.880062) (xy 380.022171 -279.925125)
			(xy 379.991598 -279.965811) (xy 379.954894 -280.001066) (xy 379.91301 -280.029976) (xy 379.867031 -280.051793)
			(xy 379.818147 -280.065953) (xy 379.767626 -280.072087) (xy 379.716774 -280.070038) (xy 379.66691 -280.059858)
			(xy 379.619324 -280.041811) (xy 379.57525 -280.016365) (xy 379.535828 -279.984178) (xy 379.50208 -279.946084)
			(xy 379.474879 -279.90307) (xy 379.454931 -279.85625) (xy 379.442752 -279.806836) (xy 379.438657 -279.756108)
			(xy 379.120146 -279.756108) (xy 379.119651 -279.780715) (xy 379.111756 -279.829292) (xy 379.096172 -279.875973)
			(xy 379.073301 -279.91955) (xy 379.043736 -279.958894) (xy 379.008243 -279.992986) (xy 378.96774 -280.020942)
			(xy 378.923278 -280.04204) (xy 378.876007 -280.055732) (xy 378.827152 -280.061664) (xy 378.777977 -280.059683)
			(xy 378.729758 -280.049839) (xy 378.683742 -280.032387) (xy 378.641121 -280.00778) (xy 378.603 -279.976655)
			(xy 378.570365 -279.939818) (xy 378.544062 -279.898222) (xy 378.524771 -279.852946) (xy 378.512994 -279.805162)
			(xy 378.509034 -279.756108) (xy 378.190506 -279.756108) (xy 378.189994 -279.781554) (xy 378.18183 -279.831788)
			(xy 378.165714 -279.880062) (xy 378.142063 -279.925125) (xy 378.11149 -279.965811) (xy 378.074786 -280.001066)
			(xy 378.032902 -280.029976) (xy 377.986923 -280.051793) (xy 377.938039 -280.065953) (xy 377.887518 -280.072087)
			(xy 377.836666 -280.070038) (xy 377.786802 -280.059858) (xy 377.739216 -280.041811) (xy 377.695142 -280.016365)
			(xy 377.65572 -279.984178) (xy 377.621972 -279.946084) (xy 377.594771 -279.90307) (xy 377.574823 -279.85625)
			(xy 377.562644 -279.806836) (xy 377.558549 -279.756108) (xy 377.240038 -279.756108) (xy 377.239543 -279.780715)
			(xy 377.231648 -279.829292) (xy 377.216064 -279.875973) (xy 377.193193 -279.91955) (xy 377.163628 -279.958894)
			(xy 377.128135 -279.992986) (xy 377.087632 -280.020942) (xy 377.04317 -280.04204) (xy 376.995899 -280.055732)
			(xy 376.947044 -280.061664) (xy 376.897869 -280.059683) (xy 376.84965 -280.049839) (xy 376.803634 -280.032387)
			(xy 376.761013 -280.00778) (xy 376.722892 -279.976655) (xy 376.690257 -279.939818) (xy 376.663954 -279.898222)
			(xy 376.644663 -279.852946) (xy 376.632886 -279.805162) (xy 376.628926 -279.756108) (xy 376.310652 -279.756108)
			(xy 376.31014 -279.781554) (xy 376.301976 -279.831788) (xy 376.28586 -279.880062) (xy 376.262209 -279.925125)
			(xy 376.231636 -279.965811) (xy 376.194932 -280.001066) (xy 376.153048 -280.029976) (xy 376.107069 -280.051793)
			(xy 376.058185 -280.065953) (xy 376.007664 -280.072087) (xy 375.956812 -280.070038) (xy 375.906948 -280.059858)
			(xy 375.859362 -280.041811) (xy 375.815288 -280.016365) (xy 375.775866 -279.984178) (xy 375.742118 -279.946084)
			(xy 375.714917 -279.90307) (xy 375.694969 -279.85625) (xy 375.68279 -279.806836) (xy 375.678695 -279.756108)
			(xy 375.386073 -279.756108) (xy 375.381813 -279.809048) (xy 375.369144 -279.860629) (xy 375.348391 -279.909522)
			(xy 375.32009 -279.954468) (xy 375.284966 -279.994312) (xy 375.243925 -280.028029) (xy 375.221246 -280.041858)
			(xy 375.21375 -280.046611) (xy 375.202398 -280.060239) (xy 375.196394 -280.07693) (xy 375.1961 -280.0858)
			(xy 375.1961 -280.228294) (xy 375.1965 -280.237494) (xy 375.202984 -280.254716) (xy 375.215094 -280.268571)
			(xy 375.223024 -280.273252) (xy 375.314718 -280.322274) (xy 375.342404 -280.32075) (xy 375.354342 -280.312876)
			(xy 375.373328 -280.300577) (xy 375.414162 -280.281114) (xy 375.457421 -280.26789) (xy 375.502158 -280.261195)
			(xy 375.524776 -280.260806) (xy 375.550034 -280.261297) (xy 375.599861 -280.269608) (xy 375.647641 -280.286007)
			(xy 375.692069 -280.310048) (xy 375.731935 -280.341073) (xy 375.766149 -280.378238) (xy 375.79378 -280.420527)
			(xy 375.814073 -280.466787) (xy 375.826474 -280.515757) (xy 375.830646 -280.5661) (xy 375.830645 -280.566114)
			(xy 376.148595 -280.566114) (xy 376.15269 -280.515386) (xy 376.164869 -280.465972) (xy 376.184817 -280.419152)
			(xy 376.212018 -280.376138) (xy 376.245766 -280.338044) (xy 376.285188 -280.305857) (xy 376.329262 -280.280411)
			(xy 376.376848 -280.262364) (xy 376.426712 -280.252184) (xy 376.477564 -280.250135) (xy 376.528085 -280.256269)
			(xy 376.576969 -280.270429) (xy 376.622948 -280.292246) (xy 376.664832 -280.321156) (xy 376.701536 -280.356411)
			(xy 376.732109 -280.397097) (xy 376.75576 -280.44216) (xy 376.771876 -280.490434) (xy 376.78004 -280.540668)
			(xy 376.780552 -280.566114) (xy 377.088649 -280.566114) (xy 377.092744 -280.515386) (xy 377.104923 -280.465972)
			(xy 377.124871 -280.419152) (xy 377.152072 -280.376138) (xy 377.18582 -280.338044) (xy 377.225242 -280.305857)
			(xy 377.269316 -280.280411) (xy 377.316902 -280.262364) (xy 377.366766 -280.252184) (xy 377.417618 -280.250135)
			(xy 377.468139 -280.256269) (xy 377.517023 -280.270429) (xy 377.563002 -280.292246) (xy 377.604886 -280.321156)
			(xy 377.64159 -280.356411) (xy 377.672163 -280.397097) (xy 377.695814 -280.44216) (xy 377.71193 -280.490434)
			(xy 377.720094 -280.540668) (xy 377.720606 -280.566114) (xy 378.968503 -280.566114) (xy 378.972598 -280.515386)
			(xy 378.984777 -280.465972) (xy 379.004725 -280.419152) (xy 379.031926 -280.376138) (xy 379.065674 -280.338044)
			(xy 379.105096 -280.305857) (xy 379.14917 -280.280411) (xy 379.196756 -280.262364) (xy 379.24662 -280.252184)
			(xy 379.297472 -280.250135) (xy 379.347993 -280.256269) (xy 379.396877 -280.270429) (xy 379.442856 -280.292246)
			(xy 379.48474 -280.321156) (xy 379.521444 -280.356411) (xy 379.552017 -280.397097) (xy 379.575668 -280.44216)
			(xy 379.591784 -280.490434) (xy 379.599948 -280.540668) (xy 379.60046 -280.566114) (xy 379.918988 -280.566114)
			(xy 379.922948 -280.51706) (xy 379.934725 -280.469276) (xy 379.954016 -280.424) (xy 379.980319 -280.382404)
			(xy 380.012954 -280.345567) (xy 380.051075 -280.314442) (xy 380.093696 -280.289835) (xy 380.139712 -280.272383)
			(xy 380.187931 -280.262539) (xy 380.237106 -280.260558) (xy 380.285961 -280.26649) (xy 380.333232 -280.280182)
			(xy 380.377694 -280.30128) (xy 380.418197 -280.329236) (xy 380.45369 -280.363328) (xy 380.483255 -280.402672)
			(xy 380.506126 -280.446249) (xy 380.52171 -280.49293) (xy 380.529605 -280.541507) (xy 380.5301 -280.566114)
			(xy 380.848611 -280.566114) (xy 380.852706 -280.515386) (xy 380.864885 -280.465972) (xy 380.884833 -280.419152)
			(xy 380.912034 -280.376138) (xy 380.945782 -280.338044) (xy 380.985204 -280.305857) (xy 381.029278 -280.280411)
			(xy 381.076864 -280.262364) (xy 381.126728 -280.252184) (xy 381.17758 -280.250135) (xy 381.228101 -280.256269)
			(xy 381.276985 -280.270429) (xy 381.322964 -280.292246) (xy 381.364848 -280.321156) (xy 381.401552 -280.356411)
			(xy 381.432125 -280.397097) (xy 381.455776 -280.44216) (xy 381.471892 -280.490434) (xy 381.480056 -280.540668)
			(xy 381.480568 -280.566114) (xy 381.799096 -280.566114) (xy 381.803056 -280.51706) (xy 381.814833 -280.469276)
			(xy 381.834124 -280.424) (xy 381.860427 -280.382404) (xy 381.893062 -280.345567) (xy 381.931183 -280.314442)
			(xy 381.973804 -280.289835) (xy 382.01982 -280.272383) (xy 382.068039 -280.262539) (xy 382.117214 -280.260558)
			(xy 382.166069 -280.26649) (xy 382.21334 -280.280182) (xy 382.257802 -280.30128) (xy 382.298305 -280.329236)
			(xy 382.333798 -280.363328) (xy 382.363363 -280.402672) (xy 382.386234 -280.446249) (xy 382.401818 -280.49293)
			(xy 382.409713 -280.541507) (xy 382.410208 -280.566114) (xy 382.728465 -280.566114) (xy 382.73256 -280.515386)
			(xy 382.744739 -280.465972) (xy 382.764687 -280.419152) (xy 382.791888 -280.376138) (xy 382.825636 -280.338044)
			(xy 382.865058 -280.305857) (xy 382.909132 -280.280411) (xy 382.956718 -280.262364) (xy 383.006582 -280.252184)
			(xy 383.057434 -280.250135) (xy 383.107955 -280.256269) (xy 383.156839 -280.270429) (xy 383.202818 -280.292246)
			(xy 383.244702 -280.321156) (xy 383.281406 -280.356411) (xy 383.311979 -280.397097) (xy 383.33563 -280.44216)
			(xy 383.351746 -280.490434) (xy 383.35991 -280.540668) (xy 383.360422 -280.566114) (xy 383.668519 -280.566114)
			(xy 383.672614 -280.515386) (xy 383.684793 -280.465972) (xy 383.704741 -280.419152) (xy 383.731942 -280.376138)
			(xy 383.76569 -280.338044) (xy 383.805112 -280.305857) (xy 383.849186 -280.280411) (xy 383.896772 -280.262364)
			(xy 383.946636 -280.252184) (xy 383.997488 -280.250135) (xy 384.048009 -280.256269) (xy 384.096893 -280.270429)
			(xy 384.142872 -280.292246) (xy 384.184756 -280.321156) (xy 384.22146 -280.356411) (xy 384.252033 -280.397097)
			(xy 384.275684 -280.44216) (xy 384.2918 -280.490434) (xy 384.299964 -280.540668) (xy 384.300476 -280.566114)
			(xy 385.548627 -280.566114) (xy 385.552722 -280.515386) (xy 385.564901 -280.465972) (xy 385.584849 -280.419152)
			(xy 385.61205 -280.376138) (xy 385.645798 -280.338044) (xy 385.68522 -280.305857) (xy 385.729294 -280.280411)
			(xy 385.77688 -280.262364) (xy 385.826744 -280.252184) (xy 385.877596 -280.250135) (xy 385.928117 -280.256269)
			(xy 385.977001 -280.270429) (xy 386.02298 -280.292246) (xy 386.064864 -280.321156) (xy 386.101568 -280.356411)
			(xy 386.132141 -280.397097) (xy 386.155792 -280.44216) (xy 386.171908 -280.490434) (xy 386.180072 -280.540668)
			(xy 386.180584 -280.566114) (xy 386.499112 -280.566114) (xy 386.503072 -280.51706) (xy 386.514849 -280.469276)
			(xy 386.53414 -280.424) (xy 386.560443 -280.382404) (xy 386.593078 -280.345567) (xy 386.631199 -280.314442)
			(xy 386.67382 -280.289835) (xy 386.719836 -280.272383) (xy 386.768055 -280.262539) (xy 386.81723 -280.260558)
			(xy 386.866085 -280.26649) (xy 386.913356 -280.280182) (xy 386.957818 -280.30128) (xy 386.998321 -280.329236)
			(xy 387.033814 -280.363328) (xy 387.063379 -280.402672) (xy 387.08625 -280.446249) (xy 387.101834 -280.49293)
			(xy 387.109729 -280.541507) (xy 387.110224 -280.566114) (xy 387.428481 -280.566114) (xy 387.432576 -280.515386)
			(xy 387.444755 -280.465972) (xy 387.464703 -280.419152) (xy 387.491904 -280.376138) (xy 387.525652 -280.338044)
			(xy 387.565074 -280.305857) (xy 387.609148 -280.280411) (xy 387.656734 -280.262364) (xy 387.706598 -280.252184)
			(xy 387.75745 -280.250135) (xy 387.807971 -280.256269) (xy 387.856855 -280.270429) (xy 387.902834 -280.292246)
			(xy 387.944718 -280.321156) (xy 387.981422 -280.356411) (xy 388.011995 -280.397097) (xy 388.035646 -280.44216)
			(xy 388.051762 -280.490434) (xy 388.059926 -280.540668) (xy 388.060438 -280.566114) (xy 388.378966 -280.566114)
			(xy 388.382926 -280.51706) (xy 388.394703 -280.469276) (xy 388.413994 -280.424) (xy 388.440297 -280.382404)
			(xy 388.472932 -280.345567) (xy 388.511053 -280.314442) (xy 388.553674 -280.289835) (xy 388.59969 -280.272383)
			(xy 388.647909 -280.262539) (xy 388.697084 -280.260558) (xy 388.745939 -280.26649) (xy 388.79321 -280.280182)
			(xy 388.837672 -280.30128) (xy 388.878175 -280.329236) (xy 388.913668 -280.363328) (xy 388.943233 -280.402672)
			(xy 388.966104 -280.446249) (xy 388.981688 -280.49293) (xy 388.989583 -280.541507) (xy 388.990078 -280.566114)
			(xy 389.308589 -280.566114) (xy 389.312684 -280.515386) (xy 389.324863 -280.465972) (xy 389.344811 -280.419152)
			(xy 389.372012 -280.376138) (xy 389.40576 -280.338044) (xy 389.445182 -280.305857) (xy 389.489256 -280.280411)
			(xy 389.536842 -280.262364) (xy 389.586706 -280.252184) (xy 389.637558 -280.250135) (xy 389.688079 -280.256269)
			(xy 389.736963 -280.270429) (xy 389.782942 -280.292246) (xy 389.824826 -280.321156) (xy 389.86153 -280.356411)
			(xy 389.892103 -280.397097) (xy 389.915754 -280.44216) (xy 389.93187 -280.490434) (xy 389.940034 -280.540668)
			(xy 389.940546 -280.566114) (xy 390.248643 -280.566114) (xy 390.252738 -280.515386) (xy 390.264917 -280.465972)
			(xy 390.284865 -280.419152) (xy 390.312066 -280.376138) (xy 390.345814 -280.338044) (xy 390.385236 -280.305857)
			(xy 390.42931 -280.280411) (xy 390.476896 -280.262364) (xy 390.52676 -280.252184) (xy 390.577612 -280.250135)
			(xy 390.628133 -280.256269) (xy 390.677017 -280.270429) (xy 390.722996 -280.292246) (xy 390.76488 -280.321156)
			(xy 390.801584 -280.356411) (xy 390.832157 -280.397097) (xy 390.855808 -280.44216) (xy 390.871924 -280.490434)
			(xy 390.880088 -280.540668) (xy 390.8806 -280.566114) (xy 393.078982 -280.566114) (xy 393.082942 -280.51706)
			(xy 393.094719 -280.469276) (xy 393.11401 -280.424) (xy 393.140313 -280.382404) (xy 393.172948 -280.345567)
			(xy 393.211069 -280.314442) (xy 393.25369 -280.289835) (xy 393.299706 -280.272383) (xy 393.347925 -280.262539)
			(xy 393.3971 -280.260558) (xy 393.445955 -280.26649) (xy 393.493226 -280.280182) (xy 393.537688 -280.30128)
			(xy 393.578191 -280.329236) (xy 393.613684 -280.363328) (xy 393.643249 -280.402672) (xy 393.66612 -280.446249)
			(xy 393.681704 -280.49293) (xy 393.689599 -280.541507) (xy 393.690094 -280.566114) (xy 393.689599 -280.590721)
			(xy 393.681704 -280.639298) (xy 393.66612 -280.685979) (xy 393.643249 -280.729556) (xy 393.613684 -280.7689)
			(xy 393.578191 -280.802992) (xy 393.537688 -280.830948) (xy 393.493226 -280.852046) (xy 393.445955 -280.865738)
			(xy 393.3971 -280.87167) (xy 393.347925 -280.869689) (xy 393.299706 -280.859845) (xy 393.25369 -280.842393)
			(xy 393.211069 -280.817786) (xy 393.172948 -280.786661) (xy 393.140313 -280.749824) (xy 393.11401 -280.708228)
			(xy 393.094719 -280.662952) (xy 393.082942 -280.615168) (xy 393.078982 -280.566114) (xy 390.8806 -280.566114)
			(xy 390.880088 -280.59156) (xy 390.871924 -280.641794) (xy 390.855808 -280.690068) (xy 390.832157 -280.735131)
			(xy 390.801584 -280.775817) (xy 390.76488 -280.811072) (xy 390.722996 -280.839982) (xy 390.677017 -280.861799)
			(xy 390.628133 -280.875959) (xy 390.577612 -280.882093) (xy 390.52676 -280.880044) (xy 390.476896 -280.869864)
			(xy 390.42931 -280.851817) (xy 390.385236 -280.826371) (xy 390.345814 -280.794184) (xy 390.312066 -280.75609)
			(xy 390.284865 -280.713076) (xy 390.264917 -280.666256) (xy 390.252738 -280.616842) (xy 390.248643 -280.566114)
			(xy 389.940546 -280.566114) (xy 389.940034 -280.59156) (xy 389.93187 -280.641794) (xy 389.915754 -280.690068)
			(xy 389.892103 -280.735131) (xy 389.86153 -280.775817) (xy 389.824826 -280.811072) (xy 389.782942 -280.839982)
			(xy 389.736963 -280.861799) (xy 389.688079 -280.875959) (xy 389.637558 -280.882093) (xy 389.586706 -280.880044)
			(xy 389.536842 -280.869864) (xy 389.489256 -280.851817) (xy 389.445182 -280.826371) (xy 389.40576 -280.794184)
			(xy 389.372012 -280.75609) (xy 389.344811 -280.713076) (xy 389.324863 -280.666256) (xy 389.312684 -280.616842)
			(xy 389.308589 -280.566114) (xy 388.990078 -280.566114) (xy 388.989583 -280.590721) (xy 388.981688 -280.639298)
			(xy 388.966104 -280.685979) (xy 388.943233 -280.729556) (xy 388.913668 -280.7689) (xy 388.878175 -280.802992)
			(xy 388.837672 -280.830948) (xy 388.79321 -280.852046) (xy 388.745939 -280.865738) (xy 388.697084 -280.87167)
			(xy 388.647909 -280.869689) (xy 388.59969 -280.859845) (xy 388.553674 -280.842393) (xy 388.511053 -280.817786)
			(xy 388.472932 -280.786661) (xy 388.440297 -280.749824) (xy 388.413994 -280.708228) (xy 388.394703 -280.662952)
			(xy 388.382926 -280.615168) (xy 388.378966 -280.566114) (xy 388.060438 -280.566114) (xy 388.059926 -280.59156)
			(xy 388.051762 -280.641794) (xy 388.035646 -280.690068) (xy 388.011995 -280.735131) (xy 387.981422 -280.775817)
			(xy 387.944718 -280.811072) (xy 387.902834 -280.839982) (xy 387.856855 -280.861799) (xy 387.807971 -280.875959)
			(xy 387.75745 -280.882093) (xy 387.706598 -280.880044) (xy 387.656734 -280.869864) (xy 387.609148 -280.851817)
			(xy 387.565074 -280.826371) (xy 387.525652 -280.794184) (xy 387.491904 -280.75609) (xy 387.464703 -280.713076)
			(xy 387.444755 -280.666256) (xy 387.432576 -280.616842) (xy 387.428481 -280.566114) (xy 387.110224 -280.566114)
			(xy 387.109729 -280.590721) (xy 387.101834 -280.639298) (xy 387.08625 -280.685979) (xy 387.063379 -280.729556)
			(xy 387.033814 -280.7689) (xy 386.998321 -280.802992) (xy 386.957818 -280.830948) (xy 386.913356 -280.852046)
			(xy 386.866085 -280.865738) (xy 386.81723 -280.87167) (xy 386.768055 -280.869689) (xy 386.719836 -280.859845)
			(xy 386.67382 -280.842393) (xy 386.631199 -280.817786) (xy 386.593078 -280.786661) (xy 386.560443 -280.749824)
			(xy 386.53414 -280.708228) (xy 386.514849 -280.662952) (xy 386.503072 -280.615168) (xy 386.499112 -280.566114)
			(xy 386.180584 -280.566114) (xy 386.180072 -280.59156) (xy 386.171908 -280.641794) (xy 386.155792 -280.690068)
			(xy 386.132141 -280.735131) (xy 386.101568 -280.775817) (xy 386.064864 -280.811072) (xy 386.02298 -280.839982)
			(xy 385.977001 -280.861799) (xy 385.928117 -280.875959) (xy 385.877596 -280.882093) (xy 385.826744 -280.880044)
			(xy 385.77688 -280.869864) (xy 385.729294 -280.851817) (xy 385.68522 -280.826371) (xy 385.645798 -280.794184)
			(xy 385.61205 -280.75609) (xy 385.584849 -280.713076) (xy 385.564901 -280.666256) (xy 385.552722 -280.616842)
			(xy 385.548627 -280.566114) (xy 384.300476 -280.566114) (xy 384.299964 -280.59156) (xy 384.2918 -280.641794)
			(xy 384.275684 -280.690068) (xy 384.252033 -280.735131) (xy 384.22146 -280.775817) (xy 384.184756 -280.811072)
			(xy 384.142872 -280.839982) (xy 384.096893 -280.861799) (xy 384.048009 -280.875959) (xy 383.997488 -280.882093)
			(xy 383.946636 -280.880044) (xy 383.896772 -280.869864) (xy 383.849186 -280.851817) (xy 383.805112 -280.826371)
			(xy 383.76569 -280.794184) (xy 383.731942 -280.75609) (xy 383.704741 -280.713076) (xy 383.684793 -280.666256)
			(xy 383.672614 -280.616842) (xy 383.668519 -280.566114) (xy 383.360422 -280.566114) (xy 383.35991 -280.59156)
			(xy 383.351746 -280.641794) (xy 383.33563 -280.690068) (xy 383.311979 -280.735131) (xy 383.281406 -280.775817)
			(xy 383.244702 -280.811072) (xy 383.202818 -280.839982) (xy 383.156839 -280.861799) (xy 383.107955 -280.875959)
			(xy 383.057434 -280.882093) (xy 383.006582 -280.880044) (xy 382.956718 -280.869864) (xy 382.909132 -280.851817)
			(xy 382.865058 -280.826371) (xy 382.825636 -280.794184) (xy 382.791888 -280.75609) (xy 382.764687 -280.713076)
			(xy 382.744739 -280.666256) (xy 382.73256 -280.616842) (xy 382.728465 -280.566114) (xy 382.410208 -280.566114)
			(xy 382.409713 -280.590721) (xy 382.401818 -280.639298) (xy 382.386234 -280.685979) (xy 382.363363 -280.729556)
			(xy 382.333798 -280.7689) (xy 382.298305 -280.802992) (xy 382.257802 -280.830948) (xy 382.21334 -280.852046)
			(xy 382.166069 -280.865738) (xy 382.117214 -280.87167) (xy 382.068039 -280.869689) (xy 382.01982 -280.859845)
			(xy 381.973804 -280.842393) (xy 381.931183 -280.817786) (xy 381.893062 -280.786661) (xy 381.860427 -280.749824)
			(xy 381.834124 -280.708228) (xy 381.814833 -280.662952) (xy 381.803056 -280.615168) (xy 381.799096 -280.566114)
			(xy 381.480568 -280.566114) (xy 381.480056 -280.59156) (xy 381.471892 -280.641794) (xy 381.455776 -280.690068)
			(xy 381.432125 -280.735131) (xy 381.401552 -280.775817) (xy 381.364848 -280.811072) (xy 381.322964 -280.839982)
			(xy 381.276985 -280.861799) (xy 381.228101 -280.875959) (xy 381.17758 -280.882093) (xy 381.126728 -280.880044)
			(xy 381.076864 -280.869864) (xy 381.029278 -280.851817) (xy 380.985204 -280.826371) (xy 380.945782 -280.794184)
			(xy 380.912034 -280.75609) (xy 380.884833 -280.713076) (xy 380.864885 -280.666256) (xy 380.852706 -280.616842)
			(xy 380.848611 -280.566114) (xy 380.5301 -280.566114) (xy 380.529605 -280.590721) (xy 380.52171 -280.639298)
			(xy 380.506126 -280.685979) (xy 380.483255 -280.729556) (xy 380.45369 -280.7689) (xy 380.418197 -280.802992)
			(xy 380.377694 -280.830948) (xy 380.333232 -280.852046) (xy 380.285961 -280.865738) (xy 380.237106 -280.87167)
			(xy 380.187931 -280.869689) (xy 380.139712 -280.859845) (xy 380.093696 -280.842393) (xy 380.051075 -280.817786)
			(xy 380.012954 -280.786661) (xy 379.980319 -280.749824) (xy 379.954016 -280.708228) (xy 379.934725 -280.662952)
			(xy 379.922948 -280.615168) (xy 379.918988 -280.566114) (xy 379.60046 -280.566114) (xy 379.599948 -280.59156)
			(xy 379.591784 -280.641794) (xy 379.575668 -280.690068) (xy 379.552017 -280.735131) (xy 379.521444 -280.775817)
			(xy 379.48474 -280.811072) (xy 379.442856 -280.839982) (xy 379.396877 -280.861799) (xy 379.347993 -280.875959)
			(xy 379.297472 -280.882093) (xy 379.24662 -280.880044) (xy 379.196756 -280.869864) (xy 379.14917 -280.851817)
			(xy 379.105096 -280.826371) (xy 379.065674 -280.794184) (xy 379.031926 -280.75609) (xy 379.004725 -280.713076)
			(xy 378.984777 -280.666256) (xy 378.972598 -280.616842) (xy 378.968503 -280.566114) (xy 377.720606 -280.566114)
			(xy 377.720094 -280.59156) (xy 377.71193 -280.641794) (xy 377.695814 -280.690068) (xy 377.672163 -280.735131)
			(xy 377.64159 -280.775817) (xy 377.604886 -280.811072) (xy 377.563002 -280.839982) (xy 377.517023 -280.861799)
			(xy 377.468139 -280.875959) (xy 377.417618 -280.882093) (xy 377.366766 -280.880044) (xy 377.316902 -280.869864)
			(xy 377.269316 -280.851817) (xy 377.225242 -280.826371) (xy 377.18582 -280.794184) (xy 377.152072 -280.75609)
			(xy 377.124871 -280.713076) (xy 377.104923 -280.666256) (xy 377.092744 -280.616842) (xy 377.088649 -280.566114)
			(xy 376.780552 -280.566114) (xy 376.78004 -280.59156) (xy 376.771876 -280.641794) (xy 376.75576 -280.690068)
			(xy 376.732109 -280.735131) (xy 376.701536 -280.775817) (xy 376.664832 -280.811072) (xy 376.622948 -280.839982)
			(xy 376.576969 -280.861799) (xy 376.528085 -280.875959) (xy 376.477564 -280.882093) (xy 376.426712 -280.880044)
			(xy 376.376848 -280.869864) (xy 376.329262 -280.851817) (xy 376.285188 -280.826371) (xy 376.245766 -280.794184)
			(xy 376.212018 -280.75609) (xy 376.184817 -280.713076) (xy 376.164869 -280.666256) (xy 376.15269 -280.616842)
			(xy 376.148595 -280.566114) (xy 375.830645 -280.566114) (xy 375.826474 -280.616443) (xy 375.814073 -280.665413)
			(xy 375.79378 -280.711673) (xy 375.766149 -280.753962) (xy 375.731935 -280.791127) (xy 375.692069 -280.822152)
			(xy 375.647641 -280.846193) (xy 375.599861 -280.862592) (xy 375.550034 -280.870903) (xy 375.524776 -280.871422)
			(xy 375.502158 -280.871016) (xy 375.457417 -280.864342) (xy 375.414153 -280.851129) (xy 375.373318 -280.831667)
			(xy 375.354342 -280.819352) (xy 375.342404 -280.811478) (xy 375.314718 -280.809954) (xy 375.223024 -280.858976)
			(xy 375.215059 -280.863629) (xy 375.202874 -280.877459) (xy 375.196402 -280.894717) (xy 375.1961 -280.903934)
			(xy 375.1961 -281.076146) (xy 375.196371 -281.084678) (xy 375.201895 -281.100817) (xy 375.212443 -281.114225)
			(xy 375.219468 -281.119072) (xy 375.240665 -281.133236) (xy 375.278449 -281.167456) (xy 375.31002 -281.207479)
			(xy 375.3345 -281.252194) (xy 375.351208 -281.300354) (xy 375.359678 -281.350622) (xy 375.359677 -281.37612)
			(xy 375.678695 -281.37612) (xy 375.68279 -281.325392) (xy 375.694969 -281.275978) (xy 375.714917 -281.229158)
			(xy 375.742118 -281.186144) (xy 375.775866 -281.14805) (xy 375.815288 -281.115863) (xy 375.859362 -281.090417)
			(xy 375.906948 -281.07237) (xy 375.956812 -281.06219) (xy 376.007664 -281.060141) (xy 376.058185 -281.066275)
			(xy 376.107069 -281.080435) (xy 376.153048 -281.102252) (xy 376.194932 -281.131162) (xy 376.231636 -281.166417)
			(xy 376.262209 -281.207103) (xy 376.28586 -281.252166) (xy 376.301976 -281.30044) (xy 376.31014 -281.350674)
			(xy 376.310652 -281.37612) (xy 376.628926 -281.37612) (xy 376.632886 -281.327066) (xy 376.644663 -281.279282)
			(xy 376.663954 -281.234006) (xy 376.690257 -281.19241) (xy 376.722892 -281.155573) (xy 376.761013 -281.124448)
			(xy 376.803634 -281.099841) (xy 376.84965 -281.082389) (xy 376.897869 -281.072545) (xy 376.947044 -281.070564)
			(xy 376.995899 -281.076496) (xy 377.04317 -281.090188) (xy 377.087632 -281.111286) (xy 377.128135 -281.139242)
			(xy 377.163628 -281.173334) (xy 377.193193 -281.212678) (xy 377.216064 -281.256255) (xy 377.231648 -281.302936)
			(xy 377.239543 -281.351513) (xy 377.240038 -281.37612) (xy 377.558549 -281.37612) (xy 377.562644 -281.325392)
			(xy 377.574823 -281.275978) (xy 377.594771 -281.229158) (xy 377.621972 -281.186144) (xy 377.65572 -281.14805)
			(xy 377.695142 -281.115863) (xy 377.739216 -281.090417) (xy 377.786802 -281.07237) (xy 377.836666 -281.06219)
			(xy 377.887518 -281.060141) (xy 377.938039 -281.066275) (xy 377.986923 -281.080435) (xy 378.032902 -281.102252)
			(xy 378.074786 -281.131162) (xy 378.11149 -281.166417) (xy 378.142063 -281.207103) (xy 378.165714 -281.252166)
			(xy 378.18183 -281.30044) (xy 378.189994 -281.350674) (xy 378.190506 -281.37612) (xy 378.509034 -281.37612)
			(xy 378.512994 -281.327066) (xy 378.524771 -281.279282) (xy 378.544062 -281.234006) (xy 378.570365 -281.19241)
			(xy 378.603 -281.155573) (xy 378.641121 -281.124448) (xy 378.683742 -281.099841) (xy 378.729758 -281.082389)
			(xy 378.777977 -281.072545) (xy 378.827152 -281.070564) (xy 378.876007 -281.076496) (xy 378.923278 -281.090188)
			(xy 378.96774 -281.111286) (xy 379.008243 -281.139242) (xy 379.043736 -281.173334) (xy 379.073301 -281.212678)
			(xy 379.096172 -281.256255) (xy 379.111756 -281.302936) (xy 379.119651 -281.351513) (xy 379.120146 -281.37612)
			(xy 379.438657 -281.37612) (xy 379.442752 -281.325392) (xy 379.454931 -281.275978) (xy 379.474879 -281.229158)
			(xy 379.50208 -281.186144) (xy 379.535828 -281.14805) (xy 379.57525 -281.115863) (xy 379.619324 -281.090417)
			(xy 379.66691 -281.07237) (xy 379.716774 -281.06219) (xy 379.767626 -281.060141) (xy 379.818147 -281.066275)
			(xy 379.867031 -281.080435) (xy 379.91301 -281.102252) (xy 379.954894 -281.131162) (xy 379.991598 -281.166417)
			(xy 380.022171 -281.207103) (xy 380.045822 -281.252166) (xy 380.061938 -281.30044) (xy 380.070102 -281.350674)
			(xy 380.070614 -281.37612) (xy 380.378711 -281.37612) (xy 380.382806 -281.325392) (xy 380.394985 -281.275978)
			(xy 380.414933 -281.229158) (xy 380.442134 -281.186144) (xy 380.475882 -281.14805) (xy 380.515304 -281.115863)
			(xy 380.559378 -281.090417) (xy 380.606964 -281.07237) (xy 380.656828 -281.06219) (xy 380.70768 -281.060141)
			(xy 380.758201 -281.066275) (xy 380.807085 -281.080435) (xy 380.853064 -281.102252) (xy 380.894948 -281.131162)
			(xy 380.931652 -281.166417) (xy 380.962225 -281.207103) (xy 380.985876 -281.252166) (xy 381.001992 -281.30044)
			(xy 381.010156 -281.350674) (xy 381.010668 -281.37612) (xy 381.328942 -281.37612) (xy 381.332902 -281.327066)
			(xy 381.344679 -281.279282) (xy 381.36397 -281.234006) (xy 381.390273 -281.19241) (xy 381.422908 -281.155573)
			(xy 381.461029 -281.124448) (xy 381.50365 -281.099841) (xy 381.549666 -281.082389) (xy 381.597885 -281.072545)
			(xy 381.64706 -281.070564) (xy 381.695915 -281.076496) (xy 381.743186 -281.090188) (xy 381.787648 -281.111286)
			(xy 381.828151 -281.139242) (xy 381.863644 -281.173334) (xy 381.893209 -281.212678) (xy 381.91608 -281.256255)
			(xy 381.931664 -281.302936) (xy 381.939559 -281.351513) (xy 381.940054 -281.37612) (xy 382.258565 -281.37612)
			(xy 382.26266 -281.325392) (xy 382.274839 -281.275978) (xy 382.294787 -281.229158) (xy 382.321988 -281.186144)
			(xy 382.355736 -281.14805) (xy 382.395158 -281.115863) (xy 382.439232 -281.090417) (xy 382.486818 -281.07237)
			(xy 382.536682 -281.06219) (xy 382.587534 -281.060141) (xy 382.638055 -281.066275) (xy 382.686939 -281.080435)
			(xy 382.732918 -281.102252) (xy 382.774802 -281.131162) (xy 382.811506 -281.166417) (xy 382.842079 -281.207103)
			(xy 382.86573 -281.252166) (xy 382.881846 -281.30044) (xy 382.89001 -281.350674) (xy 382.890522 -281.37612)
			(xy 383.20905 -281.37612) (xy 383.21301 -281.327066) (xy 383.224787 -281.279282) (xy 383.244078 -281.234006)
			(xy 383.270381 -281.19241) (xy 383.303016 -281.155573) (xy 383.341137 -281.124448) (xy 383.383758 -281.099841)
			(xy 383.429774 -281.082389) (xy 383.477993 -281.072545) (xy 383.527168 -281.070564) (xy 383.576023 -281.076496)
			(xy 383.623294 -281.090188) (xy 383.667756 -281.111286) (xy 383.708259 -281.139242) (xy 383.743752 -281.173334)
			(xy 383.773317 -281.212678) (xy 383.796188 -281.256255) (xy 383.811772 -281.302936) (xy 383.819667 -281.351513)
			(xy 383.820162 -281.37612) (xy 384.138673 -281.37612) (xy 384.142768 -281.325392) (xy 384.154947 -281.275978)
			(xy 384.174895 -281.229158) (xy 384.202096 -281.186144) (xy 384.235844 -281.14805) (xy 384.275266 -281.115863)
			(xy 384.31934 -281.090417) (xy 384.366926 -281.07237) (xy 384.41679 -281.06219) (xy 384.467642 -281.060141)
			(xy 384.518163 -281.066275) (xy 384.567047 -281.080435) (xy 384.613026 -281.102252) (xy 384.65491 -281.131162)
			(xy 384.691614 -281.166417) (xy 384.722187 -281.207103) (xy 384.745838 -281.252166) (xy 384.761954 -281.30044)
			(xy 384.770118 -281.350674) (xy 384.77063 -281.37612) (xy 385.088904 -281.37612) (xy 385.092864 -281.327066)
			(xy 385.104641 -281.279282) (xy 385.123932 -281.234006) (xy 385.150235 -281.19241) (xy 385.18287 -281.155573)
			(xy 385.220991 -281.124448) (xy 385.263612 -281.099841) (xy 385.309628 -281.082389) (xy 385.357847 -281.072545)
			(xy 385.407022 -281.070564) (xy 385.455877 -281.076496) (xy 385.503148 -281.090188) (xy 385.54761 -281.111286)
			(xy 385.588113 -281.139242) (xy 385.623606 -281.173334) (xy 385.653171 -281.212678) (xy 385.676042 -281.256255)
			(xy 385.691626 -281.302936) (xy 385.699521 -281.351513) (xy 385.700016 -281.37612) (xy 386.018527 -281.37612)
			(xy 386.022622 -281.325392) (xy 386.034801 -281.275978) (xy 386.054749 -281.229158) (xy 386.08195 -281.186144)
			(xy 386.115698 -281.14805) (xy 386.15512 -281.115863) (xy 386.199194 -281.090417) (xy 386.24678 -281.07237)
			(xy 386.296644 -281.06219) (xy 386.347496 -281.060141) (xy 386.398017 -281.066275) (xy 386.446901 -281.080435)
			(xy 386.49288 -281.102252) (xy 386.534764 -281.131162) (xy 386.571468 -281.166417) (xy 386.602041 -281.207103)
			(xy 386.625692 -281.252166) (xy 386.641808 -281.30044) (xy 386.649972 -281.350674) (xy 386.650484 -281.37612)
			(xy 386.958581 -281.37612) (xy 386.962676 -281.325392) (xy 386.974855 -281.275978) (xy 386.994803 -281.229158)
			(xy 387.022004 -281.186144) (xy 387.055752 -281.14805) (xy 387.095174 -281.115863) (xy 387.139248 -281.090417)
			(xy 387.186834 -281.07237) (xy 387.236698 -281.06219) (xy 387.28755 -281.060141) (xy 387.338071 -281.066275)
			(xy 387.386955 -281.080435) (xy 387.432934 -281.102252) (xy 387.474818 -281.131162) (xy 387.511522 -281.166417)
			(xy 387.542095 -281.207103) (xy 387.565746 -281.252166) (xy 387.581862 -281.30044) (xy 387.590026 -281.350674)
			(xy 387.590538 -281.37612) (xy 387.909066 -281.37612) (xy 387.913026 -281.327066) (xy 387.924803 -281.279282)
			(xy 387.944094 -281.234006) (xy 387.970397 -281.19241) (xy 388.003032 -281.155573) (xy 388.041153 -281.124448)
			(xy 388.083774 -281.099841) (xy 388.12979 -281.082389) (xy 388.178009 -281.072545) (xy 388.227184 -281.070564)
			(xy 388.276039 -281.076496) (xy 388.32331 -281.090188) (xy 388.367772 -281.111286) (xy 388.408275 -281.139242)
			(xy 388.443768 -281.173334) (xy 388.473333 -281.212678) (xy 388.496204 -281.256255) (xy 388.511788 -281.302936)
			(xy 388.519683 -281.351513) (xy 388.520178 -281.37612) (xy 388.838689 -281.37612) (xy 388.842784 -281.325392)
			(xy 388.854963 -281.275978) (xy 388.874911 -281.229158) (xy 388.902112 -281.186144) (xy 388.93586 -281.14805)
			(xy 388.975282 -281.115863) (xy 389.019356 -281.090417) (xy 389.066942 -281.07237) (xy 389.116806 -281.06219)
			(xy 389.167658 -281.060141) (xy 389.218179 -281.066275) (xy 389.267063 -281.080435) (xy 389.313042 -281.102252)
			(xy 389.354926 -281.131162) (xy 389.39163 -281.166417) (xy 389.422203 -281.207103) (xy 389.445854 -281.252166)
			(xy 389.46197 -281.30044) (xy 389.470134 -281.350674) (xy 389.470646 -281.37612) (xy 389.78892 -281.37612)
			(xy 389.79288 -281.327066) (xy 389.804657 -281.279282) (xy 389.823948 -281.234006) (xy 389.850251 -281.19241)
			(xy 389.882886 -281.155573) (xy 389.921007 -281.124448) (xy 389.963628 -281.099841) (xy 390.009644 -281.082389)
			(xy 390.057863 -281.072545) (xy 390.107038 -281.070564) (xy 390.155893 -281.076496) (xy 390.203164 -281.090188)
			(xy 390.247626 -281.111286) (xy 390.288129 -281.139242) (xy 390.323622 -281.173334) (xy 390.353187 -281.212678)
			(xy 390.376058 -281.256255) (xy 390.391642 -281.302936) (xy 390.399537 -281.351513) (xy 390.400032 -281.37612)
			(xy 390.718543 -281.37612) (xy 390.722638 -281.325392) (xy 390.734817 -281.275978) (xy 390.754765 -281.229158)
			(xy 390.781966 -281.186144) (xy 390.815714 -281.14805) (xy 390.855136 -281.115863) (xy 390.89921 -281.090417)
			(xy 390.946796 -281.07237) (xy 390.99666 -281.06219) (xy 391.047512 -281.060141) (xy 391.098033 -281.066275)
			(xy 391.146917 -281.080435) (xy 391.192896 -281.102252) (xy 391.23478 -281.131162) (xy 391.271484 -281.166417)
			(xy 391.302057 -281.207103) (xy 391.325708 -281.252166) (xy 391.341824 -281.30044) (xy 391.349988 -281.350674)
			(xy 391.3505 -281.37612) (xy 391.669028 -281.37612) (xy 391.672988 -281.327066) (xy 391.684765 -281.279282)
			(xy 391.704056 -281.234006) (xy 391.730359 -281.19241) (xy 391.762994 -281.155573) (xy 391.801115 -281.124448)
			(xy 391.843736 -281.099841) (xy 391.889752 -281.082389) (xy 391.937971 -281.072545) (xy 391.987146 -281.070564)
			(xy 392.036001 -281.076496) (xy 392.083272 -281.090188) (xy 392.125407 -281.110182) (xy 394.67715 -281.110182)
			(xy 394.68111 -281.061128) (xy 394.692887 -281.013344) (xy 394.712178 -280.968068) (xy 394.738481 -280.926472)
			(xy 394.771116 -280.889635) (xy 394.809237 -280.85851) (xy 394.851858 -280.833903) (xy 394.897874 -280.816451)
			(xy 394.946093 -280.806607) (xy 394.995268 -280.804626) (xy 395.044123 -280.810558) (xy 395.091394 -280.82425)
			(xy 395.135856 -280.845348) (xy 395.176359 -280.873304) (xy 395.211852 -280.907396) (xy 395.241417 -280.94674)
			(xy 395.264288 -280.990317) (xy 395.279872 -281.036998) (xy 395.287767 -281.085575) (xy 395.288262 -281.110182)
			(xy 395.287767 -281.134789) (xy 395.279872 -281.183366) (xy 395.264288 -281.230047) (xy 395.241417 -281.273624)
			(xy 395.211852 -281.312968) (xy 395.176359 -281.34706) (xy 395.135856 -281.375016) (xy 395.091394 -281.396114)
			(xy 395.044123 -281.409806) (xy 394.995268 -281.415738) (xy 394.946093 -281.413757) (xy 394.897874 -281.403913)
			(xy 394.851858 -281.386461) (xy 394.809237 -281.361854) (xy 394.771116 -281.330729) (xy 394.738481 -281.293892)
			(xy 394.712178 -281.252296) (xy 394.692887 -281.20702) (xy 394.68111 -281.159236) (xy 394.67715 -281.110182)
			(xy 392.125407 -281.110182) (xy 392.127734 -281.111286) (xy 392.168237 -281.139242) (xy 392.20373 -281.173334)
			(xy 392.233295 -281.212678) (xy 392.256166 -281.256255) (xy 392.27175 -281.302936) (xy 392.279645 -281.351513)
			(xy 392.28014 -281.37612) (xy 392.279645 -281.400727) (xy 392.27175 -281.449304) (xy 392.256166 -281.495985)
			(xy 392.233295 -281.539562) (xy 392.20373 -281.578906) (xy 392.168237 -281.612998) (xy 392.127734 -281.640954)
			(xy 392.083272 -281.662052) (xy 392.036001 -281.675744) (xy 391.987146 -281.681676) (xy 391.937971 -281.679695)
			(xy 391.889752 -281.669851) (xy 391.843736 -281.652399) (xy 391.801115 -281.627792) (xy 391.762994 -281.596667)
			(xy 391.730359 -281.55983) (xy 391.704056 -281.518234) (xy 391.684765 -281.472958) (xy 391.672988 -281.425174)
			(xy 391.669028 -281.37612) (xy 391.3505 -281.37612) (xy 391.349988 -281.401566) (xy 391.341824 -281.4518)
			(xy 391.325708 -281.500074) (xy 391.302057 -281.545137) (xy 391.271484 -281.585823) (xy 391.23478 -281.621078)
			(xy 391.192896 -281.649988) (xy 391.146917 -281.671805) (xy 391.098033 -281.685965) (xy 391.047512 -281.692099)
			(xy 390.99666 -281.69005) (xy 390.946796 -281.67987) (xy 390.89921 -281.661823) (xy 390.855136 -281.636377)
			(xy 390.815714 -281.60419) (xy 390.781966 -281.566096) (xy 390.754765 -281.523082) (xy 390.734817 -281.476262)
			(xy 390.722638 -281.426848) (xy 390.718543 -281.37612) (xy 390.400032 -281.37612) (xy 390.399537 -281.400727)
			(xy 390.391642 -281.449304) (xy 390.376058 -281.495985) (xy 390.353187 -281.539562) (xy 390.323622 -281.578906)
			(xy 390.288129 -281.612998) (xy 390.247626 -281.640954) (xy 390.203164 -281.662052) (xy 390.155893 -281.675744)
			(xy 390.107038 -281.681676) (xy 390.057863 -281.679695) (xy 390.009644 -281.669851) (xy 389.963628 -281.652399)
			(xy 389.921007 -281.627792) (xy 389.882886 -281.596667) (xy 389.850251 -281.55983) (xy 389.823948 -281.518234)
			(xy 389.804657 -281.472958) (xy 389.79288 -281.425174) (xy 389.78892 -281.37612) (xy 389.470646 -281.37612)
			(xy 389.470134 -281.401566) (xy 389.46197 -281.4518) (xy 389.445854 -281.500074) (xy 389.422203 -281.545137)
			(xy 389.39163 -281.585823) (xy 389.354926 -281.621078) (xy 389.313042 -281.649988) (xy 389.267063 -281.671805)
			(xy 389.218179 -281.685965) (xy 389.167658 -281.692099) (xy 389.116806 -281.69005) (xy 389.066942 -281.67987)
			(xy 389.019356 -281.661823) (xy 388.975282 -281.636377) (xy 388.93586 -281.60419) (xy 388.902112 -281.566096)
			(xy 388.874911 -281.523082) (xy 388.854963 -281.476262) (xy 388.842784 -281.426848) (xy 388.838689 -281.37612)
			(xy 388.520178 -281.37612) (xy 388.519683 -281.400727) (xy 388.511788 -281.449304) (xy 388.496204 -281.495985)
			(xy 388.473333 -281.539562) (xy 388.443768 -281.578906) (xy 388.408275 -281.612998) (xy 388.367772 -281.640954)
			(xy 388.32331 -281.662052) (xy 388.276039 -281.675744) (xy 388.227184 -281.681676) (xy 388.178009 -281.679695)
			(xy 388.12979 -281.669851) (xy 388.083774 -281.652399) (xy 388.041153 -281.627792) (xy 388.003032 -281.596667)
			(xy 387.970397 -281.55983) (xy 387.944094 -281.518234) (xy 387.924803 -281.472958) (xy 387.913026 -281.425174)
			(xy 387.909066 -281.37612) (xy 387.590538 -281.37612) (xy 387.590026 -281.401566) (xy 387.581862 -281.4518)
			(xy 387.565746 -281.500074) (xy 387.542095 -281.545137) (xy 387.511522 -281.585823) (xy 387.474818 -281.621078)
			(xy 387.432934 -281.649988) (xy 387.386955 -281.671805) (xy 387.338071 -281.685965) (xy 387.28755 -281.692099)
			(xy 387.236698 -281.69005) (xy 387.186834 -281.67987) (xy 387.139248 -281.661823) (xy 387.095174 -281.636377)
			(xy 387.055752 -281.60419) (xy 387.022004 -281.566096) (xy 386.994803 -281.523082) (xy 386.974855 -281.476262)
			(xy 386.962676 -281.426848) (xy 386.958581 -281.37612) (xy 386.650484 -281.37612) (xy 386.649972 -281.401566)
			(xy 386.641808 -281.4518) (xy 386.625692 -281.500074) (xy 386.602041 -281.545137) (xy 386.571468 -281.585823)
			(xy 386.534764 -281.621078) (xy 386.49288 -281.649988) (xy 386.446901 -281.671805) (xy 386.398017 -281.685965)
			(xy 386.347496 -281.692099) (xy 386.296644 -281.69005) (xy 386.24678 -281.67987) (xy 386.199194 -281.661823)
			(xy 386.15512 -281.636377) (xy 386.115698 -281.60419) (xy 386.08195 -281.566096) (xy 386.054749 -281.523082)
			(xy 386.034801 -281.476262) (xy 386.022622 -281.426848) (xy 386.018527 -281.37612) (xy 385.700016 -281.37612)
			(xy 385.699521 -281.400727) (xy 385.691626 -281.449304) (xy 385.676042 -281.495985) (xy 385.653171 -281.539562)
			(xy 385.623606 -281.578906) (xy 385.588113 -281.612998) (xy 385.54761 -281.640954) (xy 385.503148 -281.662052)
			(xy 385.455877 -281.675744) (xy 385.407022 -281.681676) (xy 385.357847 -281.679695) (xy 385.309628 -281.669851)
			(xy 385.263612 -281.652399) (xy 385.220991 -281.627792) (xy 385.18287 -281.596667) (xy 385.150235 -281.55983)
			(xy 385.123932 -281.518234) (xy 385.104641 -281.472958) (xy 385.092864 -281.425174) (xy 385.088904 -281.37612)
			(xy 384.77063 -281.37612) (xy 384.770118 -281.401566) (xy 384.761954 -281.4518) (xy 384.745838 -281.500074)
			(xy 384.722187 -281.545137) (xy 384.691614 -281.585823) (xy 384.65491 -281.621078) (xy 384.613026 -281.649988)
			(xy 384.567047 -281.671805) (xy 384.518163 -281.685965) (xy 384.467642 -281.692099) (xy 384.41679 -281.69005)
			(xy 384.366926 -281.67987) (xy 384.31934 -281.661823) (xy 384.275266 -281.636377) (xy 384.235844 -281.60419)
			(xy 384.202096 -281.566096) (xy 384.174895 -281.523082) (xy 384.154947 -281.476262) (xy 384.142768 -281.426848)
			(xy 384.138673 -281.37612) (xy 383.820162 -281.37612) (xy 383.819667 -281.400727) (xy 383.811772 -281.449304)
			(xy 383.796188 -281.495985) (xy 383.773317 -281.539562) (xy 383.743752 -281.578906) (xy 383.708259 -281.612998)
			(xy 383.667756 -281.640954) (xy 383.623294 -281.662052) (xy 383.576023 -281.675744) (xy 383.527168 -281.681676)
			(xy 383.477993 -281.679695) (xy 383.429774 -281.669851) (xy 383.383758 -281.652399) (xy 383.341137 -281.627792)
			(xy 383.303016 -281.596667) (xy 383.270381 -281.55983) (xy 383.244078 -281.518234) (xy 383.224787 -281.472958)
			(xy 383.21301 -281.425174) (xy 383.20905 -281.37612) (xy 382.890522 -281.37612) (xy 382.89001 -281.401566)
			(xy 382.881846 -281.4518) (xy 382.86573 -281.500074) (xy 382.842079 -281.545137) (xy 382.811506 -281.585823)
			(xy 382.774802 -281.621078) (xy 382.732918 -281.649988) (xy 382.686939 -281.671805) (xy 382.638055 -281.685965)
			(xy 382.587534 -281.692099) (xy 382.536682 -281.69005) (xy 382.486818 -281.67987) (xy 382.439232 -281.661823)
			(xy 382.395158 -281.636377) (xy 382.355736 -281.60419) (xy 382.321988 -281.566096) (xy 382.294787 -281.523082)
			(xy 382.274839 -281.476262) (xy 382.26266 -281.426848) (xy 382.258565 -281.37612) (xy 381.940054 -281.37612)
			(xy 381.939559 -281.400727) (xy 381.931664 -281.449304) (xy 381.91608 -281.495985) (xy 381.893209 -281.539562)
			(xy 381.863644 -281.578906) (xy 381.828151 -281.612998) (xy 381.787648 -281.640954) (xy 381.743186 -281.662052)
			(xy 381.695915 -281.675744) (xy 381.64706 -281.681676) (xy 381.597885 -281.679695) (xy 381.549666 -281.669851)
			(xy 381.50365 -281.652399) (xy 381.461029 -281.627792) (xy 381.422908 -281.596667) (xy 381.390273 -281.55983)
			(xy 381.36397 -281.518234) (xy 381.344679 -281.472958) (xy 381.332902 -281.425174) (xy 381.328942 -281.37612)
			(xy 381.010668 -281.37612) (xy 381.010156 -281.401566) (xy 381.001992 -281.4518) (xy 380.985876 -281.500074)
			(xy 380.962225 -281.545137) (xy 380.931652 -281.585823) (xy 380.894948 -281.621078) (xy 380.853064 -281.649988)
			(xy 380.807085 -281.671805) (xy 380.758201 -281.685965) (xy 380.70768 -281.692099) (xy 380.656828 -281.69005)
			(xy 380.606964 -281.67987) (xy 380.559378 -281.661823) (xy 380.515304 -281.636377) (xy 380.475882 -281.60419)
			(xy 380.442134 -281.566096) (xy 380.414933 -281.523082) (xy 380.394985 -281.476262) (xy 380.382806 -281.426848)
			(xy 380.378711 -281.37612) (xy 380.070614 -281.37612) (xy 380.070102 -281.401566) (xy 380.061938 -281.4518)
			(xy 380.045822 -281.500074) (xy 380.022171 -281.545137) (xy 379.991598 -281.585823) (xy 379.954894 -281.621078)
			(xy 379.91301 -281.649988) (xy 379.867031 -281.671805) (xy 379.818147 -281.685965) (xy 379.767626 -281.692099)
			(xy 379.716774 -281.69005) (xy 379.66691 -281.67987) (xy 379.619324 -281.661823) (xy 379.57525 -281.636377)
			(xy 379.535828 -281.60419) (xy 379.50208 -281.566096) (xy 379.474879 -281.523082) (xy 379.454931 -281.476262)
			(xy 379.442752 -281.426848) (xy 379.438657 -281.37612) (xy 379.120146 -281.37612) (xy 379.119651 -281.400727)
			(xy 379.111756 -281.449304) (xy 379.096172 -281.495985) (xy 379.073301 -281.539562) (xy 379.043736 -281.578906)
			(xy 379.008243 -281.612998) (xy 378.96774 -281.640954) (xy 378.923278 -281.662052) (xy 378.876007 -281.675744)
			(xy 378.827152 -281.681676) (xy 378.777977 -281.679695) (xy 378.729758 -281.669851) (xy 378.683742 -281.652399)
			(xy 378.641121 -281.627792) (xy 378.603 -281.596667) (xy 378.570365 -281.55983) (xy 378.544062 -281.518234)
			(xy 378.524771 -281.472958) (xy 378.512994 -281.425174) (xy 378.509034 -281.37612) (xy 378.190506 -281.37612)
			(xy 378.189994 -281.401566) (xy 378.18183 -281.4518) (xy 378.165714 -281.500074) (xy 378.142063 -281.545137)
			(xy 378.11149 -281.585823) (xy 378.074786 -281.621078) (xy 378.032902 -281.649988) (xy 377.986923 -281.671805)
			(xy 377.938039 -281.685965) (xy 377.887518 -281.692099) (xy 377.836666 -281.69005) (xy 377.786802 -281.67987)
			(xy 377.739216 -281.661823) (xy 377.695142 -281.636377) (xy 377.65572 -281.60419) (xy 377.621972 -281.566096)
			(xy 377.594771 -281.523082) (xy 377.574823 -281.476262) (xy 377.562644 -281.426848) (xy 377.558549 -281.37612)
			(xy 377.240038 -281.37612) (xy 377.239543 -281.400727) (xy 377.231648 -281.449304) (xy 377.216064 -281.495985)
			(xy 377.193193 -281.539562) (xy 377.163628 -281.578906) (xy 377.128135 -281.612998) (xy 377.087632 -281.640954)
			(xy 377.04317 -281.662052) (xy 376.995899 -281.675744) (xy 376.947044 -281.681676) (xy 376.897869 -281.679695)
			(xy 376.84965 -281.669851) (xy 376.803634 -281.652399) (xy 376.761013 -281.627792) (xy 376.722892 -281.596667)
			(xy 376.690257 -281.55983) (xy 376.663954 -281.518234) (xy 376.644663 -281.472958) (xy 376.632886 -281.425174)
			(xy 376.628926 -281.37612) (xy 376.310652 -281.37612) (xy 376.31014 -281.401566) (xy 376.301976 -281.4518)
			(xy 376.28586 -281.500074) (xy 376.262209 -281.545137) (xy 376.231636 -281.585823) (xy 376.194932 -281.621078)
			(xy 376.153048 -281.649988) (xy 376.107069 -281.671805) (xy 376.058185 -281.685965) (xy 376.007664 -281.692099)
			(xy 375.956812 -281.69005) (xy 375.906948 -281.67987) (xy 375.859362 -281.661823) (xy 375.815288 -281.636377)
			(xy 375.775866 -281.60419) (xy 375.742118 -281.566096) (xy 375.714917 -281.523082) (xy 375.694969 -281.476262)
			(xy 375.68279 -281.426848) (xy 375.678695 -281.37612) (xy 375.359677 -281.37612) (xy 375.359677 -281.401599)
			(xy 375.351202 -281.451866) (xy 375.334491 -281.500026) (xy 375.310008 -281.544739) (xy 375.278434 -281.58476)
			(xy 375.240647 -281.618977) (xy 375.219468 -281.633168) (xy 375.212482 -281.638053) (xy 375.201974 -281.651464)
			(xy 375.196431 -281.667575) (xy 375.1961 -281.676094) (xy 375.1961 -282.186126) (xy 376.148595 -282.186126)
			(xy 376.15269 -282.135398) (xy 376.164869 -282.085984) (xy 376.184817 -282.039164) (xy 376.212018 -281.99615)
			(xy 376.245766 -281.958056) (xy 376.285188 -281.925869) (xy 376.329262 -281.900423) (xy 376.376848 -281.882376)
			(xy 376.426712 -281.872196) (xy 376.477564 -281.870147) (xy 376.528085 -281.876281) (xy 376.576969 -281.890441)
			(xy 376.622948 -281.912258) (xy 376.664832 -281.941168) (xy 376.701536 -281.976423) (xy 376.732109 -282.017109)
			(xy 376.75576 -282.062172) (xy 376.771876 -282.110446) (xy 376.78004 -282.16068) (xy 376.780552 -282.186126)
			(xy 377.088649 -282.186126) (xy 377.092744 -282.135398) (xy 377.104923 -282.085984) (xy 377.124871 -282.039164)
			(xy 377.152072 -281.99615) (xy 377.18582 -281.958056) (xy 377.225242 -281.925869) (xy 377.269316 -281.900423)
			(xy 377.316902 -281.882376) (xy 377.366766 -281.872196) (xy 377.417618 -281.870147) (xy 377.468139 -281.876281)
			(xy 377.517023 -281.890441) (xy 377.563002 -281.912258) (xy 377.604886 -281.941168) (xy 377.64159 -281.976423)
			(xy 377.672163 -282.017109) (xy 377.695814 -282.062172) (xy 377.71193 -282.110446) (xy 377.720094 -282.16068)
			(xy 377.720606 -282.186126) (xy 378.039134 -282.186126) (xy 378.043094 -282.137072) (xy 378.054871 -282.089288)
			(xy 378.074162 -282.044012) (xy 378.100465 -282.002416) (xy 378.1331 -281.965579) (xy 378.171221 -281.934454)
			(xy 378.213842 -281.909847) (xy 378.259858 -281.892395) (xy 378.308077 -281.882551) (xy 378.357252 -281.88057)
			(xy 378.406107 -281.886502) (xy 378.453378 -281.900194) (xy 378.49784 -281.921292) (xy 378.538343 -281.949248)
			(xy 378.573836 -281.98334) (xy 378.603401 -282.022684) (xy 378.626272 -282.066261) (xy 378.641856 -282.112942)
			(xy 378.649751 -282.161519) (xy 378.650246 -282.186126) (xy 378.968503 -282.186126) (xy 378.972598 -282.135398)
			(xy 378.984777 -282.085984) (xy 379.004725 -282.039164) (xy 379.031926 -281.99615) (xy 379.065674 -281.958056)
			(xy 379.105096 -281.925869) (xy 379.14917 -281.900423) (xy 379.196756 -281.882376) (xy 379.24662 -281.872196)
			(xy 379.297472 -281.870147) (xy 379.347993 -281.876281) (xy 379.396877 -281.890441) (xy 379.442856 -281.912258)
			(xy 379.48474 -281.941168) (xy 379.521444 -281.976423) (xy 379.552017 -282.017109) (xy 379.575668 -282.062172)
			(xy 379.591784 -282.110446) (xy 379.599948 -282.16068) (xy 379.60046 -282.186126) (xy 379.918988 -282.186126)
			(xy 379.922948 -282.137072) (xy 379.934725 -282.089288) (xy 379.954016 -282.044012) (xy 379.980319 -282.002416)
			(xy 380.012954 -281.965579) (xy 380.051075 -281.934454) (xy 380.093696 -281.909847) (xy 380.139712 -281.892395)
			(xy 380.187931 -281.882551) (xy 380.237106 -281.88057) (xy 380.285961 -281.886502) (xy 380.333232 -281.900194)
			(xy 380.377694 -281.921292) (xy 380.418197 -281.949248) (xy 380.45369 -281.98334) (xy 380.483255 -282.022684)
			(xy 380.506126 -282.066261) (xy 380.52171 -282.112942) (xy 380.529605 -282.161519) (xy 380.5301 -282.186126)
			(xy 380.848611 -282.186126) (xy 380.852706 -282.135398) (xy 380.864885 -282.085984) (xy 380.884833 -282.039164)
			(xy 380.912034 -281.99615) (xy 380.945782 -281.958056) (xy 380.985204 -281.925869) (xy 381.029278 -281.900423)
			(xy 381.076864 -281.882376) (xy 381.126728 -281.872196) (xy 381.17758 -281.870147) (xy 381.228101 -281.876281)
			(xy 381.276985 -281.890441) (xy 381.322964 -281.912258) (xy 381.364848 -281.941168) (xy 381.401552 -281.976423)
			(xy 381.432125 -282.017109) (xy 381.455776 -282.062172) (xy 381.471892 -282.110446) (xy 381.480056 -282.16068)
			(xy 381.480568 -282.186126) (xy 381.799096 -282.186126) (xy 381.803056 -282.137072) (xy 381.814833 -282.089288)
			(xy 381.834124 -282.044012) (xy 381.860427 -282.002416) (xy 381.893062 -281.965579) (xy 381.931183 -281.934454)
			(xy 381.973804 -281.909847) (xy 382.01982 -281.892395) (xy 382.068039 -281.882551) (xy 382.117214 -281.88057)
			(xy 382.166069 -281.886502) (xy 382.21334 -281.900194) (xy 382.257802 -281.921292) (xy 382.298305 -281.949248)
			(xy 382.333798 -281.98334) (xy 382.363363 -282.022684) (xy 382.386234 -282.066261) (xy 382.401818 -282.112942)
			(xy 382.409713 -282.161519) (xy 382.410208 -282.186126) (xy 382.728465 -282.186126) (xy 382.73256 -282.135398)
			(xy 382.744739 -282.085984) (xy 382.764687 -282.039164) (xy 382.791888 -281.99615) (xy 382.825636 -281.958056)
			(xy 382.865058 -281.925869) (xy 382.909132 -281.900423) (xy 382.956718 -281.882376) (xy 383.006582 -281.872196)
			(xy 383.057434 -281.870147) (xy 383.107955 -281.876281) (xy 383.156839 -281.890441) (xy 383.202818 -281.912258)
			(xy 383.244702 -281.941168) (xy 383.281406 -281.976423) (xy 383.311979 -282.017109) (xy 383.33563 -282.062172)
			(xy 383.351746 -282.110446) (xy 383.35991 -282.16068) (xy 383.360422 -282.186126) (xy 383.668519 -282.186126)
			(xy 383.672614 -282.135398) (xy 383.684793 -282.085984) (xy 383.704741 -282.039164) (xy 383.731942 -281.99615)
			(xy 383.76569 -281.958056) (xy 383.805112 -281.925869) (xy 383.849186 -281.900423) (xy 383.896772 -281.882376)
			(xy 383.946636 -281.872196) (xy 383.997488 -281.870147) (xy 384.048009 -281.876281) (xy 384.096893 -281.890441)
			(xy 384.142872 -281.912258) (xy 384.184756 -281.941168) (xy 384.22146 -281.976423) (xy 384.252033 -282.017109)
			(xy 384.275684 -282.062172) (xy 384.2918 -282.110446) (xy 384.299964 -282.16068) (xy 384.300476 -282.186126)
			(xy 384.619004 -282.186126) (xy 384.622964 -282.137072) (xy 384.634741 -282.089288) (xy 384.654032 -282.044012)
			(xy 384.680335 -282.002416) (xy 384.71297 -281.965579) (xy 384.751091 -281.934454) (xy 384.793712 -281.909847)
			(xy 384.839728 -281.892395) (xy 384.887947 -281.882551) (xy 384.937122 -281.88057) (xy 384.985977 -281.886502)
			(xy 385.033248 -281.900194) (xy 385.07771 -281.921292) (xy 385.118213 -281.949248) (xy 385.153706 -281.98334)
			(xy 385.183271 -282.022684) (xy 385.206142 -282.066261) (xy 385.221726 -282.112942) (xy 385.229621 -282.161519)
			(xy 385.230116 -282.186126) (xy 385.548627 -282.186126) (xy 385.552722 -282.135398) (xy 385.564901 -282.085984)
			(xy 385.584849 -282.039164) (xy 385.61205 -281.99615) (xy 385.645798 -281.958056) (xy 385.68522 -281.925869)
			(xy 385.729294 -281.900423) (xy 385.77688 -281.882376) (xy 385.826744 -281.872196) (xy 385.877596 -281.870147)
			(xy 385.928117 -281.876281) (xy 385.977001 -281.890441) (xy 386.02298 -281.912258) (xy 386.064864 -281.941168)
			(xy 386.101568 -281.976423) (xy 386.132141 -282.017109) (xy 386.155792 -282.062172) (xy 386.171908 -282.110446)
			(xy 386.180072 -282.16068) (xy 386.180584 -282.186126) (xy 386.499112 -282.186126) (xy 386.503072 -282.137072)
			(xy 386.514849 -282.089288) (xy 386.53414 -282.044012) (xy 386.560443 -282.002416) (xy 386.593078 -281.965579)
			(xy 386.631199 -281.934454) (xy 386.67382 -281.909847) (xy 386.719836 -281.892395) (xy 386.768055 -281.882551)
			(xy 386.81723 -281.88057) (xy 386.866085 -281.886502) (xy 386.913356 -281.900194) (xy 386.957818 -281.921292)
			(xy 386.998321 -281.949248) (xy 387.033814 -281.98334) (xy 387.063379 -282.022684) (xy 387.08625 -282.066261)
			(xy 387.101834 -282.112942) (xy 387.109729 -282.161519) (xy 387.110224 -282.186126) (xy 387.428481 -282.186126)
			(xy 387.432576 -282.135398) (xy 387.444755 -282.085984) (xy 387.464703 -282.039164) (xy 387.491904 -281.99615)
			(xy 387.525652 -281.958056) (xy 387.565074 -281.925869) (xy 387.609148 -281.900423) (xy 387.656734 -281.882376)
			(xy 387.706598 -281.872196) (xy 387.75745 -281.870147) (xy 387.807971 -281.876281) (xy 387.856855 -281.890441)
			(xy 387.902834 -281.912258) (xy 387.944718 -281.941168) (xy 387.981422 -281.976423) (xy 388.011995 -282.017109)
			(xy 388.035646 -282.062172) (xy 388.051762 -282.110446) (xy 388.059926 -282.16068) (xy 388.060438 -282.186126)
			(xy 388.378966 -282.186126) (xy 388.382926 -282.137072) (xy 388.394703 -282.089288) (xy 388.413994 -282.044012)
			(xy 388.440297 -282.002416) (xy 388.472932 -281.965579) (xy 388.511053 -281.934454) (xy 388.553674 -281.909847)
			(xy 388.59969 -281.892395) (xy 388.647909 -281.882551) (xy 388.697084 -281.88057) (xy 388.745939 -281.886502)
			(xy 388.79321 -281.900194) (xy 388.837672 -281.921292) (xy 388.878175 -281.949248) (xy 388.913668 -281.98334)
			(xy 388.943233 -282.022684) (xy 388.966104 -282.066261) (xy 388.981688 -282.112942) (xy 388.989583 -282.161519)
			(xy 388.990078 -282.186126) (xy 389.308589 -282.186126) (xy 389.312684 -282.135398) (xy 389.324863 -282.085984)
			(xy 389.344811 -282.039164) (xy 389.372012 -281.99615) (xy 389.40576 -281.958056) (xy 389.445182 -281.925869)
			(xy 389.489256 -281.900423) (xy 389.536842 -281.882376) (xy 389.586706 -281.872196) (xy 389.637558 -281.870147)
			(xy 389.688079 -281.876281) (xy 389.736963 -281.890441) (xy 389.782942 -281.912258) (xy 389.824826 -281.941168)
			(xy 389.86153 -281.976423) (xy 389.892103 -282.017109) (xy 389.915754 -282.062172) (xy 389.93187 -282.110446)
			(xy 389.940034 -282.16068) (xy 389.940546 -282.186126) (xy 390.248643 -282.186126) (xy 390.252738 -282.135398)
			(xy 390.264917 -282.085984) (xy 390.284865 -282.039164) (xy 390.312066 -281.99615) (xy 390.345814 -281.958056)
			(xy 390.385236 -281.925869) (xy 390.42931 -281.900423) (xy 390.476896 -281.882376) (xy 390.52676 -281.872196)
			(xy 390.577612 -281.870147) (xy 390.628133 -281.876281) (xy 390.677017 -281.890441) (xy 390.722996 -281.912258)
			(xy 390.76488 -281.941168) (xy 390.801584 -281.976423) (xy 390.832157 -282.017109) (xy 390.855808 -282.062172)
			(xy 390.871924 -282.110446) (xy 390.880088 -282.16068) (xy 390.8806 -282.186126) (xy 391.198874 -282.186126)
			(xy 391.202834 -282.137072) (xy 391.214611 -282.089288) (xy 391.233902 -282.044012) (xy 391.260205 -282.002416)
			(xy 391.29284 -281.965579) (xy 391.330961 -281.934454) (xy 391.373582 -281.909847) (xy 391.419598 -281.892395)
			(xy 391.467817 -281.882551) (xy 391.516992 -281.88057) (xy 391.565847 -281.886502) (xy 391.613118 -281.900194)
			(xy 391.65758 -281.921292) (xy 391.698083 -281.949248) (xy 391.733576 -281.98334) (xy 391.763141 -282.022684)
			(xy 391.786012 -282.066261) (xy 391.801596 -282.112942) (xy 391.809491 -282.161519) (xy 391.809986 -282.186126)
			(xy 393.078982 -282.186126) (xy 393.082942 -282.137072) (xy 393.094719 -282.089288) (xy 393.11401 -282.044012)
			(xy 393.140313 -282.002416) (xy 393.172948 -281.965579) (xy 393.211069 -281.934454) (xy 393.25369 -281.909847)
			(xy 393.299706 -281.892395) (xy 393.347925 -281.882551) (xy 393.3971 -281.88057) (xy 393.445955 -281.886502)
			(xy 393.493226 -281.900194) (xy 393.537688 -281.921292) (xy 393.578191 -281.949248) (xy 393.613684 -281.98334)
			(xy 393.643249 -282.022684) (xy 393.66612 -282.066261) (xy 393.681704 -282.112942) (xy 393.689599 -282.161519)
			(xy 393.690094 -282.186126) (xy 393.689599 -282.210733) (xy 393.681704 -282.25931) (xy 393.66612 -282.305991)
			(xy 393.643249 -282.349568) (xy 393.613684 -282.388912) (xy 393.578191 -282.423004) (xy 393.537688 -282.45096)
			(xy 393.493226 -282.472058) (xy 393.445955 -282.48575) (xy 393.3971 -282.491682) (xy 393.347925 -282.489701)
			(xy 393.299706 -282.479857) (xy 393.25369 -282.462405) (xy 393.211069 -282.437798) (xy 393.172948 -282.406673)
			(xy 393.140313 -282.369836) (xy 393.11401 -282.32824) (xy 393.094719 -282.282964) (xy 393.082942 -282.23518)
			(xy 393.078982 -282.186126) (xy 391.809986 -282.186126) (xy 391.809491 -282.210733) (xy 391.801596 -282.25931)
			(xy 391.786012 -282.305991) (xy 391.763141 -282.349568) (xy 391.733576 -282.388912) (xy 391.698083 -282.423004)
			(xy 391.65758 -282.45096) (xy 391.613118 -282.472058) (xy 391.565847 -282.48575) (xy 391.516992 -282.491682)
			(xy 391.467817 -282.489701) (xy 391.419598 -282.479857) (xy 391.373582 -282.462405) (xy 391.330961 -282.437798)
			(xy 391.29284 -282.406673) (xy 391.260205 -282.369836) (xy 391.233902 -282.32824) (xy 391.214611 -282.282964)
			(xy 391.202834 -282.23518) (xy 391.198874 -282.186126) (xy 390.8806 -282.186126) (xy 390.880088 -282.211572)
			(xy 390.871924 -282.261806) (xy 390.855808 -282.31008) (xy 390.832157 -282.355143) (xy 390.801584 -282.395829)
			(xy 390.76488 -282.431084) (xy 390.722996 -282.459994) (xy 390.677017 -282.481811) (xy 390.628133 -282.495971)
			(xy 390.577612 -282.502105) (xy 390.52676 -282.500056) (xy 390.476896 -282.489876) (xy 390.42931 -282.471829)
			(xy 390.385236 -282.446383) (xy 390.345814 -282.414196) (xy 390.312066 -282.376102) (xy 390.284865 -282.333088)
			(xy 390.264917 -282.286268) (xy 390.252738 -282.236854) (xy 390.248643 -282.186126) (xy 389.940546 -282.186126)
			(xy 389.940034 -282.211572) (xy 389.93187 -282.261806) (xy 389.915754 -282.31008) (xy 389.892103 -282.355143)
			(xy 389.86153 -282.395829) (xy 389.824826 -282.431084) (xy 389.782942 -282.459994) (xy 389.736963 -282.481811)
			(xy 389.688079 -282.495971) (xy 389.637558 -282.502105) (xy 389.586706 -282.500056) (xy 389.536842 -282.489876)
			(xy 389.489256 -282.471829) (xy 389.445182 -282.446383) (xy 389.40576 -282.414196) (xy 389.372012 -282.376102)
			(xy 389.344811 -282.333088) (xy 389.324863 -282.286268) (xy 389.312684 -282.236854) (xy 389.308589 -282.186126)
			(xy 388.990078 -282.186126) (xy 388.989583 -282.210733) (xy 388.981688 -282.25931) (xy 388.966104 -282.305991)
			(xy 388.943233 -282.349568) (xy 388.913668 -282.388912) (xy 388.878175 -282.423004) (xy 388.837672 -282.45096)
			(xy 388.79321 -282.472058) (xy 388.745939 -282.48575) (xy 388.697084 -282.491682) (xy 388.647909 -282.489701)
			(xy 388.59969 -282.479857) (xy 388.553674 -282.462405) (xy 388.511053 -282.437798) (xy 388.472932 -282.406673)
			(xy 388.440297 -282.369836) (xy 388.413994 -282.32824) (xy 388.394703 -282.282964) (xy 388.382926 -282.23518)
			(xy 388.378966 -282.186126) (xy 388.060438 -282.186126) (xy 388.059926 -282.211572) (xy 388.051762 -282.261806)
			(xy 388.035646 -282.31008) (xy 388.011995 -282.355143) (xy 387.981422 -282.395829) (xy 387.944718 -282.431084)
			(xy 387.902834 -282.459994) (xy 387.856855 -282.481811) (xy 387.807971 -282.495971) (xy 387.75745 -282.502105)
			(xy 387.706598 -282.500056) (xy 387.656734 -282.489876) (xy 387.609148 -282.471829) (xy 387.565074 -282.446383)
			(xy 387.525652 -282.414196) (xy 387.491904 -282.376102) (xy 387.464703 -282.333088) (xy 387.444755 -282.286268)
			(xy 387.432576 -282.236854) (xy 387.428481 -282.186126) (xy 387.110224 -282.186126) (xy 387.109729 -282.210733)
			(xy 387.101834 -282.25931) (xy 387.08625 -282.305991) (xy 387.063379 -282.349568) (xy 387.033814 -282.388912)
			(xy 386.998321 -282.423004) (xy 386.957818 -282.45096) (xy 386.913356 -282.472058) (xy 386.866085 -282.48575)
			(xy 386.81723 -282.491682) (xy 386.768055 -282.489701) (xy 386.719836 -282.479857) (xy 386.67382 -282.462405)
			(xy 386.631199 -282.437798) (xy 386.593078 -282.406673) (xy 386.560443 -282.369836) (xy 386.53414 -282.32824)
			(xy 386.514849 -282.282964) (xy 386.503072 -282.23518) (xy 386.499112 -282.186126) (xy 386.180584 -282.186126)
			(xy 386.180072 -282.211572) (xy 386.171908 -282.261806) (xy 386.155792 -282.31008) (xy 386.132141 -282.355143)
			(xy 386.101568 -282.395829) (xy 386.064864 -282.431084) (xy 386.02298 -282.459994) (xy 385.977001 -282.481811)
			(xy 385.928117 -282.495971) (xy 385.877596 -282.502105) (xy 385.826744 -282.500056) (xy 385.77688 -282.489876)
			(xy 385.729294 -282.471829) (xy 385.68522 -282.446383) (xy 385.645798 -282.414196) (xy 385.61205 -282.376102)
			(xy 385.584849 -282.333088) (xy 385.564901 -282.286268) (xy 385.552722 -282.236854) (xy 385.548627 -282.186126)
			(xy 385.230116 -282.186126) (xy 385.229621 -282.210733) (xy 385.221726 -282.25931) (xy 385.206142 -282.305991)
			(xy 385.183271 -282.349568) (xy 385.153706 -282.388912) (xy 385.118213 -282.423004) (xy 385.07771 -282.45096)
			(xy 385.033248 -282.472058) (xy 384.985977 -282.48575) (xy 384.937122 -282.491682) (xy 384.887947 -282.489701)
			(xy 384.839728 -282.479857) (xy 384.793712 -282.462405) (xy 384.751091 -282.437798) (xy 384.71297 -282.406673)
			(xy 384.680335 -282.369836) (xy 384.654032 -282.32824) (xy 384.634741 -282.282964) (xy 384.622964 -282.23518)
			(xy 384.619004 -282.186126) (xy 384.300476 -282.186126) (xy 384.299964 -282.211572) (xy 384.2918 -282.261806)
			(xy 384.275684 -282.31008) (xy 384.252033 -282.355143) (xy 384.22146 -282.395829) (xy 384.184756 -282.431084)
			(xy 384.142872 -282.459994) (xy 384.096893 -282.481811) (xy 384.048009 -282.495971) (xy 383.997488 -282.502105)
			(xy 383.946636 -282.500056) (xy 383.896772 -282.489876) (xy 383.849186 -282.471829) (xy 383.805112 -282.446383)
			(xy 383.76569 -282.414196) (xy 383.731942 -282.376102) (xy 383.704741 -282.333088) (xy 383.684793 -282.286268)
			(xy 383.672614 -282.236854) (xy 383.668519 -282.186126) (xy 383.360422 -282.186126) (xy 383.35991 -282.211572)
			(xy 383.351746 -282.261806) (xy 383.33563 -282.31008) (xy 383.311979 -282.355143) (xy 383.281406 -282.395829)
			(xy 383.244702 -282.431084) (xy 383.202818 -282.459994) (xy 383.156839 -282.481811) (xy 383.107955 -282.495971)
			(xy 383.057434 -282.502105) (xy 383.006582 -282.500056) (xy 382.956718 -282.489876) (xy 382.909132 -282.471829)
			(xy 382.865058 -282.446383) (xy 382.825636 -282.414196) (xy 382.791888 -282.376102) (xy 382.764687 -282.333088)
			(xy 382.744739 -282.286268) (xy 382.73256 -282.236854) (xy 382.728465 -282.186126) (xy 382.410208 -282.186126)
			(xy 382.409713 -282.210733) (xy 382.401818 -282.25931) (xy 382.386234 -282.305991) (xy 382.363363 -282.349568)
			(xy 382.333798 -282.388912) (xy 382.298305 -282.423004) (xy 382.257802 -282.45096) (xy 382.21334 -282.472058)
			(xy 382.166069 -282.48575) (xy 382.117214 -282.491682) (xy 382.068039 -282.489701) (xy 382.01982 -282.479857)
			(xy 381.973804 -282.462405) (xy 381.931183 -282.437798) (xy 381.893062 -282.406673) (xy 381.860427 -282.369836)
			(xy 381.834124 -282.32824) (xy 381.814833 -282.282964) (xy 381.803056 -282.23518) (xy 381.799096 -282.186126)
			(xy 381.480568 -282.186126) (xy 381.480056 -282.211572) (xy 381.471892 -282.261806) (xy 381.455776 -282.31008)
			(xy 381.432125 -282.355143) (xy 381.401552 -282.395829) (xy 381.364848 -282.431084) (xy 381.322964 -282.459994)
			(xy 381.276985 -282.481811) (xy 381.228101 -282.495971) (xy 381.17758 -282.502105) (xy 381.126728 -282.500056)
			(xy 381.076864 -282.489876) (xy 381.029278 -282.471829) (xy 380.985204 -282.446383) (xy 380.945782 -282.414196)
			(xy 380.912034 -282.376102) (xy 380.884833 -282.333088) (xy 380.864885 -282.286268) (xy 380.852706 -282.236854)
			(xy 380.848611 -282.186126) (xy 380.5301 -282.186126) (xy 380.529605 -282.210733) (xy 380.52171 -282.25931)
			(xy 380.506126 -282.305991) (xy 380.483255 -282.349568) (xy 380.45369 -282.388912) (xy 380.418197 -282.423004)
			(xy 380.377694 -282.45096) (xy 380.333232 -282.472058) (xy 380.285961 -282.48575) (xy 380.237106 -282.491682)
			(xy 380.187931 -282.489701) (xy 380.139712 -282.479857) (xy 380.093696 -282.462405) (xy 380.051075 -282.437798)
			(xy 380.012954 -282.406673) (xy 379.980319 -282.369836) (xy 379.954016 -282.32824) (xy 379.934725 -282.282964)
			(xy 379.922948 -282.23518) (xy 379.918988 -282.186126) (xy 379.60046 -282.186126) (xy 379.599948 -282.211572)
			(xy 379.591784 -282.261806) (xy 379.575668 -282.31008) (xy 379.552017 -282.355143) (xy 379.521444 -282.395829)
			(xy 379.48474 -282.431084) (xy 379.442856 -282.459994) (xy 379.396877 -282.481811) (xy 379.347993 -282.495971)
			(xy 379.297472 -282.502105) (xy 379.24662 -282.500056) (xy 379.196756 -282.489876) (xy 379.14917 -282.471829)
			(xy 379.105096 -282.446383) (xy 379.065674 -282.414196) (xy 379.031926 -282.376102) (xy 379.004725 -282.333088)
			(xy 378.984777 -282.286268) (xy 378.972598 -282.236854) (xy 378.968503 -282.186126) (xy 378.650246 -282.186126)
			(xy 378.649751 -282.210733) (xy 378.641856 -282.25931) (xy 378.626272 -282.305991) (xy 378.603401 -282.349568)
			(xy 378.573836 -282.388912) (xy 378.538343 -282.423004) (xy 378.49784 -282.45096) (xy 378.453378 -282.472058)
			(xy 378.406107 -282.48575) (xy 378.357252 -282.491682) (xy 378.308077 -282.489701) (xy 378.259858 -282.479857)
			(xy 378.213842 -282.462405) (xy 378.171221 -282.437798) (xy 378.1331 -282.406673) (xy 378.100465 -282.369836)
			(xy 378.074162 -282.32824) (xy 378.054871 -282.282964) (xy 378.043094 -282.23518) (xy 378.039134 -282.186126)
			(xy 377.720606 -282.186126) (xy 377.720094 -282.211572) (xy 377.71193 -282.261806) (xy 377.695814 -282.31008)
			(xy 377.672163 -282.355143) (xy 377.64159 -282.395829) (xy 377.604886 -282.431084) (xy 377.563002 -282.459994)
			(xy 377.517023 -282.481811) (xy 377.468139 -282.495971) (xy 377.417618 -282.502105) (xy 377.366766 -282.500056)
			(xy 377.316902 -282.489876) (xy 377.269316 -282.471829) (xy 377.225242 -282.446383) (xy 377.18582 -282.414196)
			(xy 377.152072 -282.376102) (xy 377.124871 -282.333088) (xy 377.104923 -282.286268) (xy 377.092744 -282.236854)
			(xy 377.088649 -282.186126) (xy 376.780552 -282.186126) (xy 376.78004 -282.211572) (xy 376.771876 -282.261806)
			(xy 376.75576 -282.31008) (xy 376.732109 -282.355143) (xy 376.701536 -282.395829) (xy 376.664832 -282.431084)
			(xy 376.622948 -282.459994) (xy 376.576969 -282.481811) (xy 376.528085 -282.495971) (xy 376.477564 -282.502105)
			(xy 376.426712 -282.500056) (xy 376.376848 -282.489876) (xy 376.329262 -282.471829) (xy 376.285188 -282.446383)
			(xy 376.245766 -282.414196) (xy 376.212018 -282.376102) (xy 376.184817 -282.333088) (xy 376.164869 -282.286268)
			(xy 376.15269 -282.236854) (xy 376.148595 -282.186126) (xy 375.1961 -282.186126) (xy 375.1961 -282.696158)
			(xy 375.196372 -282.704689) (xy 375.2019 -282.720825) (xy 375.212448 -282.73423) (xy 375.219468 -282.739084)
			(xy 375.240664 -282.753248) (xy 375.278446 -282.787467) (xy 375.310015 -282.82749) (xy 375.334493 -282.872204)
			(xy 375.351199 -282.920363) (xy 375.359669 -282.97063) (xy 375.359667 -282.996132) (xy 375.678695 -282.996132)
			(xy 375.68279 -282.945404) (xy 375.694969 -282.89599) (xy 375.714917 -282.84917) (xy 375.742118 -282.806156)
			(xy 375.775866 -282.768062) (xy 375.815288 -282.735875) (xy 375.859362 -282.710429) (xy 375.906948 -282.692382)
			(xy 375.956812 -282.682202) (xy 376.007664 -282.680153) (xy 376.058185 -282.686287) (xy 376.107069 -282.700447)
			(xy 376.153048 -282.722264) (xy 376.194932 -282.751174) (xy 376.231636 -282.786429) (xy 376.262209 -282.827115)
			(xy 376.28586 -282.872178) (xy 376.301976 -282.920452) (xy 376.31014 -282.970686) (xy 376.310652 -282.996132)
			(xy 376.628926 -282.996132) (xy 376.632886 -282.947078) (xy 376.644663 -282.899294) (xy 376.663954 -282.854018)
			(xy 376.690257 -282.812422) (xy 376.722892 -282.775585) (xy 376.761013 -282.74446) (xy 376.803634 -282.719853)
			(xy 376.84965 -282.702401) (xy 376.897869 -282.692557) (xy 376.947044 -282.690576) (xy 376.995899 -282.696508)
			(xy 377.04317 -282.7102) (xy 377.087632 -282.731298) (xy 377.128135 -282.759254) (xy 377.163628 -282.793346)
			(xy 377.193193 -282.83269) (xy 377.216064 -282.876267) (xy 377.231648 -282.922948) (xy 377.239543 -282.971525)
			(xy 377.240038 -282.996132) (xy 377.558549 -282.996132) (xy 377.562644 -282.945404) (xy 377.574823 -282.89599)
			(xy 377.594771 -282.84917) (xy 377.621972 -282.806156) (xy 377.65572 -282.768062) (xy 377.695142 -282.735875)
			(xy 377.739216 -282.710429) (xy 377.786802 -282.692382) (xy 377.836666 -282.682202) (xy 377.887518 -282.680153)
			(xy 377.938039 -282.686287) (xy 377.986923 -282.700447) (xy 378.032902 -282.722264) (xy 378.074786 -282.751174)
			(xy 378.11149 -282.786429) (xy 378.142063 -282.827115) (xy 378.165714 -282.872178) (xy 378.18183 -282.920452)
			(xy 378.189994 -282.970686) (xy 378.190506 -282.996132) (xy 379.438657 -282.996132) (xy 379.442752 -282.945404)
			(xy 379.454931 -282.89599) (xy 379.474879 -282.84917) (xy 379.50208 -282.806156) (xy 379.535828 -282.768062)
			(xy 379.57525 -282.735875) (xy 379.619324 -282.710429) (xy 379.66691 -282.692382) (xy 379.716774 -282.682202)
			(xy 379.767626 -282.680153) (xy 379.818147 -282.686287) (xy 379.867031 -282.700447) (xy 379.91301 -282.722264)
			(xy 379.954894 -282.751174) (xy 379.991598 -282.786429) (xy 380.022171 -282.827115) (xy 380.045822 -282.872178)
			(xy 380.061938 -282.920452) (xy 380.070102 -282.970686) (xy 380.070614 -282.996132) (xy 380.378711 -282.996132)
			(xy 380.382806 -282.945404) (xy 380.394985 -282.89599) (xy 380.414933 -282.84917) (xy 380.442134 -282.806156)
			(xy 380.475882 -282.768062) (xy 380.515304 -282.735875) (xy 380.559378 -282.710429) (xy 380.606964 -282.692382)
			(xy 380.656828 -282.682202) (xy 380.70768 -282.680153) (xy 380.758201 -282.686287) (xy 380.807085 -282.700447)
			(xy 380.853064 -282.722264) (xy 380.894948 -282.751174) (xy 380.931652 -282.786429) (xy 380.962225 -282.827115)
			(xy 380.985876 -282.872178) (xy 381.001992 -282.920452) (xy 381.010156 -282.970686) (xy 381.010668 -282.996132)
			(xy 381.328942 -282.996132) (xy 381.332902 -282.947078) (xy 381.344679 -282.899294) (xy 381.36397 -282.854018)
			(xy 381.390273 -282.812422) (xy 381.422908 -282.775585) (xy 381.461029 -282.74446) (xy 381.50365 -282.719853)
			(xy 381.549666 -282.702401) (xy 381.597885 -282.692557) (xy 381.64706 -282.690576) (xy 381.695915 -282.696508)
			(xy 381.743186 -282.7102) (xy 381.787648 -282.731298) (xy 381.828151 -282.759254) (xy 381.863644 -282.793346)
			(xy 381.893209 -282.83269) (xy 381.91608 -282.876267) (xy 381.931664 -282.922948) (xy 381.939559 -282.971525)
			(xy 381.940054 -282.996132) (xy 382.258565 -282.996132) (xy 382.26266 -282.945404) (xy 382.274839 -282.89599)
			(xy 382.294787 -282.84917) (xy 382.321988 -282.806156) (xy 382.355736 -282.768062) (xy 382.395158 -282.735875)
			(xy 382.439232 -282.710429) (xy 382.486818 -282.692382) (xy 382.536682 -282.682202) (xy 382.587534 -282.680153)
			(xy 382.638055 -282.686287) (xy 382.686939 -282.700447) (xy 382.732918 -282.722264) (xy 382.774802 -282.751174)
			(xy 382.811506 -282.786429) (xy 382.842079 -282.827115) (xy 382.86573 -282.872178) (xy 382.881846 -282.920452)
			(xy 382.89001 -282.970686) (xy 382.890522 -282.996132) (xy 383.20905 -282.996132) (xy 383.21301 -282.947078)
			(xy 383.224787 -282.899294) (xy 383.244078 -282.854018) (xy 383.270381 -282.812422) (xy 383.303016 -282.775585)
			(xy 383.341137 -282.74446) (xy 383.383758 -282.719853) (xy 383.429774 -282.702401) (xy 383.477993 -282.692557)
			(xy 383.527168 -282.690576) (xy 383.576023 -282.696508) (xy 383.623294 -282.7102) (xy 383.667756 -282.731298)
			(xy 383.708259 -282.759254) (xy 383.743752 -282.793346) (xy 383.773317 -282.83269) (xy 383.796188 -282.876267)
			(xy 383.811772 -282.922948) (xy 383.819667 -282.971525) (xy 383.820162 -282.996132) (xy 384.138673 -282.996132)
			(xy 384.142768 -282.945404) (xy 384.154947 -282.89599) (xy 384.174895 -282.84917) (xy 384.202096 -282.806156)
			(xy 384.235844 -282.768062) (xy 384.275266 -282.735875) (xy 384.31934 -282.710429) (xy 384.366926 -282.692382)
			(xy 384.41679 -282.682202) (xy 384.467642 -282.680153) (xy 384.518163 -282.686287) (xy 384.567047 -282.700447)
			(xy 384.613026 -282.722264) (xy 384.65491 -282.751174) (xy 384.691614 -282.786429) (xy 384.722187 -282.827115)
			(xy 384.745838 -282.872178) (xy 384.761954 -282.920452) (xy 384.770118 -282.970686) (xy 384.77063 -282.996132)
			(xy 386.018527 -282.996132) (xy 386.022622 -282.945404) (xy 386.034801 -282.89599) (xy 386.054749 -282.84917)
			(xy 386.08195 -282.806156) (xy 386.115698 -282.768062) (xy 386.15512 -282.735875) (xy 386.199194 -282.710429)
			(xy 386.24678 -282.692382) (xy 386.296644 -282.682202) (xy 386.347496 -282.680153) (xy 386.398017 -282.686287)
			(xy 386.446901 -282.700447) (xy 386.49288 -282.722264) (xy 386.534764 -282.751174) (xy 386.571468 -282.786429)
			(xy 386.602041 -282.827115) (xy 386.625692 -282.872178) (xy 386.641808 -282.920452) (xy 386.649972 -282.970686)
			(xy 386.650484 -282.996132) (xy 386.958581 -282.996132) (xy 386.962676 -282.945404) (xy 386.974855 -282.89599)
			(xy 386.994803 -282.84917) (xy 387.022004 -282.806156) (xy 387.055752 -282.768062) (xy 387.095174 -282.735875)
			(xy 387.139248 -282.710429) (xy 387.186834 -282.692382) (xy 387.236698 -282.682202) (xy 387.28755 -282.680153)
			(xy 387.338071 -282.686287) (xy 387.386955 -282.700447) (xy 387.432934 -282.722264) (xy 387.474818 -282.751174)
			(xy 387.511522 -282.786429) (xy 387.542095 -282.827115) (xy 387.565746 -282.872178) (xy 387.581862 -282.920452)
			(xy 387.590026 -282.970686) (xy 387.590538 -282.996132) (xy 387.909066 -282.996132) (xy 387.913026 -282.947078)
			(xy 387.924803 -282.899294) (xy 387.944094 -282.854018) (xy 387.970397 -282.812422) (xy 388.003032 -282.775585)
			(xy 388.041153 -282.74446) (xy 388.083774 -282.719853) (xy 388.12979 -282.702401) (xy 388.178009 -282.692557)
			(xy 388.227184 -282.690576) (xy 388.276039 -282.696508) (xy 388.32331 -282.7102) (xy 388.367772 -282.731298)
			(xy 388.408275 -282.759254) (xy 388.443768 -282.793346) (xy 388.473333 -282.83269) (xy 388.496204 -282.876267)
			(xy 388.511788 -282.922948) (xy 388.519683 -282.971525) (xy 388.520178 -282.996132) (xy 388.838689 -282.996132)
			(xy 388.842784 -282.945404) (xy 388.854963 -282.89599) (xy 388.874911 -282.84917) (xy 388.902112 -282.806156)
			(xy 388.93586 -282.768062) (xy 388.975282 -282.735875) (xy 389.019356 -282.710429) (xy 389.066942 -282.692382)
			(xy 389.116806 -282.682202) (xy 389.167658 -282.680153) (xy 389.218179 -282.686287) (xy 389.267063 -282.700447)
			(xy 389.313042 -282.722264) (xy 389.354926 -282.751174) (xy 389.39163 -282.786429) (xy 389.422203 -282.827115)
			(xy 389.445854 -282.872178) (xy 389.46197 -282.920452) (xy 389.470134 -282.970686) (xy 389.470646 -282.996132)
			(xy 389.78892 -282.996132) (xy 389.79288 -282.947078) (xy 389.804657 -282.899294) (xy 389.823948 -282.854018)
			(xy 389.850251 -282.812422) (xy 389.882886 -282.775585) (xy 389.921007 -282.74446) (xy 389.963628 -282.719853)
			(xy 390.009644 -282.702401) (xy 390.057863 -282.692557) (xy 390.107038 -282.690576) (xy 390.155893 -282.696508)
			(xy 390.203164 -282.7102) (xy 390.247626 -282.731298) (xy 390.288129 -282.759254) (xy 390.323622 -282.793346)
			(xy 390.353187 -282.83269) (xy 390.376058 -282.876267) (xy 390.391642 -282.922948) (xy 390.399537 -282.971525)
			(xy 390.400032 -282.996132) (xy 390.718543 -282.996132) (xy 390.722638 -282.945404) (xy 390.734817 -282.89599)
			(xy 390.754765 -282.84917) (xy 390.781966 -282.806156) (xy 390.815714 -282.768062) (xy 390.855136 -282.735875)
			(xy 390.89921 -282.710429) (xy 390.946796 -282.692382) (xy 390.99666 -282.682202) (xy 391.047512 -282.680153)
			(xy 391.098033 -282.686287) (xy 391.146917 -282.700447) (xy 391.192896 -282.722264) (xy 391.204385 -282.730194)
			(xy 394.67715 -282.730194) (xy 394.68111 -282.68114) (xy 394.692887 -282.633356) (xy 394.712178 -282.58808)
			(xy 394.738481 -282.546484) (xy 394.771116 -282.509647) (xy 394.809237 -282.478522) (xy 394.851858 -282.453915)
			(xy 394.897874 -282.436463) (xy 394.946093 -282.426619) (xy 394.995268 -282.424638) (xy 395.044123 -282.43057)
			(xy 395.091394 -282.444262) (xy 395.135856 -282.46536) (xy 395.176359 -282.493316) (xy 395.211852 -282.527408)
			(xy 395.241417 -282.566752) (xy 395.264288 -282.610329) (xy 395.279872 -282.65701) (xy 395.287767 -282.705587)
			(xy 395.288262 -282.730194) (xy 395.287767 -282.754801) (xy 395.279872 -282.803378) (xy 395.264288 -282.850059)
			(xy 395.241417 -282.893636) (xy 395.211852 -282.93298) (xy 395.176359 -282.967072) (xy 395.135856 -282.995028)
			(xy 395.091394 -283.016126) (xy 395.044123 -283.029818) (xy 394.995268 -283.03575) (xy 394.946093 -283.033769)
			(xy 394.897874 -283.023925) (xy 394.851858 -283.006473) (xy 394.809237 -282.981866) (xy 394.771116 -282.950741)
			(xy 394.738481 -282.913904) (xy 394.712178 -282.872308) (xy 394.692887 -282.827032) (xy 394.68111 -282.779248)
			(xy 394.67715 -282.730194) (xy 391.204385 -282.730194) (xy 391.23478 -282.751174) (xy 391.271484 -282.786429)
			(xy 391.302057 -282.827115) (xy 391.325708 -282.872178) (xy 391.341824 -282.920452) (xy 391.349988 -282.970686)
			(xy 391.3505 -282.996132) (xy 391.349988 -283.021578) (xy 391.341824 -283.071812) (xy 391.325708 -283.120086)
			(xy 391.302057 -283.165149) (xy 391.271484 -283.205835) (xy 391.23478 -283.24109) (xy 391.192896 -283.27)
			(xy 391.146917 -283.291817) (xy 391.098033 -283.305977) (xy 391.047512 -283.312111) (xy 390.99666 -283.310062)
			(xy 390.946796 -283.299882) (xy 390.89921 -283.281835) (xy 390.855136 -283.256389) (xy 390.815714 -283.224202)
			(xy 390.781966 -283.186108) (xy 390.754765 -283.143094) (xy 390.734817 -283.096274) (xy 390.722638 -283.04686)
			(xy 390.718543 -282.996132) (xy 390.400032 -282.996132) (xy 390.399537 -283.020739) (xy 390.391642 -283.069316)
			(xy 390.376058 -283.115997) (xy 390.353187 -283.159574) (xy 390.323622 -283.198918) (xy 390.288129 -283.23301)
			(xy 390.247626 -283.260966) (xy 390.203164 -283.282064) (xy 390.155893 -283.295756) (xy 390.107038 -283.301688)
			(xy 390.057863 -283.299707) (xy 390.009644 -283.289863) (xy 389.963628 -283.272411) (xy 389.921007 -283.247804)
			(xy 389.882886 -283.216679) (xy 389.850251 -283.179842) (xy 389.823948 -283.138246) (xy 389.804657 -283.09297)
			(xy 389.79288 -283.045186) (xy 389.78892 -282.996132) (xy 389.470646 -282.996132) (xy 389.470134 -283.021578)
			(xy 389.46197 -283.071812) (xy 389.445854 -283.120086) (xy 389.422203 -283.165149) (xy 389.39163 -283.205835)
			(xy 389.354926 -283.24109) (xy 389.313042 -283.27) (xy 389.267063 -283.291817) (xy 389.218179 -283.305977)
			(xy 389.167658 -283.312111) (xy 389.116806 -283.310062) (xy 389.066942 -283.299882) (xy 389.019356 -283.281835)
			(xy 388.975282 -283.256389) (xy 388.93586 -283.224202) (xy 388.902112 -283.186108) (xy 388.874911 -283.143094)
			(xy 388.854963 -283.096274) (xy 388.842784 -283.04686) (xy 388.838689 -282.996132) (xy 388.520178 -282.996132)
			(xy 388.519683 -283.020739) (xy 388.511788 -283.069316) (xy 388.496204 -283.115997) (xy 388.473333 -283.159574)
			(xy 388.443768 -283.198918) (xy 388.408275 -283.23301) (xy 388.367772 -283.260966) (xy 388.32331 -283.282064)
			(xy 388.276039 -283.295756) (xy 388.227184 -283.301688) (xy 388.178009 -283.299707) (xy 388.12979 -283.289863)
			(xy 388.083774 -283.272411) (xy 388.041153 -283.247804) (xy 388.003032 -283.216679) (xy 387.970397 -283.179842)
			(xy 387.944094 -283.138246) (xy 387.924803 -283.09297) (xy 387.913026 -283.045186) (xy 387.909066 -282.996132)
			(xy 387.590538 -282.996132) (xy 387.590026 -283.021578) (xy 387.581862 -283.071812) (xy 387.565746 -283.120086)
			(xy 387.542095 -283.165149) (xy 387.511522 -283.205835) (xy 387.474818 -283.24109) (xy 387.432934 -283.27)
			(xy 387.386955 -283.291817) (xy 387.338071 -283.305977) (xy 387.28755 -283.312111) (xy 387.236698 -283.310062)
			(xy 387.186834 -283.299882) (xy 387.139248 -283.281835) (xy 387.095174 -283.256389) (xy 387.055752 -283.224202)
			(xy 387.022004 -283.186108) (xy 386.994803 -283.143094) (xy 386.974855 -283.096274) (xy 386.962676 -283.04686)
			(xy 386.958581 -282.996132) (xy 386.650484 -282.996132) (xy 386.649972 -283.021578) (xy 386.641808 -283.071812)
			(xy 386.625692 -283.120086) (xy 386.602041 -283.165149) (xy 386.571468 -283.205835) (xy 386.534764 -283.24109)
			(xy 386.49288 -283.27) (xy 386.446901 -283.291817) (xy 386.398017 -283.305977) (xy 386.347496 -283.312111)
			(xy 386.296644 -283.310062) (xy 386.24678 -283.299882) (xy 386.199194 -283.281835) (xy 386.15512 -283.256389)
			(xy 386.115698 -283.224202) (xy 386.08195 -283.186108) (xy 386.054749 -283.143094) (xy 386.034801 -283.096274)
			(xy 386.022622 -283.04686) (xy 386.018527 -282.996132) (xy 384.77063 -282.996132) (xy 384.770118 -283.021578)
			(xy 384.761954 -283.071812) (xy 384.745838 -283.120086) (xy 384.722187 -283.165149) (xy 384.691614 -283.205835)
			(xy 384.65491 -283.24109) (xy 384.613026 -283.27) (xy 384.567047 -283.291817) (xy 384.518163 -283.305977)
			(xy 384.467642 -283.312111) (xy 384.41679 -283.310062) (xy 384.366926 -283.299882) (xy 384.31934 -283.281835)
			(xy 384.275266 -283.256389) (xy 384.235844 -283.224202) (xy 384.202096 -283.186108) (xy 384.174895 -283.143094)
			(xy 384.154947 -283.096274) (xy 384.142768 -283.04686) (xy 384.138673 -282.996132) (xy 383.820162 -282.996132)
			(xy 383.819667 -283.020739) (xy 383.811772 -283.069316) (xy 383.796188 -283.115997) (xy 383.773317 -283.159574)
			(xy 383.743752 -283.198918) (xy 383.708259 -283.23301) (xy 383.667756 -283.260966) (xy 383.623294 -283.282064)
			(xy 383.576023 -283.295756) (xy 383.527168 -283.301688) (xy 383.477993 -283.299707) (xy 383.429774 -283.289863)
			(xy 383.383758 -283.272411) (xy 383.341137 -283.247804) (xy 383.303016 -283.216679) (xy 383.270381 -283.179842)
			(xy 383.244078 -283.138246) (xy 383.224787 -283.09297) (xy 383.21301 -283.045186) (xy 383.20905 -282.996132)
			(xy 382.890522 -282.996132) (xy 382.89001 -283.021578) (xy 382.881846 -283.071812) (xy 382.86573 -283.120086)
			(xy 382.842079 -283.165149) (xy 382.811506 -283.205835) (xy 382.774802 -283.24109) (xy 382.732918 -283.27)
			(xy 382.686939 -283.291817) (xy 382.638055 -283.305977) (xy 382.587534 -283.312111) (xy 382.536682 -283.310062)
			(xy 382.486818 -283.299882) (xy 382.439232 -283.281835) (xy 382.395158 -283.256389) (xy 382.355736 -283.224202)
			(xy 382.321988 -283.186108) (xy 382.294787 -283.143094) (xy 382.274839 -283.096274) (xy 382.26266 -283.04686)
			(xy 382.258565 -282.996132) (xy 381.940054 -282.996132) (xy 381.939559 -283.020739) (xy 381.931664 -283.069316)
			(xy 381.91608 -283.115997) (xy 381.893209 -283.159574) (xy 381.863644 -283.198918) (xy 381.828151 -283.23301)
			(xy 381.787648 -283.260966) (xy 381.743186 -283.282064) (xy 381.695915 -283.295756) (xy 381.64706 -283.301688)
			(xy 381.597885 -283.299707) (xy 381.549666 -283.289863) (xy 381.50365 -283.272411) (xy 381.461029 -283.247804)
			(xy 381.422908 -283.216679) (xy 381.390273 -283.179842) (xy 381.36397 -283.138246) (xy 381.344679 -283.09297)
			(xy 381.332902 -283.045186) (xy 381.328942 -282.996132) (xy 381.010668 -282.996132) (xy 381.010156 -283.021578)
			(xy 381.001992 -283.071812) (xy 380.985876 -283.120086) (xy 380.962225 -283.165149) (xy 380.931652 -283.205835)
			(xy 380.894948 -283.24109) (xy 380.853064 -283.27) (xy 380.807085 -283.291817) (xy 380.758201 -283.305977)
			(xy 380.70768 -283.312111) (xy 380.656828 -283.310062) (xy 380.606964 -283.299882) (xy 380.559378 -283.281835)
			(xy 380.515304 -283.256389) (xy 380.475882 -283.224202) (xy 380.442134 -283.186108) (xy 380.414933 -283.143094)
			(xy 380.394985 -283.096274) (xy 380.382806 -283.04686) (xy 380.378711 -282.996132) (xy 380.070614 -282.996132)
			(xy 380.070102 -283.021578) (xy 380.061938 -283.071812) (xy 380.045822 -283.120086) (xy 380.022171 -283.165149)
			(xy 379.991598 -283.205835) (xy 379.954894 -283.24109) (xy 379.91301 -283.27) (xy 379.867031 -283.291817)
			(xy 379.818147 -283.305977) (xy 379.767626 -283.312111) (xy 379.716774 -283.310062) (xy 379.66691 -283.299882)
			(xy 379.619324 -283.281835) (xy 379.57525 -283.256389) (xy 379.535828 -283.224202) (xy 379.50208 -283.186108)
			(xy 379.474879 -283.143094) (xy 379.454931 -283.096274) (xy 379.442752 -283.04686) (xy 379.438657 -282.996132)
			(xy 378.190506 -282.996132) (xy 378.189994 -283.021578) (xy 378.18183 -283.071812) (xy 378.165714 -283.120086)
			(xy 378.142063 -283.165149) (xy 378.11149 -283.205835) (xy 378.074786 -283.24109) (xy 378.032902 -283.27)
			(xy 377.986923 -283.291817) (xy 377.938039 -283.305977) (xy 377.887518 -283.312111) (xy 377.836666 -283.310062)
			(xy 377.786802 -283.299882) (xy 377.739216 -283.281835) (xy 377.695142 -283.256389) (xy 377.65572 -283.224202)
			(xy 377.621972 -283.186108) (xy 377.594771 -283.143094) (xy 377.574823 -283.096274) (xy 377.562644 -283.04686)
			(xy 377.558549 -282.996132) (xy 377.240038 -282.996132) (xy 377.239543 -283.020739) (xy 377.231648 -283.069316)
			(xy 377.216064 -283.115997) (xy 377.193193 -283.159574) (xy 377.163628 -283.198918) (xy 377.128135 -283.23301)
			(xy 377.087632 -283.260966) (xy 377.04317 -283.282064) (xy 376.995899 -283.295756) (xy 376.947044 -283.301688)
			(xy 376.897869 -283.299707) (xy 376.84965 -283.289863) (xy 376.803634 -283.272411) (xy 376.761013 -283.247804)
			(xy 376.722892 -283.216679) (xy 376.690257 -283.179842) (xy 376.663954 -283.138246) (xy 376.644663 -283.09297)
			(xy 376.632886 -283.045186) (xy 376.628926 -282.996132) (xy 376.310652 -282.996132) (xy 376.31014 -283.021578)
			(xy 376.301976 -283.071812) (xy 376.28586 -283.120086) (xy 376.262209 -283.165149) (xy 376.231636 -283.205835)
			(xy 376.194932 -283.24109) (xy 376.153048 -283.27) (xy 376.107069 -283.291817) (xy 376.058185 -283.305977)
			(xy 376.007664 -283.312111) (xy 375.956812 -283.310062) (xy 375.906948 -283.299882) (xy 375.859362 -283.281835)
			(xy 375.815288 -283.256389) (xy 375.775866 -283.224202) (xy 375.742118 -283.186108) (xy 375.714917 -283.143094)
			(xy 375.694969 -283.096274) (xy 375.68279 -283.04686) (xy 375.678695 -282.996132) (xy 375.359667 -282.996132)
			(xy 375.359666 -283.021605) (xy 375.351191 -283.07187) (xy 375.334479 -283.120028) (xy 375.309996 -283.164738)
			(xy 375.278422 -283.204758) (xy 375.240636 -283.238973) (xy 375.219468 -283.25318) (xy 375.212473 -283.258062)
			(xy 375.201942 -283.271469) (xy 375.196371 -283.287582) (xy 375.1961 -283.296106) (xy 375.1961 -283.468318)
			(xy 375.196504 -283.477516) (xy 375.202993 -283.494732) (xy 375.215105 -283.50858) (xy 375.223024 -283.513276)
			(xy 375.314718 -283.562298) (xy 375.342404 -283.560774) (xy 375.354342 -283.5529) (xy 375.373328 -283.5406)
			(xy 375.414161 -283.521135) (xy 375.457421 -283.50791) (xy 375.502158 -283.501215) (xy 375.524776 -283.50083)
			(xy 375.550032 -283.501321) (xy 375.599855 -283.509631) (xy 375.647631 -283.526029) (xy 375.692056 -283.550068)
			(xy 375.731918 -283.581091) (xy 375.76613 -283.618252) (xy 375.793759 -283.660538) (xy 375.81405 -283.706795)
			(xy 375.826451 -283.755761) (xy 375.830622 -283.8061) (xy 375.830619 -283.806138) (xy 376.148595 -283.806138)
			(xy 376.15269 -283.75541) (xy 376.164869 -283.705996) (xy 376.184817 -283.659176) (xy 376.212018 -283.616162)
			(xy 376.245766 -283.578068) (xy 376.285188 -283.545881) (xy 376.329262 -283.520435) (xy 376.376848 -283.502388)
			(xy 376.426712 -283.492208) (xy 376.477564 -283.490159) (xy 376.528085 -283.496293) (xy 376.576969 -283.510453)
			(xy 376.622948 -283.53227) (xy 376.664832 -283.56118) (xy 376.701536 -283.596435) (xy 376.732109 -283.637121)
			(xy 376.75576 -283.682184) (xy 376.771876 -283.730458) (xy 376.78004 -283.780692) (xy 376.780552 -283.806138)
			(xy 377.088649 -283.806138) (xy 377.092744 -283.75541) (xy 377.104923 -283.705996) (xy 377.124871 -283.659176)
			(xy 377.152072 -283.616162) (xy 377.18582 -283.578068) (xy 377.225242 -283.545881) (xy 377.269316 -283.520435)
			(xy 377.316902 -283.502388) (xy 377.366766 -283.492208) (xy 377.417618 -283.490159) (xy 377.468139 -283.496293)
			(xy 377.517023 -283.510453) (xy 377.563002 -283.53227) (xy 377.604886 -283.56118) (xy 377.64159 -283.596435)
			(xy 377.672163 -283.637121) (xy 377.695814 -283.682184) (xy 377.71193 -283.730458) (xy 377.720094 -283.780692)
			(xy 377.720606 -283.806138) (xy 378.039134 -283.806138) (xy 378.043094 -283.757084) (xy 378.054871 -283.7093)
			(xy 378.074162 -283.664024) (xy 378.100465 -283.622428) (xy 378.1331 -283.585591) (xy 378.171221 -283.554466)
			(xy 378.213842 -283.529859) (xy 378.259858 -283.512407) (xy 378.308077 -283.502563) (xy 378.357252 -283.500582)
			(xy 378.406107 -283.506514) (xy 378.453378 -283.520206) (xy 378.49784 -283.541304) (xy 378.538343 -283.56926)
			(xy 378.573836 -283.603352) (xy 378.603401 -283.642696) (xy 378.626272 -283.686273) (xy 378.641856 -283.732954)
			(xy 378.649751 -283.781531) (xy 378.650246 -283.806138) (xy 378.968503 -283.806138) (xy 378.972598 -283.75541)
			(xy 378.984777 -283.705996) (xy 379.004725 -283.659176) (xy 379.031926 -283.616162) (xy 379.065674 -283.578068)
			(xy 379.105096 -283.545881) (xy 379.14917 -283.520435) (xy 379.196756 -283.502388) (xy 379.24662 -283.492208)
			(xy 379.297472 -283.490159) (xy 379.347993 -283.496293) (xy 379.396877 -283.510453) (xy 379.442856 -283.53227)
			(xy 379.48474 -283.56118) (xy 379.521444 -283.596435) (xy 379.552017 -283.637121) (xy 379.575668 -283.682184)
			(xy 379.591784 -283.730458) (xy 379.599948 -283.780692) (xy 379.60046 -283.806138) (xy 379.918988 -283.806138)
			(xy 379.922948 -283.757084) (xy 379.934725 -283.7093) (xy 379.954016 -283.664024) (xy 379.980319 -283.622428)
			(xy 380.012954 -283.585591) (xy 380.051075 -283.554466) (xy 380.093696 -283.529859) (xy 380.139712 -283.512407)
			(xy 380.187931 -283.502563) (xy 380.237106 -283.500582) (xy 380.285961 -283.506514) (xy 380.333232 -283.520206)
			(xy 380.377694 -283.541304) (xy 380.418197 -283.56926) (xy 380.45369 -283.603352) (xy 380.483255 -283.642696)
			(xy 380.506126 -283.686273) (xy 380.52171 -283.732954) (xy 380.529605 -283.781531) (xy 380.5301 -283.806138)
			(xy 380.848611 -283.806138) (xy 380.852706 -283.75541) (xy 380.864885 -283.705996) (xy 380.884833 -283.659176)
			(xy 380.912034 -283.616162) (xy 380.945782 -283.578068) (xy 380.985204 -283.545881) (xy 381.029278 -283.520435)
			(xy 381.076864 -283.502388) (xy 381.126728 -283.492208) (xy 381.17758 -283.490159) (xy 381.228101 -283.496293)
			(xy 381.276985 -283.510453) (xy 381.322964 -283.53227) (xy 381.364848 -283.56118) (xy 381.401552 -283.596435)
			(xy 381.432125 -283.637121) (xy 381.455776 -283.682184) (xy 381.471892 -283.730458) (xy 381.480056 -283.780692)
			(xy 381.480568 -283.806138) (xy 381.799096 -283.806138) (xy 381.803056 -283.757084) (xy 381.814833 -283.7093)
			(xy 381.834124 -283.664024) (xy 381.860427 -283.622428) (xy 381.893062 -283.585591) (xy 381.931183 -283.554466)
			(xy 381.973804 -283.529859) (xy 382.01982 -283.512407) (xy 382.068039 -283.502563) (xy 382.117214 -283.500582)
			(xy 382.166069 -283.506514) (xy 382.21334 -283.520206) (xy 382.257802 -283.541304) (xy 382.298305 -283.56926)
			(xy 382.333798 -283.603352) (xy 382.363363 -283.642696) (xy 382.386234 -283.686273) (xy 382.401818 -283.732954)
			(xy 382.409713 -283.781531) (xy 382.410208 -283.806138) (xy 382.728465 -283.806138) (xy 382.73256 -283.75541)
			(xy 382.744739 -283.705996) (xy 382.764687 -283.659176) (xy 382.791888 -283.616162) (xy 382.825636 -283.578068)
			(xy 382.865058 -283.545881) (xy 382.909132 -283.520435) (xy 382.956718 -283.502388) (xy 383.006582 -283.492208)
			(xy 383.057434 -283.490159) (xy 383.107955 -283.496293) (xy 383.156839 -283.510453) (xy 383.202818 -283.53227)
			(xy 383.244702 -283.56118) (xy 383.281406 -283.596435) (xy 383.311979 -283.637121) (xy 383.33563 -283.682184)
			(xy 383.351746 -283.730458) (xy 383.35991 -283.780692) (xy 383.360422 -283.806138) (xy 383.668519 -283.806138)
			(xy 383.672614 -283.75541) (xy 383.684793 -283.705996) (xy 383.704741 -283.659176) (xy 383.731942 -283.616162)
			(xy 383.76569 -283.578068) (xy 383.805112 -283.545881) (xy 383.849186 -283.520435) (xy 383.896772 -283.502388)
			(xy 383.946636 -283.492208) (xy 383.997488 -283.490159) (xy 384.048009 -283.496293) (xy 384.096893 -283.510453)
			(xy 384.142872 -283.53227) (xy 384.184756 -283.56118) (xy 384.22146 -283.596435) (xy 384.252033 -283.637121)
			(xy 384.275684 -283.682184) (xy 384.2918 -283.730458) (xy 384.299964 -283.780692) (xy 384.300476 -283.806138)
			(xy 384.619004 -283.806138) (xy 384.622964 -283.757084) (xy 384.634741 -283.7093) (xy 384.654032 -283.664024)
			(xy 384.680335 -283.622428) (xy 384.71297 -283.585591) (xy 384.751091 -283.554466) (xy 384.793712 -283.529859)
			(xy 384.839728 -283.512407) (xy 384.887947 -283.502563) (xy 384.937122 -283.500582) (xy 384.985977 -283.506514)
			(xy 385.033248 -283.520206) (xy 385.07771 -283.541304) (xy 385.118213 -283.56926) (xy 385.153706 -283.603352)
			(xy 385.183271 -283.642696) (xy 385.206142 -283.686273) (xy 385.221726 -283.732954) (xy 385.229621 -283.781531)
			(xy 385.230116 -283.806138) (xy 385.548627 -283.806138) (xy 385.552722 -283.75541) (xy 385.564901 -283.705996)
			(xy 385.584849 -283.659176) (xy 385.61205 -283.616162) (xy 385.645798 -283.578068) (xy 385.68522 -283.545881)
			(xy 385.729294 -283.520435) (xy 385.77688 -283.502388) (xy 385.826744 -283.492208) (xy 385.877596 -283.490159)
			(xy 385.928117 -283.496293) (xy 385.977001 -283.510453) (xy 386.02298 -283.53227) (xy 386.064864 -283.56118)
			(xy 386.101568 -283.596435) (xy 386.132141 -283.637121) (xy 386.155792 -283.682184) (xy 386.171908 -283.730458)
			(xy 386.180072 -283.780692) (xy 386.180584 -283.806138) (xy 386.499112 -283.806138) (xy 386.503072 -283.757084)
			(xy 386.514849 -283.7093) (xy 386.53414 -283.664024) (xy 386.560443 -283.622428) (xy 386.593078 -283.585591)
			(xy 386.631199 -283.554466) (xy 386.67382 -283.529859) (xy 386.719836 -283.512407) (xy 386.768055 -283.502563)
			(xy 386.81723 -283.500582) (xy 386.866085 -283.506514) (xy 386.913356 -283.520206) (xy 386.957818 -283.541304)
			(xy 386.998321 -283.56926) (xy 387.033814 -283.603352) (xy 387.063379 -283.642696) (xy 387.08625 -283.686273)
			(xy 387.101834 -283.732954) (xy 387.109729 -283.781531) (xy 387.110224 -283.806138) (xy 387.428481 -283.806138)
			(xy 387.432576 -283.75541) (xy 387.444755 -283.705996) (xy 387.464703 -283.659176) (xy 387.491904 -283.616162)
			(xy 387.525652 -283.578068) (xy 387.565074 -283.545881) (xy 387.609148 -283.520435) (xy 387.656734 -283.502388)
			(xy 387.706598 -283.492208) (xy 387.75745 -283.490159) (xy 387.807971 -283.496293) (xy 387.856855 -283.510453)
			(xy 387.902834 -283.53227) (xy 387.944718 -283.56118) (xy 387.981422 -283.596435) (xy 388.011995 -283.637121)
			(xy 388.035646 -283.682184) (xy 388.051762 -283.730458) (xy 388.059926 -283.780692) (xy 388.060438 -283.806138)
			(xy 388.378966 -283.806138) (xy 388.382926 -283.757084) (xy 388.394703 -283.7093) (xy 388.413994 -283.664024)
			(xy 388.440297 -283.622428) (xy 388.472932 -283.585591) (xy 388.511053 -283.554466) (xy 388.553674 -283.529859)
			(xy 388.59969 -283.512407) (xy 388.647909 -283.502563) (xy 388.697084 -283.500582) (xy 388.745939 -283.506514)
			(xy 388.79321 -283.520206) (xy 388.837672 -283.541304) (xy 388.878175 -283.56926) (xy 388.913668 -283.603352)
			(xy 388.943233 -283.642696) (xy 388.966104 -283.686273) (xy 388.981688 -283.732954) (xy 388.989583 -283.781531)
			(xy 388.990078 -283.806138) (xy 389.308589 -283.806138) (xy 389.312684 -283.75541) (xy 389.324863 -283.705996)
			(xy 389.344811 -283.659176) (xy 389.372012 -283.616162) (xy 389.40576 -283.578068) (xy 389.445182 -283.545881)
			(xy 389.489256 -283.520435) (xy 389.536842 -283.502388) (xy 389.586706 -283.492208) (xy 389.637558 -283.490159)
			(xy 389.688079 -283.496293) (xy 389.736963 -283.510453) (xy 389.782942 -283.53227) (xy 389.824826 -283.56118)
			(xy 389.86153 -283.596435) (xy 389.892103 -283.637121) (xy 389.915754 -283.682184) (xy 389.93187 -283.730458)
			(xy 389.940034 -283.780692) (xy 389.940546 -283.806138) (xy 390.248643 -283.806138) (xy 390.252738 -283.75541)
			(xy 390.264917 -283.705996) (xy 390.284865 -283.659176) (xy 390.312066 -283.616162) (xy 390.345814 -283.578068)
			(xy 390.385236 -283.545881) (xy 390.42931 -283.520435) (xy 390.476896 -283.502388) (xy 390.52676 -283.492208)
			(xy 390.577612 -283.490159) (xy 390.628133 -283.496293) (xy 390.677017 -283.510453) (xy 390.722996 -283.53227)
			(xy 390.76488 -283.56118) (xy 390.801584 -283.596435) (xy 390.832157 -283.637121) (xy 390.855808 -283.682184)
			(xy 390.871924 -283.730458) (xy 390.880088 -283.780692) (xy 390.8806 -283.806138) (xy 391.198874 -283.806138)
			(xy 391.202834 -283.757084) (xy 391.214611 -283.7093) (xy 391.233902 -283.664024) (xy 391.260205 -283.622428)
			(xy 391.29284 -283.585591) (xy 391.330961 -283.554466) (xy 391.373582 -283.529859) (xy 391.419598 -283.512407)
			(xy 391.467817 -283.502563) (xy 391.516992 -283.500582) (xy 391.565847 -283.506514) (xy 391.613118 -283.520206)
			(xy 391.65758 -283.541304) (xy 391.698083 -283.56926) (xy 391.733576 -283.603352) (xy 391.763141 -283.642696)
			(xy 391.786012 -283.686273) (xy 391.801596 -283.732954) (xy 391.809491 -283.781531) (xy 391.809986 -283.806138)
			(xy 393.078982 -283.806138) (xy 393.082942 -283.757084) (xy 393.094719 -283.7093) (xy 393.11401 -283.664024)
			(xy 393.140313 -283.622428) (xy 393.172948 -283.585591) (xy 393.211069 -283.554466) (xy 393.25369 -283.529859)
			(xy 393.299706 -283.512407) (xy 393.347925 -283.502563) (xy 393.3971 -283.500582) (xy 393.445955 -283.506514)
			(xy 393.493226 -283.520206) (xy 393.537688 -283.541304) (xy 393.578191 -283.56926) (xy 393.613684 -283.603352)
			(xy 393.643249 -283.642696) (xy 393.66612 -283.686273) (xy 393.681704 -283.732954) (xy 393.689599 -283.781531)
			(xy 393.690094 -283.806138) (xy 393.689599 -283.830745) (xy 393.681704 -283.879322) (xy 393.66612 -283.926003)
			(xy 393.643249 -283.96958) (xy 393.613684 -284.008924) (xy 393.578191 -284.043016) (xy 393.537688 -284.070972)
			(xy 393.493226 -284.09207) (xy 393.445955 -284.105762) (xy 393.3971 -284.111694) (xy 393.347925 -284.109713)
			(xy 393.299706 -284.099869) (xy 393.25369 -284.082417) (xy 393.211069 -284.05781) (xy 393.172948 -284.026685)
			(xy 393.140313 -283.989848) (xy 393.11401 -283.948252) (xy 393.094719 -283.902976) (xy 393.082942 -283.855192)
			(xy 393.078982 -283.806138) (xy 391.809986 -283.806138) (xy 391.809491 -283.830745) (xy 391.801596 -283.879322)
			(xy 391.786012 -283.926003) (xy 391.763141 -283.96958) (xy 391.733576 -284.008924) (xy 391.698083 -284.043016)
			(xy 391.65758 -284.070972) (xy 391.613118 -284.09207) (xy 391.565847 -284.105762) (xy 391.516992 -284.111694)
			(xy 391.467817 -284.109713) (xy 391.419598 -284.099869) (xy 391.373582 -284.082417) (xy 391.330961 -284.05781)
			(xy 391.29284 -284.026685) (xy 391.260205 -283.989848) (xy 391.233902 -283.948252) (xy 391.214611 -283.902976)
			(xy 391.202834 -283.855192) (xy 391.198874 -283.806138) (xy 390.8806 -283.806138) (xy 390.880088 -283.831584)
			(xy 390.871924 -283.881818) (xy 390.855808 -283.930092) (xy 390.832157 -283.975155) (xy 390.801584 -284.015841)
			(xy 390.76488 -284.051096) (xy 390.722996 -284.080006) (xy 390.677017 -284.101823) (xy 390.628133 -284.115983)
			(xy 390.577612 -284.122117) (xy 390.52676 -284.120068) (xy 390.476896 -284.109888) (xy 390.42931 -284.091841)
			(xy 390.385236 -284.066395) (xy 390.345814 -284.034208) (xy 390.312066 -283.996114) (xy 390.284865 -283.9531)
			(xy 390.264917 -283.90628) (xy 390.252738 -283.856866) (xy 390.248643 -283.806138) (xy 389.940546 -283.806138)
			(xy 389.940034 -283.831584) (xy 389.93187 -283.881818) (xy 389.915754 -283.930092) (xy 389.892103 -283.975155)
			(xy 389.86153 -284.015841) (xy 389.824826 -284.051096) (xy 389.782942 -284.080006) (xy 389.736963 -284.101823)
			(xy 389.688079 -284.115983) (xy 389.637558 -284.122117) (xy 389.586706 -284.120068) (xy 389.536842 -284.109888)
			(xy 389.489256 -284.091841) (xy 389.445182 -284.066395) (xy 389.40576 -284.034208) (xy 389.372012 -283.996114)
			(xy 389.344811 -283.9531) (xy 389.324863 -283.90628) (xy 389.312684 -283.856866) (xy 389.308589 -283.806138)
			(xy 388.990078 -283.806138) (xy 388.989583 -283.830745) (xy 388.981688 -283.879322) (xy 388.966104 -283.926003)
			(xy 388.943233 -283.96958) (xy 388.913668 -284.008924) (xy 388.878175 -284.043016) (xy 388.837672 -284.070972)
			(xy 388.79321 -284.09207) (xy 388.745939 -284.105762) (xy 388.697084 -284.111694) (xy 388.647909 -284.109713)
			(xy 388.59969 -284.099869) (xy 388.553674 -284.082417) (xy 388.511053 -284.05781) (xy 388.472932 -284.026685)
			(xy 388.440297 -283.989848) (xy 388.413994 -283.948252) (xy 388.394703 -283.902976) (xy 388.382926 -283.855192)
			(xy 388.378966 -283.806138) (xy 388.060438 -283.806138) (xy 388.059926 -283.831584) (xy 388.051762 -283.881818)
			(xy 388.035646 -283.930092) (xy 388.011995 -283.975155) (xy 387.981422 -284.015841) (xy 387.944718 -284.051096)
			(xy 387.902834 -284.080006) (xy 387.856855 -284.101823) (xy 387.807971 -284.115983) (xy 387.75745 -284.122117)
			(xy 387.706598 -284.120068) (xy 387.656734 -284.109888) (xy 387.609148 -284.091841) (xy 387.565074 -284.066395)
			(xy 387.525652 -284.034208) (xy 387.491904 -283.996114) (xy 387.464703 -283.9531) (xy 387.444755 -283.90628)
			(xy 387.432576 -283.856866) (xy 387.428481 -283.806138) (xy 387.110224 -283.806138) (xy 387.109729 -283.830745)
			(xy 387.101834 -283.879322) (xy 387.08625 -283.926003) (xy 387.063379 -283.96958) (xy 387.033814 -284.008924)
			(xy 386.998321 -284.043016) (xy 386.957818 -284.070972) (xy 386.913356 -284.09207) (xy 386.866085 -284.105762)
			(xy 386.81723 -284.111694) (xy 386.768055 -284.109713) (xy 386.719836 -284.099869) (xy 386.67382 -284.082417)
			(xy 386.631199 -284.05781) (xy 386.593078 -284.026685) (xy 386.560443 -283.989848) (xy 386.53414 -283.948252)
			(xy 386.514849 -283.902976) (xy 386.503072 -283.855192) (xy 386.499112 -283.806138) (xy 386.180584 -283.806138)
			(xy 386.180072 -283.831584) (xy 386.171908 -283.881818) (xy 386.155792 -283.930092) (xy 386.132141 -283.975155)
			(xy 386.101568 -284.015841) (xy 386.064864 -284.051096) (xy 386.02298 -284.080006) (xy 385.977001 -284.101823)
			(xy 385.928117 -284.115983) (xy 385.877596 -284.122117) (xy 385.826744 -284.120068) (xy 385.77688 -284.109888)
			(xy 385.729294 -284.091841) (xy 385.68522 -284.066395) (xy 385.645798 -284.034208) (xy 385.61205 -283.996114)
			(xy 385.584849 -283.9531) (xy 385.564901 -283.90628) (xy 385.552722 -283.856866) (xy 385.548627 -283.806138)
			(xy 385.230116 -283.806138) (xy 385.229621 -283.830745) (xy 385.221726 -283.879322) (xy 385.206142 -283.926003)
			(xy 385.183271 -283.96958) (xy 385.153706 -284.008924) (xy 385.118213 -284.043016) (xy 385.07771 -284.070972)
			(xy 385.033248 -284.09207) (xy 384.985977 -284.105762) (xy 384.937122 -284.111694) (xy 384.887947 -284.109713)
			(xy 384.839728 -284.099869) (xy 384.793712 -284.082417) (xy 384.751091 -284.05781) (xy 384.71297 -284.026685)
			(xy 384.680335 -283.989848) (xy 384.654032 -283.948252) (xy 384.634741 -283.902976) (xy 384.622964 -283.855192)
			(xy 384.619004 -283.806138) (xy 384.300476 -283.806138) (xy 384.299964 -283.831584) (xy 384.2918 -283.881818)
			(xy 384.275684 -283.930092) (xy 384.252033 -283.975155) (xy 384.22146 -284.015841) (xy 384.184756 -284.051096)
			(xy 384.142872 -284.080006) (xy 384.096893 -284.101823) (xy 384.048009 -284.115983) (xy 383.997488 -284.122117)
			(xy 383.946636 -284.120068) (xy 383.896772 -284.109888) (xy 383.849186 -284.091841) (xy 383.805112 -284.066395)
			(xy 383.76569 -284.034208) (xy 383.731942 -283.996114) (xy 383.704741 -283.9531) (xy 383.684793 -283.90628)
			(xy 383.672614 -283.856866) (xy 383.668519 -283.806138) (xy 383.360422 -283.806138) (xy 383.35991 -283.831584)
			(xy 383.351746 -283.881818) (xy 383.33563 -283.930092) (xy 383.311979 -283.975155) (xy 383.281406 -284.015841)
			(xy 383.244702 -284.051096) (xy 383.202818 -284.080006) (xy 383.156839 -284.101823) (xy 383.107955 -284.115983)
			(xy 383.057434 -284.122117) (xy 383.006582 -284.120068) (xy 382.956718 -284.109888) (xy 382.909132 -284.091841)
			(xy 382.865058 -284.066395) (xy 382.825636 -284.034208) (xy 382.791888 -283.996114) (xy 382.764687 -283.9531)
			(xy 382.744739 -283.90628) (xy 382.73256 -283.856866) (xy 382.728465 -283.806138) (xy 382.410208 -283.806138)
			(xy 382.409713 -283.830745) (xy 382.401818 -283.879322) (xy 382.386234 -283.926003) (xy 382.363363 -283.96958)
			(xy 382.333798 -284.008924) (xy 382.298305 -284.043016) (xy 382.257802 -284.070972) (xy 382.21334 -284.09207)
			(xy 382.166069 -284.105762) (xy 382.117214 -284.111694) (xy 382.068039 -284.109713) (xy 382.01982 -284.099869)
			(xy 381.973804 -284.082417) (xy 381.931183 -284.05781) (xy 381.893062 -284.026685) (xy 381.860427 -283.989848)
			(xy 381.834124 -283.948252) (xy 381.814833 -283.902976) (xy 381.803056 -283.855192) (xy 381.799096 -283.806138)
			(xy 381.480568 -283.806138) (xy 381.480056 -283.831584) (xy 381.471892 -283.881818) (xy 381.455776 -283.930092)
			(xy 381.432125 -283.975155) (xy 381.401552 -284.015841) (xy 381.364848 -284.051096) (xy 381.322964 -284.080006)
			(xy 381.276985 -284.101823) (xy 381.228101 -284.115983) (xy 381.17758 -284.122117) (xy 381.126728 -284.120068)
			(xy 381.076864 -284.109888) (xy 381.029278 -284.091841) (xy 380.985204 -284.066395) (xy 380.945782 -284.034208)
			(xy 380.912034 -283.996114) (xy 380.884833 -283.9531) (xy 380.864885 -283.90628) (xy 380.852706 -283.856866)
			(xy 380.848611 -283.806138) (xy 380.5301 -283.806138) (xy 380.529605 -283.830745) (xy 380.52171 -283.879322)
			(xy 380.506126 -283.926003) (xy 380.483255 -283.96958) (xy 380.45369 -284.008924) (xy 380.418197 -284.043016)
			(xy 380.377694 -284.070972) (xy 380.333232 -284.09207) (xy 380.285961 -284.105762) (xy 380.237106 -284.111694)
			(xy 380.187931 -284.109713) (xy 380.139712 -284.099869) (xy 380.093696 -284.082417) (xy 380.051075 -284.05781)
			(xy 380.012954 -284.026685) (xy 379.980319 -283.989848) (xy 379.954016 -283.948252) (xy 379.934725 -283.902976)
			(xy 379.922948 -283.855192) (xy 379.918988 -283.806138) (xy 379.60046 -283.806138) (xy 379.599948 -283.831584)
			(xy 379.591784 -283.881818) (xy 379.575668 -283.930092) (xy 379.552017 -283.975155) (xy 379.521444 -284.015841)
			(xy 379.48474 -284.051096) (xy 379.442856 -284.080006) (xy 379.396877 -284.101823) (xy 379.347993 -284.115983)
			(xy 379.297472 -284.122117) (xy 379.24662 -284.120068) (xy 379.196756 -284.109888) (xy 379.14917 -284.091841)
			(xy 379.105096 -284.066395) (xy 379.065674 -284.034208) (xy 379.031926 -283.996114) (xy 379.004725 -283.9531)
			(xy 378.984777 -283.90628) (xy 378.972598 -283.856866) (xy 378.968503 -283.806138) (xy 378.650246 -283.806138)
			(xy 378.649751 -283.830745) (xy 378.641856 -283.879322) (xy 378.626272 -283.926003) (xy 378.603401 -283.96958)
			(xy 378.573836 -284.008924) (xy 378.538343 -284.043016) (xy 378.49784 -284.070972) (xy 378.453378 -284.09207)
			(xy 378.406107 -284.105762) (xy 378.357252 -284.111694) (xy 378.308077 -284.109713) (xy 378.259858 -284.099869)
			(xy 378.213842 -284.082417) (xy 378.171221 -284.05781) (xy 378.1331 -284.026685) (xy 378.100465 -283.989848)
			(xy 378.074162 -283.948252) (xy 378.054871 -283.902976) (xy 378.043094 -283.855192) (xy 378.039134 -283.806138)
			(xy 377.720606 -283.806138) (xy 377.720094 -283.831584) (xy 377.71193 -283.881818) (xy 377.695814 -283.930092)
			(xy 377.672163 -283.975155) (xy 377.64159 -284.015841) (xy 377.604886 -284.051096) (xy 377.563002 -284.080006)
			(xy 377.517023 -284.101823) (xy 377.468139 -284.115983) (xy 377.417618 -284.122117) (xy 377.366766 -284.120068)
			(xy 377.316902 -284.109888) (xy 377.269316 -284.091841) (xy 377.225242 -284.066395) (xy 377.18582 -284.034208)
			(xy 377.152072 -283.996114) (xy 377.124871 -283.9531) (xy 377.104923 -283.90628) (xy 377.092744 -283.856866)
			(xy 377.088649 -283.806138) (xy 376.780552 -283.806138) (xy 376.78004 -283.831584) (xy 376.771876 -283.881818)
			(xy 376.75576 -283.930092) (xy 376.732109 -283.975155) (xy 376.701536 -284.015841) (xy 376.664832 -284.051096)
			(xy 376.622948 -284.080006) (xy 376.576969 -284.101823) (xy 376.528085 -284.115983) (xy 376.477564 -284.122117)
			(xy 376.426712 -284.120068) (xy 376.376848 -284.109888) (xy 376.329262 -284.091841) (xy 376.285188 -284.066395)
			(xy 376.245766 -284.034208) (xy 376.212018 -283.996114) (xy 376.184817 -283.9531) (xy 376.164869 -283.90628)
			(xy 376.15269 -283.856866) (xy 376.148595 -283.806138) (xy 375.830619 -283.806138) (xy 375.826451 -283.856439)
			(xy 375.81405 -283.905405) (xy 375.793759 -283.951662) (xy 375.76613 -283.993948) (xy 375.731918 -284.031109)
			(xy 375.692056 -284.062132) (xy 375.647631 -284.086171) (xy 375.599855 -284.102569) (xy 375.550032 -284.110879)
			(xy 375.524776 -284.111446) (xy 375.502158 -284.11104) (xy 375.457416 -284.104366) (xy 375.414152 -284.091154)
			(xy 375.373316 -284.071694) (xy 375.354342 -284.059376) (xy 375.342404 -284.051502) (xy 375.314718 -284.049978)
			(xy 375.223024 -284.099) (xy 375.215062 -284.103654) (xy 375.202884 -284.117485) (xy 375.196419 -284.134742)
			(xy 375.1961 -284.143958) (xy 375.1961 -284.31617) (xy 375.196374 -284.3247) (xy 375.201904 -284.340834)
			(xy 375.212454 -284.354235) (xy 375.219468 -284.359096) (xy 375.240663 -284.37326) (xy 375.278443 -284.407479)
			(xy 375.31001 -284.447501) (xy 375.334487 -284.492214) (xy 375.351191 -284.540372) (xy 375.359659 -284.590637)
			(xy 375.359657 -284.616144) (xy 375.678695 -284.616144) (xy 375.68279 -284.565416) (xy 375.694969 -284.516002)
			(xy 375.714917 -284.469182) (xy 375.742118 -284.426168) (xy 375.775866 -284.388074) (xy 375.815288 -284.355887)
			(xy 375.859362 -284.330441) (xy 375.906948 -284.312394) (xy 375.956812 -284.302214) (xy 376.007664 -284.300165)
			(xy 376.058185 -284.306299) (xy 376.107069 -284.320459) (xy 376.153048 -284.342276) (xy 376.194932 -284.371186)
			(xy 376.231636 -284.406441) (xy 376.262209 -284.447127) (xy 376.28586 -284.49219) (xy 376.301976 -284.540464)
			(xy 376.31014 -284.590698) (xy 376.310652 -284.616144) (xy 376.628926 -284.616144) (xy 376.632886 -284.56709)
			(xy 376.644663 -284.519306) (xy 376.663954 -284.47403) (xy 376.690257 -284.432434) (xy 376.722892 -284.395597)
			(xy 376.761013 -284.364472) (xy 376.803634 -284.339865) (xy 376.84965 -284.322413) (xy 376.897869 -284.312569)
			(xy 376.947044 -284.310588) (xy 376.995899 -284.31652) (xy 377.04317 -284.330212) (xy 377.087632 -284.35131)
			(xy 377.128135 -284.379266) (xy 377.163628 -284.413358) (xy 377.193193 -284.452702) (xy 377.216064 -284.496279)
			(xy 377.231648 -284.54296) (xy 377.239543 -284.591537) (xy 377.240038 -284.616144) (xy 377.558549 -284.616144)
			(xy 377.562644 -284.565416) (xy 377.574823 -284.516002) (xy 377.594771 -284.469182) (xy 377.621972 -284.426168)
			(xy 377.65572 -284.388074) (xy 377.695142 -284.355887) (xy 377.739216 -284.330441) (xy 377.786802 -284.312394)
			(xy 377.836666 -284.302214) (xy 377.887518 -284.300165) (xy 377.938039 -284.306299) (xy 377.986923 -284.320459)
			(xy 378.032902 -284.342276) (xy 378.074786 -284.371186) (xy 378.11149 -284.406441) (xy 378.142063 -284.447127)
			(xy 378.165714 -284.49219) (xy 378.18183 -284.540464) (xy 378.189994 -284.590698) (xy 378.190506 -284.616144)
			(xy 378.509034 -284.616144) (xy 378.512994 -284.56709) (xy 378.524771 -284.519306) (xy 378.544062 -284.47403)
			(xy 378.570365 -284.432434) (xy 378.603 -284.395597) (xy 378.641121 -284.364472) (xy 378.683742 -284.339865)
			(xy 378.729758 -284.322413) (xy 378.777977 -284.312569) (xy 378.827152 -284.310588) (xy 378.876007 -284.31652)
			(xy 378.923278 -284.330212) (xy 378.96774 -284.35131) (xy 379.008243 -284.379266) (xy 379.043736 -284.413358)
			(xy 379.073301 -284.452702) (xy 379.096172 -284.496279) (xy 379.111756 -284.54296) (xy 379.119651 -284.591537)
			(xy 379.120146 -284.616144) (xy 379.438657 -284.616144) (xy 379.442752 -284.565416) (xy 379.454931 -284.516002)
			(xy 379.474879 -284.469182) (xy 379.50208 -284.426168) (xy 379.535828 -284.388074) (xy 379.57525 -284.355887)
			(xy 379.619324 -284.330441) (xy 379.66691 -284.312394) (xy 379.716774 -284.302214) (xy 379.767626 -284.300165)
			(xy 379.818147 -284.306299) (xy 379.867031 -284.320459) (xy 379.91301 -284.342276) (xy 379.954894 -284.371186)
			(xy 379.991598 -284.406441) (xy 380.022171 -284.447127) (xy 380.045822 -284.49219) (xy 380.061938 -284.540464)
			(xy 380.070102 -284.590698) (xy 380.070614 -284.616144) (xy 380.378711 -284.616144) (xy 380.382806 -284.565416)
			(xy 380.394985 -284.516002) (xy 380.414933 -284.469182) (xy 380.442134 -284.426168) (xy 380.475882 -284.388074)
			(xy 380.515304 -284.355887) (xy 380.559378 -284.330441) (xy 380.606964 -284.312394) (xy 380.656828 -284.302214)
			(xy 380.70768 -284.300165) (xy 380.758201 -284.306299) (xy 380.807085 -284.320459) (xy 380.853064 -284.342276)
			(xy 380.894948 -284.371186) (xy 380.931652 -284.406441) (xy 380.962225 -284.447127) (xy 380.985876 -284.49219)
			(xy 381.001992 -284.540464) (xy 381.010156 -284.590698) (xy 381.010668 -284.616144) (xy 381.328942 -284.616144)
			(xy 381.332902 -284.56709) (xy 381.344679 -284.519306) (xy 381.36397 -284.47403) (xy 381.390273 -284.432434)
			(xy 381.422908 -284.395597) (xy 381.461029 -284.364472) (xy 381.50365 -284.339865) (xy 381.549666 -284.322413)
			(xy 381.597885 -284.312569) (xy 381.64706 -284.310588) (xy 381.695915 -284.31652) (xy 381.743186 -284.330212)
			(xy 381.787648 -284.35131) (xy 381.828151 -284.379266) (xy 381.863644 -284.413358) (xy 381.893209 -284.452702)
			(xy 381.91608 -284.496279) (xy 381.931664 -284.54296) (xy 381.939559 -284.591537) (xy 381.940054 -284.616144)
			(xy 382.258565 -284.616144) (xy 382.26266 -284.565416) (xy 382.274839 -284.516002) (xy 382.294787 -284.469182)
			(xy 382.321988 -284.426168) (xy 382.355736 -284.388074) (xy 382.395158 -284.355887) (xy 382.439232 -284.330441)
			(xy 382.486818 -284.312394) (xy 382.536682 -284.302214) (xy 382.587534 -284.300165) (xy 382.638055 -284.306299)
			(xy 382.686939 -284.320459) (xy 382.732918 -284.342276) (xy 382.774802 -284.371186) (xy 382.811506 -284.406441)
			(xy 382.842079 -284.447127) (xy 382.86573 -284.49219) (xy 382.881846 -284.540464) (xy 382.89001 -284.590698)
			(xy 382.890522 -284.616144) (xy 383.20905 -284.616144) (xy 383.21301 -284.56709) (xy 383.224787 -284.519306)
			(xy 383.244078 -284.47403) (xy 383.270381 -284.432434) (xy 383.303016 -284.395597) (xy 383.341137 -284.364472)
			(xy 383.383758 -284.339865) (xy 383.429774 -284.322413) (xy 383.477993 -284.312569) (xy 383.527168 -284.310588)
			(xy 383.576023 -284.31652) (xy 383.623294 -284.330212) (xy 383.667756 -284.35131) (xy 383.708259 -284.379266)
			(xy 383.743752 -284.413358) (xy 383.773317 -284.452702) (xy 383.796188 -284.496279) (xy 383.811772 -284.54296)
			(xy 383.819667 -284.591537) (xy 383.820162 -284.616144) (xy 384.138673 -284.616144) (xy 384.142768 -284.565416)
			(xy 384.154947 -284.516002) (xy 384.174895 -284.469182) (xy 384.202096 -284.426168) (xy 384.235844 -284.388074)
			(xy 384.275266 -284.355887) (xy 384.31934 -284.330441) (xy 384.366926 -284.312394) (xy 384.41679 -284.302214)
			(xy 384.467642 -284.300165) (xy 384.518163 -284.306299) (xy 384.567047 -284.320459) (xy 384.613026 -284.342276)
			(xy 384.65491 -284.371186) (xy 384.691614 -284.406441) (xy 384.722187 -284.447127) (xy 384.745838 -284.49219)
			(xy 384.761954 -284.540464) (xy 384.770118 -284.590698) (xy 384.77063 -284.616144) (xy 385.088904 -284.616144)
			(xy 385.092864 -284.56709) (xy 385.104641 -284.519306) (xy 385.123932 -284.47403) (xy 385.150235 -284.432434)
			(xy 385.18287 -284.395597) (xy 385.220991 -284.364472) (xy 385.263612 -284.339865) (xy 385.309628 -284.322413)
			(xy 385.357847 -284.312569) (xy 385.407022 -284.310588) (xy 385.455877 -284.31652) (xy 385.503148 -284.330212)
			(xy 385.54761 -284.35131) (xy 385.588113 -284.379266) (xy 385.623606 -284.413358) (xy 385.653171 -284.452702)
			(xy 385.676042 -284.496279) (xy 385.691626 -284.54296) (xy 385.699521 -284.591537) (xy 385.700016 -284.616144)
			(xy 386.018527 -284.616144) (xy 386.022622 -284.565416) (xy 386.034801 -284.516002) (xy 386.054749 -284.469182)
			(xy 386.08195 -284.426168) (xy 386.115698 -284.388074) (xy 386.15512 -284.355887) (xy 386.199194 -284.330441)
			(xy 386.24678 -284.312394) (xy 386.296644 -284.302214) (xy 386.347496 -284.300165) (xy 386.398017 -284.306299)
			(xy 386.446901 -284.320459) (xy 386.49288 -284.342276) (xy 386.534764 -284.371186) (xy 386.571468 -284.406441)
			(xy 386.602041 -284.447127) (xy 386.625692 -284.49219) (xy 386.641808 -284.540464) (xy 386.649972 -284.590698)
			(xy 386.650484 -284.616144) (xy 386.958581 -284.616144) (xy 386.962676 -284.565416) (xy 386.974855 -284.516002)
			(xy 386.994803 -284.469182) (xy 387.022004 -284.426168) (xy 387.055752 -284.388074) (xy 387.095174 -284.355887)
			(xy 387.139248 -284.330441) (xy 387.186834 -284.312394) (xy 387.236698 -284.302214) (xy 387.28755 -284.300165)
			(xy 387.338071 -284.306299) (xy 387.386955 -284.320459) (xy 387.432934 -284.342276) (xy 387.474818 -284.371186)
			(xy 387.511522 -284.406441) (xy 387.542095 -284.447127) (xy 387.565746 -284.49219) (xy 387.581862 -284.540464)
			(xy 387.590026 -284.590698) (xy 387.590538 -284.616144) (xy 387.909066 -284.616144) (xy 387.913026 -284.56709)
			(xy 387.924803 -284.519306) (xy 387.944094 -284.47403) (xy 387.970397 -284.432434) (xy 388.003032 -284.395597)
			(xy 388.041153 -284.364472) (xy 388.083774 -284.339865) (xy 388.12979 -284.322413) (xy 388.178009 -284.312569)
			(xy 388.227184 -284.310588) (xy 388.276039 -284.31652) (xy 388.32331 -284.330212) (xy 388.367772 -284.35131)
			(xy 388.408275 -284.379266) (xy 388.443768 -284.413358) (xy 388.473333 -284.452702) (xy 388.496204 -284.496279)
			(xy 388.511788 -284.54296) (xy 388.519683 -284.591537) (xy 388.520178 -284.616144) (xy 388.838689 -284.616144)
			(xy 388.842784 -284.565416) (xy 388.854963 -284.516002) (xy 388.874911 -284.469182) (xy 388.902112 -284.426168)
			(xy 388.93586 -284.388074) (xy 388.975282 -284.355887) (xy 389.019356 -284.330441) (xy 389.066942 -284.312394)
			(xy 389.116806 -284.302214) (xy 389.167658 -284.300165) (xy 389.218179 -284.306299) (xy 389.267063 -284.320459)
			(xy 389.313042 -284.342276) (xy 389.354926 -284.371186) (xy 389.39163 -284.406441) (xy 389.422203 -284.447127)
			(xy 389.445854 -284.49219) (xy 389.46197 -284.540464) (xy 389.470134 -284.590698) (xy 389.470646 -284.616144)
			(xy 389.78892 -284.616144) (xy 389.79288 -284.56709) (xy 389.804657 -284.519306) (xy 389.823948 -284.47403)
			(xy 389.850251 -284.432434) (xy 389.882886 -284.395597) (xy 389.921007 -284.364472) (xy 389.963628 -284.339865)
			(xy 390.009644 -284.322413) (xy 390.057863 -284.312569) (xy 390.107038 -284.310588) (xy 390.155893 -284.31652)
			(xy 390.203164 -284.330212) (xy 390.247626 -284.35131) (xy 390.288129 -284.379266) (xy 390.323622 -284.413358)
			(xy 390.353187 -284.452702) (xy 390.376058 -284.496279) (xy 390.391642 -284.54296) (xy 390.399537 -284.591537)
			(xy 390.400032 -284.616144) (xy 390.718543 -284.616144) (xy 390.722638 -284.565416) (xy 390.734817 -284.516002)
			(xy 390.754765 -284.469182) (xy 390.781966 -284.426168) (xy 390.815714 -284.388074) (xy 390.855136 -284.355887)
			(xy 390.89921 -284.330441) (xy 390.946796 -284.312394) (xy 390.99666 -284.302214) (xy 391.047512 -284.300165)
			(xy 391.098033 -284.306299) (xy 391.146917 -284.320459) (xy 391.192896 -284.342276) (xy 391.23478 -284.371186)
			(xy 391.271484 -284.406441) (xy 391.302057 -284.447127) (xy 391.325708 -284.49219) (xy 391.341824 -284.540464)
			(xy 391.349988 -284.590698) (xy 391.3505 -284.616144) (xy 391.669028 -284.616144) (xy 391.672988 -284.56709)
			(xy 391.684765 -284.519306) (xy 391.704056 -284.47403) (xy 391.730359 -284.432434) (xy 391.762994 -284.395597)
			(xy 391.801115 -284.364472) (xy 391.843736 -284.339865) (xy 391.889752 -284.322413) (xy 391.937971 -284.312569)
			(xy 391.987146 -284.310588) (xy 392.036001 -284.31652) (xy 392.083272 -284.330212) (xy 392.125407 -284.350206)
			(xy 394.67715 -284.350206) (xy 394.68111 -284.301152) (xy 394.692887 -284.253368) (xy 394.712178 -284.208092)
			(xy 394.738481 -284.166496) (xy 394.771116 -284.129659) (xy 394.809237 -284.098534) (xy 394.851858 -284.073927)
			(xy 394.897874 -284.056475) (xy 394.946093 -284.046631) (xy 394.995268 -284.04465) (xy 395.044123 -284.050582)
			(xy 395.091394 -284.064274) (xy 395.135856 -284.085372) (xy 395.176359 -284.113328) (xy 395.211852 -284.14742)
			(xy 395.241417 -284.186764) (xy 395.264288 -284.230341) (xy 395.279872 -284.277022) (xy 395.287767 -284.325599)
			(xy 395.288262 -284.350206) (xy 395.287767 -284.374813) (xy 395.279872 -284.42339) (xy 395.264288 -284.470071)
			(xy 395.241417 -284.513648) (xy 395.211852 -284.552992) (xy 395.176359 -284.587084) (xy 395.135856 -284.61504)
			(xy 395.091394 -284.636138) (xy 395.044123 -284.64983) (xy 394.995268 -284.655762) (xy 394.946093 -284.653781)
			(xy 394.897874 -284.643937) (xy 394.851858 -284.626485) (xy 394.809237 -284.601878) (xy 394.771116 -284.570753)
			(xy 394.738481 -284.533916) (xy 394.712178 -284.49232) (xy 394.692887 -284.447044) (xy 394.68111 -284.39926)
			(xy 394.67715 -284.350206) (xy 392.125407 -284.350206) (xy 392.127734 -284.35131) (xy 392.168237 -284.379266)
			(xy 392.20373 -284.413358) (xy 392.233295 -284.452702) (xy 392.256166 -284.496279) (xy 392.27175 -284.54296)
			(xy 392.279645 -284.591537) (xy 392.28014 -284.616144) (xy 392.279645 -284.640751) (xy 392.27175 -284.689328)
			(xy 392.256166 -284.736009) (xy 392.233295 -284.779586) (xy 392.20373 -284.81893) (xy 392.168237 -284.853022)
			(xy 392.127734 -284.880978) (xy 392.083272 -284.902076) (xy 392.036001 -284.915768) (xy 391.987146 -284.9217)
			(xy 391.937971 -284.919719) (xy 391.889752 -284.909875) (xy 391.843736 -284.892423) (xy 391.801115 -284.867816)
			(xy 391.762994 -284.836691) (xy 391.730359 -284.799854) (xy 391.704056 -284.758258) (xy 391.684765 -284.712982)
			(xy 391.672988 -284.665198) (xy 391.669028 -284.616144) (xy 391.3505 -284.616144) (xy 391.349988 -284.64159)
			(xy 391.341824 -284.691824) (xy 391.325708 -284.740098) (xy 391.302057 -284.785161) (xy 391.271484 -284.825847)
			(xy 391.23478 -284.861102) (xy 391.192896 -284.890012) (xy 391.146917 -284.911829) (xy 391.098033 -284.925989)
			(xy 391.047512 -284.932123) (xy 390.99666 -284.930074) (xy 390.946796 -284.919894) (xy 390.89921 -284.901847)
			(xy 390.855136 -284.876401) (xy 390.815714 -284.844214) (xy 390.781966 -284.80612) (xy 390.754765 -284.763106)
			(xy 390.734817 -284.716286) (xy 390.722638 -284.666872) (xy 390.718543 -284.616144) (xy 390.400032 -284.616144)
			(xy 390.399537 -284.640751) (xy 390.391642 -284.689328) (xy 390.376058 -284.736009) (xy 390.353187 -284.779586)
			(xy 390.323622 -284.81893) (xy 390.288129 -284.853022) (xy 390.247626 -284.880978) (xy 390.203164 -284.902076)
			(xy 390.155893 -284.915768) (xy 390.107038 -284.9217) (xy 390.057863 -284.919719) (xy 390.009644 -284.909875)
			(xy 389.963628 -284.892423) (xy 389.921007 -284.867816) (xy 389.882886 -284.836691) (xy 389.850251 -284.799854)
			(xy 389.823948 -284.758258) (xy 389.804657 -284.712982) (xy 389.79288 -284.665198) (xy 389.78892 -284.616144)
			(xy 389.470646 -284.616144) (xy 389.470134 -284.64159) (xy 389.46197 -284.691824) (xy 389.445854 -284.740098)
			(xy 389.422203 -284.785161) (xy 389.39163 -284.825847) (xy 389.354926 -284.861102) (xy 389.313042 -284.890012)
			(xy 389.267063 -284.911829) (xy 389.218179 -284.925989) (xy 389.167658 -284.932123) (xy 389.116806 -284.930074)
			(xy 389.066942 -284.919894) (xy 389.019356 -284.901847) (xy 388.975282 -284.876401) (xy 388.93586 -284.844214)
			(xy 388.902112 -284.80612) (xy 388.874911 -284.763106) (xy 388.854963 -284.716286) (xy 388.842784 -284.666872)
			(xy 388.838689 -284.616144) (xy 388.520178 -284.616144) (xy 388.519683 -284.640751) (xy 388.511788 -284.689328)
			(xy 388.496204 -284.736009) (xy 388.473333 -284.779586) (xy 388.443768 -284.81893) (xy 388.408275 -284.853022)
			(xy 388.367772 -284.880978) (xy 388.32331 -284.902076) (xy 388.276039 -284.915768) (xy 388.227184 -284.9217)
			(xy 388.178009 -284.919719) (xy 388.12979 -284.909875) (xy 388.083774 -284.892423) (xy 388.041153 -284.867816)
			(xy 388.003032 -284.836691) (xy 387.970397 -284.799854) (xy 387.944094 -284.758258) (xy 387.924803 -284.712982)
			(xy 387.913026 -284.665198) (xy 387.909066 -284.616144) (xy 387.590538 -284.616144) (xy 387.590026 -284.64159)
			(xy 387.581862 -284.691824) (xy 387.565746 -284.740098) (xy 387.542095 -284.785161) (xy 387.511522 -284.825847)
			(xy 387.474818 -284.861102) (xy 387.432934 -284.890012) (xy 387.386955 -284.911829) (xy 387.338071 -284.925989)
			(xy 387.28755 -284.932123) (xy 387.236698 -284.930074) (xy 387.186834 -284.919894) (xy 387.139248 -284.901847)
			(xy 387.095174 -284.876401) (xy 387.055752 -284.844214) (xy 387.022004 -284.80612) (xy 386.994803 -284.763106)
			(xy 386.974855 -284.716286) (xy 386.962676 -284.666872) (xy 386.958581 -284.616144) (xy 386.650484 -284.616144)
			(xy 386.649972 -284.64159) (xy 386.641808 -284.691824) (xy 386.625692 -284.740098) (xy 386.602041 -284.785161)
			(xy 386.571468 -284.825847) (xy 386.534764 -284.861102) (xy 386.49288 -284.890012) (xy 386.446901 -284.911829)
			(xy 386.398017 -284.925989) (xy 386.347496 -284.932123) (xy 386.296644 -284.930074) (xy 386.24678 -284.919894)
			(xy 386.199194 -284.901847) (xy 386.15512 -284.876401) (xy 386.115698 -284.844214) (xy 386.08195 -284.80612)
			(xy 386.054749 -284.763106) (xy 386.034801 -284.716286) (xy 386.022622 -284.666872) (xy 386.018527 -284.616144)
			(xy 385.700016 -284.616144) (xy 385.699521 -284.640751) (xy 385.691626 -284.689328) (xy 385.676042 -284.736009)
			(xy 385.653171 -284.779586) (xy 385.623606 -284.81893) (xy 385.588113 -284.853022) (xy 385.54761 -284.880978)
			(xy 385.503148 -284.902076) (xy 385.455877 -284.915768) (xy 385.407022 -284.9217) (xy 385.357847 -284.919719)
			(xy 385.309628 -284.909875) (xy 385.263612 -284.892423) (xy 385.220991 -284.867816) (xy 385.18287 -284.836691)
			(xy 385.150235 -284.799854) (xy 385.123932 -284.758258) (xy 385.104641 -284.712982) (xy 385.092864 -284.665198)
			(xy 385.088904 -284.616144) (xy 384.77063 -284.616144) (xy 384.770118 -284.64159) (xy 384.761954 -284.691824)
			(xy 384.745838 -284.740098) (xy 384.722187 -284.785161) (xy 384.691614 -284.825847) (xy 384.65491 -284.861102)
			(xy 384.613026 -284.890012) (xy 384.567047 -284.911829) (xy 384.518163 -284.925989) (xy 384.467642 -284.932123)
			(xy 384.41679 -284.930074) (xy 384.366926 -284.919894) (xy 384.31934 -284.901847) (xy 384.275266 -284.876401)
			(xy 384.235844 -284.844214) (xy 384.202096 -284.80612) (xy 384.174895 -284.763106) (xy 384.154947 -284.716286)
			(xy 384.142768 -284.666872) (xy 384.138673 -284.616144) (xy 383.820162 -284.616144) (xy 383.819667 -284.640751)
			(xy 383.811772 -284.689328) (xy 383.796188 -284.736009) (xy 383.773317 -284.779586) (xy 383.743752 -284.81893)
			(xy 383.708259 -284.853022) (xy 383.667756 -284.880978) (xy 383.623294 -284.902076) (xy 383.576023 -284.915768)
			(xy 383.527168 -284.9217) (xy 383.477993 -284.919719) (xy 383.429774 -284.909875) (xy 383.383758 -284.892423)
			(xy 383.341137 -284.867816) (xy 383.303016 -284.836691) (xy 383.270381 -284.799854) (xy 383.244078 -284.758258)
			(xy 383.224787 -284.712982) (xy 383.21301 -284.665198) (xy 383.20905 -284.616144) (xy 382.890522 -284.616144)
			(xy 382.89001 -284.64159) (xy 382.881846 -284.691824) (xy 382.86573 -284.740098) (xy 382.842079 -284.785161)
			(xy 382.811506 -284.825847) (xy 382.774802 -284.861102) (xy 382.732918 -284.890012) (xy 382.686939 -284.911829)
			(xy 382.638055 -284.925989) (xy 382.587534 -284.932123) (xy 382.536682 -284.930074) (xy 382.486818 -284.919894)
			(xy 382.439232 -284.901847) (xy 382.395158 -284.876401) (xy 382.355736 -284.844214) (xy 382.321988 -284.80612)
			(xy 382.294787 -284.763106) (xy 382.274839 -284.716286) (xy 382.26266 -284.666872) (xy 382.258565 -284.616144)
			(xy 381.940054 -284.616144) (xy 381.939559 -284.640751) (xy 381.931664 -284.689328) (xy 381.91608 -284.736009)
			(xy 381.893209 -284.779586) (xy 381.863644 -284.81893) (xy 381.828151 -284.853022) (xy 381.787648 -284.880978)
			(xy 381.743186 -284.902076) (xy 381.695915 -284.915768) (xy 381.64706 -284.9217) (xy 381.597885 -284.919719)
			(xy 381.549666 -284.909875) (xy 381.50365 -284.892423) (xy 381.461029 -284.867816) (xy 381.422908 -284.836691)
			(xy 381.390273 -284.799854) (xy 381.36397 -284.758258) (xy 381.344679 -284.712982) (xy 381.332902 -284.665198)
			(xy 381.328942 -284.616144) (xy 381.010668 -284.616144) (xy 381.010156 -284.64159) (xy 381.001992 -284.691824)
			(xy 380.985876 -284.740098) (xy 380.962225 -284.785161) (xy 380.931652 -284.825847) (xy 380.894948 -284.861102)
			(xy 380.853064 -284.890012) (xy 380.807085 -284.911829) (xy 380.758201 -284.925989) (xy 380.70768 -284.932123)
			(xy 380.656828 -284.930074) (xy 380.606964 -284.919894) (xy 380.559378 -284.901847) (xy 380.515304 -284.876401)
			(xy 380.475882 -284.844214) (xy 380.442134 -284.80612) (xy 380.414933 -284.763106) (xy 380.394985 -284.716286)
			(xy 380.382806 -284.666872) (xy 380.378711 -284.616144) (xy 380.070614 -284.616144) (xy 380.070102 -284.64159)
			(xy 380.061938 -284.691824) (xy 380.045822 -284.740098) (xy 380.022171 -284.785161) (xy 379.991598 -284.825847)
			(xy 379.954894 -284.861102) (xy 379.91301 -284.890012) (xy 379.867031 -284.911829) (xy 379.818147 -284.925989)
			(xy 379.767626 -284.932123) (xy 379.716774 -284.930074) (xy 379.66691 -284.919894) (xy 379.619324 -284.901847)
			(xy 379.57525 -284.876401) (xy 379.535828 -284.844214) (xy 379.50208 -284.80612) (xy 379.474879 -284.763106)
			(xy 379.454931 -284.716286) (xy 379.442752 -284.666872) (xy 379.438657 -284.616144) (xy 379.120146 -284.616144)
			(xy 379.119651 -284.640751) (xy 379.111756 -284.689328) (xy 379.096172 -284.736009) (xy 379.073301 -284.779586)
			(xy 379.043736 -284.81893) (xy 379.008243 -284.853022) (xy 378.96774 -284.880978) (xy 378.923278 -284.902076)
			(xy 378.876007 -284.915768) (xy 378.827152 -284.9217) (xy 378.777977 -284.919719) (xy 378.729758 -284.909875)
			(xy 378.683742 -284.892423) (xy 378.641121 -284.867816) (xy 378.603 -284.836691) (xy 378.570365 -284.799854)
			(xy 378.544062 -284.758258) (xy 378.524771 -284.712982) (xy 378.512994 -284.665198) (xy 378.509034 -284.616144)
			(xy 378.190506 -284.616144) (xy 378.189994 -284.64159) (xy 378.18183 -284.691824) (xy 378.165714 -284.740098)
			(xy 378.142063 -284.785161) (xy 378.11149 -284.825847) (xy 378.074786 -284.861102) (xy 378.032902 -284.890012)
			(xy 377.986923 -284.911829) (xy 377.938039 -284.925989) (xy 377.887518 -284.932123) (xy 377.836666 -284.930074)
			(xy 377.786802 -284.919894) (xy 377.739216 -284.901847) (xy 377.695142 -284.876401) (xy 377.65572 -284.844214)
			(xy 377.621972 -284.80612) (xy 377.594771 -284.763106) (xy 377.574823 -284.716286) (xy 377.562644 -284.666872)
			(xy 377.558549 -284.616144) (xy 377.240038 -284.616144) (xy 377.239543 -284.640751) (xy 377.231648 -284.689328)
			(xy 377.216064 -284.736009) (xy 377.193193 -284.779586) (xy 377.163628 -284.81893) (xy 377.128135 -284.853022)
			(xy 377.087632 -284.880978) (xy 377.04317 -284.902076) (xy 376.995899 -284.915768) (xy 376.947044 -284.9217)
			(xy 376.897869 -284.919719) (xy 376.84965 -284.909875) (xy 376.803634 -284.892423) (xy 376.761013 -284.867816)
			(xy 376.722892 -284.836691) (xy 376.690257 -284.799854) (xy 376.663954 -284.758258) (xy 376.644663 -284.712982)
			(xy 376.632886 -284.665198) (xy 376.628926 -284.616144) (xy 376.310652 -284.616144) (xy 376.31014 -284.64159)
			(xy 376.301976 -284.691824) (xy 376.28586 -284.740098) (xy 376.262209 -284.785161) (xy 376.231636 -284.825847)
			(xy 376.194932 -284.861102) (xy 376.153048 -284.890012) (xy 376.107069 -284.911829) (xy 376.058185 -284.925989)
			(xy 376.007664 -284.932123) (xy 375.956812 -284.930074) (xy 375.906948 -284.919894) (xy 375.859362 -284.901847)
			(xy 375.815288 -284.876401) (xy 375.775866 -284.844214) (xy 375.742118 -284.80612) (xy 375.714917 -284.763106)
			(xy 375.694969 -284.716286) (xy 375.68279 -284.666872) (xy 375.678695 -284.616144) (xy 375.359657 -284.616144)
			(xy 375.359655 -284.64161) (xy 375.351179 -284.691874) (xy 375.334467 -284.74003) (xy 375.309984 -284.784738)
			(xy 375.27841 -284.824756) (xy 375.240625 -284.858969) (xy 375.219468 -284.873192) (xy 375.212474 -284.878074)
			(xy 375.201946 -284.891482) (xy 375.196379 -284.907594) (xy 375.1961 -284.916118) (xy 375.1961 -285.42615)
			(xy 376.148595 -285.42615) (xy 376.15269 -285.375422) (xy 376.164869 -285.326008) (xy 376.184817 -285.279188)
			(xy 376.212018 -285.236174) (xy 376.245766 -285.19808) (xy 376.285188 -285.165893) (xy 376.329262 -285.140447)
			(xy 376.376848 -285.1224) (xy 376.426712 -285.11222) (xy 376.477564 -285.110171) (xy 376.528085 -285.116305)
			(xy 376.576969 -285.130465) (xy 376.622948 -285.152282) (xy 376.664832 -285.181192) (xy 376.701536 -285.216447)
			(xy 376.732109 -285.257133) (xy 376.75576 -285.302196) (xy 376.771876 -285.35047) (xy 376.78004 -285.400704)
			(xy 376.780552 -285.42615) (xy 377.088649 -285.42615) (xy 377.092744 -285.375422) (xy 377.104923 -285.326008)
			(xy 377.124871 -285.279188) (xy 377.152072 -285.236174) (xy 377.18582 -285.19808) (xy 377.225242 -285.165893)
			(xy 377.269316 -285.140447) (xy 377.316902 -285.1224) (xy 377.366766 -285.11222) (xy 377.417618 -285.110171)
			(xy 377.468139 -285.116305) (xy 377.517023 -285.130465) (xy 377.563002 -285.152282) (xy 377.604886 -285.181192)
			(xy 377.64159 -285.216447) (xy 377.672163 -285.257133) (xy 377.695814 -285.302196) (xy 377.71193 -285.35047)
			(xy 377.720094 -285.400704) (xy 377.720606 -285.42615) (xy 378.968503 -285.42615) (xy 378.972598 -285.375422)
			(xy 378.984777 -285.326008) (xy 379.004725 -285.279188) (xy 379.031926 -285.236174) (xy 379.065674 -285.19808)
			(xy 379.105096 -285.165893) (xy 379.14917 -285.140447) (xy 379.196756 -285.1224) (xy 379.24662 -285.11222)
			(xy 379.297472 -285.110171) (xy 379.347993 -285.116305) (xy 379.396877 -285.130465) (xy 379.442856 -285.152282)
			(xy 379.48474 -285.181192) (xy 379.521444 -285.216447) (xy 379.552017 -285.257133) (xy 379.575668 -285.302196)
			(xy 379.591784 -285.35047) (xy 379.599948 -285.400704) (xy 379.60046 -285.42615) (xy 379.918988 -285.42615)
			(xy 379.922948 -285.377096) (xy 379.934725 -285.329312) (xy 379.954016 -285.284036) (xy 379.980319 -285.24244)
			(xy 380.012954 -285.205603) (xy 380.051075 -285.174478) (xy 380.093696 -285.149871) (xy 380.139712 -285.132419)
			(xy 380.187931 -285.122575) (xy 380.237106 -285.120594) (xy 380.285961 -285.126526) (xy 380.333232 -285.140218)
			(xy 380.377694 -285.161316) (xy 380.418197 -285.189272) (xy 380.45369 -285.223364) (xy 380.483255 -285.262708)
			(xy 380.506126 -285.306285) (xy 380.52171 -285.352966) (xy 380.529605 -285.401543) (xy 380.5301 -285.42615)
			(xy 380.848611 -285.42615) (xy 380.852706 -285.375422) (xy 380.864885 -285.326008) (xy 380.884833 -285.279188)
			(xy 380.912034 -285.236174) (xy 380.945782 -285.19808) (xy 380.985204 -285.165893) (xy 381.029278 -285.140447)
			(xy 381.076864 -285.1224) (xy 381.126728 -285.11222) (xy 381.17758 -285.110171) (xy 381.228101 -285.116305)
			(xy 381.276985 -285.130465) (xy 381.322964 -285.152282) (xy 381.364848 -285.181192) (xy 381.401552 -285.216447)
			(xy 381.432125 -285.257133) (xy 381.455776 -285.302196) (xy 381.471892 -285.35047) (xy 381.480056 -285.400704)
			(xy 381.480568 -285.42615) (xy 381.799096 -285.42615) (xy 381.803056 -285.377096) (xy 381.814833 -285.329312)
			(xy 381.834124 -285.284036) (xy 381.860427 -285.24244) (xy 381.893062 -285.205603) (xy 381.931183 -285.174478)
			(xy 381.973804 -285.149871) (xy 382.01982 -285.132419) (xy 382.068039 -285.122575) (xy 382.117214 -285.120594)
			(xy 382.166069 -285.126526) (xy 382.21334 -285.140218) (xy 382.257802 -285.161316) (xy 382.298305 -285.189272)
			(xy 382.333798 -285.223364) (xy 382.363363 -285.262708) (xy 382.386234 -285.306285) (xy 382.401818 -285.352966)
			(xy 382.409713 -285.401543) (xy 382.410208 -285.42615) (xy 382.728465 -285.42615) (xy 382.73256 -285.375422)
			(xy 382.744739 -285.326008) (xy 382.764687 -285.279188) (xy 382.791888 -285.236174) (xy 382.825636 -285.19808)
			(xy 382.865058 -285.165893) (xy 382.909132 -285.140447) (xy 382.956718 -285.1224) (xy 383.006582 -285.11222)
			(xy 383.057434 -285.110171) (xy 383.107955 -285.116305) (xy 383.156839 -285.130465) (xy 383.202818 -285.152282)
			(xy 383.244702 -285.181192) (xy 383.281406 -285.216447) (xy 383.311979 -285.257133) (xy 383.33563 -285.302196)
			(xy 383.351746 -285.35047) (xy 383.35991 -285.400704) (xy 383.360422 -285.42615) (xy 383.668519 -285.42615)
			(xy 383.672614 -285.375422) (xy 383.684793 -285.326008) (xy 383.704741 -285.279188) (xy 383.731942 -285.236174)
			(xy 383.76569 -285.19808) (xy 383.805112 -285.165893) (xy 383.849186 -285.140447) (xy 383.896772 -285.1224)
			(xy 383.946636 -285.11222) (xy 383.997488 -285.110171) (xy 384.048009 -285.116305) (xy 384.096893 -285.130465)
			(xy 384.142872 -285.152282) (xy 384.184756 -285.181192) (xy 384.22146 -285.216447) (xy 384.252033 -285.257133)
			(xy 384.275684 -285.302196) (xy 384.2918 -285.35047) (xy 384.299964 -285.400704) (xy 384.300476 -285.42615)
			(xy 385.548627 -285.42615) (xy 385.552722 -285.375422) (xy 385.564901 -285.326008) (xy 385.584849 -285.279188)
			(xy 385.61205 -285.236174) (xy 385.645798 -285.19808) (xy 385.68522 -285.165893) (xy 385.729294 -285.140447)
			(xy 385.77688 -285.1224) (xy 385.826744 -285.11222) (xy 385.877596 -285.110171) (xy 385.928117 -285.116305)
			(xy 385.977001 -285.130465) (xy 386.02298 -285.152282) (xy 386.064864 -285.181192) (xy 386.101568 -285.216447)
			(xy 386.132141 -285.257133) (xy 386.155792 -285.302196) (xy 386.171908 -285.35047) (xy 386.180072 -285.400704)
			(xy 386.180584 -285.42615) (xy 386.499112 -285.42615) (xy 386.503072 -285.377096) (xy 386.514849 -285.329312)
			(xy 386.53414 -285.284036) (xy 386.560443 -285.24244) (xy 386.593078 -285.205603) (xy 386.631199 -285.174478)
			(xy 386.67382 -285.149871) (xy 386.719836 -285.132419) (xy 386.768055 -285.122575) (xy 386.81723 -285.120594)
			(xy 386.866085 -285.126526) (xy 386.913356 -285.140218) (xy 386.957818 -285.161316) (xy 386.998321 -285.189272)
			(xy 387.033814 -285.223364) (xy 387.063379 -285.262708) (xy 387.08625 -285.306285) (xy 387.101834 -285.352966)
			(xy 387.109729 -285.401543) (xy 387.110224 -285.42615) (xy 387.428481 -285.42615) (xy 387.432576 -285.375422)
			(xy 387.444755 -285.326008) (xy 387.464703 -285.279188) (xy 387.491904 -285.236174) (xy 387.525652 -285.19808)
			(xy 387.565074 -285.165893) (xy 387.609148 -285.140447) (xy 387.656734 -285.1224) (xy 387.706598 -285.11222)
			(xy 387.75745 -285.110171) (xy 387.807971 -285.116305) (xy 387.856855 -285.130465) (xy 387.902834 -285.152282)
			(xy 387.944718 -285.181192) (xy 387.981422 -285.216447) (xy 388.011995 -285.257133) (xy 388.035646 -285.302196)
			(xy 388.051762 -285.35047) (xy 388.059926 -285.400704) (xy 388.060438 -285.42615) (xy 388.378966 -285.42615)
			(xy 388.382926 -285.377096) (xy 388.394703 -285.329312) (xy 388.413994 -285.284036) (xy 388.440297 -285.24244)
			(xy 388.472932 -285.205603) (xy 388.511053 -285.174478) (xy 388.553674 -285.149871) (xy 388.59969 -285.132419)
			(xy 388.647909 -285.122575) (xy 388.697084 -285.120594) (xy 388.745939 -285.126526) (xy 388.79321 -285.140218)
			(xy 388.837672 -285.161316) (xy 388.878175 -285.189272) (xy 388.913668 -285.223364) (xy 388.943233 -285.262708)
			(xy 388.966104 -285.306285) (xy 388.981688 -285.352966) (xy 388.989583 -285.401543) (xy 388.990078 -285.42615)
			(xy 389.308589 -285.42615) (xy 389.312684 -285.375422) (xy 389.324863 -285.326008) (xy 389.344811 -285.279188)
			(xy 389.372012 -285.236174) (xy 389.40576 -285.19808) (xy 389.445182 -285.165893) (xy 389.489256 -285.140447)
			(xy 389.536842 -285.1224) (xy 389.586706 -285.11222) (xy 389.637558 -285.110171) (xy 389.688079 -285.116305)
			(xy 389.736963 -285.130465) (xy 389.782942 -285.152282) (xy 389.824826 -285.181192) (xy 389.86153 -285.216447)
			(xy 389.892103 -285.257133) (xy 389.915754 -285.302196) (xy 389.93187 -285.35047) (xy 389.940034 -285.400704)
			(xy 389.940546 -285.42615) (xy 390.248643 -285.42615) (xy 390.252738 -285.375422) (xy 390.264917 -285.326008)
			(xy 390.284865 -285.279188) (xy 390.312066 -285.236174) (xy 390.345814 -285.19808) (xy 390.385236 -285.165893)
			(xy 390.42931 -285.140447) (xy 390.476896 -285.1224) (xy 390.52676 -285.11222) (xy 390.577612 -285.110171)
			(xy 390.628133 -285.116305) (xy 390.677017 -285.130465) (xy 390.722996 -285.152282) (xy 390.76488 -285.181192)
			(xy 390.801584 -285.216447) (xy 390.832157 -285.257133) (xy 390.855808 -285.302196) (xy 390.871924 -285.35047)
			(xy 390.880088 -285.400704) (xy 390.8806 -285.42615) (xy 393.078982 -285.42615) (xy 393.082942 -285.377096)
			(xy 393.094719 -285.329312) (xy 393.11401 -285.284036) (xy 393.140313 -285.24244) (xy 393.172948 -285.205603)
			(xy 393.211069 -285.174478) (xy 393.25369 -285.149871) (xy 393.299706 -285.132419) (xy 393.347925 -285.122575)
			(xy 393.3971 -285.120594) (xy 393.445955 -285.126526) (xy 393.493226 -285.140218) (xy 393.537688 -285.161316)
			(xy 393.578191 -285.189272) (xy 393.613684 -285.223364) (xy 393.643249 -285.262708) (xy 393.66612 -285.306285)
			(xy 393.681704 -285.352966) (xy 393.689599 -285.401543) (xy 393.690094 -285.42615) (xy 393.689599 -285.450757)
			(xy 393.681704 -285.499334) (xy 393.66612 -285.546015) (xy 393.643249 -285.589592) (xy 393.613684 -285.628936)
			(xy 393.578191 -285.663028) (xy 393.537688 -285.690984) (xy 393.493226 -285.712082) (xy 393.445955 -285.725774)
			(xy 393.3971 -285.731706) (xy 393.347925 -285.729725) (xy 393.299706 -285.719881) (xy 393.25369 -285.702429)
			(xy 393.211069 -285.677822) (xy 393.172948 -285.646697) (xy 393.140313 -285.60986) (xy 393.11401 -285.568264)
			(xy 393.094719 -285.522988) (xy 393.082942 -285.475204) (xy 393.078982 -285.42615) (xy 390.8806 -285.42615)
			(xy 390.880088 -285.451596) (xy 390.871924 -285.50183) (xy 390.855808 -285.550104) (xy 390.832157 -285.595167)
			(xy 390.801584 -285.635853) (xy 390.76488 -285.671108) (xy 390.722996 -285.700018) (xy 390.677017 -285.721835)
			(xy 390.628133 -285.735995) (xy 390.577612 -285.742129) (xy 390.52676 -285.74008) (xy 390.476896 -285.7299)
			(xy 390.42931 -285.711853) (xy 390.385236 -285.686407) (xy 390.345814 -285.65422) (xy 390.312066 -285.616126)
			(xy 390.284865 -285.573112) (xy 390.264917 -285.526292) (xy 390.252738 -285.476878) (xy 390.248643 -285.42615)
			(xy 389.940546 -285.42615) (xy 389.940034 -285.451596) (xy 389.93187 -285.50183) (xy 389.915754 -285.550104)
			(xy 389.892103 -285.595167) (xy 389.86153 -285.635853) (xy 389.824826 -285.671108) (xy 389.782942 -285.700018)
			(xy 389.736963 -285.721835) (xy 389.688079 -285.735995) (xy 389.637558 -285.742129) (xy 389.586706 -285.74008)
			(xy 389.536842 -285.7299) (xy 389.489256 -285.711853) (xy 389.445182 -285.686407) (xy 389.40576 -285.65422)
			(xy 389.372012 -285.616126) (xy 389.344811 -285.573112) (xy 389.324863 -285.526292) (xy 389.312684 -285.476878)
			(xy 389.308589 -285.42615) (xy 388.990078 -285.42615) (xy 388.989583 -285.450757) (xy 388.981688 -285.499334)
			(xy 388.966104 -285.546015) (xy 388.943233 -285.589592) (xy 388.913668 -285.628936) (xy 388.878175 -285.663028)
			(xy 388.837672 -285.690984) (xy 388.79321 -285.712082) (xy 388.745939 -285.725774) (xy 388.697084 -285.731706)
			(xy 388.647909 -285.729725) (xy 388.59969 -285.719881) (xy 388.553674 -285.702429) (xy 388.511053 -285.677822)
			(xy 388.472932 -285.646697) (xy 388.440297 -285.60986) (xy 388.413994 -285.568264) (xy 388.394703 -285.522988)
			(xy 388.382926 -285.475204) (xy 388.378966 -285.42615) (xy 388.060438 -285.42615) (xy 388.059926 -285.451596)
			(xy 388.051762 -285.50183) (xy 388.035646 -285.550104) (xy 388.011995 -285.595167) (xy 387.981422 -285.635853)
			(xy 387.944718 -285.671108) (xy 387.902834 -285.700018) (xy 387.856855 -285.721835) (xy 387.807971 -285.735995)
			(xy 387.75745 -285.742129) (xy 387.706598 -285.74008) (xy 387.656734 -285.7299) (xy 387.609148 -285.711853)
			(xy 387.565074 -285.686407) (xy 387.525652 -285.65422) (xy 387.491904 -285.616126) (xy 387.464703 -285.573112)
			(xy 387.444755 -285.526292) (xy 387.432576 -285.476878) (xy 387.428481 -285.42615) (xy 387.110224 -285.42615)
			(xy 387.109729 -285.450757) (xy 387.101834 -285.499334) (xy 387.08625 -285.546015) (xy 387.063379 -285.589592)
			(xy 387.033814 -285.628936) (xy 386.998321 -285.663028) (xy 386.957818 -285.690984) (xy 386.913356 -285.712082)
			(xy 386.866085 -285.725774) (xy 386.81723 -285.731706) (xy 386.768055 -285.729725) (xy 386.719836 -285.719881)
			(xy 386.67382 -285.702429) (xy 386.631199 -285.677822) (xy 386.593078 -285.646697) (xy 386.560443 -285.60986)
			(xy 386.53414 -285.568264) (xy 386.514849 -285.522988) (xy 386.503072 -285.475204) (xy 386.499112 -285.42615)
			(xy 386.180584 -285.42615) (xy 386.180072 -285.451596) (xy 386.171908 -285.50183) (xy 386.155792 -285.550104)
			(xy 386.132141 -285.595167) (xy 386.101568 -285.635853) (xy 386.064864 -285.671108) (xy 386.02298 -285.700018)
			(xy 385.977001 -285.721835) (xy 385.928117 -285.735995) (xy 385.877596 -285.742129) (xy 385.826744 -285.74008)
			(xy 385.77688 -285.7299) (xy 385.729294 -285.711853) (xy 385.68522 -285.686407) (xy 385.645798 -285.65422)
			(xy 385.61205 -285.616126) (xy 385.584849 -285.573112) (xy 385.564901 -285.526292) (xy 385.552722 -285.476878)
			(xy 385.548627 -285.42615) (xy 384.300476 -285.42615) (xy 384.299964 -285.451596) (xy 384.2918 -285.50183)
			(xy 384.275684 -285.550104) (xy 384.252033 -285.595167) (xy 384.22146 -285.635853) (xy 384.184756 -285.671108)
			(xy 384.142872 -285.700018) (xy 384.096893 -285.721835) (xy 384.048009 -285.735995) (xy 383.997488 -285.742129)
			(xy 383.946636 -285.74008) (xy 383.896772 -285.7299) (xy 383.849186 -285.711853) (xy 383.805112 -285.686407)
			(xy 383.76569 -285.65422) (xy 383.731942 -285.616126) (xy 383.704741 -285.573112) (xy 383.684793 -285.526292)
			(xy 383.672614 -285.476878) (xy 383.668519 -285.42615) (xy 383.360422 -285.42615) (xy 383.35991 -285.451596)
			(xy 383.351746 -285.50183) (xy 383.33563 -285.550104) (xy 383.311979 -285.595167) (xy 383.281406 -285.635853)
			(xy 383.244702 -285.671108) (xy 383.202818 -285.700018) (xy 383.156839 -285.721835) (xy 383.107955 -285.735995)
			(xy 383.057434 -285.742129) (xy 383.006582 -285.74008) (xy 382.956718 -285.7299) (xy 382.909132 -285.711853)
			(xy 382.865058 -285.686407) (xy 382.825636 -285.65422) (xy 382.791888 -285.616126) (xy 382.764687 -285.573112)
			(xy 382.744739 -285.526292) (xy 382.73256 -285.476878) (xy 382.728465 -285.42615) (xy 382.410208 -285.42615)
			(xy 382.409713 -285.450757) (xy 382.401818 -285.499334) (xy 382.386234 -285.546015) (xy 382.363363 -285.589592)
			(xy 382.333798 -285.628936) (xy 382.298305 -285.663028) (xy 382.257802 -285.690984) (xy 382.21334 -285.712082)
			(xy 382.166069 -285.725774) (xy 382.117214 -285.731706) (xy 382.068039 -285.729725) (xy 382.01982 -285.719881)
			(xy 381.973804 -285.702429) (xy 381.931183 -285.677822) (xy 381.893062 -285.646697) (xy 381.860427 -285.60986)
			(xy 381.834124 -285.568264) (xy 381.814833 -285.522988) (xy 381.803056 -285.475204) (xy 381.799096 -285.42615)
			(xy 381.480568 -285.42615) (xy 381.480056 -285.451596) (xy 381.471892 -285.50183) (xy 381.455776 -285.550104)
			(xy 381.432125 -285.595167) (xy 381.401552 -285.635853) (xy 381.364848 -285.671108) (xy 381.322964 -285.700018)
			(xy 381.276985 -285.721835) (xy 381.228101 -285.735995) (xy 381.17758 -285.742129) (xy 381.126728 -285.74008)
			(xy 381.076864 -285.7299) (xy 381.029278 -285.711853) (xy 380.985204 -285.686407) (xy 380.945782 -285.65422)
			(xy 380.912034 -285.616126) (xy 380.884833 -285.573112) (xy 380.864885 -285.526292) (xy 380.852706 -285.476878)
			(xy 380.848611 -285.42615) (xy 380.5301 -285.42615) (xy 380.529605 -285.450757) (xy 380.52171 -285.499334)
			(xy 380.506126 -285.546015) (xy 380.483255 -285.589592) (xy 380.45369 -285.628936) (xy 380.418197 -285.663028)
			(xy 380.377694 -285.690984) (xy 380.333232 -285.712082) (xy 380.285961 -285.725774) (xy 380.237106 -285.731706)
			(xy 380.187931 -285.729725) (xy 380.139712 -285.719881) (xy 380.093696 -285.702429) (xy 380.051075 -285.677822)
			(xy 380.012954 -285.646697) (xy 379.980319 -285.60986) (xy 379.954016 -285.568264) (xy 379.934725 -285.522988)
			(xy 379.922948 -285.475204) (xy 379.918988 -285.42615) (xy 379.60046 -285.42615) (xy 379.599948 -285.451596)
			(xy 379.591784 -285.50183) (xy 379.575668 -285.550104) (xy 379.552017 -285.595167) (xy 379.521444 -285.635853)
			(xy 379.48474 -285.671108) (xy 379.442856 -285.700018) (xy 379.396877 -285.721835) (xy 379.347993 -285.735995)
			(xy 379.297472 -285.742129) (xy 379.24662 -285.74008) (xy 379.196756 -285.7299) (xy 379.14917 -285.711853)
			(xy 379.105096 -285.686407) (xy 379.065674 -285.65422) (xy 379.031926 -285.616126) (xy 379.004725 -285.573112)
			(xy 378.984777 -285.526292) (xy 378.972598 -285.476878) (xy 378.968503 -285.42615) (xy 377.720606 -285.42615)
			(xy 377.720094 -285.451596) (xy 377.71193 -285.50183) (xy 377.695814 -285.550104) (xy 377.672163 -285.595167)
			(xy 377.64159 -285.635853) (xy 377.604886 -285.671108) (xy 377.563002 -285.700018) (xy 377.517023 -285.721835)
			(xy 377.468139 -285.735995) (xy 377.417618 -285.742129) (xy 377.366766 -285.74008) (xy 377.316902 -285.7299)
			(xy 377.269316 -285.711853) (xy 377.225242 -285.686407) (xy 377.18582 -285.65422) (xy 377.152072 -285.616126)
			(xy 377.124871 -285.573112) (xy 377.104923 -285.526292) (xy 377.092744 -285.476878) (xy 377.088649 -285.42615)
			(xy 376.780552 -285.42615) (xy 376.78004 -285.451596) (xy 376.771876 -285.50183) (xy 376.75576 -285.550104)
			(xy 376.732109 -285.595167) (xy 376.701536 -285.635853) (xy 376.664832 -285.671108) (xy 376.622948 -285.700018)
			(xy 376.576969 -285.721835) (xy 376.528085 -285.735995) (xy 376.477564 -285.742129) (xy 376.426712 -285.74008)
			(xy 376.376848 -285.7299) (xy 376.329262 -285.711853) (xy 376.285188 -285.686407) (xy 376.245766 -285.65422)
			(xy 376.212018 -285.616126) (xy 376.184817 -285.573112) (xy 376.164869 -285.526292) (xy 376.15269 -285.476878)
			(xy 376.148595 -285.42615) (xy 375.1961 -285.42615) (xy 375.1961 -285.936182) (xy 375.196376 -285.944711)
			(xy 375.201909 -285.960842) (xy 375.212459 -285.974239) (xy 375.219468 -285.979108) (xy 375.24067 -285.993272)
			(xy 375.278465 -286.027494) (xy 375.310046 -286.067521) (xy 375.334535 -286.11224) (xy 375.351251 -286.160408)
			(xy 375.359729 -286.210683) (xy 375.359731 -286.236156) (xy 375.678695 -286.236156) (xy 375.68279 -286.185428)
			(xy 375.694969 -286.136014) (xy 375.714917 -286.089194) (xy 375.742118 -286.04618) (xy 375.775866 -286.008086)
			(xy 375.815288 -285.975899) (xy 375.859362 -285.950453) (xy 375.906948 -285.932406) (xy 375.956812 -285.922226)
			(xy 376.007664 -285.920177) (xy 376.058185 -285.926311) (xy 376.107069 -285.940471) (xy 376.153048 -285.962288)
			(xy 376.194932 -285.991198) (xy 376.231636 -286.026453) (xy 376.262209 -286.067139) (xy 376.28586 -286.112202)
			(xy 376.301976 -286.160476) (xy 376.31014 -286.21071) (xy 376.310652 -286.236156) (xy 376.628926 -286.236156)
			(xy 376.632886 -286.187102) (xy 376.644663 -286.139318) (xy 376.663954 -286.094042) (xy 376.690257 -286.052446)
			(xy 376.722892 -286.015609) (xy 376.761013 -285.984484) (xy 376.803634 -285.959877) (xy 376.84965 -285.942425)
			(xy 376.897869 -285.932581) (xy 376.947044 -285.9306) (xy 376.995899 -285.936532) (xy 377.04317 -285.950224)
			(xy 377.087632 -285.971322) (xy 377.128135 -285.999278) (xy 377.163628 -286.03337) (xy 377.193193 -286.072714)
			(xy 377.216064 -286.116291) (xy 377.231648 -286.162972) (xy 377.239543 -286.211549) (xy 377.240038 -286.236156)
			(xy 377.558549 -286.236156) (xy 377.562644 -286.185428) (xy 377.574823 -286.136014) (xy 377.594771 -286.089194)
			(xy 377.621972 -286.04618) (xy 377.65572 -286.008086) (xy 377.695142 -285.975899) (xy 377.739216 -285.950453)
			(xy 377.786802 -285.932406) (xy 377.836666 -285.922226) (xy 377.887518 -285.920177) (xy 377.938039 -285.926311)
			(xy 377.986923 -285.940471) (xy 378.032902 -285.962288) (xy 378.074786 -285.991198) (xy 378.11149 -286.026453)
			(xy 378.142063 -286.067139) (xy 378.165714 -286.112202) (xy 378.18183 -286.160476) (xy 378.189994 -286.21071)
			(xy 378.190506 -286.236156) (xy 378.509034 -286.236156) (xy 378.512994 -286.187102) (xy 378.524771 -286.139318)
			(xy 378.544062 -286.094042) (xy 378.570365 -286.052446) (xy 378.603 -286.015609) (xy 378.641121 -285.984484)
			(xy 378.683742 -285.959877) (xy 378.729758 -285.942425) (xy 378.777977 -285.932581) (xy 378.827152 -285.9306)
			(xy 378.876007 -285.936532) (xy 378.923278 -285.950224) (xy 378.96774 -285.971322) (xy 379.008243 -285.999278)
			(xy 379.043736 -286.03337) (xy 379.073301 -286.072714) (xy 379.096172 -286.116291) (xy 379.111756 -286.162972)
			(xy 379.119651 -286.211549) (xy 379.120146 -286.236156) (xy 379.438657 -286.236156) (xy 379.442752 -286.185428)
			(xy 379.454931 -286.136014) (xy 379.474879 -286.089194) (xy 379.50208 -286.04618) (xy 379.535828 -286.008086)
			(xy 379.57525 -285.975899) (xy 379.619324 -285.950453) (xy 379.66691 -285.932406) (xy 379.716774 -285.922226)
			(xy 379.767626 -285.920177) (xy 379.818147 -285.926311) (xy 379.867031 -285.940471) (xy 379.91301 -285.962288)
			(xy 379.954894 -285.991198) (xy 379.991598 -286.026453) (xy 380.022171 -286.067139) (xy 380.045822 -286.112202)
			(xy 380.061938 -286.160476) (xy 380.070102 -286.21071) (xy 380.070614 -286.236156) (xy 380.378711 -286.236156)
			(xy 380.382806 -286.185428) (xy 380.394985 -286.136014) (xy 380.414933 -286.089194) (xy 380.442134 -286.04618)
			(xy 380.475882 -286.008086) (xy 380.515304 -285.975899) (xy 380.559378 -285.950453) (xy 380.606964 -285.932406)
			(xy 380.656828 -285.922226) (xy 380.70768 -285.920177) (xy 380.758201 -285.926311) (xy 380.807085 -285.940471)
			(xy 380.853064 -285.962288) (xy 380.894948 -285.991198) (xy 380.931652 -286.026453) (xy 380.962225 -286.067139)
			(xy 380.985876 -286.112202) (xy 381.001992 -286.160476) (xy 381.010156 -286.21071) (xy 381.010668 -286.236156)
			(xy 381.328942 -286.236156) (xy 381.332902 -286.187102) (xy 381.344679 -286.139318) (xy 381.36397 -286.094042)
			(xy 381.390273 -286.052446) (xy 381.422908 -286.015609) (xy 381.461029 -285.984484) (xy 381.50365 -285.959877)
			(xy 381.549666 -285.942425) (xy 381.597885 -285.932581) (xy 381.64706 -285.9306) (xy 381.695915 -285.936532)
			(xy 381.743186 -285.950224) (xy 381.787648 -285.971322) (xy 381.828151 -285.999278) (xy 381.863644 -286.03337)
			(xy 381.893209 -286.072714) (xy 381.91608 -286.116291) (xy 381.931664 -286.162972) (xy 381.939559 -286.211549)
			(xy 381.940054 -286.236156) (xy 382.258565 -286.236156) (xy 382.26266 -286.185428) (xy 382.274839 -286.136014)
			(xy 382.294787 -286.089194) (xy 382.321988 -286.04618) (xy 382.355736 -286.008086) (xy 382.395158 -285.975899)
			(xy 382.439232 -285.950453) (xy 382.486818 -285.932406) (xy 382.536682 -285.922226) (xy 382.587534 -285.920177)
			(xy 382.638055 -285.926311) (xy 382.686939 -285.940471) (xy 382.732918 -285.962288) (xy 382.774802 -285.991198)
			(xy 382.811506 -286.026453) (xy 382.842079 -286.067139) (xy 382.86573 -286.112202) (xy 382.881846 -286.160476)
			(xy 382.89001 -286.21071) (xy 382.890522 -286.236156) (xy 383.20905 -286.236156) (xy 383.21301 -286.187102)
			(xy 383.224787 -286.139318) (xy 383.244078 -286.094042) (xy 383.270381 -286.052446) (xy 383.303016 -286.015609)
			(xy 383.341137 -285.984484) (xy 383.383758 -285.959877) (xy 383.429774 -285.942425) (xy 383.477993 -285.932581)
			(xy 383.527168 -285.9306) (xy 383.576023 -285.936532) (xy 383.623294 -285.950224) (xy 383.667756 -285.971322)
			(xy 383.708259 -285.999278) (xy 383.743752 -286.03337) (xy 383.773317 -286.072714) (xy 383.796188 -286.116291)
			(xy 383.811772 -286.162972) (xy 383.819667 -286.211549) (xy 383.820162 -286.236156) (xy 384.138673 -286.236156)
			(xy 384.142768 -286.185428) (xy 384.154947 -286.136014) (xy 384.174895 -286.089194) (xy 384.202096 -286.04618)
			(xy 384.235844 -286.008086) (xy 384.275266 -285.975899) (xy 384.31934 -285.950453) (xy 384.366926 -285.932406)
			(xy 384.41679 -285.922226) (xy 384.467642 -285.920177) (xy 384.518163 -285.926311) (xy 384.567047 -285.940471)
			(xy 384.613026 -285.962288) (xy 384.65491 -285.991198) (xy 384.691614 -286.026453) (xy 384.722187 -286.067139)
			(xy 384.745838 -286.112202) (xy 384.761954 -286.160476) (xy 384.770118 -286.21071) (xy 384.77063 -286.236156)
			(xy 385.088904 -286.236156) (xy 385.092864 -286.187102) (xy 385.104641 -286.139318) (xy 385.123932 -286.094042)
			(xy 385.150235 -286.052446) (xy 385.18287 -286.015609) (xy 385.220991 -285.984484) (xy 385.263612 -285.959877)
			(xy 385.309628 -285.942425) (xy 385.357847 -285.932581) (xy 385.407022 -285.9306) (xy 385.455877 -285.936532)
			(xy 385.503148 -285.950224) (xy 385.54761 -285.971322) (xy 385.588113 -285.999278) (xy 385.623606 -286.03337)
			(xy 385.653171 -286.072714) (xy 385.676042 -286.116291) (xy 385.691626 -286.162972) (xy 385.699521 -286.211549)
			(xy 385.700016 -286.236156) (xy 386.018527 -286.236156) (xy 386.022622 -286.185428) (xy 386.034801 -286.136014)
			(xy 386.054749 -286.089194) (xy 386.08195 -286.04618) (xy 386.115698 -286.008086) (xy 386.15512 -285.975899)
			(xy 386.199194 -285.950453) (xy 386.24678 -285.932406) (xy 386.296644 -285.922226) (xy 386.347496 -285.920177)
			(xy 386.398017 -285.926311) (xy 386.446901 -285.940471) (xy 386.49288 -285.962288) (xy 386.534764 -285.991198)
			(xy 386.571468 -286.026453) (xy 386.602041 -286.067139) (xy 386.625692 -286.112202) (xy 386.641808 -286.160476)
			(xy 386.649972 -286.21071) (xy 386.650484 -286.236156) (xy 386.958581 -286.236156) (xy 386.962676 -286.185428)
			(xy 386.974855 -286.136014) (xy 386.994803 -286.089194) (xy 387.022004 -286.04618) (xy 387.055752 -286.008086)
			(xy 387.095174 -285.975899) (xy 387.139248 -285.950453) (xy 387.186834 -285.932406) (xy 387.236698 -285.922226)
			(xy 387.28755 -285.920177) (xy 387.338071 -285.926311) (xy 387.386955 -285.940471) (xy 387.432934 -285.962288)
			(xy 387.474818 -285.991198) (xy 387.511522 -286.026453) (xy 387.542095 -286.067139) (xy 387.565746 -286.112202)
			(xy 387.581862 -286.160476) (xy 387.590026 -286.21071) (xy 387.590538 -286.236156) (xy 387.909066 -286.236156)
			(xy 387.913026 -286.187102) (xy 387.924803 -286.139318) (xy 387.944094 -286.094042) (xy 387.970397 -286.052446)
			(xy 388.003032 -286.015609) (xy 388.041153 -285.984484) (xy 388.083774 -285.959877) (xy 388.12979 -285.942425)
			(xy 388.178009 -285.932581) (xy 388.227184 -285.9306) (xy 388.276039 -285.936532) (xy 388.32331 -285.950224)
			(xy 388.367772 -285.971322) (xy 388.408275 -285.999278) (xy 388.443768 -286.03337) (xy 388.473333 -286.072714)
			(xy 388.496204 -286.116291) (xy 388.511788 -286.162972) (xy 388.519683 -286.211549) (xy 388.520178 -286.236156)
			(xy 388.838689 -286.236156) (xy 388.842784 -286.185428) (xy 388.854963 -286.136014) (xy 388.874911 -286.089194)
			(xy 388.902112 -286.04618) (xy 388.93586 -286.008086) (xy 388.975282 -285.975899) (xy 389.019356 -285.950453)
			(xy 389.066942 -285.932406) (xy 389.116806 -285.922226) (xy 389.167658 -285.920177) (xy 389.218179 -285.926311)
			(xy 389.267063 -285.940471) (xy 389.313042 -285.962288) (xy 389.354926 -285.991198) (xy 389.39163 -286.026453)
			(xy 389.422203 -286.067139) (xy 389.445854 -286.112202) (xy 389.46197 -286.160476) (xy 389.470134 -286.21071)
			(xy 389.470646 -286.236156) (xy 389.78892 -286.236156) (xy 389.79288 -286.187102) (xy 389.804657 -286.139318)
			(xy 389.823948 -286.094042) (xy 389.850251 -286.052446) (xy 389.882886 -286.015609) (xy 389.921007 -285.984484)
			(xy 389.963628 -285.959877) (xy 390.009644 -285.942425) (xy 390.057863 -285.932581) (xy 390.107038 -285.9306)
			(xy 390.155893 -285.936532) (xy 390.203164 -285.950224) (xy 390.247626 -285.971322) (xy 390.288129 -285.999278)
			(xy 390.323622 -286.03337) (xy 390.353187 -286.072714) (xy 390.376058 -286.116291) (xy 390.391642 -286.162972)
			(xy 390.399537 -286.211549) (xy 390.400032 -286.236156) (xy 390.718543 -286.236156) (xy 390.722638 -286.185428)
			(xy 390.734817 -286.136014) (xy 390.754765 -286.089194) (xy 390.781966 -286.04618) (xy 390.815714 -286.008086)
			(xy 390.855136 -285.975899) (xy 390.89921 -285.950453) (xy 390.946796 -285.932406) (xy 390.99666 -285.922226)
			(xy 391.047512 -285.920177) (xy 391.098033 -285.926311) (xy 391.146917 -285.940471) (xy 391.192896 -285.962288)
			(xy 391.23478 -285.991198) (xy 391.271484 -286.026453) (xy 391.302057 -286.067139) (xy 391.325708 -286.112202)
			(xy 391.341824 -286.160476) (xy 391.349988 -286.21071) (xy 391.3505 -286.236156) (xy 391.669028 -286.236156)
			(xy 391.672988 -286.187102) (xy 391.684765 -286.139318) (xy 391.704056 -286.094042) (xy 391.730359 -286.052446)
			(xy 391.762994 -286.015609) (xy 391.801115 -285.984484) (xy 391.843736 -285.959877) (xy 391.889752 -285.942425)
			(xy 391.937971 -285.932581) (xy 391.987146 -285.9306) (xy 392.036001 -285.936532) (xy 392.083272 -285.950224)
			(xy 392.125407 -285.970218) (xy 394.67715 -285.970218) (xy 394.68111 -285.921164) (xy 394.692887 -285.87338)
			(xy 394.712178 -285.828104) (xy 394.738481 -285.786508) (xy 394.771116 -285.749671) (xy 394.809237 -285.718546)
			(xy 394.851858 -285.693939) (xy 394.897874 -285.676487) (xy 394.946093 -285.666643) (xy 394.995268 -285.664662)
			(xy 395.044123 -285.670594) (xy 395.091394 -285.684286) (xy 395.135856 -285.705384) (xy 395.176359 -285.73334)
			(xy 395.211852 -285.767432) (xy 395.241417 -285.806776) (xy 395.264288 -285.850353) (xy 395.279872 -285.897034)
			(xy 395.287767 -285.945611) (xy 395.288262 -285.970218) (xy 395.287767 -285.994825) (xy 395.279872 -286.043402)
			(xy 395.264288 -286.090083) (xy 395.241417 -286.13366) (xy 395.211852 -286.173004) (xy 395.176359 -286.207096)
			(xy 395.135856 -286.235052) (xy 395.091394 -286.25615) (xy 395.044123 -286.269842) (xy 394.995268 -286.275774)
			(xy 394.946093 -286.273793) (xy 394.897874 -286.263949) (xy 394.851858 -286.246497) (xy 394.809237 -286.22189)
			(xy 394.771116 -286.190765) (xy 394.738481 -286.153928) (xy 394.712178 -286.112332) (xy 394.692887 -286.067056)
			(xy 394.68111 -286.019272) (xy 394.67715 -285.970218) (xy 392.125407 -285.970218) (xy 392.127734 -285.971322)
			(xy 392.168237 -285.999278) (xy 392.20373 -286.03337) (xy 392.233295 -286.072714) (xy 392.256166 -286.116291)
			(xy 392.27175 -286.162972) (xy 392.279645 -286.211549) (xy 392.28014 -286.236156) (xy 392.279645 -286.260763)
			(xy 392.27175 -286.30934) (xy 392.256166 -286.356021) (xy 392.233295 -286.399598) (xy 392.20373 -286.438942)
			(xy 392.168237 -286.473034) (xy 392.127734 -286.50099) (xy 392.083272 -286.522088) (xy 392.036001 -286.53578)
			(xy 391.987146 -286.541712) (xy 391.937971 -286.539731) (xy 391.889752 -286.529887) (xy 391.843736 -286.512435)
			(xy 391.801115 -286.487828) (xy 391.762994 -286.456703) (xy 391.730359 -286.419866) (xy 391.704056 -286.37827)
			(xy 391.684765 -286.332994) (xy 391.672988 -286.28521) (xy 391.669028 -286.236156) (xy 391.3505 -286.236156)
			(xy 391.349988 -286.261602) (xy 391.341824 -286.311836) (xy 391.325708 -286.36011) (xy 391.302057 -286.405173)
			(xy 391.271484 -286.445859) (xy 391.23478 -286.481114) (xy 391.192896 -286.510024) (xy 391.146917 -286.531841)
			(xy 391.098033 -286.546001) (xy 391.047512 -286.552135) (xy 390.99666 -286.550086) (xy 390.946796 -286.539906)
			(xy 390.89921 -286.521859) (xy 390.855136 -286.496413) (xy 390.815714 -286.464226) (xy 390.781966 -286.426132)
			(xy 390.754765 -286.383118) (xy 390.734817 -286.336298) (xy 390.722638 -286.286884) (xy 390.718543 -286.236156)
			(xy 390.400032 -286.236156) (xy 390.399537 -286.260763) (xy 390.391642 -286.30934) (xy 390.376058 -286.356021)
			(xy 390.353187 -286.399598) (xy 390.323622 -286.438942) (xy 390.288129 -286.473034) (xy 390.247626 -286.50099)
			(xy 390.203164 -286.522088) (xy 390.155893 -286.53578) (xy 390.107038 -286.541712) (xy 390.057863 -286.539731)
			(xy 390.009644 -286.529887) (xy 389.963628 -286.512435) (xy 389.921007 -286.487828) (xy 389.882886 -286.456703)
			(xy 389.850251 -286.419866) (xy 389.823948 -286.37827) (xy 389.804657 -286.332994) (xy 389.79288 -286.28521)
			(xy 389.78892 -286.236156) (xy 389.470646 -286.236156) (xy 389.470134 -286.261602) (xy 389.46197 -286.311836)
			(xy 389.445854 -286.36011) (xy 389.422203 -286.405173) (xy 389.39163 -286.445859) (xy 389.354926 -286.481114)
			(xy 389.313042 -286.510024) (xy 389.267063 -286.531841) (xy 389.218179 -286.546001) (xy 389.167658 -286.552135)
			(xy 389.116806 -286.550086) (xy 389.066942 -286.539906) (xy 389.019356 -286.521859) (xy 388.975282 -286.496413)
			(xy 388.93586 -286.464226) (xy 388.902112 -286.426132) (xy 388.874911 -286.383118) (xy 388.854963 -286.336298)
			(xy 388.842784 -286.286884) (xy 388.838689 -286.236156) (xy 388.520178 -286.236156) (xy 388.519683 -286.260763)
			(xy 388.511788 -286.30934) (xy 388.496204 -286.356021) (xy 388.473333 -286.399598) (xy 388.443768 -286.438942)
			(xy 388.408275 -286.473034) (xy 388.367772 -286.50099) (xy 388.32331 -286.522088) (xy 388.276039 -286.53578)
			(xy 388.227184 -286.541712) (xy 388.178009 -286.539731) (xy 388.12979 -286.529887) (xy 388.083774 -286.512435)
			(xy 388.041153 -286.487828) (xy 388.003032 -286.456703) (xy 387.970397 -286.419866) (xy 387.944094 -286.37827)
			(xy 387.924803 -286.332994) (xy 387.913026 -286.28521) (xy 387.909066 -286.236156) (xy 387.590538 -286.236156)
			(xy 387.590026 -286.261602) (xy 387.581862 -286.311836) (xy 387.565746 -286.36011) (xy 387.542095 -286.405173)
			(xy 387.511522 -286.445859) (xy 387.474818 -286.481114) (xy 387.432934 -286.510024) (xy 387.386955 -286.531841)
			(xy 387.338071 -286.546001) (xy 387.28755 -286.552135) (xy 387.236698 -286.550086) (xy 387.186834 -286.539906)
			(xy 387.139248 -286.521859) (xy 387.095174 -286.496413) (xy 387.055752 -286.464226) (xy 387.022004 -286.426132)
			(xy 386.994803 -286.383118) (xy 386.974855 -286.336298) (xy 386.962676 -286.286884) (xy 386.958581 -286.236156)
			(xy 386.650484 -286.236156) (xy 386.649972 -286.261602) (xy 386.641808 -286.311836) (xy 386.625692 -286.36011)
			(xy 386.602041 -286.405173) (xy 386.571468 -286.445859) (xy 386.534764 -286.481114) (xy 386.49288 -286.510024)
			(xy 386.446901 -286.531841) (xy 386.398017 -286.546001) (xy 386.347496 -286.552135) (xy 386.296644 -286.550086)
			(xy 386.24678 -286.539906) (xy 386.199194 -286.521859) (xy 386.15512 -286.496413) (xy 386.115698 -286.464226)
			(xy 386.08195 -286.426132) (xy 386.054749 -286.383118) (xy 386.034801 -286.336298) (xy 386.022622 -286.286884)
			(xy 386.018527 -286.236156) (xy 385.700016 -286.236156) (xy 385.699521 -286.260763) (xy 385.691626 -286.30934)
			(xy 385.676042 -286.356021) (xy 385.653171 -286.399598) (xy 385.623606 -286.438942) (xy 385.588113 -286.473034)
			(xy 385.54761 -286.50099) (xy 385.503148 -286.522088) (xy 385.455877 -286.53578) (xy 385.407022 -286.541712)
			(xy 385.357847 -286.539731) (xy 385.309628 -286.529887) (xy 385.263612 -286.512435) (xy 385.220991 -286.487828)
			(xy 385.18287 -286.456703) (xy 385.150235 -286.419866) (xy 385.123932 -286.37827) (xy 385.104641 -286.332994)
			(xy 385.092864 -286.28521) (xy 385.088904 -286.236156) (xy 384.77063 -286.236156) (xy 384.770118 -286.261602)
			(xy 384.761954 -286.311836) (xy 384.745838 -286.36011) (xy 384.722187 -286.405173) (xy 384.691614 -286.445859)
			(xy 384.65491 -286.481114) (xy 384.613026 -286.510024) (xy 384.567047 -286.531841) (xy 384.518163 -286.546001)
			(xy 384.467642 -286.552135) (xy 384.41679 -286.550086) (xy 384.366926 -286.539906) (xy 384.31934 -286.521859)
			(xy 384.275266 -286.496413) (xy 384.235844 -286.464226) (xy 384.202096 -286.426132) (xy 384.174895 -286.383118)
			(xy 384.154947 -286.336298) (xy 384.142768 -286.286884) (xy 384.138673 -286.236156) (xy 383.820162 -286.236156)
			(xy 383.819667 -286.260763) (xy 383.811772 -286.30934) (xy 383.796188 -286.356021) (xy 383.773317 -286.399598)
			(xy 383.743752 -286.438942) (xy 383.708259 -286.473034) (xy 383.667756 -286.50099) (xy 383.623294 -286.522088)
			(xy 383.576023 -286.53578) (xy 383.527168 -286.541712) (xy 383.477993 -286.539731) (xy 383.429774 -286.529887)
			(xy 383.383758 -286.512435) (xy 383.341137 -286.487828) (xy 383.303016 -286.456703) (xy 383.270381 -286.419866)
			(xy 383.244078 -286.37827) (xy 383.224787 -286.332994) (xy 383.21301 -286.28521) (xy 383.20905 -286.236156)
			(xy 382.890522 -286.236156) (xy 382.89001 -286.261602) (xy 382.881846 -286.311836) (xy 382.86573 -286.36011)
			(xy 382.842079 -286.405173) (xy 382.811506 -286.445859) (xy 382.774802 -286.481114) (xy 382.732918 -286.510024)
			(xy 382.686939 -286.531841) (xy 382.638055 -286.546001) (xy 382.587534 -286.552135) (xy 382.536682 -286.550086)
			(xy 382.486818 -286.539906) (xy 382.439232 -286.521859) (xy 382.395158 -286.496413) (xy 382.355736 -286.464226)
			(xy 382.321988 -286.426132) (xy 382.294787 -286.383118) (xy 382.274839 -286.336298) (xy 382.26266 -286.286884)
			(xy 382.258565 -286.236156) (xy 381.940054 -286.236156) (xy 381.939559 -286.260763) (xy 381.931664 -286.30934)
			(xy 381.91608 -286.356021) (xy 381.893209 -286.399598) (xy 381.863644 -286.438942) (xy 381.828151 -286.473034)
			(xy 381.787648 -286.50099) (xy 381.743186 -286.522088) (xy 381.695915 -286.53578) (xy 381.64706 -286.541712)
			(xy 381.597885 -286.539731) (xy 381.549666 -286.529887) (xy 381.50365 -286.512435) (xy 381.461029 -286.487828)
			(xy 381.422908 -286.456703) (xy 381.390273 -286.419866) (xy 381.36397 -286.37827) (xy 381.344679 -286.332994)
			(xy 381.332902 -286.28521) (xy 381.328942 -286.236156) (xy 381.010668 -286.236156) (xy 381.010156 -286.261602)
			(xy 381.001992 -286.311836) (xy 380.985876 -286.36011) (xy 380.962225 -286.405173) (xy 380.931652 -286.445859)
			(xy 380.894948 -286.481114) (xy 380.853064 -286.510024) (xy 380.807085 -286.531841) (xy 380.758201 -286.546001)
			(xy 380.70768 -286.552135) (xy 380.656828 -286.550086) (xy 380.606964 -286.539906) (xy 380.559378 -286.521859)
			(xy 380.515304 -286.496413) (xy 380.475882 -286.464226) (xy 380.442134 -286.426132) (xy 380.414933 -286.383118)
			(xy 380.394985 -286.336298) (xy 380.382806 -286.286884) (xy 380.378711 -286.236156) (xy 380.070614 -286.236156)
			(xy 380.070102 -286.261602) (xy 380.061938 -286.311836) (xy 380.045822 -286.36011) (xy 380.022171 -286.405173)
			(xy 379.991598 -286.445859) (xy 379.954894 -286.481114) (xy 379.91301 -286.510024) (xy 379.867031 -286.531841)
			(xy 379.818147 -286.546001) (xy 379.767626 -286.552135) (xy 379.716774 -286.550086) (xy 379.66691 -286.539906)
			(xy 379.619324 -286.521859) (xy 379.57525 -286.496413) (xy 379.535828 -286.464226) (xy 379.50208 -286.426132)
			(xy 379.474879 -286.383118) (xy 379.454931 -286.336298) (xy 379.442752 -286.286884) (xy 379.438657 -286.236156)
			(xy 379.120146 -286.236156) (xy 379.119651 -286.260763) (xy 379.111756 -286.30934) (xy 379.096172 -286.356021)
			(xy 379.073301 -286.399598) (xy 379.043736 -286.438942) (xy 379.008243 -286.473034) (xy 378.96774 -286.50099)
			(xy 378.923278 -286.522088) (xy 378.876007 -286.53578) (xy 378.827152 -286.541712) (xy 378.777977 -286.539731)
			(xy 378.729758 -286.529887) (xy 378.683742 -286.512435) (xy 378.641121 -286.487828) (xy 378.603 -286.456703)
			(xy 378.570365 -286.419866) (xy 378.544062 -286.37827) (xy 378.524771 -286.332994) (xy 378.512994 -286.28521)
			(xy 378.509034 -286.236156) (xy 378.190506 -286.236156) (xy 378.189994 -286.261602) (xy 378.18183 -286.311836)
			(xy 378.165714 -286.36011) (xy 378.142063 -286.405173) (xy 378.11149 -286.445859) (xy 378.074786 -286.481114)
			(xy 378.032902 -286.510024) (xy 377.986923 -286.531841) (xy 377.938039 -286.546001) (xy 377.887518 -286.552135)
			(xy 377.836666 -286.550086) (xy 377.786802 -286.539906) (xy 377.739216 -286.521859) (xy 377.695142 -286.496413)
			(xy 377.65572 -286.464226) (xy 377.621972 -286.426132) (xy 377.594771 -286.383118) (xy 377.574823 -286.336298)
			(xy 377.562644 -286.286884) (xy 377.558549 -286.236156) (xy 377.240038 -286.236156) (xy 377.239543 -286.260763)
			(xy 377.231648 -286.30934) (xy 377.216064 -286.356021) (xy 377.193193 -286.399598) (xy 377.163628 -286.438942)
			(xy 377.128135 -286.473034) (xy 377.087632 -286.50099) (xy 377.04317 -286.522088) (xy 376.995899 -286.53578)
			(xy 376.947044 -286.541712) (xy 376.897869 -286.539731) (xy 376.84965 -286.529887) (xy 376.803634 -286.512435)
			(xy 376.761013 -286.487828) (xy 376.722892 -286.456703) (xy 376.690257 -286.419866) (xy 376.663954 -286.37827)
			(xy 376.644663 -286.332994) (xy 376.632886 -286.28521) (xy 376.628926 -286.236156) (xy 376.310652 -286.236156)
			(xy 376.31014 -286.261602) (xy 376.301976 -286.311836) (xy 376.28586 -286.36011) (xy 376.262209 -286.405173)
			(xy 376.231636 -286.445859) (xy 376.194932 -286.481114) (xy 376.153048 -286.510024) (xy 376.107069 -286.531841)
			(xy 376.058185 -286.546001) (xy 376.007664 -286.552135) (xy 375.956812 -286.550086) (xy 375.906948 -286.539906)
			(xy 375.859362 -286.521859) (xy 375.815288 -286.496413) (xy 375.775866 -286.464226) (xy 375.742118 -286.426132)
			(xy 375.714917 -286.383118) (xy 375.694969 -286.336298) (xy 375.68279 -286.286884) (xy 375.678695 -286.236156)
			(xy 375.359731 -286.236156) (xy 375.359733 -286.261669) (xy 375.351263 -286.311946) (xy 375.334554 -286.360116)
			(xy 375.310072 -286.40484) (xy 375.278497 -286.444872) (xy 375.240708 -286.479099) (xy 375.219468 -286.493204)
			(xy 375.212475 -286.498087) (xy 375.20195 -286.511495) (xy 375.196387 -286.527607) (xy 375.1961 -286.53613)
			(xy 375.1961 -286.708088) (xy 375.196499 -286.717289) (xy 375.202981 -286.734512) (xy 375.215092 -286.748369)
			(xy 375.223024 -286.753046) (xy 375.314718 -286.802068) (xy 375.342404 -286.800544) (xy 375.354342 -286.79267)
			(xy 375.373328 -286.780372) (xy 375.414162 -286.760908) (xy 375.457421 -286.747684) (xy 375.502159 -286.74099)
			(xy 375.524776 -286.7406) (xy 375.550034 -286.741091) (xy 375.599863 -286.749402) (xy 375.647643 -286.765802)
			(xy 375.692072 -286.789843) (xy 375.731939 -286.820869) (xy 375.766154 -286.858034) (xy 375.793785 -286.900324)
			(xy 375.814078 -286.946585) (xy 375.82648 -286.995556) (xy 375.830652 -287.0459) (xy 375.830651 -287.045908)
			(xy 376.148595 -287.045908) (xy 376.15269 -286.99518) (xy 376.164869 -286.945766) (xy 376.184817 -286.898946)
			(xy 376.212018 -286.855932) (xy 376.245766 -286.817838) (xy 376.285188 -286.785651) (xy 376.329262 -286.760205)
			(xy 376.376848 -286.742158) (xy 376.426712 -286.731978) (xy 376.477564 -286.729929) (xy 376.528085 -286.736063)
			(xy 376.576969 -286.750223) (xy 376.622948 -286.77204) (xy 376.664832 -286.80095) (xy 376.701536 -286.836205)
			(xy 376.732109 -286.876891) (xy 376.75576 -286.921954) (xy 376.771876 -286.970228) (xy 376.78004 -287.020462)
			(xy 376.780552 -287.045908) (xy 377.088649 -287.045908) (xy 377.092744 -286.99518) (xy 377.104923 -286.945766)
			(xy 377.124871 -286.898946) (xy 377.152072 -286.855932) (xy 377.18582 -286.817838) (xy 377.225242 -286.785651)
			(xy 377.269316 -286.760205) (xy 377.316902 -286.742158) (xy 377.366766 -286.731978) (xy 377.417618 -286.729929)
			(xy 377.468139 -286.736063) (xy 377.517023 -286.750223) (xy 377.563002 -286.77204) (xy 377.604886 -286.80095)
			(xy 377.64159 -286.836205) (xy 377.672163 -286.876891) (xy 377.695814 -286.921954) (xy 377.71193 -286.970228)
			(xy 377.720094 -287.020462) (xy 377.720606 -287.045908) (xy 377.720601 -287.046162) (xy 378.039134 -287.046162)
			(xy 378.043094 -286.997108) (xy 378.054871 -286.949324) (xy 378.074162 -286.904048) (xy 378.100465 -286.862452)
			(xy 378.1331 -286.825615) (xy 378.171221 -286.79449) (xy 378.213842 -286.769883) (xy 378.259858 -286.752431)
			(xy 378.308077 -286.742587) (xy 378.357252 -286.740606) (xy 378.406107 -286.746538) (xy 378.453378 -286.76023)
			(xy 378.49784 -286.781328) (xy 378.538343 -286.809284) (xy 378.573836 -286.843376) (xy 378.603401 -286.88272)
			(xy 378.626272 -286.926297) (xy 378.641856 -286.972978) (xy 378.649751 -287.021555) (xy 378.650241 -287.045908)
			(xy 378.968503 -287.045908) (xy 378.972598 -286.99518) (xy 378.984777 -286.945766) (xy 379.004725 -286.898946)
			(xy 379.031926 -286.855932) (xy 379.065674 -286.817838) (xy 379.105096 -286.785651) (xy 379.14917 -286.760205)
			(xy 379.196756 -286.742158) (xy 379.24662 -286.731978) (xy 379.297472 -286.729929) (xy 379.347993 -286.736063)
			(xy 379.396877 -286.750223) (xy 379.442856 -286.77204) (xy 379.48474 -286.80095) (xy 379.521444 -286.836205)
			(xy 379.552017 -286.876891) (xy 379.575668 -286.921954) (xy 379.591784 -286.970228) (xy 379.599948 -287.020462)
			(xy 379.60046 -287.045908) (xy 379.918988 -287.045908) (xy 379.922948 -286.996854) (xy 379.934725 -286.94907)
			(xy 379.954016 -286.903794) (xy 379.980319 -286.862198) (xy 380.012954 -286.825361) (xy 380.051075 -286.794236)
			(xy 380.093696 -286.769629) (xy 380.139712 -286.752177) (xy 380.187931 -286.742333) (xy 380.237106 -286.740352)
			(xy 380.285961 -286.746284) (xy 380.333232 -286.759976) (xy 380.377694 -286.781074) (xy 380.418197 -286.80903)
			(xy 380.45369 -286.843122) (xy 380.483255 -286.882466) (xy 380.506126 -286.926043) (xy 380.52171 -286.972724)
			(xy 380.529605 -287.021301) (xy 380.5301 -287.045908) (xy 380.848611 -287.045908) (xy 380.852706 -286.99518)
			(xy 380.864885 -286.945766) (xy 380.884833 -286.898946) (xy 380.912034 -286.855932) (xy 380.945782 -286.817838)
			(xy 380.985204 -286.785651) (xy 381.029278 -286.760205) (xy 381.076864 -286.742158) (xy 381.126728 -286.731978)
			(xy 381.17758 -286.729929) (xy 381.228101 -286.736063) (xy 381.276985 -286.750223) (xy 381.322964 -286.77204)
			(xy 381.364848 -286.80095) (xy 381.401552 -286.836205) (xy 381.432125 -286.876891) (xy 381.455776 -286.921954)
			(xy 381.471892 -286.970228) (xy 381.480056 -287.020462) (xy 381.480568 -287.045908) (xy 381.480563 -287.046162)
			(xy 381.799096 -287.046162) (xy 381.803056 -286.997108) (xy 381.814833 -286.949324) (xy 381.834124 -286.904048)
			(xy 381.860427 -286.862452) (xy 381.893062 -286.825615) (xy 381.931183 -286.79449) (xy 381.973804 -286.769883)
			(xy 382.01982 -286.752431) (xy 382.068039 -286.742587) (xy 382.117214 -286.740606) (xy 382.166069 -286.746538)
			(xy 382.21334 -286.76023) (xy 382.257802 -286.781328) (xy 382.298305 -286.809284) (xy 382.333798 -286.843376)
			(xy 382.363363 -286.88272) (xy 382.386234 -286.926297) (xy 382.401818 -286.972978) (xy 382.409713 -287.021555)
			(xy 382.410203 -287.045908) (xy 382.728465 -287.045908) (xy 382.73256 -286.99518) (xy 382.744739 -286.945766)
			(xy 382.764687 -286.898946) (xy 382.791888 -286.855932) (xy 382.825636 -286.817838) (xy 382.865058 -286.785651)
			(xy 382.909132 -286.760205) (xy 382.956718 -286.742158) (xy 383.006582 -286.731978) (xy 383.057434 -286.729929)
			(xy 383.107955 -286.736063) (xy 383.156839 -286.750223) (xy 383.202818 -286.77204) (xy 383.244702 -286.80095)
			(xy 383.281406 -286.836205) (xy 383.311979 -286.876891) (xy 383.33563 -286.921954) (xy 383.351746 -286.970228)
			(xy 383.35991 -287.020462) (xy 383.360422 -287.045908) (xy 383.668519 -287.045908) (xy 383.672614 -286.99518)
			(xy 383.684793 -286.945766) (xy 383.704741 -286.898946) (xy 383.731942 -286.855932) (xy 383.76569 -286.817838)
			(xy 383.805112 -286.785651) (xy 383.849186 -286.760205) (xy 383.896772 -286.742158) (xy 383.946636 -286.731978)
			(xy 383.997488 -286.729929) (xy 384.048009 -286.736063) (xy 384.096893 -286.750223) (xy 384.142872 -286.77204)
			(xy 384.184756 -286.80095) (xy 384.22146 -286.836205) (xy 384.252033 -286.876891) (xy 384.275684 -286.921954)
			(xy 384.2918 -286.970228) (xy 384.299964 -287.020462) (xy 384.300476 -287.045908) (xy 384.619004 -287.045908)
			(xy 384.622964 -286.996854) (xy 384.634741 -286.94907) (xy 384.654032 -286.903794) (xy 384.680335 -286.862198)
			(xy 384.71297 -286.825361) (xy 384.751091 -286.794236) (xy 384.793712 -286.769629) (xy 384.839728 -286.752177)
			(xy 384.887947 -286.742333) (xy 384.937122 -286.740352) (xy 384.985977 -286.746284) (xy 385.033248 -286.759976)
			(xy 385.07771 -286.781074) (xy 385.118213 -286.80903) (xy 385.153706 -286.843122) (xy 385.183271 -286.882466)
			(xy 385.206142 -286.926043) (xy 385.221726 -286.972724) (xy 385.229621 -287.021301) (xy 385.230116 -287.045908)
			(xy 385.548627 -287.045908) (xy 385.552722 -286.99518) (xy 385.564901 -286.945766) (xy 385.584849 -286.898946)
			(xy 385.61205 -286.855932) (xy 385.645798 -286.817838) (xy 385.68522 -286.785651) (xy 385.729294 -286.760205)
			(xy 385.77688 -286.742158) (xy 385.826744 -286.731978) (xy 385.877596 -286.729929) (xy 385.928117 -286.736063)
			(xy 385.977001 -286.750223) (xy 386.02298 -286.77204) (xy 386.064864 -286.80095) (xy 386.101568 -286.836205)
			(xy 386.132141 -286.876891) (xy 386.155792 -286.921954) (xy 386.171908 -286.970228) (xy 386.180072 -287.020462)
			(xy 386.180584 -287.045908) (xy 386.180579 -287.046162) (xy 386.499112 -287.046162) (xy 386.503072 -286.997108)
			(xy 386.514849 -286.949324) (xy 386.53414 -286.904048) (xy 386.560443 -286.862452) (xy 386.593078 -286.825615)
			(xy 386.631199 -286.79449) (xy 386.67382 -286.769883) (xy 386.719836 -286.752431) (xy 386.768055 -286.742587)
			(xy 386.81723 -286.740606) (xy 386.866085 -286.746538) (xy 386.913356 -286.76023) (xy 386.957818 -286.781328)
			(xy 386.998321 -286.809284) (xy 387.033814 -286.843376) (xy 387.063379 -286.88272) (xy 387.08625 -286.926297)
			(xy 387.101834 -286.972978) (xy 387.109729 -287.021555) (xy 387.110219 -287.045908) (xy 387.428481 -287.045908)
			(xy 387.432576 -286.99518) (xy 387.444755 -286.945766) (xy 387.464703 -286.898946) (xy 387.491904 -286.855932)
			(xy 387.525652 -286.817838) (xy 387.565074 -286.785651) (xy 387.609148 -286.760205) (xy 387.656734 -286.742158)
			(xy 387.706598 -286.731978) (xy 387.75745 -286.729929) (xy 387.807971 -286.736063) (xy 387.856855 -286.750223)
			(xy 387.902834 -286.77204) (xy 387.944718 -286.80095) (xy 387.981422 -286.836205) (xy 388.011995 -286.876891)
			(xy 388.035646 -286.921954) (xy 388.051762 -286.970228) (xy 388.059926 -287.020462) (xy 388.060438 -287.045908)
			(xy 388.378966 -287.045908) (xy 388.382926 -286.996854) (xy 388.394703 -286.94907) (xy 388.413994 -286.903794)
			(xy 388.440297 -286.862198) (xy 388.472932 -286.825361) (xy 388.511053 -286.794236) (xy 388.553674 -286.769629)
			(xy 388.59969 -286.752177) (xy 388.647909 -286.742333) (xy 388.697084 -286.740352) (xy 388.745939 -286.746284)
			(xy 388.79321 -286.759976) (xy 388.837672 -286.781074) (xy 388.878175 -286.80903) (xy 388.913668 -286.843122)
			(xy 388.943233 -286.882466) (xy 388.966104 -286.926043) (xy 388.981688 -286.972724) (xy 388.989583 -287.021301)
			(xy 388.990078 -287.045908) (xy 389.308589 -287.045908) (xy 389.312684 -286.99518) (xy 389.324863 -286.945766)
			(xy 389.344811 -286.898946) (xy 389.372012 -286.855932) (xy 389.40576 -286.817838) (xy 389.445182 -286.785651)
			(xy 389.489256 -286.760205) (xy 389.536842 -286.742158) (xy 389.586706 -286.731978) (xy 389.637558 -286.729929)
			(xy 389.688079 -286.736063) (xy 389.736963 -286.750223) (xy 389.782942 -286.77204) (xy 389.824826 -286.80095)
			(xy 389.86153 -286.836205) (xy 389.892103 -286.876891) (xy 389.915754 -286.921954) (xy 389.93187 -286.970228)
			(xy 389.940034 -287.020462) (xy 389.940546 -287.045908) (xy 390.248643 -287.045908) (xy 390.252738 -286.99518)
			(xy 390.264917 -286.945766) (xy 390.284865 -286.898946) (xy 390.312066 -286.855932) (xy 390.345814 -286.817838)
			(xy 390.385236 -286.785651) (xy 390.42931 -286.760205) (xy 390.476896 -286.742158) (xy 390.52676 -286.731978)
			(xy 390.577612 -286.729929) (xy 390.628133 -286.736063) (xy 390.677017 -286.750223) (xy 390.722996 -286.77204)
			(xy 390.76488 -286.80095) (xy 390.801584 -286.836205) (xy 390.832157 -286.876891) (xy 390.855808 -286.921954)
			(xy 390.871924 -286.970228) (xy 390.880088 -287.020462) (xy 390.8806 -287.045908) (xy 391.198874 -287.045908)
			(xy 391.202834 -286.996854) (xy 391.214611 -286.94907) (xy 391.233902 -286.903794) (xy 391.260205 -286.862198)
			(xy 391.29284 -286.825361) (xy 391.330961 -286.794236) (xy 391.373582 -286.769629) (xy 391.419598 -286.752177)
			(xy 391.467817 -286.742333) (xy 391.516992 -286.740352) (xy 391.565847 -286.746284) (xy 391.613118 -286.759976)
			(xy 391.65758 -286.781074) (xy 391.698083 -286.80903) (xy 391.733576 -286.843122) (xy 391.763141 -286.882466)
			(xy 391.786012 -286.926043) (xy 391.801596 -286.972724) (xy 391.809491 -287.021301) (xy 391.809986 -287.045908)
			(xy 393.078982 -287.045908) (xy 393.082942 -286.996854) (xy 393.094719 -286.94907) (xy 393.11401 -286.903794)
			(xy 393.140313 -286.862198) (xy 393.172948 -286.825361) (xy 393.211069 -286.794236) (xy 393.25369 -286.769629)
			(xy 393.299706 -286.752177) (xy 393.347925 -286.742333) (xy 393.3971 -286.740352) (xy 393.445955 -286.746284)
			(xy 393.493226 -286.759976) (xy 393.537688 -286.781074) (xy 393.578191 -286.80903) (xy 393.613684 -286.843122)
			(xy 393.643249 -286.882466) (xy 393.66612 -286.926043) (xy 393.681704 -286.972724) (xy 393.689599 -287.021301)
			(xy 393.690094 -287.045908) (xy 393.689599 -287.070515) (xy 393.681704 -287.119092) (xy 393.66612 -287.165773)
			(xy 393.643249 -287.20935) (xy 393.613684 -287.248694) (xy 393.578191 -287.282786) (xy 393.537688 -287.310742)
			(xy 393.493226 -287.33184) (xy 393.445955 -287.345532) (xy 393.3971 -287.351464) (xy 393.347925 -287.349483)
			(xy 393.299706 -287.339639) (xy 393.25369 -287.322187) (xy 393.211069 -287.29758) (xy 393.172948 -287.266455)
			(xy 393.140313 -287.229618) (xy 393.11401 -287.188022) (xy 393.094719 -287.142746) (xy 393.082942 -287.094962)
			(xy 393.078982 -287.045908) (xy 391.809986 -287.045908) (xy 391.809491 -287.070515) (xy 391.801596 -287.119092)
			(xy 391.786012 -287.165773) (xy 391.763141 -287.20935) (xy 391.733576 -287.248694) (xy 391.698083 -287.282786)
			(xy 391.65758 -287.310742) (xy 391.613118 -287.33184) (xy 391.565847 -287.345532) (xy 391.516992 -287.351464)
			(xy 391.467817 -287.349483) (xy 391.419598 -287.339639) (xy 391.373582 -287.322187) (xy 391.330961 -287.29758)
			(xy 391.29284 -287.266455) (xy 391.260205 -287.229618) (xy 391.233902 -287.188022) (xy 391.214611 -287.142746)
			(xy 391.202834 -287.094962) (xy 391.198874 -287.045908) (xy 390.8806 -287.045908) (xy 390.880088 -287.071354)
			(xy 390.871924 -287.121588) (xy 390.855808 -287.169862) (xy 390.832157 -287.214925) (xy 390.801584 -287.255611)
			(xy 390.76488 -287.290866) (xy 390.722996 -287.319776) (xy 390.677017 -287.341593) (xy 390.628133 -287.355753)
			(xy 390.577612 -287.361887) (xy 390.52676 -287.359838) (xy 390.476896 -287.349658) (xy 390.42931 -287.331611)
			(xy 390.385236 -287.306165) (xy 390.345814 -287.273978) (xy 390.312066 -287.235884) (xy 390.284865 -287.19287)
			(xy 390.264917 -287.14605) (xy 390.252738 -287.096636) (xy 390.248643 -287.045908) (xy 389.940546 -287.045908)
			(xy 389.940034 -287.071354) (xy 389.93187 -287.121588) (xy 389.915754 -287.169862) (xy 389.892103 -287.214925)
			(xy 389.86153 -287.255611) (xy 389.824826 -287.290866) (xy 389.782942 -287.319776) (xy 389.736963 -287.341593)
			(xy 389.688079 -287.355753) (xy 389.637558 -287.361887) (xy 389.586706 -287.359838) (xy 389.536842 -287.349658)
			(xy 389.489256 -287.331611) (xy 389.445182 -287.306165) (xy 389.40576 -287.273978) (xy 389.372012 -287.235884)
			(xy 389.344811 -287.19287) (xy 389.324863 -287.14605) (xy 389.312684 -287.096636) (xy 389.308589 -287.045908)
			(xy 388.990078 -287.045908) (xy 388.989583 -287.070515) (xy 388.981688 -287.119092) (xy 388.966104 -287.165773)
			(xy 388.943233 -287.20935) (xy 388.913668 -287.248694) (xy 388.878175 -287.282786) (xy 388.837672 -287.310742)
			(xy 388.79321 -287.33184) (xy 388.745939 -287.345532) (xy 388.697084 -287.351464) (xy 388.647909 -287.349483)
			(xy 388.59969 -287.339639) (xy 388.553674 -287.322187) (xy 388.511053 -287.29758) (xy 388.472932 -287.266455)
			(xy 388.440297 -287.229618) (xy 388.413994 -287.188022) (xy 388.394703 -287.142746) (xy 388.382926 -287.094962)
			(xy 388.378966 -287.045908) (xy 388.060438 -287.045908) (xy 388.059926 -287.071354) (xy 388.051762 -287.121588)
			(xy 388.035646 -287.169862) (xy 388.011995 -287.214925) (xy 387.981422 -287.255611) (xy 387.944718 -287.290866)
			(xy 387.902834 -287.319776) (xy 387.856855 -287.341593) (xy 387.807971 -287.355753) (xy 387.75745 -287.361887)
			(xy 387.706598 -287.359838) (xy 387.656734 -287.349658) (xy 387.609148 -287.331611) (xy 387.565074 -287.306165)
			(xy 387.525652 -287.273978) (xy 387.491904 -287.235884) (xy 387.464703 -287.19287) (xy 387.444755 -287.14605)
			(xy 387.432576 -287.096636) (xy 387.428481 -287.045908) (xy 387.110219 -287.045908) (xy 387.110224 -287.046162)
			(xy 387.109729 -287.070769) (xy 387.101834 -287.119346) (xy 387.08625 -287.166027) (xy 387.063379 -287.209604)
			(xy 387.033814 -287.248948) (xy 386.998321 -287.28304) (xy 386.957818 -287.310996) (xy 386.913356 -287.332094)
			(xy 386.866085 -287.345786) (xy 386.81723 -287.351718) (xy 386.768055 -287.349737) (xy 386.719836 -287.339893)
			(xy 386.67382 -287.322441) (xy 386.631199 -287.297834) (xy 386.593078 -287.266709) (xy 386.560443 -287.229872)
			(xy 386.53414 -287.188276) (xy 386.514849 -287.143) (xy 386.503072 -287.095216) (xy 386.499112 -287.046162)
			(xy 386.180579 -287.046162) (xy 386.180072 -287.071354) (xy 386.171908 -287.121588) (xy 386.155792 -287.169862)
			(xy 386.132141 -287.214925) (xy 386.101568 -287.255611) (xy 386.064864 -287.290866) (xy 386.02298 -287.319776)
			(xy 385.977001 -287.341593) (xy 385.928117 -287.355753) (xy 385.877596 -287.361887) (xy 385.826744 -287.359838)
			(xy 385.77688 -287.349658) (xy 385.729294 -287.331611) (xy 385.68522 -287.306165) (xy 385.645798 -287.273978)
			(xy 385.61205 -287.235884) (xy 385.584849 -287.19287) (xy 385.564901 -287.14605) (xy 385.552722 -287.096636)
			(xy 385.548627 -287.045908) (xy 385.230116 -287.045908) (xy 385.229621 -287.070515) (xy 385.221726 -287.119092)
			(xy 385.206142 -287.165773) (xy 385.183271 -287.20935) (xy 385.153706 -287.248694) (xy 385.118213 -287.282786)
			(xy 385.07771 -287.310742) (xy 385.033248 -287.33184) (xy 384.985977 -287.345532) (xy 384.937122 -287.351464)
			(xy 384.887947 -287.349483) (xy 384.839728 -287.339639) (xy 384.793712 -287.322187) (xy 384.751091 -287.29758)
			(xy 384.71297 -287.266455) (xy 384.680335 -287.229618) (xy 384.654032 -287.188022) (xy 384.634741 -287.142746)
			(xy 384.622964 -287.094962) (xy 384.619004 -287.045908) (xy 384.300476 -287.045908) (xy 384.299964 -287.071354)
			(xy 384.2918 -287.121588) (xy 384.275684 -287.169862) (xy 384.252033 -287.214925) (xy 384.22146 -287.255611)
			(xy 384.184756 -287.290866) (xy 384.142872 -287.319776) (xy 384.096893 -287.341593) (xy 384.048009 -287.355753)
			(xy 383.997488 -287.361887) (xy 383.946636 -287.359838) (xy 383.896772 -287.349658) (xy 383.849186 -287.331611)
			(xy 383.805112 -287.306165) (xy 383.76569 -287.273978) (xy 383.731942 -287.235884) (xy 383.704741 -287.19287)
			(xy 383.684793 -287.14605) (xy 383.672614 -287.096636) (xy 383.668519 -287.045908) (xy 383.360422 -287.045908)
			(xy 383.35991 -287.071354) (xy 383.351746 -287.121588) (xy 383.33563 -287.169862) (xy 383.311979 -287.214925)
			(xy 383.281406 -287.255611) (xy 383.244702 -287.290866) (xy 383.202818 -287.319776) (xy 383.156839 -287.341593)
			(xy 383.107955 -287.355753) (xy 383.057434 -287.361887) (xy 383.006582 -287.359838) (xy 382.956718 -287.349658)
			(xy 382.909132 -287.331611) (xy 382.865058 -287.306165) (xy 382.825636 -287.273978) (xy 382.791888 -287.235884)
			(xy 382.764687 -287.19287) (xy 382.744739 -287.14605) (xy 382.73256 -287.096636) (xy 382.728465 -287.045908)
			(xy 382.410203 -287.045908) (xy 382.410208 -287.046162) (xy 382.409713 -287.070769) (xy 382.401818 -287.119346)
			(xy 382.386234 -287.166027) (xy 382.363363 -287.209604) (xy 382.333798 -287.248948) (xy 382.298305 -287.28304)
			(xy 382.257802 -287.310996) (xy 382.21334 -287.332094) (xy 382.166069 -287.345786) (xy 382.117214 -287.351718)
			(xy 382.068039 -287.349737) (xy 382.01982 -287.339893) (xy 381.973804 -287.322441) (xy 381.931183 -287.297834)
			(xy 381.893062 -287.266709) (xy 381.860427 -287.229872) (xy 381.834124 -287.188276) (xy 381.814833 -287.143)
			(xy 381.803056 -287.095216) (xy 381.799096 -287.046162) (xy 381.480563 -287.046162) (xy 381.480056 -287.071354)
			(xy 381.471892 -287.121588) (xy 381.455776 -287.169862) (xy 381.432125 -287.214925) (xy 381.401552 -287.255611)
			(xy 381.364848 -287.290866) (xy 381.322964 -287.319776) (xy 381.276985 -287.341593) (xy 381.228101 -287.355753)
			(xy 381.17758 -287.361887) (xy 381.126728 -287.359838) (xy 381.076864 -287.349658) (xy 381.029278 -287.331611)
			(xy 380.985204 -287.306165) (xy 380.945782 -287.273978) (xy 380.912034 -287.235884) (xy 380.884833 -287.19287)
			(xy 380.864885 -287.14605) (xy 380.852706 -287.096636) (xy 380.848611 -287.045908) (xy 380.5301 -287.045908)
			(xy 380.529605 -287.070515) (xy 380.52171 -287.119092) (xy 380.506126 -287.165773) (xy 380.483255 -287.20935)
			(xy 380.45369 -287.248694) (xy 380.418197 -287.282786) (xy 380.377694 -287.310742) (xy 380.333232 -287.33184)
			(xy 380.285961 -287.345532) (xy 380.237106 -287.351464) (xy 380.187931 -287.349483) (xy 380.139712 -287.339639)
			(xy 380.093696 -287.322187) (xy 380.051075 -287.29758) (xy 380.012954 -287.266455) (xy 379.980319 -287.229618)
			(xy 379.954016 -287.188022) (xy 379.934725 -287.142746) (xy 379.922948 -287.094962) (xy 379.918988 -287.045908)
			(xy 379.60046 -287.045908) (xy 379.599948 -287.071354) (xy 379.591784 -287.121588) (xy 379.575668 -287.169862)
			(xy 379.552017 -287.214925) (xy 379.521444 -287.255611) (xy 379.48474 -287.290866) (xy 379.442856 -287.319776)
			(xy 379.396877 -287.341593) (xy 379.347993 -287.355753) (xy 379.297472 -287.361887) (xy 379.24662 -287.359838)
			(xy 379.196756 -287.349658) (xy 379.14917 -287.331611) (xy 379.105096 -287.306165) (xy 379.065674 -287.273978)
			(xy 379.031926 -287.235884) (xy 379.004725 -287.19287) (xy 378.984777 -287.14605) (xy 378.972598 -287.096636)
			(xy 378.968503 -287.045908) (xy 378.650241 -287.045908) (xy 378.650246 -287.046162) (xy 378.649751 -287.070769)
			(xy 378.641856 -287.119346) (xy 378.626272 -287.166027) (xy 378.603401 -287.209604) (xy 378.573836 -287.248948)
			(xy 378.538343 -287.28304) (xy 378.49784 -287.310996) (xy 378.453378 -287.332094) (xy 378.406107 -287.345786)
			(xy 378.357252 -287.351718) (xy 378.308077 -287.349737) (xy 378.259858 -287.339893) (xy 378.213842 -287.322441)
			(xy 378.171221 -287.297834) (xy 378.1331 -287.266709) (xy 378.100465 -287.229872) (xy 378.074162 -287.188276)
			(xy 378.054871 -287.143) (xy 378.043094 -287.095216) (xy 378.039134 -287.046162) (xy 377.720601 -287.046162)
			(xy 377.720094 -287.071354) (xy 377.71193 -287.121588) (xy 377.695814 -287.169862) (xy 377.672163 -287.214925)
			(xy 377.64159 -287.255611) (xy 377.604886 -287.290866) (xy 377.563002 -287.319776) (xy 377.517023 -287.341593)
			(xy 377.468139 -287.355753) (xy 377.417618 -287.361887) (xy 377.366766 -287.359838) (xy 377.316902 -287.349658)
			(xy 377.269316 -287.331611) (xy 377.225242 -287.306165) (xy 377.18582 -287.273978) (xy 377.152072 -287.235884)
			(xy 377.124871 -287.19287) (xy 377.104923 -287.14605) (xy 377.092744 -287.096636) (xy 377.088649 -287.045908)
			(xy 376.780552 -287.045908) (xy 376.78004 -287.071354) (xy 376.771876 -287.121588) (xy 376.75576 -287.169862)
			(xy 376.732109 -287.214925) (xy 376.701536 -287.255611) (xy 376.664832 -287.290866) (xy 376.622948 -287.319776)
			(xy 376.576969 -287.341593) (xy 376.528085 -287.355753) (xy 376.477564 -287.361887) (xy 376.426712 -287.359838)
			(xy 376.376848 -287.349658) (xy 376.329262 -287.331611) (xy 376.285188 -287.306165) (xy 376.245766 -287.273978)
			(xy 376.212018 -287.235884) (xy 376.184817 -287.19287) (xy 376.164869 -287.14605) (xy 376.15269 -287.096636)
			(xy 376.148595 -287.045908) (xy 375.830651 -287.045908) (xy 375.82648 -287.096244) (xy 375.814078 -287.145215)
			(xy 375.793785 -287.191476) (xy 375.766154 -287.233766) (xy 375.731939 -287.270931) (xy 375.692072 -287.301957)
			(xy 375.647643 -287.325998) (xy 375.599863 -287.342398) (xy 375.550034 -287.350709) (xy 375.524776 -287.351216)
			(xy 375.502157 -287.35081) (xy 375.457415 -287.344138) (xy 375.41415 -287.330928) (xy 375.373311 -287.311472)
			(xy 375.354342 -287.299146) (xy 375.342404 -287.291272) (xy 375.314718 -287.289748) (xy 375.223024 -287.33877)
			(xy 375.215058 -287.343423) (xy 375.202872 -287.357252) (xy 375.196398 -287.37451) (xy 375.1961 -287.383728)
			(xy 375.1961 -287.556194) (xy 375.196378 -287.564722) (xy 375.201913 -287.58085) (xy 375.212465 -287.594244)
			(xy 375.219468 -287.59912) (xy 375.240669 -287.613284) (xy 375.278462 -287.647505) (xy 375.310041 -287.687532)
			(xy 375.334528 -287.73225) (xy 375.351243 -287.780416) (xy 375.35972 -287.830691) (xy 375.359721 -287.856168)
			(xy 375.678695 -287.856168) (xy 375.68279 -287.80544) (xy 375.694969 -287.756026) (xy 375.714917 -287.709206)
			(xy 375.742118 -287.666192) (xy 375.775866 -287.628098) (xy 375.815288 -287.595911) (xy 375.859362 -287.570465)
			(xy 375.906948 -287.552418) (xy 375.956812 -287.542238) (xy 376.007664 -287.540189) (xy 376.058185 -287.546323)
			(xy 376.107069 -287.560483) (xy 376.153048 -287.5823) (xy 376.194932 -287.61121) (xy 376.231636 -287.646465)
			(xy 376.262209 -287.687151) (xy 376.28586 -287.732214) (xy 376.301976 -287.780488) (xy 376.31014 -287.830722)
			(xy 376.310652 -287.856168) (xy 376.628926 -287.856168) (xy 376.632886 -287.807114) (xy 376.644663 -287.75933)
			(xy 376.663954 -287.714054) (xy 376.690257 -287.672458) (xy 376.722892 -287.635621) (xy 376.761013 -287.604496)
			(xy 376.803634 -287.579889) (xy 376.84965 -287.562437) (xy 376.897869 -287.552593) (xy 376.947044 -287.550612)
			(xy 376.995899 -287.556544) (xy 377.04317 -287.570236) (xy 377.087632 -287.591334) (xy 377.128135 -287.61929)
			(xy 377.163628 -287.653382) (xy 377.193193 -287.692726) (xy 377.216064 -287.736303) (xy 377.231648 -287.782984)
			(xy 377.239543 -287.831561) (xy 377.240038 -287.856168) (xy 377.558549 -287.856168) (xy 377.562644 -287.80544)
			(xy 377.574823 -287.756026) (xy 377.594771 -287.709206) (xy 377.621972 -287.666192) (xy 377.65572 -287.628098)
			(xy 377.695142 -287.595911) (xy 377.739216 -287.570465) (xy 377.786802 -287.552418) (xy 377.836666 -287.542238)
			(xy 377.887518 -287.540189) (xy 377.938039 -287.546323) (xy 377.986923 -287.560483) (xy 378.032902 -287.5823)
			(xy 378.074786 -287.61121) (xy 378.11149 -287.646465) (xy 378.142063 -287.687151) (xy 378.165714 -287.732214)
			(xy 378.18183 -287.780488) (xy 378.189994 -287.830722) (xy 378.190506 -287.856168) (xy 379.438657 -287.856168)
			(xy 379.442752 -287.80544) (xy 379.454931 -287.756026) (xy 379.474879 -287.709206) (xy 379.50208 -287.666192)
			(xy 379.535828 -287.628098) (xy 379.57525 -287.595911) (xy 379.619324 -287.570465) (xy 379.66691 -287.552418)
			(xy 379.716774 -287.542238) (xy 379.767626 -287.540189) (xy 379.818147 -287.546323) (xy 379.867031 -287.560483)
			(xy 379.91301 -287.5823) (xy 379.954894 -287.61121) (xy 379.991598 -287.646465) (xy 380.022171 -287.687151)
			(xy 380.045822 -287.732214) (xy 380.061938 -287.780488) (xy 380.070102 -287.830722) (xy 380.070614 -287.856168)
			(xy 380.378711 -287.856168) (xy 380.382806 -287.80544) (xy 380.394985 -287.756026) (xy 380.414933 -287.709206)
			(xy 380.442134 -287.666192) (xy 380.475882 -287.628098) (xy 380.515304 -287.595911) (xy 380.559378 -287.570465)
			(xy 380.606964 -287.552418) (xy 380.656828 -287.542238) (xy 380.70768 -287.540189) (xy 380.758201 -287.546323)
			(xy 380.807085 -287.560483) (xy 380.853064 -287.5823) (xy 380.894948 -287.61121) (xy 380.931652 -287.646465)
			(xy 380.962225 -287.687151) (xy 380.985876 -287.732214) (xy 381.001992 -287.780488) (xy 381.010156 -287.830722)
			(xy 381.010668 -287.856168) (xy 381.328942 -287.856168) (xy 381.332902 -287.807114) (xy 381.344679 -287.75933)
			(xy 381.36397 -287.714054) (xy 381.390273 -287.672458) (xy 381.422908 -287.635621) (xy 381.461029 -287.604496)
			(xy 381.50365 -287.579889) (xy 381.549666 -287.562437) (xy 381.597885 -287.552593) (xy 381.64706 -287.550612)
			(xy 381.695915 -287.556544) (xy 381.743186 -287.570236) (xy 381.787648 -287.591334) (xy 381.828151 -287.61929)
			(xy 381.863644 -287.653382) (xy 381.893209 -287.692726) (xy 381.91608 -287.736303) (xy 381.931664 -287.782984)
			(xy 381.939559 -287.831561) (xy 381.940054 -287.856168) (xy 382.258565 -287.856168) (xy 382.26266 -287.80544)
			(xy 382.274839 -287.756026) (xy 382.294787 -287.709206) (xy 382.321988 -287.666192) (xy 382.355736 -287.628098)
			(xy 382.395158 -287.595911) (xy 382.439232 -287.570465) (xy 382.486818 -287.552418) (xy 382.536682 -287.542238)
			(xy 382.587534 -287.540189) (xy 382.638055 -287.546323) (xy 382.686939 -287.560483) (xy 382.732918 -287.5823)
			(xy 382.774802 -287.61121) (xy 382.811506 -287.646465) (xy 382.842079 -287.687151) (xy 382.86573 -287.732214)
			(xy 382.881846 -287.780488) (xy 382.89001 -287.830722) (xy 382.890522 -287.856168) (xy 383.20905 -287.856168)
			(xy 383.21301 -287.807114) (xy 383.224787 -287.75933) (xy 383.244078 -287.714054) (xy 383.270381 -287.672458)
			(xy 383.303016 -287.635621) (xy 383.341137 -287.604496) (xy 383.383758 -287.579889) (xy 383.429774 -287.562437)
			(xy 383.477993 -287.552593) (xy 383.527168 -287.550612) (xy 383.576023 -287.556544) (xy 383.623294 -287.570236)
			(xy 383.667756 -287.591334) (xy 383.708259 -287.61929) (xy 383.743752 -287.653382) (xy 383.773317 -287.692726)
			(xy 383.796188 -287.736303) (xy 383.811772 -287.782984) (xy 383.819667 -287.831561) (xy 383.820162 -287.856168)
			(xy 384.138673 -287.856168) (xy 384.142768 -287.80544) (xy 384.154947 -287.756026) (xy 384.174895 -287.709206)
			(xy 384.202096 -287.666192) (xy 384.235844 -287.628098) (xy 384.275266 -287.595911) (xy 384.31934 -287.570465)
			(xy 384.366926 -287.552418) (xy 384.41679 -287.542238) (xy 384.467642 -287.540189) (xy 384.518163 -287.546323)
			(xy 384.567047 -287.560483) (xy 384.613026 -287.5823) (xy 384.65491 -287.61121) (xy 384.691614 -287.646465)
			(xy 384.722187 -287.687151) (xy 384.745838 -287.732214) (xy 384.761954 -287.780488) (xy 384.770118 -287.830722)
			(xy 384.77063 -287.856168) (xy 386.018527 -287.856168) (xy 386.022622 -287.80544) (xy 386.034801 -287.756026)
			(xy 386.054749 -287.709206) (xy 386.08195 -287.666192) (xy 386.115698 -287.628098) (xy 386.15512 -287.595911)
			(xy 386.199194 -287.570465) (xy 386.24678 -287.552418) (xy 386.296644 -287.542238) (xy 386.347496 -287.540189)
			(xy 386.398017 -287.546323) (xy 386.446901 -287.560483) (xy 386.49288 -287.5823) (xy 386.534764 -287.61121)
			(xy 386.571468 -287.646465) (xy 386.602041 -287.687151) (xy 386.625692 -287.732214) (xy 386.641808 -287.780488)
			(xy 386.649972 -287.830722) (xy 386.650484 -287.856168) (xy 386.958581 -287.856168) (xy 386.962676 -287.80544)
			(xy 386.974855 -287.756026) (xy 386.994803 -287.709206) (xy 387.022004 -287.666192) (xy 387.055752 -287.628098)
			(xy 387.095174 -287.595911) (xy 387.139248 -287.570465) (xy 387.186834 -287.552418) (xy 387.236698 -287.542238)
			(xy 387.28755 -287.540189) (xy 387.338071 -287.546323) (xy 387.386955 -287.560483) (xy 387.432934 -287.5823)
			(xy 387.474818 -287.61121) (xy 387.511522 -287.646465) (xy 387.542095 -287.687151) (xy 387.565746 -287.732214)
			(xy 387.581862 -287.780488) (xy 387.590026 -287.830722) (xy 387.590538 -287.856168) (xy 387.909066 -287.856168)
			(xy 387.913026 -287.807114) (xy 387.924803 -287.75933) (xy 387.944094 -287.714054) (xy 387.970397 -287.672458)
			(xy 388.003032 -287.635621) (xy 388.041153 -287.604496) (xy 388.083774 -287.579889) (xy 388.12979 -287.562437)
			(xy 388.178009 -287.552593) (xy 388.227184 -287.550612) (xy 388.276039 -287.556544) (xy 388.32331 -287.570236)
			(xy 388.367772 -287.591334) (xy 388.408275 -287.61929) (xy 388.443768 -287.653382) (xy 388.473333 -287.692726)
			(xy 388.496204 -287.736303) (xy 388.511788 -287.782984) (xy 388.519683 -287.831561) (xy 388.520178 -287.856168)
			(xy 388.838689 -287.856168) (xy 388.842784 -287.80544) (xy 388.854963 -287.756026) (xy 388.874911 -287.709206)
			(xy 388.902112 -287.666192) (xy 388.93586 -287.628098) (xy 388.975282 -287.595911) (xy 389.019356 -287.570465)
			(xy 389.066942 -287.552418) (xy 389.116806 -287.542238) (xy 389.167658 -287.540189) (xy 389.218179 -287.546323)
			(xy 389.267063 -287.560483) (xy 389.313042 -287.5823) (xy 389.354926 -287.61121) (xy 389.39163 -287.646465)
			(xy 389.422203 -287.687151) (xy 389.445854 -287.732214) (xy 389.46197 -287.780488) (xy 389.470134 -287.830722)
			(xy 389.470646 -287.856168) (xy 389.78892 -287.856168) (xy 389.79288 -287.807114) (xy 389.804657 -287.75933)
			(xy 389.823948 -287.714054) (xy 389.850251 -287.672458) (xy 389.882886 -287.635621) (xy 389.921007 -287.604496)
			(xy 389.963628 -287.579889) (xy 390.009644 -287.562437) (xy 390.057863 -287.552593) (xy 390.107038 -287.550612)
			(xy 390.155893 -287.556544) (xy 390.203164 -287.570236) (xy 390.247626 -287.591334) (xy 390.288129 -287.61929)
			(xy 390.323622 -287.653382) (xy 390.353187 -287.692726) (xy 390.376058 -287.736303) (xy 390.391642 -287.782984)
			(xy 390.399537 -287.831561) (xy 390.400032 -287.856168) (xy 390.718543 -287.856168) (xy 390.722638 -287.80544)
			(xy 390.734817 -287.756026) (xy 390.754765 -287.709206) (xy 390.781966 -287.666192) (xy 390.815714 -287.628098)
			(xy 390.855136 -287.595911) (xy 390.89921 -287.570465) (xy 390.946796 -287.552418) (xy 390.99666 -287.542238)
			(xy 391.047512 -287.540189) (xy 391.098033 -287.546323) (xy 391.146917 -287.560483) (xy 391.192896 -287.5823)
			(xy 391.204385 -287.59023) (xy 394.67715 -287.59023) (xy 394.68111 -287.541176) (xy 394.692887 -287.493392)
			(xy 394.712178 -287.448116) (xy 394.738481 -287.40652) (xy 394.771116 -287.369683) (xy 394.809237 -287.338558)
			(xy 394.851858 -287.313951) (xy 394.897874 -287.296499) (xy 394.946093 -287.286655) (xy 394.995268 -287.284674)
			(xy 395.044123 -287.290606) (xy 395.091394 -287.304298) (xy 395.135856 -287.325396) (xy 395.176359 -287.353352)
			(xy 395.211852 -287.387444) (xy 395.241417 -287.426788) (xy 395.264288 -287.470365) (xy 395.279872 -287.517046)
			(xy 395.287767 -287.565623) (xy 395.288262 -287.59023) (xy 395.287767 -287.614837) (xy 395.279872 -287.663414)
			(xy 395.264288 -287.710095) (xy 395.241417 -287.753672) (xy 395.211852 -287.793016) (xy 395.176359 -287.827108)
			(xy 395.135856 -287.855064) (xy 395.091394 -287.876162) (xy 395.044123 -287.889854) (xy 394.995268 -287.895786)
			(xy 394.946093 -287.893805) (xy 394.897874 -287.883961) (xy 394.851858 -287.866509) (xy 394.809237 -287.841902)
			(xy 394.771116 -287.810777) (xy 394.738481 -287.77394) (xy 394.712178 -287.732344) (xy 394.692887 -287.687068)
			(xy 394.68111 -287.639284) (xy 394.67715 -287.59023) (xy 391.204385 -287.59023) (xy 391.23478 -287.61121)
			(xy 391.271484 -287.646465) (xy 391.302057 -287.687151) (xy 391.325708 -287.732214) (xy 391.341824 -287.780488)
			(xy 391.349988 -287.830722) (xy 391.3505 -287.856168) (xy 391.349988 -287.881614) (xy 391.341824 -287.931848)
			(xy 391.325708 -287.980122) (xy 391.302057 -288.025185) (xy 391.271484 -288.065871) (xy 391.23478 -288.101126)
			(xy 391.192896 -288.130036) (xy 391.146917 -288.151853) (xy 391.098033 -288.166013) (xy 391.047512 -288.172147)
			(xy 390.99666 -288.170098) (xy 390.946796 -288.159918) (xy 390.89921 -288.141871) (xy 390.855136 -288.116425)
			(xy 390.815714 -288.084238) (xy 390.781966 -288.046144) (xy 390.754765 -288.00313) (xy 390.734817 -287.95631)
			(xy 390.722638 -287.906896) (xy 390.718543 -287.856168) (xy 390.400032 -287.856168) (xy 390.399537 -287.880775)
			(xy 390.391642 -287.929352) (xy 390.376058 -287.976033) (xy 390.353187 -288.01961) (xy 390.323622 -288.058954)
			(xy 390.288129 -288.093046) (xy 390.247626 -288.121002) (xy 390.203164 -288.1421) (xy 390.155893 -288.155792)
			(xy 390.107038 -288.161724) (xy 390.057863 -288.159743) (xy 390.009644 -288.149899) (xy 389.963628 -288.132447)
			(xy 389.921007 -288.10784) (xy 389.882886 -288.076715) (xy 389.850251 -288.039878) (xy 389.823948 -287.998282)
			(xy 389.804657 -287.953006) (xy 389.79288 -287.905222) (xy 389.78892 -287.856168) (xy 389.470646 -287.856168)
			(xy 389.470134 -287.881614) (xy 389.46197 -287.931848) (xy 389.445854 -287.980122) (xy 389.422203 -288.025185)
			(xy 389.39163 -288.065871) (xy 389.354926 -288.101126) (xy 389.313042 -288.130036) (xy 389.267063 -288.151853)
			(xy 389.218179 -288.166013) (xy 389.167658 -288.172147) (xy 389.116806 -288.170098) (xy 389.066942 -288.159918)
			(xy 389.019356 -288.141871) (xy 388.975282 -288.116425) (xy 388.93586 -288.084238) (xy 388.902112 -288.046144)
			(xy 388.874911 -288.00313) (xy 388.854963 -287.95631) (xy 388.842784 -287.906896) (xy 388.838689 -287.856168)
			(xy 388.520178 -287.856168) (xy 388.519683 -287.880775) (xy 388.511788 -287.929352) (xy 388.496204 -287.976033)
			(xy 388.473333 -288.01961) (xy 388.443768 -288.058954) (xy 388.408275 -288.093046) (xy 388.367772 -288.121002)
			(xy 388.32331 -288.1421) (xy 388.276039 -288.155792) (xy 388.227184 -288.161724) (xy 388.178009 -288.159743)
			(xy 388.12979 -288.149899) (xy 388.083774 -288.132447) (xy 388.041153 -288.10784) (xy 388.003032 -288.076715)
			(xy 387.970397 -288.039878) (xy 387.944094 -287.998282) (xy 387.924803 -287.953006) (xy 387.913026 -287.905222)
			(xy 387.909066 -287.856168) (xy 387.590538 -287.856168) (xy 387.590026 -287.881614) (xy 387.581862 -287.931848)
			(xy 387.565746 -287.980122) (xy 387.542095 -288.025185) (xy 387.511522 -288.065871) (xy 387.474818 -288.101126)
			(xy 387.432934 -288.130036) (xy 387.386955 -288.151853) (xy 387.338071 -288.166013) (xy 387.28755 -288.172147)
			(xy 387.236698 -288.170098) (xy 387.186834 -288.159918) (xy 387.139248 -288.141871) (xy 387.095174 -288.116425)
			(xy 387.055752 -288.084238) (xy 387.022004 -288.046144) (xy 386.994803 -288.00313) (xy 386.974855 -287.95631)
			(xy 386.962676 -287.906896) (xy 386.958581 -287.856168) (xy 386.650484 -287.856168) (xy 386.649972 -287.881614)
			(xy 386.641808 -287.931848) (xy 386.625692 -287.980122) (xy 386.602041 -288.025185) (xy 386.571468 -288.065871)
			(xy 386.534764 -288.101126) (xy 386.49288 -288.130036) (xy 386.446901 -288.151853) (xy 386.398017 -288.166013)
			(xy 386.347496 -288.172147) (xy 386.296644 -288.170098) (xy 386.24678 -288.159918) (xy 386.199194 -288.141871)
			(xy 386.15512 -288.116425) (xy 386.115698 -288.084238) (xy 386.08195 -288.046144) (xy 386.054749 -288.00313)
			(xy 386.034801 -287.95631) (xy 386.022622 -287.906896) (xy 386.018527 -287.856168) (xy 384.77063 -287.856168)
			(xy 384.770118 -287.881614) (xy 384.761954 -287.931848) (xy 384.745838 -287.980122) (xy 384.722187 -288.025185)
			(xy 384.691614 -288.065871) (xy 384.65491 -288.101126) (xy 384.613026 -288.130036) (xy 384.567047 -288.151853)
			(xy 384.518163 -288.166013) (xy 384.467642 -288.172147) (xy 384.41679 -288.170098) (xy 384.366926 -288.159918)
			(xy 384.31934 -288.141871) (xy 384.275266 -288.116425) (xy 384.235844 -288.084238) (xy 384.202096 -288.046144)
			(xy 384.174895 -288.00313) (xy 384.154947 -287.95631) (xy 384.142768 -287.906896) (xy 384.138673 -287.856168)
			(xy 383.820162 -287.856168) (xy 383.819667 -287.880775) (xy 383.811772 -287.929352) (xy 383.796188 -287.976033)
			(xy 383.773317 -288.01961) (xy 383.743752 -288.058954) (xy 383.708259 -288.093046) (xy 383.667756 -288.121002)
			(xy 383.623294 -288.1421) (xy 383.576023 -288.155792) (xy 383.527168 -288.161724) (xy 383.477993 -288.159743)
			(xy 383.429774 -288.149899) (xy 383.383758 -288.132447) (xy 383.341137 -288.10784) (xy 383.303016 -288.076715)
			(xy 383.270381 -288.039878) (xy 383.244078 -287.998282) (xy 383.224787 -287.953006) (xy 383.21301 -287.905222)
			(xy 383.20905 -287.856168) (xy 382.890522 -287.856168) (xy 382.89001 -287.881614) (xy 382.881846 -287.931848)
			(xy 382.86573 -287.980122) (xy 382.842079 -288.025185) (xy 382.811506 -288.065871) (xy 382.774802 -288.101126)
			(xy 382.732918 -288.130036) (xy 382.686939 -288.151853) (xy 382.638055 -288.166013) (xy 382.587534 -288.172147)
			(xy 382.536682 -288.170098) (xy 382.486818 -288.159918) (xy 382.439232 -288.141871) (xy 382.395158 -288.116425)
			(xy 382.355736 -288.084238) (xy 382.321988 -288.046144) (xy 382.294787 -288.00313) (xy 382.274839 -287.95631)
			(xy 382.26266 -287.906896) (xy 382.258565 -287.856168) (xy 381.940054 -287.856168) (xy 381.939559 -287.880775)
			(xy 381.931664 -287.929352) (xy 381.91608 -287.976033) (xy 381.893209 -288.01961) (xy 381.863644 -288.058954)
			(xy 381.828151 -288.093046) (xy 381.787648 -288.121002) (xy 381.743186 -288.1421) (xy 381.695915 -288.155792)
			(xy 381.64706 -288.161724) (xy 381.597885 -288.159743) (xy 381.549666 -288.149899) (xy 381.50365 -288.132447)
			(xy 381.461029 -288.10784) (xy 381.422908 -288.076715) (xy 381.390273 -288.039878) (xy 381.36397 -287.998282)
			(xy 381.344679 -287.953006) (xy 381.332902 -287.905222) (xy 381.328942 -287.856168) (xy 381.010668 -287.856168)
			(xy 381.010156 -287.881614) (xy 381.001992 -287.931848) (xy 380.985876 -287.980122) (xy 380.962225 -288.025185)
			(xy 380.931652 -288.065871) (xy 380.894948 -288.101126) (xy 380.853064 -288.130036) (xy 380.807085 -288.151853)
			(xy 380.758201 -288.166013) (xy 380.70768 -288.172147) (xy 380.656828 -288.170098) (xy 380.606964 -288.159918)
			(xy 380.559378 -288.141871) (xy 380.515304 -288.116425) (xy 380.475882 -288.084238) (xy 380.442134 -288.046144)
			(xy 380.414933 -288.00313) (xy 380.394985 -287.95631) (xy 380.382806 -287.906896) (xy 380.378711 -287.856168)
			(xy 380.070614 -287.856168) (xy 380.070102 -287.881614) (xy 380.061938 -287.931848) (xy 380.045822 -287.980122)
			(xy 380.022171 -288.025185) (xy 379.991598 -288.065871) (xy 379.954894 -288.101126) (xy 379.91301 -288.130036)
			(xy 379.867031 -288.151853) (xy 379.818147 -288.166013) (xy 379.767626 -288.172147) (xy 379.716774 -288.170098)
			(xy 379.66691 -288.159918) (xy 379.619324 -288.141871) (xy 379.57525 -288.116425) (xy 379.535828 -288.084238)
			(xy 379.50208 -288.046144) (xy 379.474879 -288.00313) (xy 379.454931 -287.95631) (xy 379.442752 -287.906896)
			(xy 379.438657 -287.856168) (xy 378.190506 -287.856168) (xy 378.189994 -287.881614) (xy 378.18183 -287.931848)
			(xy 378.165714 -287.980122) (xy 378.142063 -288.025185) (xy 378.11149 -288.065871) (xy 378.074786 -288.101126)
			(xy 378.032902 -288.130036) (xy 377.986923 -288.151853) (xy 377.938039 -288.166013) (xy 377.887518 -288.172147)
			(xy 377.836666 -288.170098) (xy 377.786802 -288.159918) (xy 377.739216 -288.141871) (xy 377.695142 -288.116425)
			(xy 377.65572 -288.084238) (xy 377.621972 -288.046144) (xy 377.594771 -288.00313) (xy 377.574823 -287.95631)
			(xy 377.562644 -287.906896) (xy 377.558549 -287.856168) (xy 377.240038 -287.856168) (xy 377.239543 -287.880775)
			(xy 377.231648 -287.929352) (xy 377.216064 -287.976033) (xy 377.193193 -288.01961) (xy 377.163628 -288.058954)
			(xy 377.128135 -288.093046) (xy 377.087632 -288.121002) (xy 377.04317 -288.1421) (xy 376.995899 -288.155792)
			(xy 376.947044 -288.161724) (xy 376.897869 -288.159743) (xy 376.84965 -288.149899) (xy 376.803634 -288.132447)
			(xy 376.761013 -288.10784) (xy 376.722892 -288.076715) (xy 376.690257 -288.039878) (xy 376.663954 -287.998282)
			(xy 376.644663 -287.953006) (xy 376.632886 -287.905222) (xy 376.628926 -287.856168) (xy 376.310652 -287.856168)
			(xy 376.31014 -287.881614) (xy 376.301976 -287.931848) (xy 376.28586 -287.980122) (xy 376.262209 -288.025185)
			(xy 376.231636 -288.065871) (xy 376.194932 -288.101126) (xy 376.153048 -288.130036) (xy 376.107069 -288.151853)
			(xy 376.058185 -288.166013) (xy 376.007664 -288.172147) (xy 375.956812 -288.170098) (xy 375.906948 -288.159918)
			(xy 375.859362 -288.141871) (xy 375.815288 -288.116425) (xy 375.775866 -288.084238) (xy 375.742118 -288.046144)
			(xy 375.714917 -288.00313) (xy 375.694969 -287.95631) (xy 375.68279 -287.906896) (xy 375.678695 -287.856168)
			(xy 375.359721 -287.856168) (xy 375.359723 -287.881675) (xy 375.351252 -287.93195) (xy 375.334542 -287.980118)
			(xy 375.31006 -288.024839) (xy 375.278485 -288.064869) (xy 375.240696 -288.099095) (xy 375.219468 -288.113216)
			(xy 375.212476 -288.118099) (xy 375.201955 -288.131508) (xy 375.196395 -288.14762) (xy 375.1961 -288.156142)
			(xy 375.1961 -288.66592) (xy 376.148595 -288.66592) (xy 376.15269 -288.615192) (xy 376.164869 -288.565778)
			(xy 376.184817 -288.518958) (xy 376.212018 -288.475944) (xy 376.245766 -288.43785) (xy 376.285188 -288.405663)
			(xy 376.329262 -288.380217) (xy 376.376848 -288.36217) (xy 376.426712 -288.35199) (xy 376.477564 -288.349941)
			(xy 376.528085 -288.356075) (xy 376.576969 -288.370235) (xy 376.622948 -288.392052) (xy 376.664832 -288.420962)
			(xy 376.701536 -288.456217) (xy 376.732109 -288.496903) (xy 376.75576 -288.541966) (xy 376.771876 -288.59024)
			(xy 376.78004 -288.640474) (xy 376.780552 -288.66592) (xy 377.088649 -288.66592) (xy 377.092744 -288.615192)
			(xy 377.104923 -288.565778) (xy 377.124871 -288.518958) (xy 377.152072 -288.475944) (xy 377.18582 -288.43785)
			(xy 377.225242 -288.405663) (xy 377.269316 -288.380217) (xy 377.316902 -288.36217) (xy 377.366766 -288.35199)
			(xy 377.417618 -288.349941) (xy 377.468139 -288.356075) (xy 377.517023 -288.370235) (xy 377.563002 -288.392052)
			(xy 377.604886 -288.420962) (xy 377.64159 -288.456217) (xy 377.672163 -288.496903) (xy 377.695814 -288.541966)
			(xy 377.71193 -288.59024) (xy 377.720094 -288.640474) (xy 377.720606 -288.66592) (xy 378.039134 -288.66592)
			(xy 378.043094 -288.616866) (xy 378.054871 -288.569082) (xy 378.074162 -288.523806) (xy 378.100465 -288.48221)
			(xy 378.1331 -288.445373) (xy 378.171221 -288.414248) (xy 378.213842 -288.389641) (xy 378.259858 -288.372189)
			(xy 378.308077 -288.362345) (xy 378.357252 -288.360364) (xy 378.406107 -288.366296) (xy 378.453378 -288.379988)
			(xy 378.49784 -288.401086) (xy 378.538343 -288.429042) (xy 378.573836 -288.463134) (xy 378.603401 -288.502478)
			(xy 378.626272 -288.546055) (xy 378.641856 -288.592736) (xy 378.649751 -288.641313) (xy 378.650246 -288.66592)
			(xy 378.968503 -288.66592) (xy 378.972598 -288.615192) (xy 378.984777 -288.565778) (xy 379.004725 -288.518958)
			(xy 379.031926 -288.475944) (xy 379.065674 -288.43785) (xy 379.105096 -288.405663) (xy 379.14917 -288.380217)
			(xy 379.196756 -288.36217) (xy 379.24662 -288.35199) (xy 379.297472 -288.349941) (xy 379.347993 -288.356075)
			(xy 379.396877 -288.370235) (xy 379.442856 -288.392052) (xy 379.48474 -288.420962) (xy 379.521444 -288.456217)
			(xy 379.552017 -288.496903) (xy 379.575668 -288.541966) (xy 379.591784 -288.59024) (xy 379.599948 -288.640474)
			(xy 379.60046 -288.66592) (xy 379.918988 -288.66592) (xy 379.922948 -288.616866) (xy 379.934725 -288.569082)
			(xy 379.954016 -288.523806) (xy 379.980319 -288.48221) (xy 380.012954 -288.445373) (xy 380.051075 -288.414248)
			(xy 380.093696 -288.389641) (xy 380.139712 -288.372189) (xy 380.187931 -288.362345) (xy 380.237106 -288.360364)
			(xy 380.285961 -288.366296) (xy 380.333232 -288.379988) (xy 380.377694 -288.401086) (xy 380.418197 -288.429042)
			(xy 380.45369 -288.463134) (xy 380.483255 -288.502478) (xy 380.506126 -288.546055) (xy 380.52171 -288.592736)
			(xy 380.529605 -288.641313) (xy 380.5301 -288.66592) (xy 380.848611 -288.66592) (xy 380.852706 -288.615192)
			(xy 380.864885 -288.565778) (xy 380.884833 -288.518958) (xy 380.912034 -288.475944) (xy 380.945782 -288.43785)
			(xy 380.985204 -288.405663) (xy 381.029278 -288.380217) (xy 381.076864 -288.36217) (xy 381.126728 -288.35199)
			(xy 381.17758 -288.349941) (xy 381.228101 -288.356075) (xy 381.276985 -288.370235) (xy 381.322964 -288.392052)
			(xy 381.364848 -288.420962) (xy 381.401552 -288.456217) (xy 381.432125 -288.496903) (xy 381.455776 -288.541966)
			(xy 381.471892 -288.59024) (xy 381.480056 -288.640474) (xy 381.480568 -288.66592) (xy 381.799096 -288.66592)
			(xy 381.803056 -288.616866) (xy 381.814833 -288.569082) (xy 381.834124 -288.523806) (xy 381.860427 -288.48221)
			(xy 381.893062 -288.445373) (xy 381.931183 -288.414248) (xy 381.973804 -288.389641) (xy 382.01982 -288.372189)
			(xy 382.068039 -288.362345) (xy 382.117214 -288.360364) (xy 382.166069 -288.366296) (xy 382.21334 -288.379988)
			(xy 382.257802 -288.401086) (xy 382.298305 -288.429042) (xy 382.333798 -288.463134) (xy 382.363363 -288.502478)
			(xy 382.386234 -288.546055) (xy 382.401818 -288.592736) (xy 382.409713 -288.641313) (xy 382.410208 -288.66592)
			(xy 382.728465 -288.66592) (xy 382.73256 -288.615192) (xy 382.744739 -288.565778) (xy 382.764687 -288.518958)
			(xy 382.791888 -288.475944) (xy 382.825636 -288.43785) (xy 382.865058 -288.405663) (xy 382.909132 -288.380217)
			(xy 382.956718 -288.36217) (xy 383.006582 -288.35199) (xy 383.057434 -288.349941) (xy 383.107955 -288.356075)
			(xy 383.156839 -288.370235) (xy 383.202818 -288.392052) (xy 383.244702 -288.420962) (xy 383.281406 -288.456217)
			(xy 383.311979 -288.496903) (xy 383.33563 -288.541966) (xy 383.351746 -288.59024) (xy 383.35991 -288.640474)
			(xy 383.360422 -288.66592) (xy 383.668519 -288.66592) (xy 383.672614 -288.615192) (xy 383.684793 -288.565778)
			(xy 383.704741 -288.518958) (xy 383.731942 -288.475944) (xy 383.76569 -288.43785) (xy 383.805112 -288.405663)
			(xy 383.849186 -288.380217) (xy 383.896772 -288.36217) (xy 383.946636 -288.35199) (xy 383.997488 -288.349941)
			(xy 384.048009 -288.356075) (xy 384.096893 -288.370235) (xy 384.142872 -288.392052) (xy 384.184756 -288.420962)
			(xy 384.22146 -288.456217) (xy 384.252033 -288.496903) (xy 384.275684 -288.541966) (xy 384.2918 -288.59024)
			(xy 384.299964 -288.640474) (xy 384.300476 -288.66592) (xy 384.619004 -288.66592) (xy 384.622964 -288.616866)
			(xy 384.634741 -288.569082) (xy 384.654032 -288.523806) (xy 384.680335 -288.48221) (xy 384.71297 -288.445373)
			(xy 384.751091 -288.414248) (xy 384.793712 -288.389641) (xy 384.839728 -288.372189) (xy 384.887947 -288.362345)
			(xy 384.937122 -288.360364) (xy 384.985977 -288.366296) (xy 385.033248 -288.379988) (xy 385.07771 -288.401086)
			(xy 385.118213 -288.429042) (xy 385.153706 -288.463134) (xy 385.183271 -288.502478) (xy 385.206142 -288.546055)
			(xy 385.221726 -288.592736) (xy 385.229621 -288.641313) (xy 385.230116 -288.66592) (xy 385.548627 -288.66592)
			(xy 385.552722 -288.615192) (xy 385.564901 -288.565778) (xy 385.584849 -288.518958) (xy 385.61205 -288.475944)
			(xy 385.645798 -288.43785) (xy 385.68522 -288.405663) (xy 385.729294 -288.380217) (xy 385.77688 -288.36217)
			(xy 385.826744 -288.35199) (xy 385.877596 -288.349941) (xy 385.928117 -288.356075) (xy 385.977001 -288.370235)
			(xy 386.02298 -288.392052) (xy 386.064864 -288.420962) (xy 386.101568 -288.456217) (xy 386.132141 -288.496903)
			(xy 386.155792 -288.541966) (xy 386.171908 -288.59024) (xy 386.180072 -288.640474) (xy 386.180584 -288.66592)
			(xy 386.499112 -288.66592) (xy 386.503072 -288.616866) (xy 386.514849 -288.569082) (xy 386.53414 -288.523806)
			(xy 386.560443 -288.48221) (xy 386.593078 -288.445373) (xy 386.631199 -288.414248) (xy 386.67382 -288.389641)
			(xy 386.719836 -288.372189) (xy 386.768055 -288.362345) (xy 386.81723 -288.360364) (xy 386.866085 -288.366296)
			(xy 386.913356 -288.379988) (xy 386.957818 -288.401086) (xy 386.998321 -288.429042) (xy 387.033814 -288.463134)
			(xy 387.063379 -288.502478) (xy 387.08625 -288.546055) (xy 387.101834 -288.592736) (xy 387.109729 -288.641313)
			(xy 387.110224 -288.66592) (xy 387.428481 -288.66592) (xy 387.432576 -288.615192) (xy 387.444755 -288.565778)
			(xy 387.464703 -288.518958) (xy 387.491904 -288.475944) (xy 387.525652 -288.43785) (xy 387.565074 -288.405663)
			(xy 387.609148 -288.380217) (xy 387.656734 -288.36217) (xy 387.706598 -288.35199) (xy 387.75745 -288.349941)
			(xy 387.807971 -288.356075) (xy 387.856855 -288.370235) (xy 387.902834 -288.392052) (xy 387.944718 -288.420962)
			(xy 387.981422 -288.456217) (xy 388.011995 -288.496903) (xy 388.035646 -288.541966) (xy 388.051762 -288.59024)
			(xy 388.059926 -288.640474) (xy 388.060438 -288.66592) (xy 388.378966 -288.66592) (xy 388.382926 -288.616866)
			(xy 388.394703 -288.569082) (xy 388.413994 -288.523806) (xy 388.440297 -288.48221) (xy 388.472932 -288.445373)
			(xy 388.511053 -288.414248) (xy 388.553674 -288.389641) (xy 388.59969 -288.372189) (xy 388.647909 -288.362345)
			(xy 388.697084 -288.360364) (xy 388.745939 -288.366296) (xy 388.79321 -288.379988) (xy 388.837672 -288.401086)
			(xy 388.878175 -288.429042) (xy 388.913668 -288.463134) (xy 388.943233 -288.502478) (xy 388.966104 -288.546055)
			(xy 388.981688 -288.592736) (xy 388.989583 -288.641313) (xy 388.990078 -288.66592) (xy 389.308589 -288.66592)
			(xy 389.312684 -288.615192) (xy 389.324863 -288.565778) (xy 389.344811 -288.518958) (xy 389.372012 -288.475944)
			(xy 389.40576 -288.43785) (xy 389.445182 -288.405663) (xy 389.489256 -288.380217) (xy 389.536842 -288.36217)
			(xy 389.586706 -288.35199) (xy 389.637558 -288.349941) (xy 389.688079 -288.356075) (xy 389.736963 -288.370235)
			(xy 389.782942 -288.392052) (xy 389.824826 -288.420962) (xy 389.86153 -288.456217) (xy 389.892103 -288.496903)
			(xy 389.915754 -288.541966) (xy 389.93187 -288.59024) (xy 389.940034 -288.640474) (xy 389.940546 -288.66592)
			(xy 390.248643 -288.66592) (xy 390.252738 -288.615192) (xy 390.264917 -288.565778) (xy 390.284865 -288.518958)
			(xy 390.312066 -288.475944) (xy 390.345814 -288.43785) (xy 390.385236 -288.405663) (xy 390.42931 -288.380217)
			(xy 390.476896 -288.36217) (xy 390.52676 -288.35199) (xy 390.577612 -288.349941) (xy 390.628133 -288.356075)
			(xy 390.677017 -288.370235) (xy 390.722996 -288.392052) (xy 390.76488 -288.420962) (xy 390.801584 -288.456217)
			(xy 390.832157 -288.496903) (xy 390.855808 -288.541966) (xy 390.871924 -288.59024) (xy 390.880088 -288.640474)
			(xy 390.8806 -288.66592) (xy 391.198874 -288.66592) (xy 391.202834 -288.616866) (xy 391.214611 -288.569082)
			(xy 391.233902 -288.523806) (xy 391.260205 -288.48221) (xy 391.29284 -288.445373) (xy 391.330961 -288.414248)
			(xy 391.373582 -288.389641) (xy 391.419598 -288.372189) (xy 391.467817 -288.362345) (xy 391.516992 -288.360364)
			(xy 391.565847 -288.366296) (xy 391.613118 -288.379988) (xy 391.65758 -288.401086) (xy 391.698083 -288.429042)
			(xy 391.733576 -288.463134) (xy 391.763141 -288.502478) (xy 391.786012 -288.546055) (xy 391.801596 -288.592736)
			(xy 391.809491 -288.641313) (xy 391.809986 -288.66592) (xy 393.078982 -288.66592) (xy 393.082942 -288.616866)
			(xy 393.094719 -288.569082) (xy 393.11401 -288.523806) (xy 393.140313 -288.48221) (xy 393.172948 -288.445373)
			(xy 393.211069 -288.414248) (xy 393.25369 -288.389641) (xy 393.299706 -288.372189) (xy 393.347925 -288.362345)
			(xy 393.3971 -288.360364) (xy 393.445955 -288.366296) (xy 393.493226 -288.379988) (xy 393.537688 -288.401086)
			(xy 393.578191 -288.429042) (xy 393.613684 -288.463134) (xy 393.643249 -288.502478) (xy 393.66612 -288.546055)
			(xy 393.681704 -288.592736) (xy 393.689599 -288.641313) (xy 393.690094 -288.66592) (xy 393.689599 -288.690527)
			(xy 393.681704 -288.739104) (xy 393.66612 -288.785785) (xy 393.643249 -288.829362) (xy 393.613684 -288.868706)
			(xy 393.578191 -288.902798) (xy 393.537688 -288.930754) (xy 393.493226 -288.951852) (xy 393.445955 -288.965544)
			(xy 393.3971 -288.971476) (xy 393.347925 -288.969495) (xy 393.299706 -288.959651) (xy 393.25369 -288.942199)
			(xy 393.211069 -288.917592) (xy 393.172948 -288.886467) (xy 393.140313 -288.84963) (xy 393.11401 -288.808034)
			(xy 393.094719 -288.762758) (xy 393.082942 -288.714974) (xy 393.078982 -288.66592) (xy 391.809986 -288.66592)
			(xy 391.809491 -288.690527) (xy 391.801596 -288.739104) (xy 391.786012 -288.785785) (xy 391.763141 -288.829362)
			(xy 391.733576 -288.868706) (xy 391.698083 -288.902798) (xy 391.65758 -288.930754) (xy 391.613118 -288.951852)
			(xy 391.565847 -288.965544) (xy 391.516992 -288.971476) (xy 391.467817 -288.969495) (xy 391.419598 -288.959651)
			(xy 391.373582 -288.942199) (xy 391.330961 -288.917592) (xy 391.29284 -288.886467) (xy 391.260205 -288.84963)
			(xy 391.233902 -288.808034) (xy 391.214611 -288.762758) (xy 391.202834 -288.714974) (xy 391.198874 -288.66592)
			(xy 390.8806 -288.66592) (xy 390.880088 -288.691366) (xy 390.871924 -288.7416) (xy 390.855808 -288.789874)
			(xy 390.832157 -288.834937) (xy 390.801584 -288.875623) (xy 390.76488 -288.910878) (xy 390.722996 -288.939788)
			(xy 390.677017 -288.961605) (xy 390.628133 -288.975765) (xy 390.577612 -288.981899) (xy 390.52676 -288.97985)
			(xy 390.476896 -288.96967) (xy 390.42931 -288.951623) (xy 390.385236 -288.926177) (xy 390.345814 -288.89399)
			(xy 390.312066 -288.855896) (xy 390.284865 -288.812882) (xy 390.264917 -288.766062) (xy 390.252738 -288.716648)
			(xy 390.248643 -288.66592) (xy 389.940546 -288.66592) (xy 389.940034 -288.691366) (xy 389.93187 -288.7416)
			(xy 389.915754 -288.789874) (xy 389.892103 -288.834937) (xy 389.86153 -288.875623) (xy 389.824826 -288.910878)
			(xy 389.782942 -288.939788) (xy 389.736963 -288.961605) (xy 389.688079 -288.975765) (xy 389.637558 -288.981899)
			(xy 389.586706 -288.97985) (xy 389.536842 -288.96967) (xy 389.489256 -288.951623) (xy 389.445182 -288.926177)
			(xy 389.40576 -288.89399) (xy 389.372012 -288.855896) (xy 389.344811 -288.812882) (xy 389.324863 -288.766062)
			(xy 389.312684 -288.716648) (xy 389.308589 -288.66592) (xy 388.990078 -288.66592) (xy 388.989583 -288.690527)
			(xy 388.981688 -288.739104) (xy 388.966104 -288.785785) (xy 388.943233 -288.829362) (xy 388.913668 -288.868706)
			(xy 388.878175 -288.902798) (xy 388.837672 -288.930754) (xy 388.79321 -288.951852) (xy 388.745939 -288.965544)
			(xy 388.697084 -288.971476) (xy 388.647909 -288.969495) (xy 388.59969 -288.959651) (xy 388.553674 -288.942199)
			(xy 388.511053 -288.917592) (xy 388.472932 -288.886467) (xy 388.440297 -288.84963) (xy 388.413994 -288.808034)
			(xy 388.394703 -288.762758) (xy 388.382926 -288.714974) (xy 388.378966 -288.66592) (xy 388.060438 -288.66592)
			(xy 388.059926 -288.691366) (xy 388.051762 -288.7416) (xy 388.035646 -288.789874) (xy 388.011995 -288.834937)
			(xy 387.981422 -288.875623) (xy 387.944718 -288.910878) (xy 387.902834 -288.939788) (xy 387.856855 -288.961605)
			(xy 387.807971 -288.975765) (xy 387.75745 -288.981899) (xy 387.706598 -288.97985) (xy 387.656734 -288.96967)
			(xy 387.609148 -288.951623) (xy 387.565074 -288.926177) (xy 387.525652 -288.89399) (xy 387.491904 -288.855896)
			(xy 387.464703 -288.812882) (xy 387.444755 -288.766062) (xy 387.432576 -288.716648) (xy 387.428481 -288.66592)
			(xy 387.110224 -288.66592) (xy 387.109729 -288.690527) (xy 387.101834 -288.739104) (xy 387.08625 -288.785785)
			(xy 387.063379 -288.829362) (xy 387.033814 -288.868706) (xy 386.998321 -288.902798) (xy 386.957818 -288.930754)
			(xy 386.913356 -288.951852) (xy 386.866085 -288.965544) (xy 386.81723 -288.971476) (xy 386.768055 -288.969495)
			(xy 386.719836 -288.959651) (xy 386.67382 -288.942199) (xy 386.631199 -288.917592) (xy 386.593078 -288.886467)
			(xy 386.560443 -288.84963) (xy 386.53414 -288.808034) (xy 386.514849 -288.762758) (xy 386.503072 -288.714974)
			(xy 386.499112 -288.66592) (xy 386.180584 -288.66592) (xy 386.180072 -288.691366) (xy 386.171908 -288.7416)
			(xy 386.155792 -288.789874) (xy 386.132141 -288.834937) (xy 386.101568 -288.875623) (xy 386.064864 -288.910878)
			(xy 386.02298 -288.939788) (xy 385.977001 -288.961605) (xy 385.928117 -288.975765) (xy 385.877596 -288.981899)
			(xy 385.826744 -288.97985) (xy 385.77688 -288.96967) (xy 385.729294 -288.951623) (xy 385.68522 -288.926177)
			(xy 385.645798 -288.89399) (xy 385.61205 -288.855896) (xy 385.584849 -288.812882) (xy 385.564901 -288.766062)
			(xy 385.552722 -288.716648) (xy 385.548627 -288.66592) (xy 385.230116 -288.66592) (xy 385.229621 -288.690527)
			(xy 385.221726 -288.739104) (xy 385.206142 -288.785785) (xy 385.183271 -288.829362) (xy 385.153706 -288.868706)
			(xy 385.118213 -288.902798) (xy 385.07771 -288.930754) (xy 385.033248 -288.951852) (xy 384.985977 -288.965544)
			(xy 384.937122 -288.971476) (xy 384.887947 -288.969495) (xy 384.839728 -288.959651) (xy 384.793712 -288.942199)
			(xy 384.751091 -288.917592) (xy 384.71297 -288.886467) (xy 384.680335 -288.84963) (xy 384.654032 -288.808034)
			(xy 384.634741 -288.762758) (xy 384.622964 -288.714974) (xy 384.619004 -288.66592) (xy 384.300476 -288.66592)
			(xy 384.299964 -288.691366) (xy 384.2918 -288.7416) (xy 384.275684 -288.789874) (xy 384.252033 -288.834937)
			(xy 384.22146 -288.875623) (xy 384.184756 -288.910878) (xy 384.142872 -288.939788) (xy 384.096893 -288.961605)
			(xy 384.048009 -288.975765) (xy 383.997488 -288.981899) (xy 383.946636 -288.97985) (xy 383.896772 -288.96967)
			(xy 383.849186 -288.951623) (xy 383.805112 -288.926177) (xy 383.76569 -288.89399) (xy 383.731942 -288.855896)
			(xy 383.704741 -288.812882) (xy 383.684793 -288.766062) (xy 383.672614 -288.716648) (xy 383.668519 -288.66592)
			(xy 383.360422 -288.66592) (xy 383.35991 -288.691366) (xy 383.351746 -288.7416) (xy 383.33563 -288.789874)
			(xy 383.311979 -288.834937) (xy 383.281406 -288.875623) (xy 383.244702 -288.910878) (xy 383.202818 -288.939788)
			(xy 383.156839 -288.961605) (xy 383.107955 -288.975765) (xy 383.057434 -288.981899) (xy 383.006582 -288.97985)
			(xy 382.956718 -288.96967) (xy 382.909132 -288.951623) (xy 382.865058 -288.926177) (xy 382.825636 -288.89399)
			(xy 382.791888 -288.855896) (xy 382.764687 -288.812882) (xy 382.744739 -288.766062) (xy 382.73256 -288.716648)
			(xy 382.728465 -288.66592) (xy 382.410208 -288.66592) (xy 382.409713 -288.690527) (xy 382.401818 -288.739104)
			(xy 382.386234 -288.785785) (xy 382.363363 -288.829362) (xy 382.333798 -288.868706) (xy 382.298305 -288.902798)
			(xy 382.257802 -288.930754) (xy 382.21334 -288.951852) (xy 382.166069 -288.965544) (xy 382.117214 -288.971476)
			(xy 382.068039 -288.969495) (xy 382.01982 -288.959651) (xy 381.973804 -288.942199) (xy 381.931183 -288.917592)
			(xy 381.893062 -288.886467) (xy 381.860427 -288.84963) (xy 381.834124 -288.808034) (xy 381.814833 -288.762758)
			(xy 381.803056 -288.714974) (xy 381.799096 -288.66592) (xy 381.480568 -288.66592) (xy 381.480056 -288.691366)
			(xy 381.471892 -288.7416) (xy 381.455776 -288.789874) (xy 381.432125 -288.834937) (xy 381.401552 -288.875623)
			(xy 381.364848 -288.910878) (xy 381.322964 -288.939788) (xy 381.276985 -288.961605) (xy 381.228101 -288.975765)
			(xy 381.17758 -288.981899) (xy 381.126728 -288.97985) (xy 381.076864 -288.96967) (xy 381.029278 -288.951623)
			(xy 380.985204 -288.926177) (xy 380.945782 -288.89399) (xy 380.912034 -288.855896) (xy 380.884833 -288.812882)
			(xy 380.864885 -288.766062) (xy 380.852706 -288.716648) (xy 380.848611 -288.66592) (xy 380.5301 -288.66592)
			(xy 380.529605 -288.690527) (xy 380.52171 -288.739104) (xy 380.506126 -288.785785) (xy 380.483255 -288.829362)
			(xy 380.45369 -288.868706) (xy 380.418197 -288.902798) (xy 380.377694 -288.930754) (xy 380.333232 -288.951852)
			(xy 380.285961 -288.965544) (xy 380.237106 -288.971476) (xy 380.187931 -288.969495) (xy 380.139712 -288.959651)
			(xy 380.093696 -288.942199) (xy 380.051075 -288.917592) (xy 380.012954 -288.886467) (xy 379.980319 -288.84963)
			(xy 379.954016 -288.808034) (xy 379.934725 -288.762758) (xy 379.922948 -288.714974) (xy 379.918988 -288.66592)
			(xy 379.60046 -288.66592) (xy 379.599948 -288.691366) (xy 379.591784 -288.7416) (xy 379.575668 -288.789874)
			(xy 379.552017 -288.834937) (xy 379.521444 -288.875623) (xy 379.48474 -288.910878) (xy 379.442856 -288.939788)
			(xy 379.396877 -288.961605) (xy 379.347993 -288.975765) (xy 379.297472 -288.981899) (xy 379.24662 -288.97985)
			(xy 379.196756 -288.96967) (xy 379.14917 -288.951623) (xy 379.105096 -288.926177) (xy 379.065674 -288.89399)
			(xy 379.031926 -288.855896) (xy 379.004725 -288.812882) (xy 378.984777 -288.766062) (xy 378.972598 -288.716648)
			(xy 378.968503 -288.66592) (xy 378.650246 -288.66592) (xy 378.649751 -288.690527) (xy 378.641856 -288.739104)
			(xy 378.626272 -288.785785) (xy 378.603401 -288.829362) (xy 378.573836 -288.868706) (xy 378.538343 -288.902798)
			(xy 378.49784 -288.930754) (xy 378.453378 -288.951852) (xy 378.406107 -288.965544) (xy 378.357252 -288.971476)
			(xy 378.308077 -288.969495) (xy 378.259858 -288.959651) (xy 378.213842 -288.942199) (xy 378.171221 -288.917592)
			(xy 378.1331 -288.886467) (xy 378.100465 -288.84963) (xy 378.074162 -288.808034) (xy 378.054871 -288.762758)
			(xy 378.043094 -288.714974) (xy 378.039134 -288.66592) (xy 377.720606 -288.66592) (xy 377.720094 -288.691366)
			(xy 377.71193 -288.7416) (xy 377.695814 -288.789874) (xy 377.672163 -288.834937) (xy 377.64159 -288.875623)
			(xy 377.604886 -288.910878) (xy 377.563002 -288.939788) (xy 377.517023 -288.961605) (xy 377.468139 -288.975765)
			(xy 377.417618 -288.981899) (xy 377.366766 -288.97985) (xy 377.316902 -288.96967) (xy 377.269316 -288.951623)
			(xy 377.225242 -288.926177) (xy 377.18582 -288.89399) (xy 377.152072 -288.855896) (xy 377.124871 -288.812882)
			(xy 377.104923 -288.766062) (xy 377.092744 -288.716648) (xy 377.088649 -288.66592) (xy 376.780552 -288.66592)
			(xy 376.78004 -288.691366) (xy 376.771876 -288.7416) (xy 376.75576 -288.789874) (xy 376.732109 -288.834937)
			(xy 376.701536 -288.875623) (xy 376.664832 -288.910878) (xy 376.622948 -288.939788) (xy 376.576969 -288.961605)
			(xy 376.528085 -288.975765) (xy 376.477564 -288.981899) (xy 376.426712 -288.97985) (xy 376.376848 -288.96967)
			(xy 376.329262 -288.951623) (xy 376.285188 -288.926177) (xy 376.245766 -288.89399) (xy 376.212018 -288.855896)
			(xy 376.184817 -288.812882) (xy 376.164869 -288.766062) (xy 376.15269 -288.716648) (xy 376.148595 -288.66592)
			(xy 375.1961 -288.66592) (xy 375.1961 -289.175952) (xy 375.196372 -289.184483) (xy 375.201897 -289.200621)
			(xy 375.212446 -289.214027) (xy 375.219468 -289.218878) (xy 375.240686 -289.233082) (xy 375.2785 -289.267387)
			(xy 375.310088 -289.307499) (xy 375.334571 -289.352303) (xy 375.351267 -289.400552) (xy 375.359714 -289.450905)
			(xy 375.360175 -289.475926) (xy 375.678695 -289.475926) (xy 375.68279 -289.425198) (xy 375.694969 -289.375784)
			(xy 375.714917 -289.328964) (xy 375.742118 -289.28595) (xy 375.775866 -289.247856) (xy 375.815288 -289.215669)
			(xy 375.859362 -289.190223) (xy 375.906948 -289.172176) (xy 375.956812 -289.161996) (xy 376.007664 -289.159947)
			(xy 376.058185 -289.166081) (xy 376.107069 -289.180241) (xy 376.153048 -289.202058) (xy 376.194932 -289.230968)
			(xy 376.231636 -289.266223) (xy 376.262209 -289.306909) (xy 376.28586 -289.351972) (xy 376.301976 -289.400246)
			(xy 376.31014 -289.45048) (xy 376.310652 -289.475926) (xy 376.628926 -289.475926) (xy 376.632886 -289.426872)
			(xy 376.644663 -289.379088) (xy 376.663954 -289.333812) (xy 376.690257 -289.292216) (xy 376.722892 -289.255379)
			(xy 376.761013 -289.224254) (xy 376.803634 -289.199647) (xy 376.84965 -289.182195) (xy 376.897869 -289.172351)
			(xy 376.947044 -289.17037) (xy 376.995899 -289.176302) (xy 377.04317 -289.189994) (xy 377.087632 -289.211092)
			(xy 377.128135 -289.239048) (xy 377.163628 -289.27314) (xy 377.193193 -289.312484) (xy 377.216064 -289.356061)
			(xy 377.231648 -289.402742) (xy 377.239543 -289.451319) (xy 377.240038 -289.475926) (xy 377.558549 -289.475926)
			(xy 377.562644 -289.425198) (xy 377.574823 -289.375784) (xy 377.594771 -289.328964) (xy 377.621972 -289.28595)
			(xy 377.65572 -289.247856) (xy 377.695142 -289.215669) (xy 377.739216 -289.190223) (xy 377.786802 -289.172176)
			(xy 377.836666 -289.161996) (xy 377.887518 -289.159947) (xy 377.938039 -289.166081) (xy 377.986923 -289.180241)
			(xy 378.032902 -289.202058) (xy 378.074786 -289.230968) (xy 378.11149 -289.266223) (xy 378.142063 -289.306909)
			(xy 378.165714 -289.351972) (xy 378.18183 -289.400246) (xy 378.189994 -289.45048) (xy 378.190506 -289.475926)
			(xy 378.509034 -289.475926) (xy 378.512994 -289.426872) (xy 378.524771 -289.379088) (xy 378.544062 -289.333812)
			(xy 378.570365 -289.292216) (xy 378.603 -289.255379) (xy 378.641121 -289.224254) (xy 378.683742 -289.199647)
			(xy 378.729758 -289.182195) (xy 378.777977 -289.172351) (xy 378.827152 -289.17037) (xy 378.876007 -289.176302)
			(xy 378.923278 -289.189994) (xy 378.96774 -289.211092) (xy 379.008243 -289.239048) (xy 379.043736 -289.27314)
			(xy 379.073301 -289.312484) (xy 379.096172 -289.356061) (xy 379.111756 -289.402742) (xy 379.119651 -289.451319)
			(xy 379.120146 -289.475926) (xy 379.438657 -289.475926) (xy 379.442752 -289.425198) (xy 379.454931 -289.375784)
			(xy 379.474879 -289.328964) (xy 379.50208 -289.28595) (xy 379.535828 -289.247856) (xy 379.57525 -289.215669)
			(xy 379.619324 -289.190223) (xy 379.66691 -289.172176) (xy 379.716774 -289.161996) (xy 379.767626 -289.159947)
			(xy 379.818147 -289.166081) (xy 379.867031 -289.180241) (xy 379.91301 -289.202058) (xy 379.954894 -289.230968)
			(xy 379.991598 -289.266223) (xy 380.022171 -289.306909) (xy 380.045822 -289.351972) (xy 380.061938 -289.400246)
			(xy 380.070102 -289.45048) (xy 380.070614 -289.475926) (xy 380.378711 -289.475926) (xy 380.382806 -289.425198)
			(xy 380.394985 -289.375784) (xy 380.414933 -289.328964) (xy 380.442134 -289.28595) (xy 380.475882 -289.247856)
			(xy 380.515304 -289.215669) (xy 380.559378 -289.190223) (xy 380.606964 -289.172176) (xy 380.656828 -289.161996)
			(xy 380.70768 -289.159947) (xy 380.758201 -289.166081) (xy 380.807085 -289.180241) (xy 380.853064 -289.202058)
			(xy 380.894948 -289.230968) (xy 380.931652 -289.266223) (xy 380.962225 -289.306909) (xy 380.985876 -289.351972)
			(xy 381.001992 -289.400246) (xy 381.010156 -289.45048) (xy 381.010668 -289.475926) (xy 381.328942 -289.475926)
			(xy 381.332902 -289.426872) (xy 381.344679 -289.379088) (xy 381.36397 -289.333812) (xy 381.390273 -289.292216)
			(xy 381.422908 -289.255379) (xy 381.461029 -289.224254) (xy 381.50365 -289.199647) (xy 381.549666 -289.182195)
			(xy 381.597885 -289.172351) (xy 381.64706 -289.17037) (xy 381.695915 -289.176302) (xy 381.743186 -289.189994)
			(xy 381.787648 -289.211092) (xy 381.828151 -289.239048) (xy 381.863644 -289.27314) (xy 381.893209 -289.312484)
			(xy 381.91608 -289.356061) (xy 381.931664 -289.402742) (xy 381.939559 -289.451319) (xy 381.940054 -289.475926)
			(xy 382.258565 -289.475926) (xy 382.26266 -289.425198) (xy 382.274839 -289.375784) (xy 382.294787 -289.328964)
			(xy 382.321988 -289.28595) (xy 382.355736 -289.247856) (xy 382.395158 -289.215669) (xy 382.439232 -289.190223)
			(xy 382.486818 -289.172176) (xy 382.536682 -289.161996) (xy 382.587534 -289.159947) (xy 382.638055 -289.166081)
			(xy 382.686939 -289.180241) (xy 382.732918 -289.202058) (xy 382.774802 -289.230968) (xy 382.811506 -289.266223)
			(xy 382.842079 -289.306909) (xy 382.86573 -289.351972) (xy 382.881846 -289.400246) (xy 382.89001 -289.45048)
			(xy 382.890522 -289.475926) (xy 383.20905 -289.475926) (xy 383.21301 -289.426872) (xy 383.224787 -289.379088)
			(xy 383.244078 -289.333812) (xy 383.270381 -289.292216) (xy 383.303016 -289.255379) (xy 383.341137 -289.224254)
			(xy 383.383758 -289.199647) (xy 383.429774 -289.182195) (xy 383.477993 -289.172351) (xy 383.527168 -289.17037)
			(xy 383.576023 -289.176302) (xy 383.623294 -289.189994) (xy 383.667756 -289.211092) (xy 383.708259 -289.239048)
			(xy 383.743752 -289.27314) (xy 383.773317 -289.312484) (xy 383.796188 -289.356061) (xy 383.811772 -289.402742)
			(xy 383.819667 -289.451319) (xy 383.820162 -289.475926) (xy 384.138673 -289.475926) (xy 384.142768 -289.425198)
			(xy 384.154947 -289.375784) (xy 384.174895 -289.328964) (xy 384.202096 -289.28595) (xy 384.235844 -289.247856)
			(xy 384.275266 -289.215669) (xy 384.31934 -289.190223) (xy 384.366926 -289.172176) (xy 384.41679 -289.161996)
			(xy 384.467642 -289.159947) (xy 384.518163 -289.166081) (xy 384.567047 -289.180241) (xy 384.613026 -289.202058)
			(xy 384.65491 -289.230968) (xy 384.691614 -289.266223) (xy 384.722187 -289.306909) (xy 384.745838 -289.351972)
			(xy 384.761954 -289.400246) (xy 384.770118 -289.45048) (xy 384.77063 -289.475926) (xy 385.088904 -289.475926)
			(xy 385.092864 -289.426872) (xy 385.104641 -289.379088) (xy 385.123932 -289.333812) (xy 385.150235 -289.292216)
			(xy 385.18287 -289.255379) (xy 385.220991 -289.224254) (xy 385.263612 -289.199647) (xy 385.309628 -289.182195)
			(xy 385.357847 -289.172351) (xy 385.407022 -289.17037) (xy 385.455877 -289.176302) (xy 385.503148 -289.189994)
			(xy 385.54761 -289.211092) (xy 385.588113 -289.239048) (xy 385.623606 -289.27314) (xy 385.653171 -289.312484)
			(xy 385.676042 -289.356061) (xy 385.691626 -289.402742) (xy 385.699521 -289.451319) (xy 385.700016 -289.475926)
			(xy 386.018527 -289.475926) (xy 386.022622 -289.425198) (xy 386.034801 -289.375784) (xy 386.054749 -289.328964)
			(xy 386.08195 -289.28595) (xy 386.115698 -289.247856) (xy 386.15512 -289.215669) (xy 386.199194 -289.190223)
			(xy 386.24678 -289.172176) (xy 386.296644 -289.161996) (xy 386.347496 -289.159947) (xy 386.398017 -289.166081)
			(xy 386.446901 -289.180241) (xy 386.49288 -289.202058) (xy 386.534764 -289.230968) (xy 386.571468 -289.266223)
			(xy 386.602041 -289.306909) (xy 386.625692 -289.351972) (xy 386.641808 -289.400246) (xy 386.649972 -289.45048)
			(xy 386.650484 -289.475926) (xy 386.958581 -289.475926) (xy 386.962676 -289.425198) (xy 386.974855 -289.375784)
			(xy 386.994803 -289.328964) (xy 387.022004 -289.28595) (xy 387.055752 -289.247856) (xy 387.095174 -289.215669)
			(xy 387.139248 -289.190223) (xy 387.186834 -289.172176) (xy 387.236698 -289.161996) (xy 387.28755 -289.159947)
			(xy 387.338071 -289.166081) (xy 387.386955 -289.180241) (xy 387.432934 -289.202058) (xy 387.474818 -289.230968)
			(xy 387.511522 -289.266223) (xy 387.542095 -289.306909) (xy 387.565746 -289.351972) (xy 387.581862 -289.400246)
			(xy 387.590026 -289.45048) (xy 387.590538 -289.475926) (xy 387.909066 -289.475926) (xy 387.913026 -289.426872)
			(xy 387.924803 -289.379088) (xy 387.944094 -289.333812) (xy 387.970397 -289.292216) (xy 388.003032 -289.255379)
			(xy 388.041153 -289.224254) (xy 388.083774 -289.199647) (xy 388.12979 -289.182195) (xy 388.178009 -289.172351)
			(xy 388.227184 -289.17037) (xy 388.276039 -289.176302) (xy 388.32331 -289.189994) (xy 388.367772 -289.211092)
			(xy 388.408275 -289.239048) (xy 388.443768 -289.27314) (xy 388.473333 -289.312484) (xy 388.496204 -289.356061)
			(xy 388.511788 -289.402742) (xy 388.519683 -289.451319) (xy 388.520178 -289.475926) (xy 388.838689 -289.475926)
			(xy 388.842784 -289.425198) (xy 388.854963 -289.375784) (xy 388.874911 -289.328964) (xy 388.902112 -289.28595)
			(xy 388.93586 -289.247856) (xy 388.975282 -289.215669) (xy 389.019356 -289.190223) (xy 389.066942 -289.172176)
			(xy 389.116806 -289.161996) (xy 389.167658 -289.159947) (xy 389.218179 -289.166081) (xy 389.267063 -289.180241)
			(xy 389.313042 -289.202058) (xy 389.354926 -289.230968) (xy 389.39163 -289.266223) (xy 389.422203 -289.306909)
			(xy 389.445854 -289.351972) (xy 389.46197 -289.400246) (xy 389.470134 -289.45048) (xy 389.470646 -289.475926)
			(xy 389.78892 -289.475926) (xy 389.79288 -289.426872) (xy 389.804657 -289.379088) (xy 389.823948 -289.333812)
			(xy 389.850251 -289.292216) (xy 389.882886 -289.255379) (xy 389.921007 -289.224254) (xy 389.963628 -289.199647)
			(xy 390.009644 -289.182195) (xy 390.057863 -289.172351) (xy 390.107038 -289.17037) (xy 390.155893 -289.176302)
			(xy 390.203164 -289.189994) (xy 390.247626 -289.211092) (xy 390.288129 -289.239048) (xy 390.323622 -289.27314)
			(xy 390.353187 -289.312484) (xy 390.376058 -289.356061) (xy 390.391642 -289.402742) (xy 390.399537 -289.451319)
			(xy 390.400032 -289.475926) (xy 390.718543 -289.475926) (xy 390.722638 -289.425198) (xy 390.734817 -289.375784)
			(xy 390.754765 -289.328964) (xy 390.781966 -289.28595) (xy 390.815714 -289.247856) (xy 390.855136 -289.215669)
			(xy 390.89921 -289.190223) (xy 390.946796 -289.172176) (xy 390.99666 -289.161996) (xy 391.047512 -289.159947)
			(xy 391.098033 -289.166081) (xy 391.146917 -289.180241) (xy 391.192896 -289.202058) (xy 391.23478 -289.230968)
			(xy 391.271484 -289.266223) (xy 391.302057 -289.306909) (xy 391.325708 -289.351972) (xy 391.341824 -289.400246)
			(xy 391.349988 -289.45048) (xy 391.3505 -289.475926) (xy 391.669028 -289.475926) (xy 391.672988 -289.426872)
			(xy 391.684765 -289.379088) (xy 391.704056 -289.333812) (xy 391.730359 -289.292216) (xy 391.762994 -289.255379)
			(xy 391.801115 -289.224254) (xy 391.843736 -289.199647) (xy 391.889752 -289.182195) (xy 391.937971 -289.172351)
			(xy 391.987146 -289.17037) (xy 392.036001 -289.176302) (xy 392.083272 -289.189994) (xy 392.125407 -289.209988)
			(xy 394.67715 -289.209988) (xy 394.68111 -289.160934) (xy 394.692887 -289.11315) (xy 394.712178 -289.067874)
			(xy 394.738481 -289.026278) (xy 394.771116 -288.989441) (xy 394.809237 -288.958316) (xy 394.851858 -288.933709)
			(xy 394.897874 -288.916257) (xy 394.946093 -288.906413) (xy 394.995268 -288.904432) (xy 395.044123 -288.910364)
			(xy 395.091394 -288.924056) (xy 395.135856 -288.945154) (xy 395.176359 -288.97311) (xy 395.211852 -289.007202)
			(xy 395.241417 -289.046546) (xy 395.264288 -289.090123) (xy 395.279872 -289.136804) (xy 395.287767 -289.185381)
			(xy 395.288262 -289.209988) (xy 395.287767 -289.234595) (xy 395.279872 -289.283172) (xy 395.264288 -289.329853)
			(xy 395.241417 -289.37343) (xy 395.211852 -289.412774) (xy 395.176359 -289.446866) (xy 395.135856 -289.474822)
			(xy 395.091394 -289.49592) (xy 395.044123 -289.509612) (xy 394.995268 -289.515544) (xy 394.946093 -289.513563)
			(xy 394.897874 -289.503719) (xy 394.851858 -289.486267) (xy 394.809237 -289.46166) (xy 394.771116 -289.430535)
			(xy 394.738481 -289.393698) (xy 394.712178 -289.352102) (xy 394.692887 -289.306826) (xy 394.68111 -289.259042)
			(xy 394.67715 -289.209988) (xy 392.125407 -289.209988) (xy 392.127734 -289.211092) (xy 392.168237 -289.239048)
			(xy 392.20373 -289.27314) (xy 392.233295 -289.312484) (xy 392.256166 -289.356061) (xy 392.27175 -289.402742)
			(xy 392.279645 -289.451319) (xy 392.28014 -289.475926) (xy 392.279645 -289.500533) (xy 392.27175 -289.54911)
			(xy 392.256166 -289.595791) (xy 392.233295 -289.639368) (xy 392.20373 -289.678712) (xy 392.168237 -289.712804)
			(xy 392.127734 -289.74076) (xy 392.083272 -289.761858) (xy 392.036001 -289.77555) (xy 391.987146 -289.781482)
			(xy 391.937971 -289.779501) (xy 391.889752 -289.769657) (xy 391.843736 -289.752205) (xy 391.801115 -289.727598)
			(xy 391.762994 -289.696473) (xy 391.730359 -289.659636) (xy 391.704056 -289.61804) (xy 391.684765 -289.572764)
			(xy 391.672988 -289.52498) (xy 391.669028 -289.475926) (xy 391.3505 -289.475926) (xy 391.349988 -289.501372)
			(xy 391.341824 -289.551606) (xy 391.325708 -289.59988) (xy 391.302057 -289.644943) (xy 391.271484 -289.685629)
			(xy 391.23478 -289.720884) (xy 391.192896 -289.749794) (xy 391.146917 -289.771611) (xy 391.098033 -289.785771)
			(xy 391.047512 -289.791905) (xy 390.99666 -289.789856) (xy 390.946796 -289.779676) (xy 390.89921 -289.761629)
			(xy 390.855136 -289.736183) (xy 390.815714 -289.703996) (xy 390.781966 -289.665902) (xy 390.754765 -289.622888)
			(xy 390.734817 -289.576068) (xy 390.722638 -289.526654) (xy 390.718543 -289.475926) (xy 390.400032 -289.475926)
			(xy 390.399537 -289.500533) (xy 390.391642 -289.54911) (xy 390.376058 -289.595791) (xy 390.353187 -289.639368)
			(xy 390.323622 -289.678712) (xy 390.288129 -289.712804) (xy 390.247626 -289.74076) (xy 390.203164 -289.761858)
			(xy 390.155893 -289.77555) (xy 390.107038 -289.781482) (xy 390.057863 -289.779501) (xy 390.009644 -289.769657)
			(xy 389.963628 -289.752205) (xy 389.921007 -289.727598) (xy 389.882886 -289.696473) (xy 389.850251 -289.659636)
			(xy 389.823948 -289.61804) (xy 389.804657 -289.572764) (xy 389.79288 -289.52498) (xy 389.78892 -289.475926)
			(xy 389.470646 -289.475926) (xy 389.470134 -289.501372) (xy 389.46197 -289.551606) (xy 389.445854 -289.59988)
			(xy 389.422203 -289.644943) (xy 389.39163 -289.685629) (xy 389.354926 -289.720884) (xy 389.313042 -289.749794)
			(xy 389.267063 -289.771611) (xy 389.218179 -289.785771) (xy 389.167658 -289.791905) (xy 389.116806 -289.789856)
			(xy 389.066942 -289.779676) (xy 389.019356 -289.761629) (xy 388.975282 -289.736183) (xy 388.93586 -289.703996)
			(xy 388.902112 -289.665902) (xy 388.874911 -289.622888) (xy 388.854963 -289.576068) (xy 388.842784 -289.526654)
			(xy 388.838689 -289.475926) (xy 388.520178 -289.475926) (xy 388.519683 -289.500533) (xy 388.511788 -289.54911)
			(xy 388.496204 -289.595791) (xy 388.473333 -289.639368) (xy 388.443768 -289.678712) (xy 388.408275 -289.712804)
			(xy 388.367772 -289.74076) (xy 388.32331 -289.761858) (xy 388.276039 -289.77555) (xy 388.227184 -289.781482)
			(xy 388.178009 -289.779501) (xy 388.12979 -289.769657) (xy 388.083774 -289.752205) (xy 388.041153 -289.727598)
			(xy 388.003032 -289.696473) (xy 387.970397 -289.659636) (xy 387.944094 -289.61804) (xy 387.924803 -289.572764)
			(xy 387.913026 -289.52498) (xy 387.909066 -289.475926) (xy 387.590538 -289.475926) (xy 387.590026 -289.501372)
			(xy 387.581862 -289.551606) (xy 387.565746 -289.59988) (xy 387.542095 -289.644943) (xy 387.511522 -289.685629)
			(xy 387.474818 -289.720884) (xy 387.432934 -289.749794) (xy 387.386955 -289.771611) (xy 387.338071 -289.785771)
			(xy 387.28755 -289.791905) (xy 387.236698 -289.789856) (xy 387.186834 -289.779676) (xy 387.139248 -289.761629)
			(xy 387.095174 -289.736183) (xy 387.055752 -289.703996) (xy 387.022004 -289.665902) (xy 386.994803 -289.622888)
			(xy 386.974855 -289.576068) (xy 386.962676 -289.526654) (xy 386.958581 -289.475926) (xy 386.650484 -289.475926)
			(xy 386.649972 -289.501372) (xy 386.641808 -289.551606) (xy 386.625692 -289.59988) (xy 386.602041 -289.644943)
			(xy 386.571468 -289.685629) (xy 386.534764 -289.720884) (xy 386.49288 -289.749794) (xy 386.446901 -289.771611)
			(xy 386.398017 -289.785771) (xy 386.347496 -289.791905) (xy 386.296644 -289.789856) (xy 386.24678 -289.779676)
			(xy 386.199194 -289.761629) (xy 386.15512 -289.736183) (xy 386.115698 -289.703996) (xy 386.08195 -289.665902)
			(xy 386.054749 -289.622888) (xy 386.034801 -289.576068) (xy 386.022622 -289.526654) (xy 386.018527 -289.475926)
			(xy 385.700016 -289.475926) (xy 385.699521 -289.500533) (xy 385.691626 -289.54911) (xy 385.676042 -289.595791)
			(xy 385.653171 -289.639368) (xy 385.623606 -289.678712) (xy 385.588113 -289.712804) (xy 385.54761 -289.74076)
			(xy 385.503148 -289.761858) (xy 385.455877 -289.77555) (xy 385.407022 -289.781482) (xy 385.357847 -289.779501)
			(xy 385.309628 -289.769657) (xy 385.263612 -289.752205) (xy 385.220991 -289.727598) (xy 385.18287 -289.696473)
			(xy 385.150235 -289.659636) (xy 385.123932 -289.61804) (xy 385.104641 -289.572764) (xy 385.092864 -289.52498)
			(xy 385.088904 -289.475926) (xy 384.77063 -289.475926) (xy 384.770118 -289.501372) (xy 384.761954 -289.551606)
			(xy 384.745838 -289.59988) (xy 384.722187 -289.644943) (xy 384.691614 -289.685629) (xy 384.65491 -289.720884)
			(xy 384.613026 -289.749794) (xy 384.567047 -289.771611) (xy 384.518163 -289.785771) (xy 384.467642 -289.791905)
			(xy 384.41679 -289.789856) (xy 384.366926 -289.779676) (xy 384.31934 -289.761629) (xy 384.275266 -289.736183)
			(xy 384.235844 -289.703996) (xy 384.202096 -289.665902) (xy 384.174895 -289.622888) (xy 384.154947 -289.576068)
			(xy 384.142768 -289.526654) (xy 384.138673 -289.475926) (xy 383.820162 -289.475926) (xy 383.819667 -289.500533)
			(xy 383.811772 -289.54911) (xy 383.796188 -289.595791) (xy 383.773317 -289.639368) (xy 383.743752 -289.678712)
			(xy 383.708259 -289.712804) (xy 383.667756 -289.74076) (xy 383.623294 -289.761858) (xy 383.576023 -289.77555)
			(xy 383.527168 -289.781482) (xy 383.477993 -289.779501) (xy 383.429774 -289.769657) (xy 383.383758 -289.752205)
			(xy 383.341137 -289.727598) (xy 383.303016 -289.696473) (xy 383.270381 -289.659636) (xy 383.244078 -289.61804)
			(xy 383.224787 -289.572764) (xy 383.21301 -289.52498) (xy 383.20905 -289.475926) (xy 382.890522 -289.475926)
			(xy 382.89001 -289.501372) (xy 382.881846 -289.551606) (xy 382.86573 -289.59988) (xy 382.842079 -289.644943)
			(xy 382.811506 -289.685629) (xy 382.774802 -289.720884) (xy 382.732918 -289.749794) (xy 382.686939 -289.771611)
			(xy 382.638055 -289.785771) (xy 382.587534 -289.791905) (xy 382.536682 -289.789856) (xy 382.486818 -289.779676)
			(xy 382.439232 -289.761629) (xy 382.395158 -289.736183) (xy 382.355736 -289.703996) (xy 382.321988 -289.665902)
			(xy 382.294787 -289.622888) (xy 382.274839 -289.576068) (xy 382.26266 -289.526654) (xy 382.258565 -289.475926)
			(xy 381.940054 -289.475926) (xy 381.939559 -289.500533) (xy 381.931664 -289.54911) (xy 381.91608 -289.595791)
			(xy 381.893209 -289.639368) (xy 381.863644 -289.678712) (xy 381.828151 -289.712804) (xy 381.787648 -289.74076)
			(xy 381.743186 -289.761858) (xy 381.695915 -289.77555) (xy 381.64706 -289.781482) (xy 381.597885 -289.779501)
			(xy 381.549666 -289.769657) (xy 381.50365 -289.752205) (xy 381.461029 -289.727598) (xy 381.422908 -289.696473)
			(xy 381.390273 -289.659636) (xy 381.36397 -289.61804) (xy 381.344679 -289.572764) (xy 381.332902 -289.52498)
			(xy 381.328942 -289.475926) (xy 381.010668 -289.475926) (xy 381.010156 -289.501372) (xy 381.001992 -289.551606)
			(xy 380.985876 -289.59988) (xy 380.962225 -289.644943) (xy 380.931652 -289.685629) (xy 380.894948 -289.720884)
			(xy 380.853064 -289.749794) (xy 380.807085 -289.771611) (xy 380.758201 -289.785771) (xy 380.70768 -289.791905)
			(xy 380.656828 -289.789856) (xy 380.606964 -289.779676) (xy 380.559378 -289.761629) (xy 380.515304 -289.736183)
			(xy 380.475882 -289.703996) (xy 380.442134 -289.665902) (xy 380.414933 -289.622888) (xy 380.394985 -289.576068)
			(xy 380.382806 -289.526654) (xy 380.378711 -289.475926) (xy 380.070614 -289.475926) (xy 380.070102 -289.501372)
			(xy 380.061938 -289.551606) (xy 380.045822 -289.59988) (xy 380.022171 -289.644943) (xy 379.991598 -289.685629)
			(xy 379.954894 -289.720884) (xy 379.91301 -289.749794) (xy 379.867031 -289.771611) (xy 379.818147 -289.785771)
			(xy 379.767626 -289.791905) (xy 379.716774 -289.789856) (xy 379.66691 -289.779676) (xy 379.619324 -289.761629)
			(xy 379.57525 -289.736183) (xy 379.535828 -289.703996) (xy 379.50208 -289.665902) (xy 379.474879 -289.622888)
			(xy 379.454931 -289.576068) (xy 379.442752 -289.526654) (xy 379.438657 -289.475926) (xy 379.120146 -289.475926)
			(xy 379.119651 -289.500533) (xy 379.111756 -289.54911) (xy 379.096172 -289.595791) (xy 379.073301 -289.639368)
			(xy 379.043736 -289.678712) (xy 379.008243 -289.712804) (xy 378.96774 -289.74076) (xy 378.923278 -289.761858)
			(xy 378.876007 -289.77555) (xy 378.827152 -289.781482) (xy 378.777977 -289.779501) (xy 378.729758 -289.769657)
			(xy 378.683742 -289.752205) (xy 378.641121 -289.727598) (xy 378.603 -289.696473) (xy 378.570365 -289.659636)
			(xy 378.544062 -289.61804) (xy 378.524771 -289.572764) (xy 378.512994 -289.52498) (xy 378.509034 -289.475926)
			(xy 378.190506 -289.475926) (xy 378.189994 -289.501372) (xy 378.18183 -289.551606) (xy 378.165714 -289.59988)
			(xy 378.142063 -289.644943) (xy 378.11149 -289.685629) (xy 378.074786 -289.720884) (xy 378.032902 -289.749794)
			(xy 377.986923 -289.771611) (xy 377.938039 -289.785771) (xy 377.887518 -289.791905) (xy 377.836666 -289.789856)
			(xy 377.786802 -289.779676) (xy 377.739216 -289.761629) (xy 377.695142 -289.736183) (xy 377.65572 -289.703996)
			(xy 377.621972 -289.665902) (xy 377.594771 -289.622888) (xy 377.574823 -289.576068) (xy 377.562644 -289.526654)
			(xy 377.558549 -289.475926) (xy 377.240038 -289.475926) (xy 377.239543 -289.500533) (xy 377.231648 -289.54911)
			(xy 377.216064 -289.595791) (xy 377.193193 -289.639368) (xy 377.163628 -289.678712) (xy 377.128135 -289.712804)
			(xy 377.087632 -289.74076) (xy 377.04317 -289.761858) (xy 376.995899 -289.77555) (xy 376.947044 -289.781482)
			(xy 376.897869 -289.779501) (xy 376.84965 -289.769657) (xy 376.803634 -289.752205) (xy 376.761013 -289.727598)
			(xy 376.722892 -289.696473) (xy 376.690257 -289.659636) (xy 376.663954 -289.61804) (xy 376.644663 -289.572764)
			(xy 376.632886 -289.52498) (xy 376.628926 -289.475926) (xy 376.310652 -289.475926) (xy 376.31014 -289.501372)
			(xy 376.301976 -289.551606) (xy 376.28586 -289.59988) (xy 376.262209 -289.644943) (xy 376.231636 -289.685629)
			(xy 376.194932 -289.720884) (xy 376.153048 -289.749794) (xy 376.107069 -289.771611) (xy 376.058185 -289.785771)
			(xy 376.007664 -289.791905) (xy 375.956812 -289.789856) (xy 375.906948 -289.779676) (xy 375.859362 -289.761629)
			(xy 375.815288 -289.736183) (xy 375.775866 -289.703996) (xy 375.742118 -289.665902) (xy 375.714917 -289.622888)
			(xy 375.694969 -289.576068) (xy 375.68279 -289.526654) (xy 375.678695 -289.475926) (xy 375.360175 -289.475926)
			(xy 375.360184 -289.476434) (xy 375.360184 -289.47999) (xy 375.359739 -289.496332) (xy 375.355796 -289.528788)
			(xy 375.35231 -289.54476) (xy 375.35231 -289.545014) (xy 375.350655 -289.55348) (xy 375.352488 -289.57062)
			(xy 375.359921 -289.586173) (xy 375.365772 -289.592512) (xy 376.002804 -290.229544) (xy 376.009157 -290.235367)
			(xy 376.02471 -290.242764) (xy 376.041833 -290.244609) (xy 376.050302 -290.243006) (xy 376.140472 -290.22167)
			(xy 376.159776 -290.203636) (xy 376.164094 -290.190682) (xy 376.172073 -290.167051) (xy 376.194424 -290.122465)
			(xy 376.223513 -290.081951) (xy 376.258615 -290.046521) (xy 376.298856 -290.017056) (xy 376.343233 -289.994291)
			(xy 376.390638 -289.978793) (xy 376.439893 -289.970949) (xy 376.46483 -289.970464) (xy 376.489626 -289.970952)
			(xy 376.538607 -289.97871) (xy 376.585773 -289.99403) (xy 376.629963 -290.016536) (xy 376.670092 -290.045674)
			(xy 376.705172 -290.080727) (xy 376.73434 -290.120834) (xy 376.756879 -290.165007) (xy 376.772234 -290.212162)
			(xy 376.780029 -290.261137) (xy 376.780552 -290.285932) (xy 377.088649 -290.285932) (xy 377.092744 -290.235204)
			(xy 377.104923 -290.18579) (xy 377.124871 -290.13897) (xy 377.152072 -290.095956) (xy 377.18582 -290.057862)
			(xy 377.225242 -290.025675) (xy 377.269316 -290.000229) (xy 377.316902 -289.982182) (xy 377.366766 -289.972002)
			(xy 377.417618 -289.969953) (xy 377.468139 -289.976087) (xy 377.517023 -289.990247) (xy 377.563002 -290.012064)
			(xy 377.604886 -290.040974) (xy 377.64159 -290.076229) (xy 377.672163 -290.116915) (xy 377.695814 -290.161978)
			(xy 377.71193 -290.210252) (xy 377.720094 -290.260486) (xy 377.720606 -290.285932) (xy 378.968503 -290.285932)
			(xy 378.972598 -290.235204) (xy 378.984777 -290.18579) (xy 379.004725 -290.13897) (xy 379.031926 -290.095956)
			(xy 379.065674 -290.057862) (xy 379.105096 -290.025675) (xy 379.14917 -290.000229) (xy 379.196756 -289.982182)
			(xy 379.24662 -289.972002) (xy 379.297472 -289.969953) (xy 379.347993 -289.976087) (xy 379.396877 -289.990247)
			(xy 379.442856 -290.012064) (xy 379.48474 -290.040974) (xy 379.521444 -290.076229) (xy 379.552017 -290.116915)
			(xy 379.575668 -290.161978) (xy 379.591784 -290.210252) (xy 379.599948 -290.260486) (xy 379.60046 -290.285932)
			(xy 379.918988 -290.285932) (xy 379.922948 -290.236878) (xy 379.934725 -290.189094) (xy 379.954016 -290.143818)
			(xy 379.980319 -290.102222) (xy 380.012954 -290.065385) (xy 380.051075 -290.03426) (xy 380.093696 -290.009653)
			(xy 380.139712 -289.992201) (xy 380.187931 -289.982357) (xy 380.237106 -289.980376) (xy 380.285961 -289.986308)
			(xy 380.333232 -290) (xy 380.377694 -290.021098) (xy 380.418197 -290.049054) (xy 380.45369 -290.083146)
			(xy 380.483255 -290.12249) (xy 380.506126 -290.166067) (xy 380.52171 -290.212748) (xy 380.529605 -290.261325)
			(xy 380.5301 -290.285932) (xy 380.848611 -290.285932) (xy 380.852706 -290.235204) (xy 380.864885 -290.18579)
			(xy 380.884833 -290.13897) (xy 380.912034 -290.095956) (xy 380.945782 -290.057862) (xy 380.985204 -290.025675)
			(xy 381.029278 -290.000229) (xy 381.076864 -289.982182) (xy 381.126728 -289.972002) (xy 381.17758 -289.969953)
			(xy 381.228101 -289.976087) (xy 381.276985 -289.990247) (xy 381.322964 -290.012064) (xy 381.364848 -290.040974)
			(xy 381.401552 -290.076229) (xy 381.432125 -290.116915) (xy 381.455776 -290.161978) (xy 381.471892 -290.210252)
			(xy 381.480056 -290.260486) (xy 381.480568 -290.285932) (xy 381.799096 -290.285932) (xy 381.803056 -290.236878)
			(xy 381.814833 -290.189094) (xy 381.834124 -290.143818) (xy 381.860427 -290.102222) (xy 381.893062 -290.065385)
			(xy 381.931183 -290.03426) (xy 381.973804 -290.009653) (xy 382.01982 -289.992201) (xy 382.068039 -289.982357)
			(xy 382.117214 -289.980376) (xy 382.166069 -289.986308) (xy 382.21334 -290) (xy 382.257802 -290.021098)
			(xy 382.298305 -290.049054) (xy 382.333798 -290.083146) (xy 382.363363 -290.12249) (xy 382.386234 -290.166067)
			(xy 382.401818 -290.212748) (xy 382.409713 -290.261325) (xy 382.410208 -290.285932) (xy 382.728465 -290.285932)
			(xy 382.73256 -290.235204) (xy 382.744739 -290.18579) (xy 382.764687 -290.13897) (xy 382.791888 -290.095956)
			(xy 382.825636 -290.057862) (xy 382.865058 -290.025675) (xy 382.909132 -290.000229) (xy 382.956718 -289.982182)
			(xy 383.006582 -289.972002) (xy 383.057434 -289.969953) (xy 383.107955 -289.976087) (xy 383.156839 -289.990247)
			(xy 383.202818 -290.012064) (xy 383.244702 -290.040974) (xy 383.281406 -290.076229) (xy 383.311979 -290.116915)
			(xy 383.33563 -290.161978) (xy 383.351746 -290.210252) (xy 383.35991 -290.260486) (xy 383.360422 -290.285932)
			(xy 383.668519 -290.285932) (xy 383.672614 -290.235204) (xy 383.684793 -290.18579) (xy 383.704741 -290.13897)
			(xy 383.731942 -290.095956) (xy 383.76569 -290.057862) (xy 383.805112 -290.025675) (xy 383.849186 -290.000229)
			(xy 383.896772 -289.982182) (xy 383.946636 -289.972002) (xy 383.997488 -289.969953) (xy 384.048009 -289.976087)
			(xy 384.096893 -289.990247) (xy 384.142872 -290.012064) (xy 384.184756 -290.040974) (xy 384.22146 -290.076229)
			(xy 384.252033 -290.116915) (xy 384.275684 -290.161978) (xy 384.2918 -290.210252) (xy 384.299964 -290.260486)
			(xy 384.300476 -290.285932) (xy 385.548627 -290.285932) (xy 385.552722 -290.235204) (xy 385.564901 -290.18579)
			(xy 385.584849 -290.13897) (xy 385.61205 -290.095956) (xy 385.645798 -290.057862) (xy 385.68522 -290.025675)
			(xy 385.729294 -290.000229) (xy 385.77688 -289.982182) (xy 385.826744 -289.972002) (xy 385.877596 -289.969953)
			(xy 385.928117 -289.976087) (xy 385.977001 -289.990247) (xy 386.02298 -290.012064) (xy 386.064864 -290.040974)
			(xy 386.101568 -290.076229) (xy 386.132141 -290.116915) (xy 386.155792 -290.161978) (xy 386.171908 -290.210252)
			(xy 386.180072 -290.260486) (xy 386.180584 -290.285932) (xy 386.499112 -290.285932) (xy 386.503072 -290.236878)
			(xy 386.514849 -290.189094) (xy 386.53414 -290.143818) (xy 386.560443 -290.102222) (xy 386.593078 -290.065385)
			(xy 386.631199 -290.03426) (xy 386.67382 -290.009653) (xy 386.719836 -289.992201) (xy 386.768055 -289.982357)
			(xy 386.81723 -289.980376) (xy 386.866085 -289.986308) (xy 386.913356 -290) (xy 386.957818 -290.021098)
			(xy 386.998321 -290.049054) (xy 387.033814 -290.083146) (xy 387.063379 -290.12249) (xy 387.08625 -290.166067)
			(xy 387.101834 -290.212748) (xy 387.109729 -290.261325) (xy 387.110224 -290.285932) (xy 387.428481 -290.285932)
			(xy 387.432576 -290.235204) (xy 387.444755 -290.18579) (xy 387.464703 -290.13897) (xy 387.491904 -290.095956)
			(xy 387.525652 -290.057862) (xy 387.565074 -290.025675) (xy 387.609148 -290.000229) (xy 387.656734 -289.982182)
			(xy 387.706598 -289.972002) (xy 387.75745 -289.969953) (xy 387.807971 -289.976087) (xy 387.856855 -289.990247)
			(xy 387.902834 -290.012064) (xy 387.944718 -290.040974) (xy 387.981422 -290.076229) (xy 388.011995 -290.116915)
			(xy 388.035646 -290.161978) (xy 388.051762 -290.210252) (xy 388.059926 -290.260486) (xy 388.060438 -290.285932)
			(xy 388.378966 -290.285932) (xy 388.382926 -290.236878) (xy 388.394703 -290.189094) (xy 388.413994 -290.143818)
			(xy 388.440297 -290.102222) (xy 388.472932 -290.065385) (xy 388.511053 -290.03426) (xy 388.553674 -290.009653)
			(xy 388.59969 -289.992201) (xy 388.647909 -289.982357) (xy 388.697084 -289.980376) (xy 388.745939 -289.986308)
			(xy 388.79321 -290) (xy 388.837672 -290.021098) (xy 388.878175 -290.049054) (xy 388.913668 -290.083146)
			(xy 388.943233 -290.12249) (xy 388.966104 -290.166067) (xy 388.981688 -290.212748) (xy 388.989583 -290.261325)
			(xy 388.990078 -290.285932) (xy 389.308589 -290.285932) (xy 389.312684 -290.235204) (xy 389.324863 -290.18579)
			(xy 389.344811 -290.13897) (xy 389.372012 -290.095956) (xy 389.40576 -290.057862) (xy 389.445182 -290.025675)
			(xy 389.489256 -290.000229) (xy 389.536842 -289.982182) (xy 389.586706 -289.972002) (xy 389.637558 -289.969953)
			(xy 389.688079 -289.976087) (xy 389.736963 -289.990247) (xy 389.782942 -290.012064) (xy 389.824826 -290.040974)
			(xy 389.86153 -290.076229) (xy 389.892103 -290.116915) (xy 389.915754 -290.161978) (xy 389.93187 -290.210252)
			(xy 389.940034 -290.260486) (xy 389.940546 -290.285932) (xy 390.248643 -290.285932) (xy 390.252738 -290.235204)
			(xy 390.264917 -290.18579) (xy 390.284865 -290.13897) (xy 390.312066 -290.095956) (xy 390.345814 -290.057862)
			(xy 390.385236 -290.025675) (xy 390.42931 -290.000229) (xy 390.476896 -289.982182) (xy 390.52676 -289.972002)
			(xy 390.577612 -289.969953) (xy 390.628133 -289.976087) (xy 390.677017 -289.990247) (xy 390.722996 -290.012064)
			(xy 390.76488 -290.040974) (xy 390.801584 -290.076229) (xy 390.832157 -290.116915) (xy 390.855808 -290.161978)
			(xy 390.871924 -290.210252) (xy 390.880088 -290.260486) (xy 390.8806 -290.285932) (xy 393.078982 -290.285932)
			(xy 393.082942 -290.236878) (xy 393.094719 -290.189094) (xy 393.11401 -290.143818) (xy 393.140313 -290.102222)
			(xy 393.172948 -290.065385) (xy 393.211069 -290.03426) (xy 393.25369 -290.009653) (xy 393.299706 -289.992201)
			(xy 393.347925 -289.982357) (xy 393.3971 -289.980376) (xy 393.445955 -289.986308) (xy 393.493226 -290)
			(xy 393.537688 -290.021098) (xy 393.578191 -290.049054) (xy 393.613684 -290.083146) (xy 393.643249 -290.12249)
			(xy 393.66612 -290.166067) (xy 393.681704 -290.212748) (xy 393.689599 -290.261325) (xy 393.690094 -290.285932)
			(xy 393.689599 -290.310539) (xy 393.681704 -290.359116) (xy 393.66612 -290.405797) (xy 393.643249 -290.449374)
			(xy 393.613684 -290.488718) (xy 393.578191 -290.52281) (xy 393.537688 -290.550766) (xy 393.493226 -290.571864)
			(xy 393.445955 -290.585556) (xy 393.3971 -290.591488) (xy 393.347925 -290.589507) (xy 393.299706 -290.579663)
			(xy 393.25369 -290.562211) (xy 393.211069 -290.537604) (xy 393.172948 -290.506479) (xy 393.140313 -290.469642)
			(xy 393.11401 -290.428046) (xy 393.094719 -290.38277) (xy 393.082942 -290.334986) (xy 393.078982 -290.285932)
			(xy 390.8806 -290.285932) (xy 390.880088 -290.311378) (xy 390.871924 -290.361612) (xy 390.855808 -290.409886)
			(xy 390.832157 -290.454949) (xy 390.801584 -290.495635) (xy 390.76488 -290.53089) (xy 390.722996 -290.5598)
			(xy 390.677017 -290.581617) (xy 390.628133 -290.595777) (xy 390.577612 -290.601911) (xy 390.52676 -290.599862)
			(xy 390.476896 -290.589682) (xy 390.42931 -290.571635) (xy 390.385236 -290.546189) (xy 390.345814 -290.514002)
			(xy 390.312066 -290.475908) (xy 390.284865 -290.432894) (xy 390.264917 -290.386074) (xy 390.252738 -290.33666)
			(xy 390.248643 -290.285932) (xy 389.940546 -290.285932) (xy 389.940034 -290.311378) (xy 389.93187 -290.361612)
			(xy 389.915754 -290.409886) (xy 389.892103 -290.454949) (xy 389.86153 -290.495635) (xy 389.824826 -290.53089)
			(xy 389.782942 -290.5598) (xy 389.736963 -290.581617) (xy 389.688079 -290.595777) (xy 389.637558 -290.601911)
			(xy 389.586706 -290.599862) (xy 389.536842 -290.589682) (xy 389.489256 -290.571635) (xy 389.445182 -290.546189)
			(xy 389.40576 -290.514002) (xy 389.372012 -290.475908) (xy 389.344811 -290.432894) (xy 389.324863 -290.386074)
			(xy 389.312684 -290.33666) (xy 389.308589 -290.285932) (xy 388.990078 -290.285932) (xy 388.989583 -290.310539)
			(xy 388.981688 -290.359116) (xy 388.966104 -290.405797) (xy 388.943233 -290.449374) (xy 388.913668 -290.488718)
			(xy 388.878175 -290.52281) (xy 388.837672 -290.550766) (xy 388.79321 -290.571864) (xy 388.745939 -290.585556)
			(xy 388.697084 -290.591488) (xy 388.647909 -290.589507) (xy 388.59969 -290.579663) (xy 388.553674 -290.562211)
			(xy 388.511053 -290.537604) (xy 388.472932 -290.506479) (xy 388.440297 -290.469642) (xy 388.413994 -290.428046)
			(xy 388.394703 -290.38277) (xy 388.382926 -290.334986) (xy 388.378966 -290.285932) (xy 388.060438 -290.285932)
			(xy 388.059926 -290.311378) (xy 388.051762 -290.361612) (xy 388.035646 -290.409886) (xy 388.011995 -290.454949)
			(xy 387.981422 -290.495635) (xy 387.944718 -290.53089) (xy 387.902834 -290.5598) (xy 387.856855 -290.581617)
			(xy 387.807971 -290.595777) (xy 387.75745 -290.601911) (xy 387.706598 -290.599862) (xy 387.656734 -290.589682)
			(xy 387.609148 -290.571635) (xy 387.565074 -290.546189) (xy 387.525652 -290.514002) (xy 387.491904 -290.475908)
			(xy 387.464703 -290.432894) (xy 387.444755 -290.386074) (xy 387.432576 -290.33666) (xy 387.428481 -290.285932)
			(xy 387.110224 -290.285932) (xy 387.109729 -290.310539) (xy 387.101834 -290.359116) (xy 387.08625 -290.405797)
			(xy 387.063379 -290.449374) (xy 387.033814 -290.488718) (xy 386.998321 -290.52281) (xy 386.957818 -290.550766)
			(xy 386.913356 -290.571864) (xy 386.866085 -290.585556) (xy 386.81723 -290.591488) (xy 386.768055 -290.589507)
			(xy 386.719836 -290.579663) (xy 386.67382 -290.562211) (xy 386.631199 -290.537604) (xy 386.593078 -290.506479)
			(xy 386.560443 -290.469642) (xy 386.53414 -290.428046) (xy 386.514849 -290.38277) (xy 386.503072 -290.334986)
			(xy 386.499112 -290.285932) (xy 386.180584 -290.285932) (xy 386.180072 -290.311378) (xy 386.171908 -290.361612)
			(xy 386.155792 -290.409886) (xy 386.132141 -290.454949) (xy 386.101568 -290.495635) (xy 386.064864 -290.53089)
			(xy 386.02298 -290.5598) (xy 385.977001 -290.581617) (xy 385.928117 -290.595777) (xy 385.877596 -290.601911)
			(xy 385.826744 -290.599862) (xy 385.77688 -290.589682) (xy 385.729294 -290.571635) (xy 385.68522 -290.546189)
			(xy 385.645798 -290.514002) (xy 385.61205 -290.475908) (xy 385.584849 -290.432894) (xy 385.564901 -290.386074)
			(xy 385.552722 -290.33666) (xy 385.548627 -290.285932) (xy 384.300476 -290.285932) (xy 384.299964 -290.311378)
			(xy 384.2918 -290.361612) (xy 384.275684 -290.409886) (xy 384.252033 -290.454949) (xy 384.22146 -290.495635)
			(xy 384.184756 -290.53089) (xy 384.142872 -290.5598) (xy 384.096893 -290.581617) (xy 384.048009 -290.595777)
			(xy 383.997488 -290.601911) (xy 383.946636 -290.599862) (xy 383.896772 -290.589682) (xy 383.849186 -290.571635)
			(xy 383.805112 -290.546189) (xy 383.76569 -290.514002) (xy 383.731942 -290.475908) (xy 383.704741 -290.432894)
			(xy 383.684793 -290.386074) (xy 383.672614 -290.33666) (xy 383.668519 -290.285932) (xy 383.360422 -290.285932)
			(xy 383.35991 -290.311378) (xy 383.351746 -290.361612) (xy 383.33563 -290.409886) (xy 383.311979 -290.454949)
			(xy 383.281406 -290.495635) (xy 383.244702 -290.53089) (xy 383.202818 -290.5598) (xy 383.156839 -290.581617)
			(xy 383.107955 -290.595777) (xy 383.057434 -290.601911) (xy 383.006582 -290.599862) (xy 382.956718 -290.589682)
			(xy 382.909132 -290.571635) (xy 382.865058 -290.546189) (xy 382.825636 -290.514002) (xy 382.791888 -290.475908)
			(xy 382.764687 -290.432894) (xy 382.744739 -290.386074) (xy 382.73256 -290.33666) (xy 382.728465 -290.285932)
			(xy 382.410208 -290.285932) (xy 382.409713 -290.310539) (xy 382.401818 -290.359116) (xy 382.386234 -290.405797)
			(xy 382.363363 -290.449374) (xy 382.333798 -290.488718) (xy 382.298305 -290.52281) (xy 382.257802 -290.550766)
			(xy 382.21334 -290.571864) (xy 382.166069 -290.585556) (xy 382.117214 -290.591488) (xy 382.068039 -290.589507)
			(xy 382.01982 -290.579663) (xy 381.973804 -290.562211) (xy 381.931183 -290.537604) (xy 381.893062 -290.506479)
			(xy 381.860427 -290.469642) (xy 381.834124 -290.428046) (xy 381.814833 -290.38277) (xy 381.803056 -290.334986)
			(xy 381.799096 -290.285932) (xy 381.480568 -290.285932) (xy 381.480056 -290.311378) (xy 381.471892 -290.361612)
			(xy 381.455776 -290.409886) (xy 381.432125 -290.454949) (xy 381.401552 -290.495635) (xy 381.364848 -290.53089)
			(xy 381.322964 -290.5598) (xy 381.276985 -290.581617) (xy 381.228101 -290.595777) (xy 381.17758 -290.601911)
			(xy 381.126728 -290.599862) (xy 381.076864 -290.589682) (xy 381.029278 -290.571635) (xy 380.985204 -290.546189)
			(xy 380.945782 -290.514002) (xy 380.912034 -290.475908) (xy 380.884833 -290.432894) (xy 380.864885 -290.386074)
			(xy 380.852706 -290.33666) (xy 380.848611 -290.285932) (xy 380.5301 -290.285932) (xy 380.529605 -290.310539)
			(xy 380.52171 -290.359116) (xy 380.506126 -290.405797) (xy 380.483255 -290.449374) (xy 380.45369 -290.488718)
			(xy 380.418197 -290.52281) (xy 380.377694 -290.550766) (xy 380.333232 -290.571864) (xy 380.285961 -290.585556)
			(xy 380.237106 -290.591488) (xy 380.187931 -290.589507) (xy 380.139712 -290.579663) (xy 380.093696 -290.562211)
			(xy 380.051075 -290.537604) (xy 380.012954 -290.506479) (xy 379.980319 -290.469642) (xy 379.954016 -290.428046)
			(xy 379.934725 -290.38277) (xy 379.922948 -290.334986) (xy 379.918988 -290.285932) (xy 379.60046 -290.285932)
			(xy 379.599948 -290.311378) (xy 379.591784 -290.361612) (xy 379.575668 -290.409886) (xy 379.552017 -290.454949)
			(xy 379.521444 -290.495635) (xy 379.48474 -290.53089) (xy 379.442856 -290.5598) (xy 379.396877 -290.581617)
			(xy 379.347993 -290.595777) (xy 379.297472 -290.601911) (xy 379.24662 -290.599862) (xy 379.196756 -290.589682)
			(xy 379.14917 -290.571635) (xy 379.105096 -290.546189) (xy 379.065674 -290.514002) (xy 379.031926 -290.475908)
			(xy 379.004725 -290.432894) (xy 378.984777 -290.386074) (xy 378.972598 -290.33666) (xy 378.968503 -290.285932)
			(xy 377.720606 -290.285932) (xy 377.720094 -290.311378) (xy 377.71193 -290.361612) (xy 377.695814 -290.409886)
			(xy 377.672163 -290.454949) (xy 377.64159 -290.495635) (xy 377.604886 -290.53089) (xy 377.563002 -290.5598)
			(xy 377.517023 -290.581617) (xy 377.468139 -290.595777) (xy 377.417618 -290.601911) (xy 377.366766 -290.599862)
			(xy 377.316902 -290.589682) (xy 377.269316 -290.571635) (xy 377.225242 -290.546189) (xy 377.18582 -290.514002)
			(xy 377.152072 -290.475908) (xy 377.124871 -290.432894) (xy 377.104923 -290.386074) (xy 377.092744 -290.33666)
			(xy 377.088649 -290.285932) (xy 376.780552 -290.285932) (xy 376.780047 -290.310873) (xy 376.772139 -290.360126)
			(xy 376.756587 -290.407523) (xy 376.733778 -290.451887) (xy 376.70428 -290.492114) (xy 376.668825 -290.527204)
			(xy 376.628295 -290.556285) (xy 376.583698 -290.578633) (xy 376.56008 -290.586668) (xy 376.547126 -290.590986)
			(xy 376.529092 -290.61029) (xy 376.507756 -290.70046) (xy 376.506108 -290.708923) (xy 376.507955 -290.726053)
			(xy 376.515401 -290.741591) (xy 376.521218 -290.747958) (xy 376.664982 -290.891722) (xy 376.706638 -290.891976)
			(xy 376.721624 -290.877244) (xy 376.738841 -290.861101) (xy 376.77732 -290.833777) (xy 376.819541 -290.812691)
			(xy 376.864502 -290.798346) (xy 376.911133 -290.791081) (xy 376.93473 -290.79063) (xy 376.958318 -290.791071)
			(xy 377.004934 -290.798328) (xy 377.049879 -290.812666) (xy 377.092086 -290.833744) (xy 377.13055 -290.861061)
			(xy 377.164357 -290.893966) (xy 377.192704 -290.931677) (xy 377.214915 -290.973298) (xy 377.230464 -291.017839)
			(xy 377.238979 -291.064242) (xy 377.240038 -291.08781) (xy 377.240038 -291.093652) (xy 377.240038 -291.095938)
			(xy 377.558549 -291.095938) (xy 377.562644 -291.04521) (xy 377.574823 -290.995796) (xy 377.594771 -290.948976)
			(xy 377.621972 -290.905962) (xy 377.65572 -290.867868) (xy 377.695142 -290.835681) (xy 377.739216 -290.810235)
			(xy 377.786802 -290.792188) (xy 377.836666 -290.782008) (xy 377.887518 -290.779959) (xy 377.938039 -290.786093)
			(xy 377.986923 -290.800253) (xy 378.032902 -290.82207) (xy 378.074786 -290.85098) (xy 378.11149 -290.886235)
			(xy 378.142063 -290.926921) (xy 378.165714 -290.971984) (xy 378.18183 -291.020258) (xy 378.189994 -291.070492)
			(xy 378.190506 -291.095938) (xy 378.509034 -291.095938) (xy 378.512994 -291.046884) (xy 378.524771 -290.9991)
			(xy 378.544062 -290.953824) (xy 378.570365 -290.912228) (xy 378.603 -290.875391) (xy 378.641121 -290.844266)
			(xy 378.683742 -290.819659) (xy 378.729758 -290.802207) (xy 378.777977 -290.792363) (xy 378.827152 -290.790382)
			(xy 378.876007 -290.796314) (xy 378.923278 -290.810006) (xy 378.96774 -290.831104) (xy 379.008243 -290.85906)
			(xy 379.043736 -290.893152) (xy 379.073301 -290.932496) (xy 379.096172 -290.976073) (xy 379.111756 -291.022754)
			(xy 379.119651 -291.071331) (xy 379.120146 -291.095938) (xy 379.438657 -291.095938) (xy 379.442752 -291.04521)
			(xy 379.454931 -290.995796) (xy 379.474879 -290.948976) (xy 379.50208 -290.905962) (xy 379.535828 -290.867868)
			(xy 379.57525 -290.835681) (xy 379.619324 -290.810235) (xy 379.66691 -290.792188) (xy 379.716774 -290.782008)
			(xy 379.767626 -290.779959) (xy 379.818147 -290.786093) (xy 379.867031 -290.800253) (xy 379.91301 -290.82207)
			(xy 379.954894 -290.85098) (xy 379.991598 -290.886235) (xy 380.022171 -290.926921) (xy 380.045822 -290.971984)
			(xy 380.061938 -291.020258) (xy 380.070102 -291.070492) (xy 380.070614 -291.095938) (xy 380.378711 -291.095938)
			(xy 380.382806 -291.04521) (xy 380.394985 -290.995796) (xy 380.414933 -290.948976) (xy 380.442134 -290.905962)
			(xy 380.475882 -290.867868) (xy 380.515304 -290.835681) (xy 380.559378 -290.810235) (xy 380.606964 -290.792188)
			(xy 380.656828 -290.782008) (xy 380.70768 -290.779959) (xy 380.758201 -290.786093) (xy 380.807085 -290.800253)
			(xy 380.853064 -290.82207) (xy 380.894948 -290.85098) (xy 380.931652 -290.886235) (xy 380.962225 -290.926921)
			(xy 380.985876 -290.971984) (xy 381.001992 -291.020258) (xy 381.010156 -291.070492) (xy 381.010668 -291.095938)
			(xy 381.328942 -291.095938) (xy 381.332902 -291.046884) (xy 381.344679 -290.9991) (xy 381.36397 -290.953824)
			(xy 381.390273 -290.912228) (xy 381.422908 -290.875391) (xy 381.461029 -290.844266) (xy 381.50365 -290.819659)
			(xy 381.549666 -290.802207) (xy 381.597885 -290.792363) (xy 381.64706 -290.790382) (xy 381.695915 -290.796314)
			(xy 381.743186 -290.810006) (xy 381.787648 -290.831104) (xy 381.828151 -290.85906) (xy 381.863644 -290.893152)
			(xy 381.893209 -290.932496) (xy 381.91608 -290.976073) (xy 381.931664 -291.022754) (xy 381.939559 -291.071331)
			(xy 381.940054 -291.095938) (xy 382.258565 -291.095938) (xy 382.26266 -291.04521) (xy 382.274839 -290.995796)
			(xy 382.294787 -290.948976) (xy 382.321988 -290.905962) (xy 382.355736 -290.867868) (xy 382.395158 -290.835681)
			(xy 382.439232 -290.810235) (xy 382.486818 -290.792188) (xy 382.536682 -290.782008) (xy 382.587534 -290.779959)
			(xy 382.638055 -290.786093) (xy 382.686939 -290.800253) (xy 382.732918 -290.82207) (xy 382.774802 -290.85098)
			(xy 382.811506 -290.886235) (xy 382.842079 -290.926921) (xy 382.86573 -290.971984) (xy 382.881846 -291.020258)
			(xy 382.89001 -291.070492) (xy 382.890522 -291.095938) (xy 383.20905 -291.095938) (xy 383.21301 -291.046884)
			(xy 383.224787 -290.9991) (xy 383.244078 -290.953824) (xy 383.270381 -290.912228) (xy 383.303016 -290.875391)
			(xy 383.341137 -290.844266) (xy 383.383758 -290.819659) (xy 383.429774 -290.802207) (xy 383.477993 -290.792363)
			(xy 383.527168 -290.790382) (xy 383.576023 -290.796314) (xy 383.623294 -290.810006) (xy 383.667756 -290.831104)
			(xy 383.708259 -290.85906) (xy 383.743752 -290.893152) (xy 383.773317 -290.932496) (xy 383.796188 -290.976073)
			(xy 383.811772 -291.022754) (xy 383.819667 -291.071331) (xy 383.820162 -291.095938) (xy 384.138673 -291.095938)
			(xy 384.142768 -291.04521) (xy 384.154947 -290.995796) (xy 384.174895 -290.948976) (xy 384.202096 -290.905962)
			(xy 384.235844 -290.867868) (xy 384.275266 -290.835681) (xy 384.31934 -290.810235) (xy 384.366926 -290.792188)
			(xy 384.41679 -290.782008) (xy 384.467642 -290.779959) (xy 384.518163 -290.786093) (xy 384.567047 -290.800253)
			(xy 384.613026 -290.82207) (xy 384.65491 -290.85098) (xy 384.691614 -290.886235) (xy 384.722187 -290.926921)
			(xy 384.745838 -290.971984) (xy 384.761954 -291.020258) (xy 384.770118 -291.070492) (xy 384.77063 -291.095938)
			(xy 385.088904 -291.095938) (xy 385.092864 -291.046884) (xy 385.104641 -290.9991) (xy 385.123932 -290.953824)
			(xy 385.150235 -290.912228) (xy 385.18287 -290.875391) (xy 385.220991 -290.844266) (xy 385.263612 -290.819659)
			(xy 385.309628 -290.802207) (xy 385.357847 -290.792363) (xy 385.407022 -290.790382) (xy 385.455877 -290.796314)
			(xy 385.503148 -290.810006) (xy 385.54761 -290.831104) (xy 385.588113 -290.85906) (xy 385.623606 -290.893152)
			(xy 385.653171 -290.932496) (xy 385.676042 -290.976073) (xy 385.691626 -291.022754) (xy 385.699521 -291.071331)
			(xy 385.700016 -291.095938) (xy 386.018527 -291.095938) (xy 386.022622 -291.04521) (xy 386.034801 -290.995796)
			(xy 386.054749 -290.948976) (xy 386.08195 -290.905962) (xy 386.115698 -290.867868) (xy 386.15512 -290.835681)
			(xy 386.199194 -290.810235) (xy 386.24678 -290.792188) (xy 386.296644 -290.782008) (xy 386.347496 -290.779959)
			(xy 386.398017 -290.786093) (xy 386.446901 -290.800253) (xy 386.49288 -290.82207) (xy 386.534764 -290.85098)
			(xy 386.571468 -290.886235) (xy 386.602041 -290.926921) (xy 386.625692 -290.971984) (xy 386.641808 -291.020258)
			(xy 386.649972 -291.070492) (xy 386.650484 -291.095938) (xy 386.958581 -291.095938) (xy 386.962676 -291.04521)
			(xy 386.974855 -290.995796) (xy 386.994803 -290.948976) (xy 387.022004 -290.905962) (xy 387.055752 -290.867868)
			(xy 387.095174 -290.835681) (xy 387.139248 -290.810235) (xy 387.186834 -290.792188) (xy 387.236698 -290.782008)
			(xy 387.28755 -290.779959) (xy 387.338071 -290.786093) (xy 387.386955 -290.800253) (xy 387.432934 -290.82207)
			(xy 387.474818 -290.85098) (xy 387.511522 -290.886235) (xy 387.542095 -290.926921) (xy 387.565746 -290.971984)
			(xy 387.581862 -291.020258) (xy 387.590026 -291.070492) (xy 387.590538 -291.095938) (xy 387.909066 -291.095938)
			(xy 387.913026 -291.046884) (xy 387.924803 -290.9991) (xy 387.944094 -290.953824) (xy 387.970397 -290.912228)
			(xy 388.003032 -290.875391) (xy 388.041153 -290.844266) (xy 388.083774 -290.819659) (xy 388.12979 -290.802207)
			(xy 388.178009 -290.792363) (xy 388.227184 -290.790382) (xy 388.276039 -290.796314) (xy 388.32331 -290.810006)
			(xy 388.367772 -290.831104) (xy 388.408275 -290.85906) (xy 388.443768 -290.893152) (xy 388.473333 -290.932496)
			(xy 388.496204 -290.976073) (xy 388.511788 -291.022754) (xy 388.519683 -291.071331) (xy 388.520178 -291.095938)
			(xy 388.838689 -291.095938) (xy 388.842784 -291.04521) (xy 388.854963 -290.995796) (xy 388.874911 -290.948976)
			(xy 388.902112 -290.905962) (xy 388.93586 -290.867868) (xy 388.975282 -290.835681) (xy 389.019356 -290.810235)
			(xy 389.066942 -290.792188) (xy 389.116806 -290.782008) (xy 389.167658 -290.779959) (xy 389.218179 -290.786093)
			(xy 389.267063 -290.800253) (xy 389.313042 -290.82207) (xy 389.354926 -290.85098) (xy 389.39163 -290.886235)
			(xy 389.422203 -290.926921) (xy 389.445854 -290.971984) (xy 389.46197 -291.020258) (xy 389.470134 -291.070492)
			(xy 389.470646 -291.095938) (xy 389.78892 -291.095938) (xy 389.79288 -291.046884) (xy 389.804657 -290.9991)
			(xy 389.823948 -290.953824) (xy 389.850251 -290.912228) (xy 389.882886 -290.875391) (xy 389.921007 -290.844266)
			(xy 389.963628 -290.819659) (xy 390.009644 -290.802207) (xy 390.057863 -290.792363) (xy 390.107038 -290.790382)
			(xy 390.155893 -290.796314) (xy 390.203164 -290.810006) (xy 390.247626 -290.831104) (xy 390.288129 -290.85906)
			(xy 390.323622 -290.893152) (xy 390.353187 -290.932496) (xy 390.376058 -290.976073) (xy 390.391642 -291.022754)
			(xy 390.399537 -291.071331) (xy 390.400032 -291.095938) (xy 390.718543 -291.095938) (xy 390.722638 -291.04521)
			(xy 390.734817 -290.995796) (xy 390.754765 -290.948976) (xy 390.781966 -290.905962) (xy 390.815714 -290.867868)
			(xy 390.855136 -290.835681) (xy 390.89921 -290.810235) (xy 390.946796 -290.792188) (xy 390.99666 -290.782008)
			(xy 391.047512 -290.779959) (xy 391.098033 -290.786093) (xy 391.146917 -290.800253) (xy 391.192896 -290.82207)
			(xy 391.23478 -290.85098) (xy 391.271484 -290.886235) (xy 391.302057 -290.926921) (xy 391.325708 -290.971984)
			(xy 391.341824 -291.020258) (xy 391.349988 -291.070492) (xy 391.3505 -291.095938) (xy 391.669028 -291.095938)
			(xy 391.672988 -291.046884) (xy 391.684765 -290.9991) (xy 391.704056 -290.953824) (xy 391.730359 -290.912228)
			(xy 391.762994 -290.875391) (xy 391.801115 -290.844266) (xy 391.843736 -290.819659) (xy 391.889752 -290.802207)
			(xy 391.937971 -290.792363) (xy 391.987146 -290.790382) (xy 392.036001 -290.796314) (xy 392.083272 -290.810006)
			(xy 392.125407 -290.83) (xy 394.67715 -290.83) (xy 394.68111 -290.780946) (xy 394.692887 -290.733162)
			(xy 394.712178 -290.687886) (xy 394.738481 -290.64629) (xy 394.771116 -290.609453) (xy 394.809237 -290.578328)
			(xy 394.851858 -290.553721) (xy 394.897874 -290.536269) (xy 394.946093 -290.526425) (xy 394.995268 -290.524444)
			(xy 395.044123 -290.530376) (xy 395.091394 -290.544068) (xy 395.135856 -290.565166) (xy 395.176359 -290.593122)
			(xy 395.211852 -290.627214) (xy 395.241417 -290.666558) (xy 395.264288 -290.710135) (xy 395.279872 -290.756816)
			(xy 395.287767 -290.805393) (xy 395.288262 -290.83) (xy 395.287767 -290.854607) (xy 395.279872 -290.903184)
			(xy 395.264288 -290.949865) (xy 395.241417 -290.993442) (xy 395.211852 -291.032786) (xy 395.176359 -291.066878)
			(xy 395.135856 -291.094834) (xy 395.091394 -291.115932) (xy 395.044123 -291.129624) (xy 394.995268 -291.135556)
			(xy 394.946093 -291.133575) (xy 394.897874 -291.123731) (xy 394.851858 -291.106279) (xy 394.809237 -291.081672)
			(xy 394.771116 -291.050547) (xy 394.738481 -291.01371) (xy 394.712178 -290.972114) (xy 394.692887 -290.926838)
			(xy 394.68111 -290.879054) (xy 394.67715 -290.83) (xy 392.125407 -290.83) (xy 392.127734 -290.831104)
			(xy 392.168237 -290.85906) (xy 392.20373 -290.893152) (xy 392.233295 -290.932496) (xy 392.256166 -290.976073)
			(xy 392.27175 -291.022754) (xy 392.279645 -291.071331) (xy 392.28014 -291.095938) (xy 392.279645 -291.120545)
			(xy 392.27175 -291.169122) (xy 392.256166 -291.215803) (xy 392.233295 -291.25938) (xy 392.20373 -291.298724)
			(xy 392.168237 -291.332816) (xy 392.127734 -291.360772) (xy 392.083272 -291.38187) (xy 392.036001 -291.395562)
			(xy 391.987146 -291.401494) (xy 391.937971 -291.399513) (xy 391.889752 -291.389669) (xy 391.843736 -291.372217)
			(xy 391.801115 -291.34761) (xy 391.762994 -291.316485) (xy 391.730359 -291.279648) (xy 391.704056 -291.238052)
			(xy 391.684765 -291.192776) (xy 391.672988 -291.144992) (xy 391.669028 -291.095938) (xy 391.3505 -291.095938)
			(xy 391.349988 -291.121384) (xy 391.341824 -291.171618) (xy 391.325708 -291.219892) (xy 391.302057 -291.264955)
			(xy 391.271484 -291.305641) (xy 391.23478 -291.340896) (xy 391.192896 -291.369806) (xy 391.146917 -291.391623)
			(xy 391.098033 -291.405783) (xy 391.047512 -291.411917) (xy 390.99666 -291.409868) (xy 390.946796 -291.399688)
			(xy 390.89921 -291.381641) (xy 390.855136 -291.356195) (xy 390.815714 -291.324008) (xy 390.781966 -291.285914)
			(xy 390.754765 -291.2429) (xy 390.734817 -291.19608) (xy 390.722638 -291.146666) (xy 390.718543 -291.095938)
			(xy 390.400032 -291.095938) (xy 390.399537 -291.120545) (xy 390.391642 -291.169122) (xy 390.376058 -291.215803)
			(xy 390.353187 -291.25938) (xy 390.323622 -291.298724) (xy 390.288129 -291.332816) (xy 390.247626 -291.360772)
			(xy 390.203164 -291.38187) (xy 390.155893 -291.395562) (xy 390.107038 -291.401494) (xy 390.057863 -291.399513)
			(xy 390.009644 -291.389669) (xy 389.963628 -291.372217) (xy 389.921007 -291.34761) (xy 389.882886 -291.316485)
			(xy 389.850251 -291.279648) (xy 389.823948 -291.238052) (xy 389.804657 -291.192776) (xy 389.79288 -291.144992)
			(xy 389.78892 -291.095938) (xy 389.470646 -291.095938) (xy 389.470134 -291.121384) (xy 389.46197 -291.171618)
			(xy 389.445854 -291.219892) (xy 389.422203 -291.264955) (xy 389.39163 -291.305641) (xy 389.354926 -291.340896)
			(xy 389.313042 -291.369806) (xy 389.267063 -291.391623) (xy 389.218179 -291.405783) (xy 389.167658 -291.411917)
			(xy 389.116806 -291.409868) (xy 389.066942 -291.399688) (xy 389.019356 -291.381641) (xy 388.975282 -291.356195)
			(xy 388.93586 -291.324008) (xy 388.902112 -291.285914) (xy 388.874911 -291.2429) (xy 388.854963 -291.19608)
			(xy 388.842784 -291.146666) (xy 388.838689 -291.095938) (xy 388.520178 -291.095938) (xy 388.519683 -291.120545)
			(xy 388.511788 -291.169122) (xy 388.496204 -291.215803) (xy 388.473333 -291.25938) (xy 388.443768 -291.298724)
			(xy 388.408275 -291.332816) (xy 388.367772 -291.360772) (xy 388.32331 -291.38187) (xy 388.276039 -291.395562)
			(xy 388.227184 -291.401494) (xy 388.178009 -291.399513) (xy 388.12979 -291.389669) (xy 388.083774 -291.372217)
			(xy 388.041153 -291.34761) (xy 388.003032 -291.316485) (xy 387.970397 -291.279648) (xy 387.944094 -291.238052)
			(xy 387.924803 -291.192776) (xy 387.913026 -291.144992) (xy 387.909066 -291.095938) (xy 387.590538 -291.095938)
			(xy 387.590026 -291.121384) (xy 387.581862 -291.171618) (xy 387.565746 -291.219892) (xy 387.542095 -291.264955)
			(xy 387.511522 -291.305641) (xy 387.474818 -291.340896) (xy 387.432934 -291.369806) (xy 387.386955 -291.391623)
			(xy 387.338071 -291.405783) (xy 387.28755 -291.411917) (xy 387.236698 -291.409868) (xy 387.186834 -291.399688)
			(xy 387.139248 -291.381641) (xy 387.095174 -291.356195) (xy 387.055752 -291.324008) (xy 387.022004 -291.285914)
			(xy 386.994803 -291.2429) (xy 386.974855 -291.19608) (xy 386.962676 -291.146666) (xy 386.958581 -291.095938)
			(xy 386.650484 -291.095938) (xy 386.649972 -291.121384) (xy 386.641808 -291.171618) (xy 386.625692 -291.219892)
			(xy 386.602041 -291.264955) (xy 386.571468 -291.305641) (xy 386.534764 -291.340896) (xy 386.49288 -291.369806)
			(xy 386.446901 -291.391623) (xy 386.398017 -291.405783) (xy 386.347496 -291.411917) (xy 386.296644 -291.409868)
			(xy 386.24678 -291.399688) (xy 386.199194 -291.381641) (xy 386.15512 -291.356195) (xy 386.115698 -291.324008)
			(xy 386.08195 -291.285914) (xy 386.054749 -291.2429) (xy 386.034801 -291.19608) (xy 386.022622 -291.146666)
			(xy 386.018527 -291.095938) (xy 385.700016 -291.095938) (xy 385.699521 -291.120545) (xy 385.691626 -291.169122)
			(xy 385.676042 -291.215803) (xy 385.653171 -291.25938) (xy 385.623606 -291.298724) (xy 385.588113 -291.332816)
			(xy 385.54761 -291.360772) (xy 385.503148 -291.38187) (xy 385.455877 -291.395562) (xy 385.407022 -291.401494)
			(xy 385.357847 -291.399513) (xy 385.309628 -291.389669) (xy 385.263612 -291.372217) (xy 385.220991 -291.34761)
			(xy 385.18287 -291.316485) (xy 385.150235 -291.279648) (xy 385.123932 -291.238052) (xy 385.104641 -291.192776)
			(xy 385.092864 -291.144992) (xy 385.088904 -291.095938) (xy 384.77063 -291.095938) (xy 384.770118 -291.121384)
			(xy 384.761954 -291.171618) (xy 384.745838 -291.219892) (xy 384.722187 -291.264955) (xy 384.691614 -291.305641)
			(xy 384.65491 -291.340896) (xy 384.613026 -291.369806) (xy 384.567047 -291.391623) (xy 384.518163 -291.405783)
			(xy 384.467642 -291.411917) (xy 384.41679 -291.409868) (xy 384.366926 -291.399688) (xy 384.31934 -291.381641)
			(xy 384.275266 -291.356195) (xy 384.235844 -291.324008) (xy 384.202096 -291.285914) (xy 384.174895 -291.2429)
			(xy 384.154947 -291.19608) (xy 384.142768 -291.146666) (xy 384.138673 -291.095938) (xy 383.820162 -291.095938)
			(xy 383.819667 -291.120545) (xy 383.811772 -291.169122) (xy 383.796188 -291.215803) (xy 383.773317 -291.25938)
			(xy 383.743752 -291.298724) (xy 383.708259 -291.332816) (xy 383.667756 -291.360772) (xy 383.623294 -291.38187)
			(xy 383.576023 -291.395562) (xy 383.527168 -291.401494) (xy 383.477993 -291.399513) (xy 383.429774 -291.389669)
			(xy 383.383758 -291.372217) (xy 383.341137 -291.34761) (xy 383.303016 -291.316485) (xy 383.270381 -291.279648)
			(xy 383.244078 -291.238052) (xy 383.224787 -291.192776) (xy 383.21301 -291.144992) (xy 383.20905 -291.095938)
			(xy 382.890522 -291.095938) (xy 382.89001 -291.121384) (xy 382.881846 -291.171618) (xy 382.86573 -291.219892)
			(xy 382.842079 -291.264955) (xy 382.811506 -291.305641) (xy 382.774802 -291.340896) (xy 382.732918 -291.369806)
			(xy 382.686939 -291.391623) (xy 382.638055 -291.405783) (xy 382.587534 -291.411917) (xy 382.536682 -291.409868)
			(xy 382.486818 -291.399688) (xy 382.439232 -291.381641) (xy 382.395158 -291.356195) (xy 382.355736 -291.324008)
			(xy 382.321988 -291.285914) (xy 382.294787 -291.2429) (xy 382.274839 -291.19608) (xy 382.26266 -291.146666)
			(xy 382.258565 -291.095938) (xy 381.940054 -291.095938) (xy 381.939559 -291.120545) (xy 381.931664 -291.169122)
			(xy 381.91608 -291.215803) (xy 381.893209 -291.25938) (xy 381.863644 -291.298724) (xy 381.828151 -291.332816)
			(xy 381.787648 -291.360772) (xy 381.743186 -291.38187) (xy 381.695915 -291.395562) (xy 381.64706 -291.401494)
			(xy 381.597885 -291.399513) (xy 381.549666 -291.389669) (xy 381.50365 -291.372217) (xy 381.461029 -291.34761)
			(xy 381.422908 -291.316485) (xy 381.390273 -291.279648) (xy 381.36397 -291.238052) (xy 381.344679 -291.192776)
			(xy 381.332902 -291.144992) (xy 381.328942 -291.095938) (xy 381.010668 -291.095938) (xy 381.010156 -291.121384)
			(xy 381.001992 -291.171618) (xy 380.985876 -291.219892) (xy 380.962225 -291.264955) (xy 380.931652 -291.305641)
			(xy 380.894948 -291.340896) (xy 380.853064 -291.369806) (xy 380.807085 -291.391623) (xy 380.758201 -291.405783)
			(xy 380.70768 -291.411917) (xy 380.656828 -291.409868) (xy 380.606964 -291.399688) (xy 380.559378 -291.381641)
			(xy 380.515304 -291.356195) (xy 380.475882 -291.324008) (xy 380.442134 -291.285914) (xy 380.414933 -291.2429)
			(xy 380.394985 -291.19608) (xy 380.382806 -291.146666) (xy 380.378711 -291.095938) (xy 380.070614 -291.095938)
			(xy 380.070102 -291.121384) (xy 380.061938 -291.171618) (xy 380.045822 -291.219892) (xy 380.022171 -291.264955)
			(xy 379.991598 -291.305641) (xy 379.954894 -291.340896) (xy 379.91301 -291.369806) (xy 379.867031 -291.391623)
			(xy 379.818147 -291.405783) (xy 379.767626 -291.411917) (xy 379.716774 -291.409868) (xy 379.66691 -291.399688)
			(xy 379.619324 -291.381641) (xy 379.57525 -291.356195) (xy 379.535828 -291.324008) (xy 379.50208 -291.285914)
			(xy 379.474879 -291.2429) (xy 379.454931 -291.19608) (xy 379.442752 -291.146666) (xy 379.438657 -291.095938)
			(xy 379.120146 -291.095938) (xy 379.119651 -291.120545) (xy 379.111756 -291.169122) (xy 379.096172 -291.215803)
			(xy 379.073301 -291.25938) (xy 379.043736 -291.298724) (xy 379.008243 -291.332816) (xy 378.96774 -291.360772)
			(xy 378.923278 -291.38187) (xy 378.876007 -291.395562) (xy 378.827152 -291.401494) (xy 378.777977 -291.399513)
			(xy 378.729758 -291.389669) (xy 378.683742 -291.372217) (xy 378.641121 -291.34761) (xy 378.603 -291.316485)
			(xy 378.570365 -291.279648) (xy 378.544062 -291.238052) (xy 378.524771 -291.192776) (xy 378.512994 -291.144992)
			(xy 378.509034 -291.095938) (xy 378.190506 -291.095938) (xy 378.189994 -291.121384) (xy 378.18183 -291.171618)
			(xy 378.165714 -291.219892) (xy 378.142063 -291.264955) (xy 378.11149 -291.305641) (xy 378.074786 -291.340896)
			(xy 378.032902 -291.369806) (xy 377.986923 -291.391623) (xy 377.938039 -291.405783) (xy 377.887518 -291.411917)
			(xy 377.836666 -291.409868) (xy 377.786802 -291.399688) (xy 377.739216 -291.381641) (xy 377.695142 -291.356195)
			(xy 377.65572 -291.324008) (xy 377.621972 -291.285914) (xy 377.594771 -291.2429) (xy 377.574823 -291.19608)
			(xy 377.562644 -291.146666) (xy 377.558549 -291.095938) (xy 377.240038 -291.095938) (xy 377.239528 -291.122116)
			(xy 377.23065 -291.173713) (xy 377.213094 -291.223037) (xy 377.187374 -291.268639) (xy 377.171204 -291.289232)
			(xy 377.16587 -291.295836) (xy 377.156726 -291.319966) (xy 377.155162 -291.324375) (xy 377.153494 -291.333577)
			(xy 377.153424 -291.338254) (xy 377.153678 -291.359844) (xy 377.15425 -291.369768) (xy 377.161955 -291.38807)
			(xy 377.168664 -291.395404) (xy 377.362974 -291.589714) (xy 377.369578 -291.592254) (xy 377.404884 -291.590476)
			(xy 377.429675 -291.590936) (xy 377.478647 -291.598691) (xy 377.525803 -291.614012) (xy 377.569981 -291.636522)
			(xy 377.610093 -291.665667) (xy 377.645151 -291.700728) (xy 377.674293 -291.740843) (xy 377.696799 -291.785023)
			(xy 377.712116 -291.83218) (xy 377.719866 -291.881153) (xy 377.720352 -291.905944) (xy 378.039134 -291.905944)
			(xy 378.043094 -291.85689) (xy 378.054871 -291.809106) (xy 378.074162 -291.76383) (xy 378.100465 -291.722234)
			(xy 378.1331 -291.685397) (xy 378.171221 -291.654272) (xy 378.213842 -291.629665) (xy 378.259858 -291.612213)
			(xy 378.308077 -291.602369) (xy 378.357252 -291.600388) (xy 378.406107 -291.60632) (xy 378.453378 -291.620012)
			(xy 378.49784 -291.64111) (xy 378.538343 -291.669066) (xy 378.573836 -291.703158) (xy 378.603401 -291.742502)
			(xy 378.626272 -291.786079) (xy 378.641856 -291.83276) (xy 378.649751 -291.881337) (xy 378.650246 -291.905944)
			(xy 378.968503 -291.905944) (xy 378.972598 -291.855216) (xy 378.984777 -291.805802) (xy 379.004725 -291.758982)
			(xy 379.031926 -291.715968) (xy 379.065674 -291.677874) (xy 379.105096 -291.645687) (xy 379.14917 -291.620241)
			(xy 379.196756 -291.602194) (xy 379.24662 -291.592014) (xy 379.297472 -291.589965) (xy 379.347993 -291.596099)
			(xy 379.396877 -291.610259) (xy 379.442856 -291.632076) (xy 379.48474 -291.660986) (xy 379.521444 -291.696241)
			(xy 379.552017 -291.736927) (xy 379.575668 -291.78199) (xy 379.591784 -291.830264) (xy 379.599948 -291.880498)
			(xy 379.60046 -291.905944) (xy 379.918988 -291.905944) (xy 379.922948 -291.85689) (xy 379.934725 -291.809106)
			(xy 379.954016 -291.76383) (xy 379.980319 -291.722234) (xy 380.012954 -291.685397) (xy 380.051075 -291.654272)
			(xy 380.093696 -291.629665) (xy 380.139712 -291.612213) (xy 380.187931 -291.602369) (xy 380.237106 -291.600388)
			(xy 380.285961 -291.60632) (xy 380.333232 -291.620012) (xy 380.377694 -291.64111) (xy 380.418197 -291.669066)
			(xy 380.45369 -291.703158) (xy 380.483255 -291.742502) (xy 380.506126 -291.786079) (xy 380.52171 -291.83276)
			(xy 380.529605 -291.881337) (xy 380.5301 -291.905944) (xy 380.848611 -291.905944) (xy 380.852706 -291.855216)
			(xy 380.864885 -291.805802) (xy 380.884833 -291.758982) (xy 380.912034 -291.715968) (xy 380.945782 -291.677874)
			(xy 380.985204 -291.645687) (xy 381.029278 -291.620241) (xy 381.076864 -291.602194) (xy 381.126728 -291.592014)
			(xy 381.17758 -291.589965) (xy 381.228101 -291.596099) (xy 381.276985 -291.610259) (xy 381.322964 -291.632076)
			(xy 381.364848 -291.660986) (xy 381.401552 -291.696241) (xy 381.432125 -291.736927) (xy 381.455776 -291.78199)
			(xy 381.471892 -291.830264) (xy 381.480056 -291.880498) (xy 381.480568 -291.905944) (xy 381.799096 -291.905944)
			(xy 381.803056 -291.85689) (xy 381.814833 -291.809106) (xy 381.834124 -291.76383) (xy 381.860427 -291.722234)
			(xy 381.893062 -291.685397) (xy 381.931183 -291.654272) (xy 381.973804 -291.629665) (xy 382.01982 -291.612213)
			(xy 382.068039 -291.602369) (xy 382.117214 -291.600388) (xy 382.166069 -291.60632) (xy 382.21334 -291.620012)
			(xy 382.257802 -291.64111) (xy 382.298305 -291.669066) (xy 382.333798 -291.703158) (xy 382.363363 -291.742502)
			(xy 382.386234 -291.786079) (xy 382.401818 -291.83276) (xy 382.409713 -291.881337) (xy 382.410208 -291.905944)
			(xy 382.728465 -291.905944) (xy 382.73256 -291.855216) (xy 382.744739 -291.805802) (xy 382.764687 -291.758982)
			(xy 382.791888 -291.715968) (xy 382.825636 -291.677874) (xy 382.865058 -291.645687) (xy 382.909132 -291.620241)
			(xy 382.956718 -291.602194) (xy 383.006582 -291.592014) (xy 383.057434 -291.589965) (xy 383.107955 -291.596099)
			(xy 383.156839 -291.610259) (xy 383.202818 -291.632076) (xy 383.244702 -291.660986) (xy 383.281406 -291.696241)
			(xy 383.311979 -291.736927) (xy 383.33563 -291.78199) (xy 383.351746 -291.830264) (xy 383.35991 -291.880498)
			(xy 383.360422 -291.905944) (xy 383.668519 -291.905944) (xy 383.672614 -291.855216) (xy 383.684793 -291.805802)
			(xy 383.704741 -291.758982) (xy 383.731942 -291.715968) (xy 383.76569 -291.677874) (xy 383.805112 -291.645687)
			(xy 383.849186 -291.620241) (xy 383.896772 -291.602194) (xy 383.946636 -291.592014) (xy 383.997488 -291.589965)
			(xy 384.048009 -291.596099) (xy 384.096893 -291.610259) (xy 384.142872 -291.632076) (xy 384.184756 -291.660986)
			(xy 384.22146 -291.696241) (xy 384.252033 -291.736927) (xy 384.275684 -291.78199) (xy 384.2918 -291.830264)
			(xy 384.299964 -291.880498) (xy 384.300476 -291.905944) (xy 384.619004 -291.905944) (xy 384.622964 -291.85689)
			(xy 384.634741 -291.809106) (xy 384.654032 -291.76383) (xy 384.680335 -291.722234) (xy 384.71297 -291.685397)
			(xy 384.751091 -291.654272) (xy 384.793712 -291.629665) (xy 384.839728 -291.612213) (xy 384.887947 -291.602369)
			(xy 384.937122 -291.600388) (xy 384.985977 -291.60632) (xy 385.033248 -291.620012) (xy 385.07771 -291.64111)
			(xy 385.118213 -291.669066) (xy 385.153706 -291.703158) (xy 385.183271 -291.742502) (xy 385.206142 -291.786079)
			(xy 385.221726 -291.83276) (xy 385.229621 -291.881337) (xy 385.230116 -291.905944) (xy 385.548627 -291.905944)
			(xy 385.552722 -291.855216) (xy 385.564901 -291.805802) (xy 385.584849 -291.758982) (xy 385.61205 -291.715968)
			(xy 385.645798 -291.677874) (xy 385.68522 -291.645687) (xy 385.729294 -291.620241) (xy 385.77688 -291.602194)
			(xy 385.826744 -291.592014) (xy 385.877596 -291.589965) (xy 385.928117 -291.596099) (xy 385.977001 -291.610259)
			(xy 386.02298 -291.632076) (xy 386.064864 -291.660986) (xy 386.101568 -291.696241) (xy 386.132141 -291.736927)
			(xy 386.155792 -291.78199) (xy 386.171908 -291.830264) (xy 386.180072 -291.880498) (xy 386.180584 -291.905944)
			(xy 386.499112 -291.905944) (xy 386.503072 -291.85689) (xy 386.514849 -291.809106) (xy 386.53414 -291.76383)
			(xy 386.560443 -291.722234) (xy 386.593078 -291.685397) (xy 386.631199 -291.654272) (xy 386.67382 -291.629665)
			(xy 386.719836 -291.612213) (xy 386.768055 -291.602369) (xy 386.81723 -291.600388) (xy 386.866085 -291.60632)
			(xy 386.913356 -291.620012) (xy 386.957818 -291.64111) (xy 386.998321 -291.669066) (xy 387.033814 -291.703158)
			(xy 387.063379 -291.742502) (xy 387.08625 -291.786079) (xy 387.101834 -291.83276) (xy 387.109729 -291.881337)
			(xy 387.110224 -291.905944) (xy 387.428481 -291.905944) (xy 387.432576 -291.855216) (xy 387.444755 -291.805802)
			(xy 387.464703 -291.758982) (xy 387.491904 -291.715968) (xy 387.525652 -291.677874) (xy 387.565074 -291.645687)
			(xy 387.609148 -291.620241) (xy 387.656734 -291.602194) (xy 387.706598 -291.592014) (xy 387.75745 -291.589965)
			(xy 387.807971 -291.596099) (xy 387.856855 -291.610259) (xy 387.902834 -291.632076) (xy 387.944718 -291.660986)
			(xy 387.981422 -291.696241) (xy 388.011995 -291.736927) (xy 388.035646 -291.78199) (xy 388.051762 -291.830264)
			(xy 388.059926 -291.880498) (xy 388.060438 -291.905944) (xy 388.378966 -291.905944) (xy 388.382926 -291.85689)
			(xy 388.394703 -291.809106) (xy 388.413994 -291.76383) (xy 388.440297 -291.722234) (xy 388.472932 -291.685397)
			(xy 388.511053 -291.654272) (xy 388.553674 -291.629665) (xy 388.59969 -291.612213) (xy 388.647909 -291.602369)
			(xy 388.697084 -291.600388) (xy 388.745939 -291.60632) (xy 388.79321 -291.620012) (xy 388.837672 -291.64111)
			(xy 388.878175 -291.669066) (xy 388.913668 -291.703158) (xy 388.943233 -291.742502) (xy 388.966104 -291.786079)
			(xy 388.981688 -291.83276) (xy 388.989583 -291.881337) (xy 388.990078 -291.905944) (xy 389.308589 -291.905944)
			(xy 389.312684 -291.855216) (xy 389.324863 -291.805802) (xy 389.344811 -291.758982) (xy 389.372012 -291.715968)
			(xy 389.40576 -291.677874) (xy 389.445182 -291.645687) (xy 389.489256 -291.620241) (xy 389.536842 -291.602194)
			(xy 389.586706 -291.592014) (xy 389.637558 -291.589965) (xy 389.688079 -291.596099) (xy 389.736963 -291.610259)
			(xy 389.782942 -291.632076) (xy 389.824826 -291.660986) (xy 389.86153 -291.696241) (xy 389.892103 -291.736927)
			(xy 389.915754 -291.78199) (xy 389.93187 -291.830264) (xy 389.940034 -291.880498) (xy 389.940546 -291.905944)
			(xy 390.248643 -291.905944) (xy 390.252738 -291.855216) (xy 390.264917 -291.805802) (xy 390.284865 -291.758982)
			(xy 390.312066 -291.715968) (xy 390.345814 -291.677874) (xy 390.385236 -291.645687) (xy 390.42931 -291.620241)
			(xy 390.476896 -291.602194) (xy 390.52676 -291.592014) (xy 390.577612 -291.589965) (xy 390.628133 -291.596099)
			(xy 390.677017 -291.610259) (xy 390.722996 -291.632076) (xy 390.76488 -291.660986) (xy 390.801584 -291.696241)
			(xy 390.832157 -291.736927) (xy 390.855808 -291.78199) (xy 390.871924 -291.830264) (xy 390.880088 -291.880498)
			(xy 390.8806 -291.905944) (xy 391.198874 -291.905944) (xy 391.202834 -291.85689) (xy 391.214611 -291.809106)
			(xy 391.233902 -291.76383) (xy 391.260205 -291.722234) (xy 391.29284 -291.685397) (xy 391.330961 -291.654272)
			(xy 391.373582 -291.629665) (xy 391.419598 -291.612213) (xy 391.467817 -291.602369) (xy 391.516992 -291.600388)
			(xy 391.565847 -291.60632) (xy 391.613118 -291.620012) (xy 391.65758 -291.64111) (xy 391.698083 -291.669066)
			(xy 391.733576 -291.703158) (xy 391.763141 -291.742502) (xy 391.786012 -291.786079) (xy 391.801596 -291.83276)
			(xy 391.809491 -291.881337) (xy 391.809986 -291.905944) (xy 393.078982 -291.905944) (xy 393.082942 -291.85689)
			(xy 393.094719 -291.809106) (xy 393.11401 -291.76383) (xy 393.140313 -291.722234) (xy 393.172948 -291.685397)
			(xy 393.211069 -291.654272) (xy 393.25369 -291.629665) (xy 393.299706 -291.612213) (xy 393.347925 -291.602369)
			(xy 393.3971 -291.600388) (xy 393.445955 -291.60632) (xy 393.493226 -291.620012) (xy 393.537688 -291.64111)
			(xy 393.578191 -291.669066) (xy 393.613684 -291.703158) (xy 393.643249 -291.742502) (xy 393.66612 -291.786079)
			(xy 393.681704 -291.83276) (xy 393.689599 -291.881337) (xy 393.690094 -291.905944) (xy 393.689599 -291.930551)
			(xy 393.681704 -291.979128) (xy 393.66612 -292.025809) (xy 393.643249 -292.069386) (xy 393.613684 -292.10873)
			(xy 393.578191 -292.142822) (xy 393.537688 -292.170778) (xy 393.493226 -292.191876) (xy 393.445955 -292.205568)
			(xy 393.3971 -292.2115) (xy 393.347925 -292.209519) (xy 393.299706 -292.199675) (xy 393.25369 -292.182223)
			(xy 393.211069 -292.157616) (xy 393.172948 -292.126491) (xy 393.140313 -292.089654) (xy 393.11401 -292.048058)
			(xy 393.094719 -292.002782) (xy 393.082942 -291.954998) (xy 393.078982 -291.905944) (xy 391.809986 -291.905944)
			(xy 391.809491 -291.930551) (xy 391.801596 -291.979128) (xy 391.786012 -292.025809) (xy 391.763141 -292.069386)
			(xy 391.733576 -292.10873) (xy 391.698083 -292.142822) (xy 391.65758 -292.170778) (xy 391.613118 -292.191876)
			(xy 391.565847 -292.205568) (xy 391.516992 -292.2115) (xy 391.467817 -292.209519) (xy 391.419598 -292.199675)
			(xy 391.373582 -292.182223) (xy 391.330961 -292.157616) (xy 391.29284 -292.126491) (xy 391.260205 -292.089654)
			(xy 391.233902 -292.048058) (xy 391.214611 -292.002782) (xy 391.202834 -291.954998) (xy 391.198874 -291.905944)
			(xy 390.8806 -291.905944) (xy 390.880088 -291.93139) (xy 390.871924 -291.981624) (xy 390.855808 -292.029898)
			(xy 390.832157 -292.074961) (xy 390.801584 -292.115647) (xy 390.76488 -292.150902) (xy 390.722996 -292.179812)
			(xy 390.677017 -292.201629) (xy 390.628133 -292.215789) (xy 390.577612 -292.221923) (xy 390.52676 -292.219874)
			(xy 390.476896 -292.209694) (xy 390.42931 -292.191647) (xy 390.385236 -292.166201) (xy 390.345814 -292.134014)
			(xy 390.312066 -292.09592) (xy 390.284865 -292.052906) (xy 390.264917 -292.006086) (xy 390.252738 -291.956672)
			(xy 390.248643 -291.905944) (xy 389.940546 -291.905944) (xy 389.940034 -291.93139) (xy 389.93187 -291.981624)
			(xy 389.915754 -292.029898) (xy 389.892103 -292.074961) (xy 389.86153 -292.115647) (xy 389.824826 -292.150902)
			(xy 389.782942 -292.179812) (xy 389.736963 -292.201629) (xy 389.688079 -292.215789) (xy 389.637558 -292.221923)
			(xy 389.586706 -292.219874) (xy 389.536842 -292.209694) (xy 389.489256 -292.191647) (xy 389.445182 -292.166201)
			(xy 389.40576 -292.134014) (xy 389.372012 -292.09592) (xy 389.344811 -292.052906) (xy 389.324863 -292.006086)
			(xy 389.312684 -291.956672) (xy 389.308589 -291.905944) (xy 388.990078 -291.905944) (xy 388.989583 -291.930551)
			(xy 388.981688 -291.979128) (xy 388.966104 -292.025809) (xy 388.943233 -292.069386) (xy 388.913668 -292.10873)
			(xy 388.878175 -292.142822) (xy 388.837672 -292.170778) (xy 388.79321 -292.191876) (xy 388.745939 -292.205568)
			(xy 388.697084 -292.2115) (xy 388.647909 -292.209519) (xy 388.59969 -292.199675) (xy 388.553674 -292.182223)
			(xy 388.511053 -292.157616) (xy 388.472932 -292.126491) (xy 388.440297 -292.089654) (xy 388.413994 -292.048058)
			(xy 388.394703 -292.002782) (xy 388.382926 -291.954998) (xy 388.378966 -291.905944) (xy 388.060438 -291.905944)
			(xy 388.059926 -291.93139) (xy 388.051762 -291.981624) (xy 388.035646 -292.029898) (xy 388.011995 -292.074961)
			(xy 387.981422 -292.115647) (xy 387.944718 -292.150902) (xy 387.902834 -292.179812) (xy 387.856855 -292.201629)
			(xy 387.807971 -292.215789) (xy 387.75745 -292.221923) (xy 387.706598 -292.219874) (xy 387.656734 -292.209694)
			(xy 387.609148 -292.191647) (xy 387.565074 -292.166201) (xy 387.525652 -292.134014) (xy 387.491904 -292.09592)
			(xy 387.464703 -292.052906) (xy 387.444755 -292.006086) (xy 387.432576 -291.956672) (xy 387.428481 -291.905944)
			(xy 387.110224 -291.905944) (xy 387.109729 -291.930551) (xy 387.101834 -291.979128) (xy 387.08625 -292.025809)
			(xy 387.063379 -292.069386) (xy 387.033814 -292.10873) (xy 386.998321 -292.142822) (xy 386.957818 -292.170778)
			(xy 386.913356 -292.191876) (xy 386.866085 -292.205568) (xy 386.81723 -292.2115) (xy 386.768055 -292.209519)
			(xy 386.719836 -292.199675) (xy 386.67382 -292.182223) (xy 386.631199 -292.157616) (xy 386.593078 -292.126491)
			(xy 386.560443 -292.089654) (xy 386.53414 -292.048058) (xy 386.514849 -292.002782) (xy 386.503072 -291.954998)
			(xy 386.499112 -291.905944) (xy 386.180584 -291.905944) (xy 386.180072 -291.93139) (xy 386.171908 -291.981624)
			(xy 386.155792 -292.029898) (xy 386.132141 -292.074961) (xy 386.101568 -292.115647) (xy 386.064864 -292.150902)
			(xy 386.02298 -292.179812) (xy 385.977001 -292.201629) (xy 385.928117 -292.215789) (xy 385.877596 -292.221923)
			(xy 385.826744 -292.219874) (xy 385.77688 -292.209694) (xy 385.729294 -292.191647) (xy 385.68522 -292.166201)
			(xy 385.645798 -292.134014) (xy 385.61205 -292.09592) (xy 385.584849 -292.052906) (xy 385.564901 -292.006086)
			(xy 385.552722 -291.956672) (xy 385.548627 -291.905944) (xy 385.230116 -291.905944) (xy 385.229621 -291.930551)
			(xy 385.221726 -291.979128) (xy 385.206142 -292.025809) (xy 385.183271 -292.069386) (xy 385.153706 -292.10873)
			(xy 385.118213 -292.142822) (xy 385.07771 -292.170778) (xy 385.033248 -292.191876) (xy 384.985977 -292.205568)
			(xy 384.937122 -292.2115) (xy 384.887947 -292.209519) (xy 384.839728 -292.199675) (xy 384.793712 -292.182223)
			(xy 384.751091 -292.157616) (xy 384.71297 -292.126491) (xy 384.680335 -292.089654) (xy 384.654032 -292.048058)
			(xy 384.634741 -292.002782) (xy 384.622964 -291.954998) (xy 384.619004 -291.905944) (xy 384.300476 -291.905944)
			(xy 384.299964 -291.93139) (xy 384.2918 -291.981624) (xy 384.275684 -292.029898) (xy 384.252033 -292.074961)
			(xy 384.22146 -292.115647) (xy 384.184756 -292.150902) (xy 384.142872 -292.179812) (xy 384.096893 -292.201629)
			(xy 384.048009 -292.215789) (xy 383.997488 -292.221923) (xy 383.946636 -292.219874) (xy 383.896772 -292.209694)
			(xy 383.849186 -292.191647) (xy 383.805112 -292.166201) (xy 383.76569 -292.134014) (xy 383.731942 -292.09592)
			(xy 383.704741 -292.052906) (xy 383.684793 -292.006086) (xy 383.672614 -291.956672) (xy 383.668519 -291.905944)
			(xy 383.360422 -291.905944) (xy 383.35991 -291.93139) (xy 383.351746 -291.981624) (xy 383.33563 -292.029898)
			(xy 383.311979 -292.074961) (xy 383.281406 -292.115647) (xy 383.244702 -292.150902) (xy 383.202818 -292.179812)
			(xy 383.156839 -292.201629) (xy 383.107955 -292.215789) (xy 383.057434 -292.221923) (xy 383.006582 -292.219874)
			(xy 382.956718 -292.209694) (xy 382.909132 -292.191647) (xy 382.865058 -292.166201) (xy 382.825636 -292.134014)
			(xy 382.791888 -292.09592) (xy 382.764687 -292.052906) (xy 382.744739 -292.006086) (xy 382.73256 -291.956672)
			(xy 382.728465 -291.905944) (xy 382.410208 -291.905944) (xy 382.409713 -291.930551) (xy 382.401818 -291.979128)
			(xy 382.386234 -292.025809) (xy 382.363363 -292.069386) (xy 382.333798 -292.10873) (xy 382.298305 -292.142822)
			(xy 382.257802 -292.170778) (xy 382.21334 -292.191876) (xy 382.166069 -292.205568) (xy 382.117214 -292.2115)
			(xy 382.068039 -292.209519) (xy 382.01982 -292.199675) (xy 381.973804 -292.182223) (xy 381.931183 -292.157616)
			(xy 381.893062 -292.126491) (xy 381.860427 -292.089654) (xy 381.834124 -292.048058) (xy 381.814833 -292.002782)
			(xy 381.803056 -291.954998) (xy 381.799096 -291.905944) (xy 381.480568 -291.905944) (xy 381.480056 -291.93139)
			(xy 381.471892 -291.981624) (xy 381.455776 -292.029898) (xy 381.432125 -292.074961) (xy 381.401552 -292.115647)
			(xy 381.364848 -292.150902) (xy 381.322964 -292.179812) (xy 381.276985 -292.201629) (xy 381.228101 -292.215789)
			(xy 381.17758 -292.221923) (xy 381.126728 -292.219874) (xy 381.076864 -292.209694) (xy 381.029278 -292.191647)
			(xy 380.985204 -292.166201) (xy 380.945782 -292.134014) (xy 380.912034 -292.09592) (xy 380.884833 -292.052906)
			(xy 380.864885 -292.006086) (xy 380.852706 -291.956672) (xy 380.848611 -291.905944) (xy 380.5301 -291.905944)
			(xy 380.529605 -291.930551) (xy 380.52171 -291.979128) (xy 380.506126 -292.025809) (xy 380.483255 -292.069386)
			(xy 380.45369 -292.10873) (xy 380.418197 -292.142822) (xy 380.377694 -292.170778) (xy 380.333232 -292.191876)
			(xy 380.285961 -292.205568) (xy 380.237106 -292.2115) (xy 380.187931 -292.209519) (xy 380.139712 -292.199675)
			(xy 380.093696 -292.182223) (xy 380.051075 -292.157616) (xy 380.012954 -292.126491) (xy 379.980319 -292.089654)
			(xy 379.954016 -292.048058) (xy 379.934725 -292.002782) (xy 379.922948 -291.954998) (xy 379.918988 -291.905944)
			(xy 379.60046 -291.905944) (xy 379.599948 -291.93139) (xy 379.591784 -291.981624) (xy 379.575668 -292.029898)
			(xy 379.552017 -292.074961) (xy 379.521444 -292.115647) (xy 379.48474 -292.150902) (xy 379.442856 -292.179812)
			(xy 379.396877 -292.201629) (xy 379.347993 -292.215789) (xy 379.297472 -292.221923) (xy 379.24662 -292.219874)
			(xy 379.196756 -292.209694) (xy 379.14917 -292.191647) (xy 379.105096 -292.166201) (xy 379.065674 -292.134014)
			(xy 379.031926 -292.09592) (xy 379.004725 -292.052906) (xy 378.984777 -292.006086) (xy 378.972598 -291.956672)
			(xy 378.968503 -291.905944) (xy 378.650246 -291.905944) (xy 378.649751 -291.930551) (xy 378.641856 -291.979128)
			(xy 378.626272 -292.025809) (xy 378.603401 -292.069386) (xy 378.573836 -292.10873) (xy 378.538343 -292.142822)
			(xy 378.49784 -292.170778) (xy 378.453378 -292.191876) (xy 378.406107 -292.205568) (xy 378.357252 -292.2115)
			(xy 378.308077 -292.209519) (xy 378.259858 -292.199675) (xy 378.213842 -292.182223) (xy 378.171221 -292.157616)
			(xy 378.1331 -292.126491) (xy 378.100465 -292.089654) (xy 378.074162 -292.048058) (xy 378.054871 -292.002782)
			(xy 378.043094 -291.954998) (xy 378.039134 -291.905944) (xy 377.720352 -291.905944) (xy 377.720098 -291.922962)
			(xy 377.719336 -291.933884) (xy 377.726956 -291.953696) (xy 378.48921 -292.71595) (xy 379.438657 -292.71595)
			(xy 379.442752 -292.665222) (xy 379.454931 -292.615808) (xy 379.474879 -292.568988) (xy 379.50208 -292.525974)
			(xy 379.535828 -292.48788) (xy 379.57525 -292.455693) (xy 379.619324 -292.430247) (xy 379.66691 -292.4122)
			(xy 379.716774 -292.40202) (xy 379.767626 -292.399971) (xy 379.818147 -292.406105) (xy 379.867031 -292.420265)
			(xy 379.91301 -292.442082) (xy 379.954894 -292.470992) (xy 379.991598 -292.506247) (xy 380.022171 -292.546933)
			(xy 380.045822 -292.591996) (xy 380.061938 -292.64027) (xy 380.070102 -292.690504) (xy 380.070614 -292.71595)
			(xy 380.378711 -292.71595) (xy 380.382806 -292.665222) (xy 380.394985 -292.615808) (xy 380.414933 -292.568988)
			(xy 380.442134 -292.525974) (xy 380.475882 -292.48788) (xy 380.515304 -292.455693) (xy 380.559378 -292.430247)
			(xy 380.606964 -292.4122) (xy 380.656828 -292.40202) (xy 380.70768 -292.399971) (xy 380.758201 -292.406105)
			(xy 380.807085 -292.420265) (xy 380.853064 -292.442082) (xy 380.894948 -292.470992) (xy 380.931652 -292.506247)
			(xy 380.962225 -292.546933) (xy 380.985876 -292.591996) (xy 381.001992 -292.64027) (xy 381.010156 -292.690504)
			(xy 381.010668 -292.71595) (xy 381.328942 -292.71595) (xy 381.332902 -292.666896) (xy 381.344679 -292.619112)
			(xy 381.36397 -292.573836) (xy 381.390273 -292.53224) (xy 381.422908 -292.495403) (xy 381.461029 -292.464278)
			(xy 381.50365 -292.439671) (xy 381.549666 -292.422219) (xy 381.597885 -292.412375) (xy 381.64706 -292.410394)
			(xy 381.695915 -292.416326) (xy 381.743186 -292.430018) (xy 381.787648 -292.451116) (xy 381.828151 -292.479072)
			(xy 381.863644 -292.513164) (xy 381.893209 -292.552508) (xy 381.91608 -292.596085) (xy 381.931664 -292.642766)
			(xy 381.939559 -292.691343) (xy 381.940054 -292.71595) (xy 382.258565 -292.71595) (xy 382.26266 -292.665222)
			(xy 382.274839 -292.615808) (xy 382.294787 -292.568988) (xy 382.321988 -292.525974) (xy 382.355736 -292.48788)
			(xy 382.395158 -292.455693) (xy 382.439232 -292.430247) (xy 382.486818 -292.4122) (xy 382.536682 -292.40202)
			(xy 382.587534 -292.399971) (xy 382.638055 -292.406105) (xy 382.686939 -292.420265) (xy 382.732918 -292.442082)
			(xy 382.774802 -292.470992) (xy 382.811506 -292.506247) (xy 382.842079 -292.546933) (xy 382.86573 -292.591996)
			(xy 382.881846 -292.64027) (xy 382.89001 -292.690504) (xy 382.890522 -292.71595) (xy 383.20905 -292.71595)
			(xy 383.21301 -292.666896) (xy 383.224787 -292.619112) (xy 383.244078 -292.573836) (xy 383.270381 -292.53224)
			(xy 383.303016 -292.495403) (xy 383.341137 -292.464278) (xy 383.383758 -292.439671) (xy 383.429774 -292.422219)
			(xy 383.477993 -292.412375) (xy 383.527168 -292.410394) (xy 383.576023 -292.416326) (xy 383.623294 -292.430018)
			(xy 383.667756 -292.451116) (xy 383.708259 -292.479072) (xy 383.743752 -292.513164) (xy 383.773317 -292.552508)
			(xy 383.796188 -292.596085) (xy 383.811772 -292.642766) (xy 383.819667 -292.691343) (xy 383.820162 -292.71595)
			(xy 384.138673 -292.71595) (xy 384.142768 -292.665222) (xy 384.154947 -292.615808) (xy 384.174895 -292.568988)
			(xy 384.202096 -292.525974) (xy 384.235844 -292.48788) (xy 384.275266 -292.455693) (xy 384.31934 -292.430247)
			(xy 384.366926 -292.4122) (xy 384.41679 -292.40202) (xy 384.467642 -292.399971) (xy 384.518163 -292.406105)
			(xy 384.567047 -292.420265) (xy 384.613026 -292.442082) (xy 384.65491 -292.470992) (xy 384.691614 -292.506247)
			(xy 384.722187 -292.546933) (xy 384.745838 -292.591996) (xy 384.761954 -292.64027) (xy 384.770118 -292.690504)
			(xy 384.77063 -292.71595) (xy 386.018527 -292.71595) (xy 386.022622 -292.665222) (xy 386.034801 -292.615808)
			(xy 386.054749 -292.568988) (xy 386.08195 -292.525974) (xy 386.115698 -292.48788) (xy 386.15512 -292.455693)
			(xy 386.199194 -292.430247) (xy 386.24678 -292.4122) (xy 386.296644 -292.40202) (xy 386.347496 -292.399971)
			(xy 386.398017 -292.406105) (xy 386.446901 -292.420265) (xy 386.49288 -292.442082) (xy 386.534764 -292.470992)
			(xy 386.571468 -292.506247) (xy 386.602041 -292.546933) (xy 386.625692 -292.591996) (xy 386.641808 -292.64027)
			(xy 386.649972 -292.690504) (xy 386.650484 -292.71595) (xy 386.958581 -292.71595) (xy 386.962676 -292.665222)
			(xy 386.974855 -292.615808) (xy 386.994803 -292.568988) (xy 387.022004 -292.525974) (xy 387.055752 -292.48788)
			(xy 387.095174 -292.455693) (xy 387.139248 -292.430247) (xy 387.186834 -292.4122) (xy 387.236698 -292.40202)
			(xy 387.28755 -292.399971) (xy 387.338071 -292.406105) (xy 387.386955 -292.420265) (xy 387.432934 -292.442082)
			(xy 387.474818 -292.470992) (xy 387.511522 -292.506247) (xy 387.542095 -292.546933) (xy 387.565746 -292.591996)
			(xy 387.581862 -292.64027) (xy 387.590026 -292.690504) (xy 387.590538 -292.71595) (xy 387.909066 -292.71595)
			(xy 387.913026 -292.666896) (xy 387.924803 -292.619112) (xy 387.944094 -292.573836) (xy 387.970397 -292.53224)
			(xy 388.003032 -292.495403) (xy 388.041153 -292.464278) (xy 388.083774 -292.439671) (xy 388.12979 -292.422219)
			(xy 388.178009 -292.412375) (xy 388.227184 -292.410394) (xy 388.276039 -292.416326) (xy 388.32331 -292.430018)
			(xy 388.367772 -292.451116) (xy 388.408275 -292.479072) (xy 388.443768 -292.513164) (xy 388.473333 -292.552508)
			(xy 388.496204 -292.596085) (xy 388.511788 -292.642766) (xy 388.519683 -292.691343) (xy 388.520178 -292.71595)
			(xy 388.838689 -292.71595) (xy 388.842784 -292.665222) (xy 388.854963 -292.615808) (xy 388.874911 -292.568988)
			(xy 388.902112 -292.525974) (xy 388.93586 -292.48788) (xy 388.975282 -292.455693) (xy 389.019356 -292.430247)
			(xy 389.066942 -292.4122) (xy 389.116806 -292.40202) (xy 389.167658 -292.399971) (xy 389.218179 -292.406105)
			(xy 389.267063 -292.420265) (xy 389.313042 -292.442082) (xy 389.354926 -292.470992) (xy 389.39163 -292.506247)
			(xy 389.422203 -292.546933) (xy 389.445854 -292.591996) (xy 389.46197 -292.64027) (xy 389.470134 -292.690504)
			(xy 389.470646 -292.71595) (xy 389.78892 -292.71595) (xy 389.79288 -292.666896) (xy 389.804657 -292.619112)
			(xy 389.823948 -292.573836) (xy 389.850251 -292.53224) (xy 389.882886 -292.495403) (xy 389.921007 -292.464278)
			(xy 389.963628 -292.439671) (xy 390.009644 -292.422219) (xy 390.057863 -292.412375) (xy 390.107038 -292.410394)
			(xy 390.155893 -292.416326) (xy 390.203164 -292.430018) (xy 390.247626 -292.451116) (xy 390.288129 -292.479072)
			(xy 390.323622 -292.513164) (xy 390.353187 -292.552508) (xy 390.376058 -292.596085) (xy 390.391642 -292.642766)
			(xy 390.399537 -292.691343) (xy 390.400032 -292.71595) (xy 390.718543 -292.71595) (xy 390.722638 -292.665222)
			(xy 390.734817 -292.615808) (xy 390.754765 -292.568988) (xy 390.781966 -292.525974) (xy 390.815714 -292.48788)
			(xy 390.855136 -292.455693) (xy 390.89921 -292.430247) (xy 390.946796 -292.4122) (xy 390.99666 -292.40202)
			(xy 391.047512 -292.399971) (xy 391.098033 -292.406105) (xy 391.146917 -292.420265) (xy 391.192896 -292.442082)
			(xy 391.204385 -292.450012) (xy 394.67715 -292.450012) (xy 394.68111 -292.400958) (xy 394.692887 -292.353174)
			(xy 394.712178 -292.307898) (xy 394.738481 -292.266302) (xy 394.771116 -292.229465) (xy 394.809237 -292.19834)
			(xy 394.851858 -292.173733) (xy 394.897874 -292.156281) (xy 394.946093 -292.146437) (xy 394.995268 -292.144456)
			(xy 395.044123 -292.150388) (xy 395.091394 -292.16408) (xy 395.135856 -292.185178) (xy 395.176359 -292.213134)
			(xy 395.211852 -292.247226) (xy 395.241417 -292.28657) (xy 395.264288 -292.330147) (xy 395.279872 -292.376828)
			(xy 395.287767 -292.425405) (xy 395.288262 -292.450012) (xy 395.287767 -292.474619) (xy 395.279872 -292.523196)
			(xy 395.264288 -292.569877) (xy 395.241417 -292.613454) (xy 395.211852 -292.652798) (xy 395.176359 -292.68689)
			(xy 395.135856 -292.714846) (xy 395.091394 -292.735944) (xy 395.044123 -292.749636) (xy 394.995268 -292.755568)
			(xy 394.946093 -292.753587) (xy 394.897874 -292.743743) (xy 394.851858 -292.726291) (xy 394.809237 -292.701684)
			(xy 394.771116 -292.670559) (xy 394.738481 -292.633722) (xy 394.712178 -292.592126) (xy 394.692887 -292.54685)
			(xy 394.68111 -292.499066) (xy 394.67715 -292.450012) (xy 391.204385 -292.450012) (xy 391.23478 -292.470992)
			(xy 391.271484 -292.506247) (xy 391.302057 -292.546933) (xy 391.325708 -292.591996) (xy 391.341824 -292.64027)
			(xy 391.349988 -292.690504) (xy 391.3505 -292.71595) (xy 391.349988 -292.741396) (xy 391.341824 -292.79163)
			(xy 391.325708 -292.839904) (xy 391.302057 -292.884967) (xy 391.271484 -292.925653) (xy 391.23478 -292.960908)
			(xy 391.192896 -292.989818) (xy 391.146917 -293.011635) (xy 391.098033 -293.025795) (xy 391.047512 -293.031929)
			(xy 390.99666 -293.02988) (xy 390.946796 -293.0197) (xy 390.89921 -293.001653) (xy 390.855136 -292.976207)
			(xy 390.815714 -292.94402) (xy 390.781966 -292.905926) (xy 390.754765 -292.862912) (xy 390.734817 -292.816092)
			(xy 390.722638 -292.766678) (xy 390.718543 -292.71595) (xy 390.400032 -292.71595) (xy 390.399537 -292.740557)
			(xy 390.391642 -292.789134) (xy 390.376058 -292.835815) (xy 390.353187 -292.879392) (xy 390.323622 -292.918736)
			(xy 390.288129 -292.952828) (xy 390.247626 -292.980784) (xy 390.203164 -293.001882) (xy 390.155893 -293.015574)
			(xy 390.107038 -293.021506) (xy 390.057863 -293.019525) (xy 390.009644 -293.009681) (xy 389.963628 -292.992229)
			(xy 389.921007 -292.967622) (xy 389.882886 -292.936497) (xy 389.850251 -292.89966) (xy 389.823948 -292.858064)
			(xy 389.804657 -292.812788) (xy 389.79288 -292.765004) (xy 389.78892 -292.71595) (xy 389.470646 -292.71595)
			(xy 389.470134 -292.741396) (xy 389.46197 -292.79163) (xy 389.445854 -292.839904) (xy 389.422203 -292.884967)
			(xy 389.39163 -292.925653) (xy 389.354926 -292.960908) (xy 389.313042 -292.989818) (xy 389.267063 -293.011635)
			(xy 389.218179 -293.025795) (xy 389.167658 -293.031929) (xy 389.116806 -293.02988) (xy 389.066942 -293.0197)
			(xy 389.019356 -293.001653) (xy 388.975282 -292.976207) (xy 388.93586 -292.94402) (xy 388.902112 -292.905926)
			(xy 388.874911 -292.862912) (xy 388.854963 -292.816092) (xy 388.842784 -292.766678) (xy 388.838689 -292.71595)
			(xy 388.520178 -292.71595) (xy 388.519683 -292.740557) (xy 388.511788 -292.789134) (xy 388.496204 -292.835815)
			(xy 388.473333 -292.879392) (xy 388.443768 -292.918736) (xy 388.408275 -292.952828) (xy 388.367772 -292.980784)
			(xy 388.32331 -293.001882) (xy 388.276039 -293.015574) (xy 388.227184 -293.021506) (xy 388.178009 -293.019525)
			(xy 388.12979 -293.009681) (xy 388.083774 -292.992229) (xy 388.041153 -292.967622) (xy 388.003032 -292.936497)
			(xy 387.970397 -292.89966) (xy 387.944094 -292.858064) (xy 387.924803 -292.812788) (xy 387.913026 -292.765004)
			(xy 387.909066 -292.71595) (xy 387.590538 -292.71595) (xy 387.590026 -292.741396) (xy 387.581862 -292.79163)
			(xy 387.565746 -292.839904) (xy 387.542095 -292.884967) (xy 387.511522 -292.925653) (xy 387.474818 -292.960908)
			(xy 387.432934 -292.989818) (xy 387.386955 -293.011635) (xy 387.338071 -293.025795) (xy 387.28755 -293.031929)
			(xy 387.236698 -293.02988) (xy 387.186834 -293.0197) (xy 387.139248 -293.001653) (xy 387.095174 -292.976207)
			(xy 387.055752 -292.94402) (xy 387.022004 -292.905926) (xy 386.994803 -292.862912) (xy 386.974855 -292.816092)
			(xy 386.962676 -292.766678) (xy 386.958581 -292.71595) (xy 386.650484 -292.71595) (xy 386.649972 -292.741396)
			(xy 386.641808 -292.79163) (xy 386.625692 -292.839904) (xy 386.602041 -292.884967) (xy 386.571468 -292.925653)
			(xy 386.534764 -292.960908) (xy 386.49288 -292.989818) (xy 386.446901 -293.011635) (xy 386.398017 -293.025795)
			(xy 386.347496 -293.031929) (xy 386.296644 -293.02988) (xy 386.24678 -293.0197) (xy 386.199194 -293.001653)
			(xy 386.15512 -292.976207) (xy 386.115698 -292.94402) (xy 386.08195 -292.905926) (xy 386.054749 -292.862912)
			(xy 386.034801 -292.816092) (xy 386.022622 -292.766678) (xy 386.018527 -292.71595) (xy 384.77063 -292.71595)
			(xy 384.770118 -292.741396) (xy 384.761954 -292.79163) (xy 384.745838 -292.839904) (xy 384.722187 -292.884967)
			(xy 384.691614 -292.925653) (xy 384.65491 -292.960908) (xy 384.613026 -292.989818) (xy 384.567047 -293.011635)
			(xy 384.518163 -293.025795) (xy 384.467642 -293.031929) (xy 384.41679 -293.02988) (xy 384.366926 -293.0197)
			(xy 384.31934 -293.001653) (xy 384.275266 -292.976207) (xy 384.235844 -292.94402) (xy 384.202096 -292.905926)
			(xy 384.174895 -292.862912) (xy 384.154947 -292.816092) (xy 384.142768 -292.766678) (xy 384.138673 -292.71595)
			(xy 383.820162 -292.71595) (xy 383.819667 -292.740557) (xy 383.811772 -292.789134) (xy 383.796188 -292.835815)
			(xy 383.773317 -292.879392) (xy 383.743752 -292.918736) (xy 383.708259 -292.952828) (xy 383.667756 -292.980784)
			(xy 383.623294 -293.001882) (xy 383.576023 -293.015574) (xy 383.527168 -293.021506) (xy 383.477993 -293.019525)
			(xy 383.429774 -293.009681) (xy 383.383758 -292.992229) (xy 383.341137 -292.967622) (xy 383.303016 -292.936497)
			(xy 383.270381 -292.89966) (xy 383.244078 -292.858064) (xy 383.224787 -292.812788) (xy 383.21301 -292.765004)
			(xy 383.20905 -292.71595) (xy 382.890522 -292.71595) (xy 382.89001 -292.741396) (xy 382.881846 -292.79163)
			(xy 382.86573 -292.839904) (xy 382.842079 -292.884967) (xy 382.811506 -292.925653) (xy 382.774802 -292.960908)
			(xy 382.732918 -292.989818) (xy 382.686939 -293.011635) (xy 382.638055 -293.025795) (xy 382.587534 -293.031929)
			(xy 382.536682 -293.02988) (xy 382.486818 -293.0197) (xy 382.439232 -293.001653) (xy 382.395158 -292.976207)
			(xy 382.355736 -292.94402) (xy 382.321988 -292.905926) (xy 382.294787 -292.862912) (xy 382.274839 -292.816092)
			(xy 382.26266 -292.766678) (xy 382.258565 -292.71595) (xy 381.940054 -292.71595) (xy 381.939559 -292.740557)
			(xy 381.931664 -292.789134) (xy 381.91608 -292.835815) (xy 381.893209 -292.879392) (xy 381.863644 -292.918736)
			(xy 381.828151 -292.952828) (xy 381.787648 -292.980784) (xy 381.743186 -293.001882) (xy 381.695915 -293.015574)
			(xy 381.64706 -293.021506) (xy 381.597885 -293.019525) (xy 381.549666 -293.009681) (xy 381.50365 -292.992229)
			(xy 381.461029 -292.967622) (xy 381.422908 -292.936497) (xy 381.390273 -292.89966) (xy 381.36397 -292.858064)
			(xy 381.344679 -292.812788) (xy 381.332902 -292.765004) (xy 381.328942 -292.71595) (xy 381.010668 -292.71595)
			(xy 381.010156 -292.741396) (xy 381.001992 -292.79163) (xy 380.985876 -292.839904) (xy 380.962225 -292.884967)
			(xy 380.931652 -292.925653) (xy 380.894948 -292.960908) (xy 380.853064 -292.989818) (xy 380.807085 -293.011635)
			(xy 380.758201 -293.025795) (xy 380.70768 -293.031929) (xy 380.656828 -293.02988) (xy 380.606964 -293.0197)
			(xy 380.559378 -293.001653) (xy 380.515304 -292.976207) (xy 380.475882 -292.94402) (xy 380.442134 -292.905926)
			(xy 380.414933 -292.862912) (xy 380.394985 -292.816092) (xy 380.382806 -292.766678) (xy 380.378711 -292.71595)
			(xy 380.070614 -292.71595) (xy 380.070102 -292.741396) (xy 380.061938 -292.79163) (xy 380.045822 -292.839904)
			(xy 380.022171 -292.884967) (xy 379.991598 -292.925653) (xy 379.954894 -292.960908) (xy 379.91301 -292.989818)
			(xy 379.867031 -293.011635) (xy 379.818147 -293.025795) (xy 379.767626 -293.031929) (xy 379.716774 -293.02988)
			(xy 379.66691 -293.0197) (xy 379.619324 -293.001653) (xy 379.57525 -292.976207) (xy 379.535828 -292.94402)
			(xy 379.50208 -292.905926) (xy 379.474879 -292.862912) (xy 379.454931 -292.816092) (xy 379.442752 -292.766678)
			(xy 379.438657 -292.71595) (xy 378.48921 -292.71595) (xy 379.043946 -293.270686) (xy 379.050519 -293.276664)
			(xy 379.066633 -293.284116) (xy 379.084321 -293.285634) (xy 379.101469 -293.281036) (xy 379.10897 -293.276274)
			(xy 379.128386 -293.263167) (xy 379.170365 -293.242383) (xy 379.215024 -293.228247) (xy 379.261317 -293.22109)
			(xy 379.284738 -293.220648) (xy 379.309995 -293.221172) (xy 379.359819 -293.229492) (xy 379.407594 -293.245899)
			(xy 379.452018 -293.269944) (xy 379.491879 -293.300974) (xy 379.526089 -293.33814) (xy 379.553715 -293.38043)
			(xy 379.574005 -293.42669) (xy 379.586404 -293.475658) (xy 379.590572 -293.525956) (xy 379.918988 -293.525956)
			(xy 379.922948 -293.476902) (xy 379.934725 -293.429118) (xy 379.954016 -293.383842) (xy 379.980319 -293.342246)
			(xy 380.012954 -293.305409) (xy 380.051075 -293.274284) (xy 380.093696 -293.249677) (xy 380.139712 -293.232225)
			(xy 380.187931 -293.222381) (xy 380.237106 -293.2204) (xy 380.285961 -293.226332) (xy 380.333232 -293.240024)
			(xy 380.377694 -293.261122) (xy 380.418197 -293.289078) (xy 380.45369 -293.32317) (xy 380.483255 -293.362514)
			(xy 380.506126 -293.406091) (xy 380.52171 -293.452772) (xy 380.529605 -293.501349) (xy 380.5301 -293.525956)
			(xy 380.848611 -293.525956) (xy 380.852706 -293.475228) (xy 380.864885 -293.425814) (xy 380.884833 -293.378994)
			(xy 380.912034 -293.33598) (xy 380.945782 -293.297886) (xy 380.985204 -293.265699) (xy 381.029278 -293.240253)
			(xy 381.076864 -293.222206) (xy 381.126728 -293.212026) (xy 381.17758 -293.209977) (xy 381.228101 -293.216111)
			(xy 381.276985 -293.230271) (xy 381.322964 -293.252088) (xy 381.364848 -293.280998) (xy 381.401552 -293.316253)
			(xy 381.432125 -293.356939) (xy 381.455776 -293.402002) (xy 381.471892 -293.450276) (xy 381.480056 -293.50051)
			(xy 381.480568 -293.525956) (xy 381.799096 -293.525956) (xy 381.803056 -293.476902) (xy 381.814833 -293.429118)
			(xy 381.834124 -293.383842) (xy 381.860427 -293.342246) (xy 381.893062 -293.305409) (xy 381.931183 -293.274284)
			(xy 381.973804 -293.249677) (xy 382.01982 -293.232225) (xy 382.068039 -293.222381) (xy 382.117214 -293.2204)
			(xy 382.166069 -293.226332) (xy 382.21334 -293.240024) (xy 382.257802 -293.261122) (xy 382.298305 -293.289078)
			(xy 382.333798 -293.32317) (xy 382.363363 -293.362514) (xy 382.386234 -293.406091) (xy 382.401818 -293.452772)
			(xy 382.409713 -293.501349) (xy 382.410208 -293.525956) (xy 382.728465 -293.525956) (xy 382.73256 -293.475228)
			(xy 382.744739 -293.425814) (xy 382.764687 -293.378994) (xy 382.791888 -293.33598) (xy 382.825636 -293.297886)
			(xy 382.865058 -293.265699) (xy 382.909132 -293.240253) (xy 382.956718 -293.222206) (xy 383.006582 -293.212026)
			(xy 383.057434 -293.209977) (xy 383.107955 -293.216111) (xy 383.156839 -293.230271) (xy 383.202818 -293.252088)
			(xy 383.244702 -293.280998) (xy 383.281406 -293.316253) (xy 383.311979 -293.356939) (xy 383.33563 -293.402002)
			(xy 383.351746 -293.450276) (xy 383.35991 -293.50051) (xy 383.360422 -293.525956) (xy 383.67895 -293.525956)
			(xy 383.68291 -293.476902) (xy 383.694687 -293.429118) (xy 383.713978 -293.383842) (xy 383.740281 -293.342246)
			(xy 383.772916 -293.305409) (xy 383.811037 -293.274284) (xy 383.853658 -293.249677) (xy 383.899674 -293.232225)
			(xy 383.947893 -293.222381) (xy 383.997068 -293.2204) (xy 384.045923 -293.226332) (xy 384.093194 -293.240024)
			(xy 384.137656 -293.261122) (xy 384.178159 -293.289078) (xy 384.213652 -293.32317) (xy 384.243217 -293.362514)
			(xy 384.266088 -293.406091) (xy 384.281672 -293.452772) (xy 384.289567 -293.501349) (xy 384.290062 -293.525956)
			(xy 384.619004 -293.525956) (xy 384.622964 -293.476902) (xy 384.634741 -293.429118) (xy 384.654032 -293.383842)
			(xy 384.680335 -293.342246) (xy 384.71297 -293.305409) (xy 384.751091 -293.274284) (xy 384.793712 -293.249677)
			(xy 384.839728 -293.232225) (xy 384.887947 -293.222381) (xy 384.937122 -293.2204) (xy 384.985977 -293.226332)
			(xy 385.033248 -293.240024) (xy 385.07771 -293.261122) (xy 385.118213 -293.289078) (xy 385.153706 -293.32317)
			(xy 385.183271 -293.362514) (xy 385.206142 -293.406091) (xy 385.221726 -293.452772) (xy 385.229621 -293.501349)
			(xy 385.230116 -293.525956) (xy 385.559058 -293.525956) (xy 385.563018 -293.476902) (xy 385.574795 -293.429118)
			(xy 385.594086 -293.383842) (xy 385.620389 -293.342246) (xy 385.653024 -293.305409) (xy 385.691145 -293.274284)
			(xy 385.733766 -293.249677) (xy 385.779782 -293.232225) (xy 385.828001 -293.222381) (xy 385.877176 -293.2204)
			(xy 385.926031 -293.226332) (xy 385.973302 -293.240024) (xy 386.017764 -293.261122) (xy 386.058267 -293.289078)
			(xy 386.09376 -293.32317) (xy 386.123325 -293.362514) (xy 386.146196 -293.406091) (xy 386.16178 -293.452772)
			(xy 386.169675 -293.501349) (xy 386.17017 -293.525956) (xy 386.499112 -293.525956) (xy 386.503072 -293.476902)
			(xy 386.514849 -293.429118) (xy 386.53414 -293.383842) (xy 386.560443 -293.342246) (xy 386.593078 -293.305409)
			(xy 386.631199 -293.274284) (xy 386.67382 -293.249677) (xy 386.719836 -293.232225) (xy 386.768055 -293.222381)
			(xy 386.81723 -293.2204) (xy 386.866085 -293.226332) (xy 386.913356 -293.240024) (xy 386.957818 -293.261122)
			(xy 386.998321 -293.289078) (xy 387.033814 -293.32317) (xy 387.063379 -293.362514) (xy 387.08625 -293.406091)
			(xy 387.101834 -293.452772) (xy 387.109729 -293.501349) (xy 387.110224 -293.525956) (xy 387.428481 -293.525956)
			(xy 387.432576 -293.475228) (xy 387.444755 -293.425814) (xy 387.464703 -293.378994) (xy 387.491904 -293.33598)
			(xy 387.525652 -293.297886) (xy 387.565074 -293.265699) (xy 387.609148 -293.240253) (xy 387.656734 -293.222206)
			(xy 387.706598 -293.212026) (xy 387.75745 -293.209977) (xy 387.807971 -293.216111) (xy 387.856855 -293.230271)
			(xy 387.902834 -293.252088) (xy 387.944718 -293.280998) (xy 387.981422 -293.316253) (xy 388.011995 -293.356939)
			(xy 388.035646 -293.402002) (xy 388.051762 -293.450276) (xy 388.059926 -293.50051) (xy 388.060438 -293.525956)
			(xy 388.378966 -293.525956) (xy 388.382926 -293.476902) (xy 388.394703 -293.429118) (xy 388.413994 -293.383842)
			(xy 388.440297 -293.342246) (xy 388.472932 -293.305409) (xy 388.511053 -293.274284) (xy 388.553674 -293.249677)
			(xy 388.59969 -293.232225) (xy 388.647909 -293.222381) (xy 388.697084 -293.2204) (xy 388.745939 -293.226332)
			(xy 388.79321 -293.240024) (xy 388.837672 -293.261122) (xy 388.878175 -293.289078) (xy 388.913668 -293.32317)
			(xy 388.943233 -293.362514) (xy 388.966104 -293.406091) (xy 388.981688 -293.452772) (xy 388.989583 -293.501349)
			(xy 388.990078 -293.525956) (xy 389.308589 -293.525956) (xy 389.312684 -293.475228) (xy 389.324863 -293.425814)
			(xy 389.344811 -293.378994) (xy 389.372012 -293.33598) (xy 389.40576 -293.297886) (xy 389.445182 -293.265699)
			(xy 389.489256 -293.240253) (xy 389.536842 -293.222206) (xy 389.586706 -293.212026) (xy 389.637558 -293.209977)
			(xy 389.688079 -293.216111) (xy 389.736963 -293.230271) (xy 389.782942 -293.252088) (xy 389.824826 -293.280998)
			(xy 389.86153 -293.316253) (xy 389.892103 -293.356939) (xy 389.915754 -293.402002) (xy 389.93187 -293.450276)
			(xy 389.940034 -293.50051) (xy 389.940546 -293.525956) (xy 390.259074 -293.525956) (xy 390.263034 -293.476902)
			(xy 390.274811 -293.429118) (xy 390.294102 -293.383842) (xy 390.320405 -293.342246) (xy 390.35304 -293.305409)
			(xy 390.391161 -293.274284) (xy 390.433782 -293.249677) (xy 390.479798 -293.232225) (xy 390.528017 -293.222381)
			(xy 390.577192 -293.2204) (xy 390.626047 -293.226332) (xy 390.673318 -293.240024) (xy 390.71778 -293.261122)
			(xy 390.758283 -293.289078) (xy 390.793776 -293.32317) (xy 390.823341 -293.362514) (xy 390.846212 -293.406091)
			(xy 390.861796 -293.452772) (xy 390.869691 -293.501349) (xy 390.870186 -293.525956) (xy 391.198874 -293.525956)
			(xy 391.202834 -293.476902) (xy 391.214611 -293.429118) (xy 391.233902 -293.383842) (xy 391.260205 -293.342246)
			(xy 391.29284 -293.305409) (xy 391.330961 -293.274284) (xy 391.373582 -293.249677) (xy 391.419598 -293.232225)
			(xy 391.467817 -293.222381) (xy 391.516992 -293.2204) (xy 391.565847 -293.226332) (xy 391.613118 -293.240024)
			(xy 391.65758 -293.261122) (xy 391.698083 -293.289078) (xy 391.733576 -293.32317) (xy 391.763141 -293.362514)
			(xy 391.786012 -293.406091) (xy 391.801596 -293.452772) (xy 391.809491 -293.501349) (xy 391.809986 -293.525956)
			(xy 392.138928 -293.525956) (xy 392.142888 -293.476902) (xy 392.154665 -293.429118) (xy 392.173956 -293.383842)
			(xy 392.200259 -293.342246) (xy 392.232894 -293.305409) (xy 392.271015 -293.274284) (xy 392.313636 -293.249677)
			(xy 392.359652 -293.232225) (xy 392.407871 -293.222381) (xy 392.457046 -293.2204) (xy 392.505901 -293.226332)
			(xy 392.553172 -293.240024) (xy 392.597634 -293.261122) (xy 392.638137 -293.289078) (xy 392.67363 -293.32317)
			(xy 392.703195 -293.362514) (xy 392.726066 -293.406091) (xy 392.74165 -293.452772) (xy 392.749545 -293.501349)
			(xy 392.75004 -293.525956) (xy 393.078982 -293.525956) (xy 393.082942 -293.476902) (xy 393.094719 -293.429118)
			(xy 393.11401 -293.383842) (xy 393.140313 -293.342246) (xy 393.172948 -293.305409) (xy 393.211069 -293.274284)
			(xy 393.25369 -293.249677) (xy 393.299706 -293.232225) (xy 393.347925 -293.222381) (xy 393.3971 -293.2204)
			(xy 393.445955 -293.226332) (xy 393.493226 -293.240024) (xy 393.537688 -293.261122) (xy 393.578191 -293.289078)
			(xy 393.613684 -293.32317) (xy 393.643249 -293.362514) (xy 393.66612 -293.406091) (xy 393.681704 -293.452772)
			(xy 393.689599 -293.501349) (xy 393.690094 -293.525956) (xy 393.689599 -293.550563) (xy 393.681704 -293.59914)
			(xy 393.66612 -293.645821) (xy 393.643249 -293.689398) (xy 393.613684 -293.728742) (xy 393.578191 -293.762834)
			(xy 393.537688 -293.79079) (xy 393.493226 -293.811888) (xy 393.445955 -293.82558) (xy 393.3971 -293.831512)
			(xy 393.347925 -293.829531) (xy 393.299706 -293.819687) (xy 393.25369 -293.802235) (xy 393.211069 -293.777628)
			(xy 393.172948 -293.746503) (xy 393.140313 -293.709666) (xy 393.11401 -293.66807) (xy 393.094719 -293.622794)
			(xy 393.082942 -293.57501) (xy 393.078982 -293.525956) (xy 392.75004 -293.525956) (xy 392.749545 -293.550563)
			(xy 392.74165 -293.59914) (xy 392.726066 -293.645821) (xy 392.703195 -293.689398) (xy 392.67363 -293.728742)
			(xy 392.638137 -293.762834) (xy 392.597634 -293.79079) (xy 392.553172 -293.811888) (xy 392.505901 -293.82558)
			(xy 392.457046 -293.831512) (xy 392.407871 -293.829531) (xy 392.359652 -293.819687) (xy 392.313636 -293.802235)
			(xy 392.271015 -293.777628) (xy 392.232894 -293.746503) (xy 392.200259 -293.709666) (xy 392.173956 -293.66807)
			(xy 392.154665 -293.622794) (xy 392.142888 -293.57501) (xy 392.138928 -293.525956) (xy 391.809986 -293.525956)
			(xy 391.809491 -293.550563) (xy 391.801596 -293.59914) (xy 391.786012 -293.645821) (xy 391.763141 -293.689398)
			(xy 391.733576 -293.728742) (xy 391.698083 -293.762834) (xy 391.65758 -293.79079) (xy 391.613118 -293.811888)
			(xy 391.565847 -293.82558) (xy 391.516992 -293.831512) (xy 391.467817 -293.829531) (xy 391.419598 -293.819687)
			(xy 391.373582 -293.802235) (xy 391.330961 -293.777628) (xy 391.29284 -293.746503) (xy 391.260205 -293.709666)
			(xy 391.233902 -293.66807) (xy 391.214611 -293.622794) (xy 391.202834 -293.57501) (xy 391.198874 -293.525956)
			(xy 390.870186 -293.525956) (xy 390.869691 -293.550563) (xy 390.861796 -293.59914) (xy 390.846212 -293.645821)
			(xy 390.823341 -293.689398) (xy 390.793776 -293.728742) (xy 390.758283 -293.762834) (xy 390.71778 -293.79079)
			(xy 390.673318 -293.811888) (xy 390.626047 -293.82558) (xy 390.577192 -293.831512) (xy 390.528017 -293.829531)
			(xy 390.479798 -293.819687) (xy 390.433782 -293.802235) (xy 390.391161 -293.777628) (xy 390.35304 -293.746503)
			(xy 390.320405 -293.709666) (xy 390.294102 -293.66807) (xy 390.274811 -293.622794) (xy 390.263034 -293.57501)
			(xy 390.259074 -293.525956) (xy 389.940546 -293.525956) (xy 389.940034 -293.551402) (xy 389.93187 -293.601636)
			(xy 389.915754 -293.64991) (xy 389.892103 -293.694973) (xy 389.86153 -293.735659) (xy 389.824826 -293.770914)
			(xy 389.782942 -293.799824) (xy 389.736963 -293.821641) (xy 389.688079 -293.835801) (xy 389.637558 -293.841935)
			(xy 389.586706 -293.839886) (xy 389.536842 -293.829706) (xy 389.489256 -293.811659) (xy 389.445182 -293.786213)
			(xy 389.40576 -293.754026) (xy 389.372012 -293.715932) (xy 389.344811 -293.672918) (xy 389.324863 -293.626098)
			(xy 389.312684 -293.576684) (xy 389.308589 -293.525956) (xy 388.990078 -293.525956) (xy 388.989583 -293.550563)
			(xy 388.981688 -293.59914) (xy 388.966104 -293.645821) (xy 388.943233 -293.689398) (xy 388.913668 -293.728742)
			(xy 388.878175 -293.762834) (xy 388.837672 -293.79079) (xy 388.79321 -293.811888) (xy 388.745939 -293.82558)
			(xy 388.697084 -293.831512) (xy 388.647909 -293.829531) (xy 388.59969 -293.819687) (xy 388.553674 -293.802235)
			(xy 388.511053 -293.777628) (xy 388.472932 -293.746503) (xy 388.440297 -293.709666) (xy 388.413994 -293.66807)
			(xy 388.394703 -293.622794) (xy 388.382926 -293.57501) (xy 388.378966 -293.525956) (xy 388.060438 -293.525956)
			(xy 388.059926 -293.551402) (xy 388.051762 -293.601636) (xy 388.035646 -293.64991) (xy 388.011995 -293.694973)
			(xy 387.981422 -293.735659) (xy 387.944718 -293.770914) (xy 387.902834 -293.799824) (xy 387.856855 -293.821641)
			(xy 387.807971 -293.835801) (xy 387.75745 -293.841935) (xy 387.706598 -293.839886) (xy 387.656734 -293.829706)
			(xy 387.609148 -293.811659) (xy 387.565074 -293.786213) (xy 387.525652 -293.754026) (xy 387.491904 -293.715932)
			(xy 387.464703 -293.672918) (xy 387.444755 -293.626098) (xy 387.432576 -293.576684) (xy 387.428481 -293.525956)
			(xy 387.110224 -293.525956) (xy 387.109729 -293.550563) (xy 387.101834 -293.59914) (xy 387.08625 -293.645821)
			(xy 387.063379 -293.689398) (xy 387.033814 -293.728742) (xy 386.998321 -293.762834) (xy 386.957818 -293.79079)
			(xy 386.913356 -293.811888) (xy 386.866085 -293.82558) (xy 386.81723 -293.831512) (xy 386.768055 -293.829531)
			(xy 386.719836 -293.819687) (xy 386.67382 -293.802235) (xy 386.631199 -293.777628) (xy 386.593078 -293.746503)
			(xy 386.560443 -293.709666) (xy 386.53414 -293.66807) (xy 386.514849 -293.622794) (xy 386.503072 -293.57501)
			(xy 386.499112 -293.525956) (xy 386.17017 -293.525956) (xy 386.169675 -293.550563) (xy 386.16178 -293.59914)
			(xy 386.146196 -293.645821) (xy 386.123325 -293.689398) (xy 386.09376 -293.728742) (xy 386.058267 -293.762834)
			(xy 386.017764 -293.79079) (xy 385.973302 -293.811888) (xy 385.926031 -293.82558) (xy 385.877176 -293.831512)
			(xy 385.828001 -293.829531) (xy 385.779782 -293.819687) (xy 385.733766 -293.802235) (xy 385.691145 -293.777628)
			(xy 385.653024 -293.746503) (xy 385.620389 -293.709666) (xy 385.594086 -293.66807) (xy 385.574795 -293.622794)
			(xy 385.563018 -293.57501) (xy 385.559058 -293.525956) (xy 385.230116 -293.525956) (xy 385.229621 -293.550563)
			(xy 385.221726 -293.59914) (xy 385.206142 -293.645821) (xy 385.183271 -293.689398) (xy 385.153706 -293.728742)
			(xy 385.118213 -293.762834) (xy 385.07771 -293.79079) (xy 385.033248 -293.811888) (xy 384.985977 -293.82558)
			(xy 384.937122 -293.831512) (xy 384.887947 -293.829531) (xy 384.839728 -293.819687) (xy 384.793712 -293.802235)
			(xy 384.751091 -293.777628) (xy 384.71297 -293.746503) (xy 384.680335 -293.709666) (xy 384.654032 -293.66807)
			(xy 384.634741 -293.622794) (xy 384.622964 -293.57501) (xy 384.619004 -293.525956) (xy 384.290062 -293.525956)
			(xy 384.289567 -293.550563) (xy 384.281672 -293.59914) (xy 384.266088 -293.645821) (xy 384.243217 -293.689398)
			(xy 384.213652 -293.728742) (xy 384.178159 -293.762834) (xy 384.137656 -293.79079) (xy 384.093194 -293.811888)
			(xy 384.045923 -293.82558) (xy 383.997068 -293.831512) (xy 383.947893 -293.829531) (xy 383.899674 -293.819687)
			(xy 383.853658 -293.802235) (xy 383.811037 -293.777628) (xy 383.772916 -293.746503) (xy 383.740281 -293.709666)
			(xy 383.713978 -293.66807) (xy 383.694687 -293.622794) (xy 383.68291 -293.57501) (xy 383.67895 -293.525956)
			(xy 383.360422 -293.525956) (xy 383.35991 -293.551402) (xy 383.351746 -293.601636) (xy 383.33563 -293.64991)
			(xy 383.311979 -293.694973) (xy 383.281406 -293.735659) (xy 383.244702 -293.770914) (xy 383.202818 -293.799824)
			(xy 383.156839 -293.821641) (xy 383.107955 -293.835801) (xy 383.057434 -293.841935) (xy 383.006582 -293.839886)
			(xy 382.956718 -293.829706) (xy 382.909132 -293.811659) (xy 382.865058 -293.786213) (xy 382.825636 -293.754026)
			(xy 382.791888 -293.715932) (xy 382.764687 -293.672918) (xy 382.744739 -293.626098) (xy 382.73256 -293.576684)
			(xy 382.728465 -293.525956) (xy 382.410208 -293.525956) (xy 382.409713 -293.550563) (xy 382.401818 -293.59914)
			(xy 382.386234 -293.645821) (xy 382.363363 -293.689398) (xy 382.333798 -293.728742) (xy 382.298305 -293.762834)
			(xy 382.257802 -293.79079) (xy 382.21334 -293.811888) (xy 382.166069 -293.82558) (xy 382.117214 -293.831512)
			(xy 382.068039 -293.829531) (xy 382.01982 -293.819687) (xy 381.973804 -293.802235) (xy 381.931183 -293.777628)
			(xy 381.893062 -293.746503) (xy 381.860427 -293.709666) (xy 381.834124 -293.66807) (xy 381.814833 -293.622794)
			(xy 381.803056 -293.57501) (xy 381.799096 -293.525956) (xy 381.480568 -293.525956) (xy 381.480056 -293.551402)
			(xy 381.471892 -293.601636) (xy 381.455776 -293.64991) (xy 381.432125 -293.694973) (xy 381.401552 -293.735659)
			(xy 381.364848 -293.770914) (xy 381.322964 -293.799824) (xy 381.276985 -293.821641) (xy 381.228101 -293.835801)
			(xy 381.17758 -293.841935) (xy 381.126728 -293.839886) (xy 381.076864 -293.829706) (xy 381.029278 -293.811659)
			(xy 380.985204 -293.786213) (xy 380.945782 -293.754026) (xy 380.912034 -293.715932) (xy 380.884833 -293.672918)
			(xy 380.864885 -293.626098) (xy 380.852706 -293.576684) (xy 380.848611 -293.525956) (xy 380.5301 -293.525956)
			(xy 380.529605 -293.550563) (xy 380.52171 -293.59914) (xy 380.506126 -293.645821) (xy 380.483255 -293.689398)
			(xy 380.45369 -293.728742) (xy 380.418197 -293.762834) (xy 380.377694 -293.79079) (xy 380.333232 -293.811888)
			(xy 380.285961 -293.82558) (xy 380.237106 -293.831512) (xy 380.187931 -293.829531) (xy 380.139712 -293.819687)
			(xy 380.093696 -293.802235) (xy 380.051075 -293.777628) (xy 380.012954 -293.746503) (xy 379.980319 -293.709666)
			(xy 379.954016 -293.66807) (xy 379.934725 -293.622794) (xy 379.922948 -293.57501) (xy 379.918988 -293.525956)
			(xy 379.590572 -293.525956) (xy 379.590576 -293.526) (xy 379.586404 -293.576341) (xy 379.574005 -293.62531)
			(xy 379.553715 -293.67157) (xy 379.526089 -293.71386) (xy 379.491879 -293.751026) (xy 379.452018 -293.782056)
			(xy 379.407594 -293.806101) (xy 379.359819 -293.822508) (xy 379.309995 -293.830828) (xy 379.284738 -293.831264)
			(xy 379.272943 -293.831172) (xy 379.249422 -293.829395) (xy 379.237748 -293.827708) (xy 379.226572 -293.82593)
			(xy 379.205236 -293.832026) (xy 379.13818 -293.88943) (xy 379.130163 -293.897005) (xy 379.120959 -293.917022)
			(xy 379.1204 -293.928038) (xy 379.1204 -294.335962) (xy 380.389142 -294.335962) (xy 380.393102 -294.286908)
			(xy 380.404879 -294.239124) (xy 380.42417 -294.193848) (xy 380.450473 -294.152252) (xy 380.483108 -294.115415)
			(xy 380.521229 -294.08429) (xy 380.56385 -294.059683) (xy 380.609866 -294.042231) (xy 380.658085 -294.032387)
			(xy 380.70726 -294.030406) (xy 380.756115 -294.036338) (xy 380.803386 -294.05003) (xy 380.847848 -294.071128)
			(xy 380.888351 -294.099084) (xy 380.923844 -294.133176) (xy 380.953409 -294.17252) (xy 380.97628 -294.216097)
			(xy 380.991864 -294.262778) (xy 380.999759 -294.311355) (xy 381.000254 -294.335962) (xy 381.328942 -294.335962)
			(xy 381.332902 -294.286908) (xy 381.344679 -294.239124) (xy 381.36397 -294.193848) (xy 381.390273 -294.152252)
			(xy 381.422908 -294.115415) (xy 381.461029 -294.08429) (xy 381.50365 -294.059683) (xy 381.549666 -294.042231)
			(xy 381.597885 -294.032387) (xy 381.64706 -294.030406) (xy 381.695915 -294.036338) (xy 381.743186 -294.05003)
			(xy 381.787648 -294.071128) (xy 381.828151 -294.099084) (xy 381.863644 -294.133176) (xy 381.893209 -294.17252)
			(xy 381.91608 -294.216097) (xy 381.931664 -294.262778) (xy 381.939559 -294.311355) (xy 381.940054 -294.335962)
			(xy 382.268996 -294.335962) (xy 382.272956 -294.286908) (xy 382.284733 -294.239124) (xy 382.304024 -294.193848)
			(xy 382.330327 -294.152252) (xy 382.362962 -294.115415) (xy 382.401083 -294.08429) (xy 382.443704 -294.059683)
			(xy 382.48972 -294.042231) (xy 382.537939 -294.032387) (xy 382.587114 -294.030406) (xy 382.635969 -294.036338)
			(xy 382.68324 -294.05003) (xy 382.727702 -294.071128) (xy 382.768205 -294.099084) (xy 382.803698 -294.133176)
			(xy 382.833263 -294.17252) (xy 382.856134 -294.216097) (xy 382.871718 -294.262778) (xy 382.879613 -294.311355)
			(xy 382.880108 -294.335962) (xy 383.20905 -294.335962) (xy 383.21301 -294.286908) (xy 383.224787 -294.239124)
			(xy 383.244078 -294.193848) (xy 383.270381 -294.152252) (xy 383.303016 -294.115415) (xy 383.341137 -294.08429)
			(xy 383.383758 -294.059683) (xy 383.429774 -294.042231) (xy 383.477993 -294.032387) (xy 383.527168 -294.030406)
			(xy 383.576023 -294.036338) (xy 383.623294 -294.05003) (xy 383.667756 -294.071128) (xy 383.708259 -294.099084)
			(xy 383.743752 -294.133176) (xy 383.773317 -294.17252) (xy 383.796188 -294.216097) (xy 383.811772 -294.262778)
			(xy 383.819667 -294.311355) (xy 383.820162 -294.335962) (xy 384.149104 -294.335962) (xy 384.153064 -294.286908)
			(xy 384.164841 -294.239124) (xy 384.184132 -294.193848) (xy 384.210435 -294.152252) (xy 384.24307 -294.115415)
			(xy 384.281191 -294.08429) (xy 384.323812 -294.059683) (xy 384.369828 -294.042231) (xy 384.418047 -294.032387)
			(xy 384.467222 -294.030406) (xy 384.516077 -294.036338) (xy 384.563348 -294.05003) (xy 384.60781 -294.071128)
			(xy 384.648313 -294.099084) (xy 384.683806 -294.133176) (xy 384.713371 -294.17252) (xy 384.736242 -294.216097)
			(xy 384.751826 -294.262778) (xy 384.759721 -294.311355) (xy 384.760216 -294.335962) (xy 386.028958 -294.335962)
			(xy 386.032918 -294.286908) (xy 386.044695 -294.239124) (xy 386.063986 -294.193848) (xy 386.090289 -294.152252)
			(xy 386.122924 -294.115415) (xy 386.161045 -294.08429) (xy 386.203666 -294.059683) (xy 386.249682 -294.042231)
			(xy 386.297901 -294.032387) (xy 386.347076 -294.030406) (xy 386.395931 -294.036338) (xy 386.443202 -294.05003)
			(xy 386.487664 -294.071128) (xy 386.528167 -294.099084) (xy 386.56366 -294.133176) (xy 386.593225 -294.17252)
			(xy 386.616096 -294.216097) (xy 386.63168 -294.262778) (xy 386.639575 -294.311355) (xy 386.64007 -294.335962)
			(xy 386.969012 -294.335962) (xy 386.972972 -294.286908) (xy 386.984749 -294.239124) (xy 387.00404 -294.193848)
			(xy 387.030343 -294.152252) (xy 387.062978 -294.115415) (xy 387.101099 -294.08429) (xy 387.14372 -294.059683)
			(xy 387.189736 -294.042231) (xy 387.237955 -294.032387) (xy 387.28713 -294.030406) (xy 387.335985 -294.036338)
			(xy 387.383256 -294.05003) (xy 387.427718 -294.071128) (xy 387.468221 -294.099084) (xy 387.503714 -294.133176)
			(xy 387.533279 -294.17252) (xy 387.55615 -294.216097) (xy 387.571734 -294.262778) (xy 387.579629 -294.311355)
			(xy 387.580124 -294.335962) (xy 387.909066 -294.335962) (xy 387.913026 -294.286908) (xy 387.924803 -294.239124)
			(xy 387.944094 -294.193848) (xy 387.970397 -294.152252) (xy 388.003032 -294.115415) (xy 388.041153 -294.08429)
			(xy 388.083774 -294.059683) (xy 388.12979 -294.042231) (xy 388.178009 -294.032387) (xy 388.227184 -294.030406)
			(xy 388.276039 -294.036338) (xy 388.32331 -294.05003) (xy 388.367772 -294.071128) (xy 388.408275 -294.099084)
			(xy 388.443768 -294.133176) (xy 388.473333 -294.17252) (xy 388.496204 -294.216097) (xy 388.511788 -294.262778)
			(xy 388.519683 -294.311355) (xy 388.520178 -294.335962) (xy 388.84912 -294.335962) (xy 388.85308 -294.286908)
			(xy 388.864857 -294.239124) (xy 388.884148 -294.193848) (xy 388.910451 -294.152252) (xy 388.943086 -294.115415)
			(xy 388.981207 -294.08429) (xy 389.023828 -294.059683) (xy 389.069844 -294.042231) (xy 389.118063 -294.032387)
			(xy 389.167238 -294.030406) (xy 389.216093 -294.036338) (xy 389.263364 -294.05003) (xy 389.307826 -294.071128)
			(xy 389.348329 -294.099084) (xy 389.383822 -294.133176) (xy 389.413387 -294.17252) (xy 389.436258 -294.216097)
			(xy 389.451842 -294.262778) (xy 389.459737 -294.311355) (xy 389.460232 -294.335962) (xy 389.78892 -294.335962)
			(xy 389.79288 -294.286908) (xy 389.804657 -294.239124) (xy 389.823948 -294.193848) (xy 389.850251 -294.152252)
			(xy 389.882886 -294.115415) (xy 389.921007 -294.08429) (xy 389.963628 -294.059683) (xy 390.009644 -294.042231)
			(xy 390.057863 -294.032387) (xy 390.107038 -294.030406) (xy 390.155893 -294.036338) (xy 390.203164 -294.05003)
			(xy 390.247626 -294.071128) (xy 390.288129 -294.099084) (xy 390.323622 -294.133176) (xy 390.353187 -294.17252)
			(xy 390.376058 -294.216097) (xy 390.391642 -294.262778) (xy 390.399537 -294.311355) (xy 390.400032 -294.335962)
			(xy 391.669028 -294.335962) (xy 391.672988 -294.286908) (xy 391.684765 -294.239124) (xy 391.704056 -294.193848)
			(xy 391.730359 -294.152252) (xy 391.762994 -294.115415) (xy 391.801115 -294.08429) (xy 391.843736 -294.059683)
			(xy 391.889752 -294.042231) (xy 391.937971 -294.032387) (xy 391.987146 -294.030406) (xy 392.036001 -294.036338)
			(xy 392.083272 -294.05003) (xy 392.127734 -294.071128) (xy 392.168237 -294.099084) (xy 392.20373 -294.133176)
			(xy 392.233295 -294.17252) (xy 392.256166 -294.216097) (xy 392.27175 -294.262778) (xy 392.279645 -294.311355)
			(xy 392.28014 -294.335962) (xy 393.548882 -294.335962) (xy 393.552842 -294.286908) (xy 393.564619 -294.239124)
			(xy 393.58391 -294.193848) (xy 393.610213 -294.152252) (xy 393.642848 -294.115415) (xy 393.680969 -294.08429)
			(xy 393.72359 -294.059683) (xy 393.769606 -294.042231) (xy 393.817825 -294.032387) (xy 393.867 -294.030406)
			(xy 393.915855 -294.036338) (xy 393.963126 -294.05003) (xy 394.007588 -294.071128) (xy 394.048091 -294.099084)
			(xy 394.083584 -294.133176) (xy 394.113149 -294.17252) (xy 394.13602 -294.216097) (xy 394.151604 -294.262778)
			(xy 394.159499 -294.311355) (xy 394.159994 -294.335962) (xy 394.488936 -294.335962) (xy 394.492896 -294.286908)
			(xy 394.504673 -294.239124) (xy 394.523964 -294.193848) (xy 394.550267 -294.152252) (xy 394.582902 -294.115415)
			(xy 394.621023 -294.08429) (xy 394.663644 -294.059683) (xy 394.70966 -294.042231) (xy 394.757879 -294.032387)
			(xy 394.807054 -294.030406) (xy 394.855909 -294.036338) (xy 394.90318 -294.05003) (xy 394.947642 -294.071128)
			(xy 394.988145 -294.099084) (xy 395.023638 -294.133176) (xy 395.053203 -294.17252) (xy 395.076074 -294.216097)
			(xy 395.091658 -294.262778) (xy 395.099553 -294.311355) (xy 395.100048 -294.335962) (xy 395.099553 -294.360569)
			(xy 395.091658 -294.409146) (xy 395.076074 -294.455827) (xy 395.053203 -294.499404) (xy 395.023638 -294.538748)
			(xy 394.988145 -294.57284) (xy 394.947642 -294.600796) (xy 394.90318 -294.621894) (xy 394.855909 -294.635586)
			(xy 394.807054 -294.641518) (xy 394.757879 -294.639537) (xy 394.70966 -294.629693) (xy 394.663644 -294.612241)
			(xy 394.621023 -294.587634) (xy 394.582902 -294.556509) (xy 394.550267 -294.519672) (xy 394.523964 -294.478076)
			(xy 394.504673 -294.4328) (xy 394.492896 -294.385016) (xy 394.488936 -294.335962) (xy 394.159994 -294.335962)
			(xy 394.159499 -294.360569) (xy 394.151604 -294.409146) (xy 394.13602 -294.455827) (xy 394.113149 -294.499404)
			(xy 394.083584 -294.538748) (xy 394.048091 -294.57284) (xy 394.007588 -294.600796) (xy 393.963126 -294.621894)
			(xy 393.915855 -294.635586) (xy 393.867 -294.641518) (xy 393.817825 -294.639537) (xy 393.769606 -294.629693)
			(xy 393.72359 -294.612241) (xy 393.680969 -294.587634) (xy 393.642848 -294.556509) (xy 393.610213 -294.519672)
			(xy 393.58391 -294.478076) (xy 393.564619 -294.4328) (xy 393.552842 -294.385016) (xy 393.548882 -294.335962)
			(xy 392.28014 -294.335962) (xy 392.279645 -294.360569) (xy 392.27175 -294.409146) (xy 392.256166 -294.455827)
			(xy 392.233295 -294.499404) (xy 392.20373 -294.538748) (xy 392.168237 -294.57284) (xy 392.127734 -294.600796)
			(xy 392.083272 -294.621894) (xy 392.036001 -294.635586) (xy 391.987146 -294.641518) (xy 391.937971 -294.639537)
			(xy 391.889752 -294.629693) (xy 391.843736 -294.612241) (xy 391.801115 -294.587634) (xy 391.762994 -294.556509)
			(xy 391.730359 -294.519672) (xy 391.704056 -294.478076) (xy 391.684765 -294.4328) (xy 391.672988 -294.385016)
			(xy 391.669028 -294.335962) (xy 390.400032 -294.335962) (xy 390.399537 -294.360569) (xy 390.391642 -294.409146)
			(xy 390.376058 -294.455827) (xy 390.353187 -294.499404) (xy 390.323622 -294.538748) (xy 390.288129 -294.57284)
			(xy 390.247626 -294.600796) (xy 390.203164 -294.621894) (xy 390.155893 -294.635586) (xy 390.107038 -294.641518)
			(xy 390.057863 -294.639537) (xy 390.009644 -294.629693) (xy 389.963628 -294.612241) (xy 389.921007 -294.587634)
			(xy 389.882886 -294.556509) (xy 389.850251 -294.519672) (xy 389.823948 -294.478076) (xy 389.804657 -294.4328)
			(xy 389.79288 -294.385016) (xy 389.78892 -294.335962) (xy 389.460232 -294.335962) (xy 389.459737 -294.360569)
			(xy 389.451842 -294.409146) (xy 389.436258 -294.455827) (xy 389.413387 -294.499404) (xy 389.383822 -294.538748)
			(xy 389.348329 -294.57284) (xy 389.307826 -294.600796) (xy 389.263364 -294.621894) (xy 389.216093 -294.635586)
			(xy 389.167238 -294.641518) (xy 389.118063 -294.639537) (xy 389.069844 -294.629693) (xy 389.023828 -294.612241)
			(xy 388.981207 -294.587634) (xy 388.943086 -294.556509) (xy 388.910451 -294.519672) (xy 388.884148 -294.478076)
			(xy 388.864857 -294.4328) (xy 388.85308 -294.385016) (xy 388.84912 -294.335962) (xy 388.520178 -294.335962)
			(xy 388.519683 -294.360569) (xy 388.511788 -294.409146) (xy 388.496204 -294.455827) (xy 388.473333 -294.499404)
			(xy 388.443768 -294.538748) (xy 388.408275 -294.57284) (xy 388.367772 -294.600796) (xy 388.32331 -294.621894)
			(xy 388.276039 -294.635586) (xy 388.227184 -294.641518) (xy 388.178009 -294.639537) (xy 388.12979 -294.629693)
			(xy 388.083774 -294.612241) (xy 388.041153 -294.587634) (xy 388.003032 -294.556509) (xy 387.970397 -294.519672)
			(xy 387.944094 -294.478076) (xy 387.924803 -294.4328) (xy 387.913026 -294.385016) (xy 387.909066 -294.335962)
			(xy 387.580124 -294.335962) (xy 387.579629 -294.360569) (xy 387.571734 -294.409146) (xy 387.55615 -294.455827)
			(xy 387.533279 -294.499404) (xy 387.503714 -294.538748) (xy 387.468221 -294.57284) (xy 387.427718 -294.600796)
			(xy 387.383256 -294.621894) (xy 387.335985 -294.635586) (xy 387.28713 -294.641518) (xy 387.237955 -294.639537)
			(xy 387.189736 -294.629693) (xy 387.14372 -294.612241) (xy 387.101099 -294.587634) (xy 387.062978 -294.556509)
			(xy 387.030343 -294.519672) (xy 387.00404 -294.478076) (xy 386.984749 -294.4328) (xy 386.972972 -294.385016)
			(xy 386.969012 -294.335962) (xy 386.64007 -294.335962) (xy 386.639575 -294.360569) (xy 386.63168 -294.409146)
			(xy 386.616096 -294.455827) (xy 386.593225 -294.499404) (xy 386.56366 -294.538748) (xy 386.528167 -294.57284)
			(xy 386.487664 -294.600796) (xy 386.443202 -294.621894) (xy 386.395931 -294.635586) (xy 386.347076 -294.641518)
			(xy 386.297901 -294.639537) (xy 386.249682 -294.629693) (xy 386.203666 -294.612241) (xy 386.161045 -294.587634)
			(xy 386.122924 -294.556509) (xy 386.090289 -294.519672) (xy 386.063986 -294.478076) (xy 386.044695 -294.4328)
			(xy 386.032918 -294.385016) (xy 386.028958 -294.335962) (xy 384.760216 -294.335962) (xy 384.759721 -294.360569)
			(xy 384.751826 -294.409146) (xy 384.736242 -294.455827) (xy 384.713371 -294.499404) (xy 384.683806 -294.538748)
			(xy 384.648313 -294.57284) (xy 384.60781 -294.600796) (xy 384.563348 -294.621894) (xy 384.516077 -294.635586)
			(xy 384.467222 -294.641518) (xy 384.418047 -294.639537) (xy 384.369828 -294.629693) (xy 384.323812 -294.612241)
			(xy 384.281191 -294.587634) (xy 384.24307 -294.556509) (xy 384.210435 -294.519672) (xy 384.184132 -294.478076)
			(xy 384.164841 -294.4328) (xy 384.153064 -294.385016) (xy 384.149104 -294.335962) (xy 383.820162 -294.335962)
			(xy 383.819667 -294.360569) (xy 383.811772 -294.409146) (xy 383.796188 -294.455827) (xy 383.773317 -294.499404)
			(xy 383.743752 -294.538748) (xy 383.708259 -294.57284) (xy 383.667756 -294.600796) (xy 383.623294 -294.621894)
			(xy 383.576023 -294.635586) (xy 383.527168 -294.641518) (xy 383.477993 -294.639537) (xy 383.429774 -294.629693)
			(xy 383.383758 -294.612241) (xy 383.341137 -294.587634) (xy 383.303016 -294.556509) (xy 383.270381 -294.519672)
			(xy 383.244078 -294.478076) (xy 383.224787 -294.4328) (xy 383.21301 -294.385016) (xy 383.20905 -294.335962)
			(xy 382.880108 -294.335962) (xy 382.879613 -294.360569) (xy 382.871718 -294.409146) (xy 382.856134 -294.455827)
			(xy 382.833263 -294.499404) (xy 382.803698 -294.538748) (xy 382.768205 -294.57284) (xy 382.727702 -294.600796)
			(xy 382.68324 -294.621894) (xy 382.635969 -294.635586) (xy 382.587114 -294.641518) (xy 382.537939 -294.639537)
			(xy 382.48972 -294.629693) (xy 382.443704 -294.612241) (xy 382.401083 -294.587634) (xy 382.362962 -294.556509)
			(xy 382.330327 -294.519672) (xy 382.304024 -294.478076) (xy 382.284733 -294.4328) (xy 382.272956 -294.385016)
			(xy 382.268996 -294.335962) (xy 381.940054 -294.335962) (xy 381.939559 -294.360569) (xy 381.931664 -294.409146)
			(xy 381.91608 -294.455827) (xy 381.893209 -294.499404) (xy 381.863644 -294.538748) (xy 381.828151 -294.57284)
			(xy 381.787648 -294.600796) (xy 381.743186 -294.621894) (xy 381.695915 -294.635586) (xy 381.64706 -294.641518)
			(xy 381.597885 -294.639537) (xy 381.549666 -294.629693) (xy 381.50365 -294.612241) (xy 381.461029 -294.587634)
			(xy 381.422908 -294.556509) (xy 381.390273 -294.519672) (xy 381.36397 -294.478076) (xy 381.344679 -294.4328)
			(xy 381.332902 -294.385016) (xy 381.328942 -294.335962) (xy 381.000254 -294.335962) (xy 380.999759 -294.360569)
			(xy 380.991864 -294.409146) (xy 380.97628 -294.455827) (xy 380.953409 -294.499404) (xy 380.923844 -294.538748)
			(xy 380.888351 -294.57284) (xy 380.847848 -294.600796) (xy 380.803386 -294.621894) (xy 380.756115 -294.635586)
			(xy 380.70726 -294.641518) (xy 380.658085 -294.639537) (xy 380.609866 -294.629693) (xy 380.56385 -294.612241)
			(xy 380.521229 -294.587634) (xy 380.483108 -294.556509) (xy 380.450473 -294.519672) (xy 380.42417 -294.478076)
			(xy 380.404879 -294.4328) (xy 380.393102 -294.385016) (xy 380.389142 -294.335962) (xy 379.1204 -294.335962)
			(xy 379.1204 -294.743886) (xy 379.120938 -294.754906) (xy 379.130153 -294.774925) (xy 379.13818 -294.782494)
			(xy 379.205236 -294.839898) (xy 379.226572 -294.845994) (xy 379.237748 -294.844216) (xy 379.249422 -294.842531)
			(xy 379.272943 -294.84075) (xy 379.284738 -294.84066) (xy 379.309994 -294.841185) (xy 379.359816 -294.849504)
			(xy 379.407589 -294.86591) (xy 379.452011 -294.889955) (xy 379.49187 -294.920983) (xy 379.526079 -294.958148)
			(xy 379.553704 -295.000436) (xy 379.573993 -295.046694) (xy 379.586392 -295.095661) (xy 379.59056 -295.145968)
			(xy 380.859042 -295.145968) (xy 380.863002 -295.096914) (xy 380.874779 -295.04913) (xy 380.89407 -295.003854)
			(xy 380.920373 -294.962258) (xy 380.953008 -294.925421) (xy 380.991129 -294.894296) (xy 381.03375 -294.869689)
			(xy 381.079766 -294.852237) (xy 381.127985 -294.842393) (xy 381.17716 -294.840412) (xy 381.226015 -294.846344)
			(xy 381.273286 -294.860036) (xy 381.317748 -294.881134) (xy 381.358251 -294.90909) (xy 381.393744 -294.943182)
			(xy 381.423309 -294.982526) (xy 381.44618 -295.026103) (xy 381.461764 -295.072784) (xy 381.469659 -295.121361)
			(xy 381.470154 -295.145968) (xy 381.799096 -295.145968) (xy 381.803056 -295.096914) (xy 381.814833 -295.04913)
			(xy 381.834124 -295.003854) (xy 381.860427 -294.962258) (xy 381.893062 -294.925421) (xy 381.931183 -294.894296)
			(xy 381.973804 -294.869689) (xy 382.01982 -294.852237) (xy 382.068039 -294.842393) (xy 382.117214 -294.840412)
			(xy 382.166069 -294.846344) (xy 382.21334 -294.860036) (xy 382.257802 -294.881134) (xy 382.298305 -294.90909)
			(xy 382.333798 -294.943182) (xy 382.363363 -294.982526) (xy 382.386234 -295.026103) (xy 382.401818 -295.072784)
			(xy 382.409713 -295.121361) (xy 382.410208 -295.145968) (xy 384.619004 -295.145968) (xy 384.622964 -295.096914)
			(xy 384.634741 -295.04913) (xy 384.654032 -295.003854) (xy 384.680335 -294.962258) (xy 384.71297 -294.925421)
			(xy 384.751091 -294.894296) (xy 384.793712 -294.869689) (xy 384.839728 -294.852237) (xy 384.887947 -294.842393)
			(xy 384.937122 -294.840412) (xy 384.985977 -294.846344) (xy 385.033248 -294.860036) (xy 385.07771 -294.881134)
			(xy 385.118213 -294.90909) (xy 385.153706 -294.943182) (xy 385.183271 -294.982526) (xy 385.206142 -295.026103)
			(xy 385.221726 -295.072784) (xy 385.229621 -295.121361) (xy 385.230116 -295.145968) (xy 385.559058 -295.145968)
			(xy 385.563018 -295.096914) (xy 385.574795 -295.04913) (xy 385.594086 -295.003854) (xy 385.620389 -294.962258)
			(xy 385.653024 -294.925421) (xy 385.691145 -294.894296) (xy 385.733766 -294.869689) (xy 385.779782 -294.852237)
			(xy 385.828001 -294.842393) (xy 385.877176 -294.840412) (xy 385.926031 -294.846344) (xy 385.973302 -294.860036)
			(xy 386.017764 -294.881134) (xy 386.058267 -294.90909) (xy 386.09376 -294.943182) (xy 386.123325 -294.982526)
			(xy 386.146196 -295.026103) (xy 386.16178 -295.072784) (xy 386.169675 -295.121361) (xy 386.17017 -295.145968)
			(xy 388.378966 -295.145968) (xy 388.382926 -295.096914) (xy 388.394703 -295.04913) (xy 388.413994 -295.003854)
			(xy 388.440297 -294.962258) (xy 388.472932 -294.925421) (xy 388.511053 -294.894296) (xy 388.553674 -294.869689)
			(xy 388.59969 -294.852237) (xy 388.647909 -294.842393) (xy 388.697084 -294.840412) (xy 388.745939 -294.846344)
			(xy 388.79321 -294.860036) (xy 388.837672 -294.881134) (xy 388.878175 -294.90909) (xy 388.913668 -294.943182)
			(xy 388.943233 -294.982526) (xy 388.966104 -295.026103) (xy 388.981688 -295.072784) (xy 388.989583 -295.121361)
			(xy 388.990078 -295.145968) (xy 389.31902 -295.145968) (xy 389.32298 -295.096914) (xy 389.334757 -295.04913)
			(xy 389.354048 -295.003854) (xy 389.380351 -294.962258) (xy 389.412986 -294.925421) (xy 389.451107 -294.894296)
			(xy 389.493728 -294.869689) (xy 389.539744 -294.852237) (xy 389.587963 -294.842393) (xy 389.637138 -294.840412)
			(xy 389.685993 -294.846344) (xy 389.733264 -294.860036) (xy 389.777726 -294.881134) (xy 389.818229 -294.90909)
			(xy 389.853722 -294.943182) (xy 389.883287 -294.982526) (xy 389.906158 -295.026103) (xy 389.921742 -295.072784)
			(xy 389.929637 -295.121361) (xy 389.930132 -295.145968) (xy 390.259074 -295.145968) (xy 390.263034 -295.096914)
			(xy 390.274811 -295.04913) (xy 390.294102 -295.003854) (xy 390.320405 -294.962258) (xy 390.35304 -294.925421)
			(xy 390.391161 -294.894296) (xy 390.433782 -294.869689) (xy 390.479798 -294.852237) (xy 390.528017 -294.842393)
			(xy 390.577192 -294.840412) (xy 390.626047 -294.846344) (xy 390.673318 -294.860036) (xy 390.71778 -294.881134)
			(xy 390.758283 -294.90909) (xy 390.793776 -294.943182) (xy 390.823341 -294.982526) (xy 390.846212 -295.026103)
			(xy 390.861796 -295.072784) (xy 390.869691 -295.121361) (xy 390.870186 -295.145968) (xy 391.198874 -295.145968)
			(xy 391.202834 -295.096914) (xy 391.214611 -295.04913) (xy 391.233902 -295.003854) (xy 391.260205 -294.962258)
			(xy 391.29284 -294.925421) (xy 391.330961 -294.894296) (xy 391.373582 -294.869689) (xy 391.419598 -294.852237)
			(xy 391.467817 -294.842393) (xy 391.516992 -294.840412) (xy 391.565847 -294.846344) (xy 391.613118 -294.860036)
			(xy 391.65758 -294.881134) (xy 391.698083 -294.90909) (xy 391.733576 -294.943182) (xy 391.763141 -294.982526)
			(xy 391.786012 -295.026103) (xy 391.801596 -295.072784) (xy 391.809491 -295.121361) (xy 391.809986 -295.145968)
			(xy 393.078982 -295.145968) (xy 393.082942 -295.096914) (xy 393.094719 -295.04913) (xy 393.11401 -295.003854)
			(xy 393.140313 -294.962258) (xy 393.172948 -294.925421) (xy 393.211069 -294.894296) (xy 393.25369 -294.869689)
			(xy 393.299706 -294.852237) (xy 393.347925 -294.842393) (xy 393.3971 -294.840412) (xy 393.445955 -294.846344)
			(xy 393.493226 -294.860036) (xy 393.537688 -294.881134) (xy 393.578191 -294.90909) (xy 393.613684 -294.943182)
			(xy 393.643249 -294.982526) (xy 393.66612 -295.026103) (xy 393.681704 -295.072784) (xy 393.689599 -295.121361)
			(xy 393.690094 -295.145968) (xy 393.689599 -295.170575) (xy 393.681704 -295.219152) (xy 393.66612 -295.265833)
			(xy 393.643249 -295.30941) (xy 393.613684 -295.348754) (xy 393.578191 -295.382846) (xy 393.537688 -295.410802)
			(xy 393.493226 -295.4319) (xy 393.445955 -295.445592) (xy 393.3971 -295.451524) (xy 393.347925 -295.449543)
			(xy 393.299706 -295.439699) (xy 393.25369 -295.422247) (xy 393.211069 -295.39764) (xy 393.172948 -295.366515)
			(xy 393.140313 -295.329678) (xy 393.11401 -295.288082) (xy 393.094719 -295.242806) (xy 393.082942 -295.195022)
			(xy 393.078982 -295.145968) (xy 391.809986 -295.145968) (xy 391.809491 -295.170575) (xy 391.801596 -295.219152)
			(xy 391.786012 -295.265833) (xy 391.763141 -295.30941) (xy 391.733576 -295.348754) (xy 391.698083 -295.382846)
			(xy 391.65758 -295.410802) (xy 391.613118 -295.4319) (xy 391.565847 -295.445592) (xy 391.516992 -295.451524)
			(xy 391.467817 -295.449543) (xy 391.419598 -295.439699) (xy 391.373582 -295.422247) (xy 391.330961 -295.39764)
			(xy 391.29284 -295.366515) (xy 391.260205 -295.329678) (xy 391.233902 -295.288082) (xy 391.214611 -295.242806)
			(xy 391.202834 -295.195022) (xy 391.198874 -295.145968) (xy 390.870186 -295.145968) (xy 390.869691 -295.170575)
			(xy 390.861796 -295.219152) (xy 390.846212 -295.265833) (xy 390.823341 -295.30941) (xy 390.793776 -295.348754)
			(xy 390.758283 -295.382846) (xy 390.71778 -295.410802) (xy 390.673318 -295.4319) (xy 390.626047 -295.445592)
			(xy 390.577192 -295.451524) (xy 390.528017 -295.449543) (xy 390.479798 -295.439699) (xy 390.433782 -295.422247)
			(xy 390.391161 -295.39764) (xy 390.35304 -295.366515) (xy 390.320405 -295.329678) (xy 390.294102 -295.288082)
			(xy 390.274811 -295.242806) (xy 390.263034 -295.195022) (xy 390.259074 -295.145968) (xy 389.930132 -295.145968)
			(xy 389.929637 -295.170575) (xy 389.921742 -295.219152) (xy 389.906158 -295.265833) (xy 389.883287 -295.30941)
			(xy 389.853722 -295.348754) (xy 389.818229 -295.382846) (xy 389.777726 -295.410802) (xy 389.733264 -295.4319)
			(xy 389.685993 -295.445592) (xy 389.637138 -295.451524) (xy 389.587963 -295.449543) (xy 389.539744 -295.439699)
			(xy 389.493728 -295.422247) (xy 389.451107 -295.39764) (xy 389.412986 -295.366515) (xy 389.380351 -295.329678)
			(xy 389.354048 -295.288082) (xy 389.334757 -295.242806) (xy 389.32298 -295.195022) (xy 389.31902 -295.145968)
			(xy 388.990078 -295.145968) (xy 388.989583 -295.170575) (xy 388.981688 -295.219152) (xy 388.966104 -295.265833)
			(xy 388.943233 -295.30941) (xy 388.913668 -295.348754) (xy 388.878175 -295.382846) (xy 388.837672 -295.410802)
			(xy 388.79321 -295.4319) (xy 388.745939 -295.445592) (xy 388.697084 -295.451524) (xy 388.647909 -295.449543)
			(xy 388.59969 -295.439699) (xy 388.553674 -295.422247) (xy 388.511053 -295.39764) (xy 388.472932 -295.366515)
			(xy 388.440297 -295.329678) (xy 388.413994 -295.288082) (xy 388.394703 -295.242806) (xy 388.382926 -295.195022)
			(xy 388.378966 -295.145968) (xy 386.17017 -295.145968) (xy 386.169675 -295.170575) (xy 386.16178 -295.219152)
			(xy 386.146196 -295.265833) (xy 386.123325 -295.30941) (xy 386.09376 -295.348754) (xy 386.058267 -295.382846)
			(xy 386.017764 -295.410802) (xy 385.973302 -295.4319) (xy 385.926031 -295.445592) (xy 385.877176 -295.451524)
			(xy 385.828001 -295.449543) (xy 385.779782 -295.439699) (xy 385.733766 -295.422247) (xy 385.691145 -295.39764)
			(xy 385.653024 -295.366515) (xy 385.620389 -295.329678) (xy 385.594086 -295.288082) (xy 385.574795 -295.242806)
			(xy 385.563018 -295.195022) (xy 385.559058 -295.145968) (xy 385.230116 -295.145968) (xy 385.229621 -295.170575)
			(xy 385.221726 -295.219152) (xy 385.206142 -295.265833) (xy 385.183271 -295.30941) (xy 385.153706 -295.348754)
			(xy 385.118213 -295.382846) (xy 385.07771 -295.410802) (xy 385.033248 -295.4319) (xy 384.985977 -295.445592)
			(xy 384.937122 -295.451524) (xy 384.887947 -295.449543) (xy 384.839728 -295.439699) (xy 384.793712 -295.422247)
			(xy 384.751091 -295.39764) (xy 384.71297 -295.366515) (xy 384.680335 -295.329678) (xy 384.654032 -295.288082)
			(xy 384.634741 -295.242806) (xy 384.622964 -295.195022) (xy 384.619004 -295.145968) (xy 382.410208 -295.145968)
			(xy 382.409713 -295.170575) (xy 382.401818 -295.219152) (xy 382.386234 -295.265833) (xy 382.363363 -295.30941)
			(xy 382.333798 -295.348754) (xy 382.298305 -295.382846) (xy 382.257802 -295.410802) (xy 382.21334 -295.4319)
			(xy 382.166069 -295.445592) (xy 382.117214 -295.451524) (xy 382.068039 -295.449543) (xy 382.01982 -295.439699)
			(xy 381.973804 -295.422247) (xy 381.931183 -295.39764) (xy 381.893062 -295.366515) (xy 381.860427 -295.329678)
			(xy 381.834124 -295.288082) (xy 381.814833 -295.242806) (xy 381.803056 -295.195022) (xy 381.799096 -295.145968)
			(xy 381.470154 -295.145968) (xy 381.469659 -295.170575) (xy 381.461764 -295.219152) (xy 381.44618 -295.265833)
			(xy 381.423309 -295.30941) (xy 381.393744 -295.348754) (xy 381.358251 -295.382846) (xy 381.317748 -295.410802)
			(xy 381.273286 -295.4319) (xy 381.226015 -295.445592) (xy 381.17716 -295.451524) (xy 381.127985 -295.449543)
			(xy 381.079766 -295.439699) (xy 381.03375 -295.422247) (xy 380.991129 -295.39764) (xy 380.953008 -295.366515)
			(xy 380.920373 -295.329678) (xy 380.89407 -295.288082) (xy 380.874779 -295.242806) (xy 380.863002 -295.195022)
			(xy 380.859042 -295.145968) (xy 379.59056 -295.145968) (xy 379.590563 -295.146) (xy 379.586392 -295.196339)
			(xy 379.573993 -295.245306) (xy 379.553704 -295.291564) (xy 379.526079 -295.333852) (xy 379.49187 -295.371017)
			(xy 379.452011 -295.402045) (xy 379.407589 -295.42609) (xy 379.359816 -295.442496) (xy 379.309994 -295.450815)
			(xy 379.284738 -295.451276) (xy 379.259612 -295.450768) (xy 379.210039 -295.442542) (xy 379.162483 -295.426305)
			(xy 379.118229 -295.402497) (xy 379.098048 -295.387522) (xy 379.091698 -295.382696) (xy 379.068584 -295.374314)
			(xy 379.064217 -295.372895) (xy 379.055142 -295.371498) (xy 379.05055 -295.37152) (xy 379.028706 -295.371774)
			(xy 379.0192 -295.372305) (xy 379.001575 -295.37947) (xy 378.994416 -295.385744) (xy 378.993908 -295.386252)
			(xy 378.859542 -295.520618) (xy 378.855224 -295.525444) (xy 378.848513 -295.535028) (xy 378.84377 -295.557914)
			(xy 378.84608 -295.569386) (xy 378.871226 -295.666922) (xy 378.890022 -295.686226) (xy 378.902976 -295.690036)
			(xy 378.926502 -295.697321) (xy 378.971006 -295.718407) (xy 379.011547 -295.746366) (xy 379.047072 -295.780473)
			(xy 379.076658 -295.819842) (xy 379.099538 -295.863451) (xy 379.115118 -295.910169) (xy 379.122994 -295.958782)
			(xy 379.123448 -295.983406) (xy 379.12328 -295.998815) (xy 379.120224 -296.02948) (xy 379.117352 -296.04462)
			(xy 379.115601 -296.056804) (xy 379.122359 -296.080434) (xy 379.130306 -296.089832) (xy 379.18771 -296.15003)
			(xy 379.196717 -296.158635) (xy 379.220284 -296.166619) (xy 379.232668 -296.16527) (xy 379.24642 -296.163236)
			(xy 379.274139 -296.161072) (xy 379.28804 -296.160952) (xy 379.294898 -296.160952) (xy 379.307145 -296.161289)
			(xy 379.331551 -296.163451) (xy 379.343666 -296.16527) (xy 379.356112 -296.167302) (xy 379.379988 -296.159174)
			(xy 379.446028 -296.089832) (xy 379.453965 -296.080429) (xy 379.46071 -296.056806) (xy 379.458982 -296.04462)
			(xy 379.456106 -296.029481) (xy 379.45305 -295.998815) (xy 379.452886 -295.983406) (xy 379.453408 -295.958151)
			(xy 379.461721 -295.908329) (xy 379.478122 -295.860555) (xy 379.502163 -295.816132) (xy 379.533187 -295.776272)
			(xy 379.570349 -295.742062) (xy 379.612635 -295.714436) (xy 379.658891 -295.694146) (xy 379.707856 -295.681746)
			(xy 379.758194 -295.677575) (xy 379.808532 -295.681746) (xy 379.857497 -295.694146) (xy 379.903753 -295.714436)
			(xy 379.946039 -295.742062) (xy 379.983201 -295.776272) (xy 380.014225 -295.816132) (xy 380.038266 -295.860555)
			(xy 380.054667 -295.908329) (xy 380.06298 -295.958151) (xy 380.063502 -295.983406) (xy 380.063334 -295.998815)
			(xy 380.060278 -296.02948) (xy 380.057406 -296.04462) (xy 380.054866 -296.057066) (xy 380.061724 -296.080688)
			(xy 380.136654 -296.159174) (xy 380.160276 -296.167302) (xy 380.172722 -296.16527) (xy 380.186412 -296.163249)
			(xy 380.214002 -296.161091) (xy 380.22784 -296.160952) (xy 380.241868 -296.161071) (xy 380.269841 -296.163231)
			(xy 380.28372 -296.16527) (xy 380.296166 -296.167302) (xy 380.319534 -296.159174) (xy 380.394718 -296.080688)
			(xy 380.401576 -296.057066) (xy 380.399036 -296.04462) (xy 380.39616 -296.029481) (xy 380.393105 -295.998815)
			(xy 380.39294 -295.983406) (xy 380.393425 -295.95859) (xy 380.401454 -295.909611) (xy 380.4173 -295.862576)
			(xy 380.440547 -295.818724) (xy 380.470582 -295.779211) (xy 380.506613 -295.745077) (xy 380.547692 -295.717222)
			(xy 380.592736 -295.69638) (xy 380.640559 -295.683099) (xy 380.6899 -295.67773) (xy 380.73946 -295.680413)
			(xy 380.787933 -295.691079) (xy 380.834041 -295.709447) (xy 380.876571 -295.735032) (xy 380.914402 -295.76716)
			(xy 380.946537 -295.804985) (xy 380.972129 -295.84751) (xy 380.990505 -295.893616) (xy 381.001179 -295.942087)
			(xy 381.003872 -295.991646) (xy 381.003865 -295.991713) (xy 381.332233 -295.991713) (xy 381.334917 -295.942135)
			(xy 381.345586 -295.893643) (xy 381.36396 -295.847516) (xy 381.389555 -295.80497) (xy 381.421696 -295.767125)
			(xy 381.459536 -295.734979) (xy 381.502079 -295.709379) (xy 381.548203 -295.690998) (xy 381.596693 -295.680322)
			(xy 381.646271 -295.677632) (xy 381.695632 -295.682999) (xy 381.743474 -295.696281) (xy 381.788537 -295.717128)
			(xy 381.829633 -295.744991) (xy 381.86568 -295.779136) (xy 381.895728 -295.818663) (xy 381.918985 -295.86253)
			(xy 381.934839 -295.909583) (xy 381.942871 -295.95858) (xy 381.943356 -295.983406) (xy 381.943192 -295.998815)
			(xy 381.940136 -296.029481) (xy 381.93726 -296.04462) (xy 381.93472 -296.057066) (xy 381.941578 -296.080688)
			(xy 382.016508 -296.159428) (xy 382.04013 -296.167302) (xy 382.052576 -296.16527) (xy 382.066329 -296.163246)
			(xy 382.094047 -296.161086) (xy 382.107948 -296.160952) (xy 382.121913 -296.161072) (xy 382.149758 -296.16323)
			(xy 382.163574 -296.16527) (xy 382.17602 -296.167302) (xy 382.199642 -296.159428) (xy 382.274572 -296.080688)
			(xy 382.28143 -296.057066) (xy 382.27889 -296.04462) (xy 382.276018 -296.02948) (xy 382.272962 -295.998815)
			(xy 382.272794 -295.983406) (xy 382.273316 -295.958151) (xy 382.281629 -295.908329) (xy 382.29803 -295.860555)
			(xy 382.322071 -295.816132) (xy 382.353095 -295.776272) (xy 382.390257 -295.742062) (xy 382.432543 -295.714436)
			(xy 382.478799 -295.694146) (xy 382.527764 -295.681746) (xy 382.578102 -295.677575) (xy 382.62844 -295.681746)
			(xy 382.677405 -295.694146) (xy 382.723661 -295.714436) (xy 382.765947 -295.742062) (xy 382.803109 -295.776272)
			(xy 382.834133 -295.816132) (xy 382.858174 -295.860555) (xy 382.874575 -295.908329) (xy 382.882888 -295.958151)
			(xy 382.88341 -295.983406) (xy 382.883246 -295.998815) (xy 382.88019 -296.029481) (xy 382.877314 -296.04462)
			(xy 382.874774 -296.057066) (xy 382.881632 -296.080688) (xy 382.956562 -296.159428) (xy 382.980184 -296.167302)
			(xy 382.99263 -296.16527) (xy 383.006384 -296.163251) (xy 383.034101 -296.161088) (xy 383.048002 -296.160952)
			(xy 383.061967 -296.161066) (xy 383.089813 -296.163228) (xy 383.103628 -296.16527) (xy 383.116074 -296.167302)
			(xy 383.139696 -296.159428) (xy 383.214626 -296.080688) (xy 383.221484 -296.057066) (xy 383.218944 -296.04462)
			(xy 383.216072 -296.02948) (xy 383.213016 -295.998815) (xy 383.212848 -295.983406) (xy 383.213371 -295.958584)
			(xy 383.221402 -295.909593) (xy 383.237254 -295.862547) (xy 383.260507 -295.818686) (xy 383.290551 -295.779164)
			(xy 383.326593 -295.745024) (xy 383.367683 -295.717165) (xy 383.41274 -295.696321) (xy 383.460575 -295.683041)
			(xy 383.509929 -295.677675) (xy 383.5595 -295.680364) (xy 383.607983 -295.691039) (xy 383.654101 -295.709416)
			(xy 383.696638 -295.735013) (xy 383.734473 -295.767154) (xy 383.76661 -295.804993) (xy 383.792201 -295.847533)
			(xy 383.810573 -295.893653) (xy 383.821241 -295.942138) (xy 383.82199 -295.955974) (xy 388.84912 -295.955974)
			(xy 388.85308 -295.90692) (xy 388.864857 -295.859136) (xy 388.884148 -295.81386) (xy 388.910451 -295.772264)
			(xy 388.943086 -295.735427) (xy 388.981207 -295.704302) (xy 389.023828 -295.679695) (xy 389.069844 -295.662243)
			(xy 389.118063 -295.652399) (xy 389.167238 -295.650418) (xy 389.216093 -295.65635) (xy 389.263364 -295.670042)
			(xy 389.307826 -295.69114) (xy 389.348329 -295.719096) (xy 389.383822 -295.753188) (xy 389.413387 -295.792532)
			(xy 389.436258 -295.836109) (xy 389.451842 -295.88279) (xy 389.459737 -295.931367) (xy 389.460232 -295.955974)
			(xy 392.609082 -295.955974) (xy 392.613042 -295.90692) (xy 392.624819 -295.859136) (xy 392.64411 -295.81386)
			(xy 392.670413 -295.772264) (xy 392.703048 -295.735427) (xy 392.741169 -295.704302) (xy 392.78379 -295.679695)
			(xy 392.829806 -295.662243) (xy 392.878025 -295.652399) (xy 392.9272 -295.650418) (xy 392.976055 -295.65635)
			(xy 393.023326 -295.670042) (xy 393.067788 -295.69114) (xy 393.108291 -295.719096) (xy 393.143784 -295.753188)
			(xy 393.173349 -295.792532) (xy 393.19622 -295.836109) (xy 393.211804 -295.88279) (xy 393.219699 -295.931367)
			(xy 393.220194 -295.955974) (xy 393.219699 -295.980581) (xy 393.211804 -296.029158) (xy 393.19622 -296.075839)
			(xy 393.173349 -296.119416) (xy 393.143784 -296.15876) (xy 393.108291 -296.192852) (xy 393.067788 -296.220808)
			(xy 393.023326 -296.241906) (xy 392.976055 -296.255598) (xy 392.9272 -296.26153) (xy 392.878025 -296.259549)
			(xy 392.829806 -296.249705) (xy 392.78379 -296.232253) (xy 392.741169 -296.207646) (xy 392.703048 -296.176521)
			(xy 392.670413 -296.139684) (xy 392.64411 -296.098088) (xy 392.624819 -296.052812) (xy 392.613042 -296.005028)
			(xy 392.609082 -295.955974) (xy 389.460232 -295.955974) (xy 389.459737 -295.980581) (xy 389.451842 -296.029158)
			(xy 389.436258 -296.075839) (xy 389.413387 -296.119416) (xy 389.383822 -296.15876) (xy 389.348329 -296.192852)
			(xy 389.307826 -296.220808) (xy 389.263364 -296.241906) (xy 389.216093 -296.255598) (xy 389.167238 -296.26153)
			(xy 389.118063 -296.259549) (xy 389.069844 -296.249705) (xy 389.023828 -296.232253) (xy 388.981207 -296.207646)
			(xy 388.943086 -296.176521) (xy 388.910451 -296.139684) (xy 388.884148 -296.098088) (xy 388.864857 -296.052812)
			(xy 388.85308 -296.005028) (xy 388.84912 -295.955974) (xy 383.82199 -295.955974) (xy 383.823924 -295.99171)
			(xy 383.818552 -296.041062) (xy 383.805266 -296.088896) (xy 383.784416 -296.13395) (xy 383.756552 -296.175037)
			(xy 383.722407 -296.211075) (xy 383.682882 -296.241113) (xy 383.639018 -296.264362) (xy 383.59197 -296.280207)
			(xy 383.542978 -296.288232) (xy 383.518156 -296.288714) (xy 383.495042 -296.287952) (xy 383.482596 -296.286936)
			(xy 383.459736 -296.296588) (xy 383.39141 -296.38117) (xy 383.38633 -296.4053) (xy 383.389886 -296.417492)
			(xy 383.39653 -296.441846) (xy 383.403671 -296.49182) (xy 383.40411 -296.51706) (xy 383.403612 -296.543709)
			(xy 383.395669 -296.596413) (xy 383.379959 -296.647343) (xy 383.356833 -296.695364) (xy 383.326809 -296.739401)
			(xy 383.290557 -296.778472) (xy 383.248886 -296.811703) (xy 383.202728 -296.838352) (xy 383.153114 -296.857824)
			(xy 383.101152 -296.869684) (xy 383.048002 -296.873668) (xy 382.994852 -296.869684) (xy 382.94289 -296.857824)
			(xy 382.893276 -296.838352) (xy 382.847118 -296.811703) (xy 382.805447 -296.778472) (xy 382.769195 -296.739401)
			(xy 382.739171 -296.695364) (xy 382.716045 -296.647343) (xy 382.700335 -296.596413) (xy 382.692392 -296.543709)
			(xy 382.691894 -296.51706) (xy 382.69234 -296.49182) (xy 382.699482 -296.441848) (xy 382.706118 -296.417492)
			(xy 382.709674 -296.405554) (xy 382.704594 -296.38117) (xy 382.636268 -296.296842) (xy 382.613408 -296.286936)
			(xy 382.600962 -296.287952) (xy 382.578102 -296.288714) (xy 382.554988 -296.287952) (xy 382.542542 -296.286936)
			(xy 382.519682 -296.296588) (xy 382.451356 -296.38117) (xy 382.446276 -296.4053) (xy 382.449832 -296.417492)
			(xy 382.456475 -296.441847) (xy 382.463617 -296.49182) (xy 382.464056 -296.51706) (xy 382.463558 -296.543709)
			(xy 382.455615 -296.596413) (xy 382.439905 -296.647343) (xy 382.416779 -296.695364) (xy 382.386755 -296.739401)
			(xy 382.350503 -296.778472) (xy 382.308832 -296.811703) (xy 382.262674 -296.838352) (xy 382.21306 -296.857824)
			(xy 382.161098 -296.869684) (xy 382.107948 -296.873668) (xy 382.054798 -296.869684) (xy 382.002836 -296.857824)
			(xy 381.953222 -296.838352) (xy 381.907064 -296.811703) (xy 381.865393 -296.778472) (xy 381.829141 -296.739401)
			(xy 381.799117 -296.695364) (xy 381.775991 -296.647343) (xy 381.760281 -296.596413) (xy 381.752338 -296.543709)
			(xy 381.75184 -296.51706) (xy 381.752284 -296.49182) (xy 381.759428 -296.441848) (xy 381.766064 -296.417492)
			(xy 381.76962 -296.405554) (xy 381.76454 -296.38117) (xy 381.696214 -296.296842) (xy 381.673354 -296.286936)
			(xy 381.660908 -296.287952) (xy 381.638048 -296.288714) (xy 381.613222 -296.288274) (xy 381.564224 -296.280249)
			(xy 381.517169 -296.264402) (xy 381.473298 -296.241151) (xy 381.433767 -296.211108) (xy 381.399617 -296.175066)
			(xy 381.371748 -296.133973) (xy 381.350895 -296.088913) (xy 381.337607 -296.041073) (xy 381.332233 -295.991713)
			(xy 381.003865 -295.991713) (xy 380.998511 -296.040988) (xy 380.985239 -296.088813) (xy 380.964404 -296.133861)
			(xy 380.936556 -296.174945) (xy 380.902429 -296.210982) (xy 380.862921 -296.241024) (xy 380.819074 -296.264279)
			(xy 380.772042 -296.280133) (xy 380.723064 -296.28817) (xy 380.698248 -296.288714) (xy 380.675134 -296.287952)
			(xy 380.67488 -296.287952) (xy 380.662494 -296.287563) (xy 380.639723 -296.297273) (xy 380.631446 -296.306494)
			(xy 380.570994 -296.38117) (xy 380.566168 -296.4053) (xy 380.569724 -296.417492) (xy 380.576361 -296.441848)
			(xy 380.583504 -296.49182) (xy 380.583948 -296.51706) (xy 380.58345 -296.543709) (xy 380.575507 -296.596413)
			(xy 380.559797 -296.647343) (xy 380.536671 -296.695364) (xy 380.506647 -296.739401) (xy 380.470395 -296.778472)
			(xy 380.428724 -296.811703) (xy 380.382566 -296.838352) (xy 380.332952 -296.857824) (xy 380.28099 -296.869684)
			(xy 380.22784 -296.873668) (xy 380.17469 -296.869684) (xy 380.122728 -296.857824) (xy 380.073114 -296.838352)
			(xy 380.026956 -296.811703) (xy 379.985285 -296.778472) (xy 379.949033 -296.739401) (xy 379.919009 -296.695364)
			(xy 379.895883 -296.647343) (xy 379.880173 -296.596413) (xy 379.87223 -296.543709) (xy 379.871732 -296.51706)
			(xy 379.872181 -296.491883) (xy 379.879315 -296.442036) (xy 379.885956 -296.417746) (xy 379.889512 -296.405554)
			(xy 379.884432 -296.38117) (xy 379.816106 -296.296842) (xy 379.7935 -296.286936) (xy 379.781054 -296.287952)
			(xy 379.758448 -296.288714) (xy 379.75794 -296.288714) (xy 379.73508 -296.287952) (xy 379.722634 -296.286936)
			(xy 379.69952 -296.296842) (xy 379.631448 -296.38117) (xy 379.626368 -296.405554) (xy 379.629924 -296.417746)
			(xy 379.636542 -296.44204) (xy 379.643676 -296.491885) (xy 379.644148 -296.51706) (xy 379.64365 -296.543709)
			(xy 379.635707 -296.596413) (xy 379.619997 -296.647343) (xy 379.596871 -296.695364) (xy 379.566847 -296.739401)
			(xy 379.530595 -296.778472) (xy 379.488924 -296.811703) (xy 379.442766 -296.838352) (xy 379.393152 -296.857824)
			(xy 379.34119 -296.869684) (xy 379.28804 -296.873668) (xy 379.23489 -296.869684) (xy 379.182928 -296.857824)
			(xy 379.133314 -296.838352) (xy 379.087156 -296.811703) (xy 379.045485 -296.778472) (xy 379.009233 -296.739401)
			(xy 378.979209 -296.695364) (xy 378.956083 -296.647343) (xy 378.940373 -296.596413) (xy 378.93243 -296.543709)
			(xy 378.931932 -296.51706) (xy 378.932381 -296.491883) (xy 378.939515 -296.442036) (xy 378.946156 -296.417746)
			(xy 378.949712 -296.405554) (xy 378.944632 -296.38117) (xy 378.876306 -296.296842) (xy 378.8537 -296.286936)
			(xy 378.841254 -296.287952) (xy 378.81941 -296.288714) (xy 378.817886 -296.288714) (xy 378.802668 -296.288514)
			(xy 378.772385 -296.285463) (xy 378.757434 -296.282618) (xy 378.756926 -296.282618) (xy 378.745821 -296.280998)
			(xy 378.724065 -296.286395) (xy 378.715016 -296.293032) (xy 378.654056 -296.342562) (xy 378.645623 -296.350231)
			(xy 378.635875 -296.370803) (xy 378.63526 -296.382186) (xy 378.63526 -297.081913) (xy 385.826756 -297.081913)
			(xy 385.826756 -297.017991) (xy 385.834767 -296.954573) (xy 385.850664 -296.892659) (xy 385.874196 -296.833226)
			(xy 385.90499 -296.777211) (xy 385.942563 -296.725496) (xy 385.98632 -296.678899) (xy 386.035573 -296.638154)
			(xy 386.089544 -296.603903) (xy 386.147383 -296.576686) (xy 386.208176 -296.556933) (xy 386.270966 -296.544955)
			(xy 386.334762 -296.540942) (xy 386.398558 -296.544955) (xy 386.461348 -296.556933) (xy 386.522141 -296.576686)
			(xy 386.57998 -296.603903) (xy 386.633951 -296.638154) (xy 386.683204 -296.678899) (xy 386.726961 -296.725496)
			(xy 386.764534 -296.777211) (xy 386.795328 -296.833226) (xy 386.81886 -296.892659) (xy 386.834757 -296.954573)
			(xy 386.842768 -297.017991) (xy 386.84327 -297.049952) (xy 386.842768 -297.081913) (xy 386.834757 -297.145331)
			(xy 386.81886 -297.207245) (xy 386.795328 -297.266678) (xy 386.764534 -297.322693) (xy 386.726961 -297.374408)
			(xy 386.683204 -297.421005) (xy 386.633951 -297.46175) (xy 386.57998 -297.496001) (xy 386.522141 -297.523218)
			(xy 386.461348 -297.542971) (xy 386.398558 -297.554949) (xy 386.334762 -297.558963) (xy 386.270966 -297.554949)
			(xy 386.208176 -297.542971) (xy 386.147383 -297.523218) (xy 386.089544 -297.496001) (xy 386.035573 -297.46175)
			(xy 385.98632 -297.421005) (xy 385.942563 -297.374408) (xy 385.90499 -297.322693) (xy 385.874196 -297.266678)
			(xy 385.850664 -297.207245) (xy 385.834767 -297.145331) (xy 385.826756 -297.081913) (xy 378.63526 -297.081913)
			(xy 378.63526 -298.848018) (xy 378.635719 -298.857896) (xy 378.643158 -298.876198) (xy 378.649738 -298.883578)
			(xy 378.649992 -298.883832) (xy 379.055122 -299.288962) (xy 379.064477 -299.297437) (xy 379.088603 -299.304751)
			(xy 379.101096 -299.302932) (xy 379.196346 -299.283882) (xy 379.216158 -299.267626) (xy 379.220984 -299.255942)
			(xy 379.232166 -299.230061) (xy 379.26103 -299.181633) (xy 379.2967 -299.137974) (xy 379.338401 -299.100034)
			(xy 379.385227 -299.068638) (xy 379.436161 -299.044467) (xy 379.490094 -299.028048) (xy 379.545855 -299.019736)
			(xy 379.574044 -299.019214) (xy 379.601293 -299.019703) (xy 379.655234 -299.027465) (xy 379.707522 -299.042824)
			(xy 379.757093 -299.065468) (xy 379.802936 -299.094936) (xy 379.844119 -299.130628) (xy 379.879804 -299.171817)
			(xy 379.909264 -299.217665) (xy 379.931899 -299.267239) (xy 379.935442 -299.27931) (xy 381.753362 -299.27931)
			(xy 381.757433 -299.223688) (xy 381.769559 -299.169251) (xy 381.789482 -299.11716) (xy 381.816778 -299.068525)
			(xy 381.850864 -299.024382) (xy 381.891013 -298.985673) (xy 381.936371 -298.953222) (xy 381.985971 -298.927721)
			(xy 382.038755 -298.909714) (xy 382.093598 -298.899584) (xy 382.149332 -298.897547) (xy 382.204769 -298.903647)
			(xy 382.258726 -298.917753) (xy 382.310055 -298.939565) (xy 382.357661 -298.968619) (xy 382.400529 -299.004294)
			(xy 382.437746 -299.045831) (xy 382.468519 -299.092344) (xy 382.492191 -299.142841) (xy 382.508259 -299.196248)
			(xy 382.516379 -299.251424) (xy 382.516888 -299.27931) (xy 384.039362 -299.27931) (xy 384.043433 -299.223688)
			(xy 384.055559 -299.169251) (xy 384.075482 -299.11716) (xy 384.102778 -299.068525) (xy 384.136864 -299.024382)
			(xy 384.177013 -298.985673) (xy 384.222371 -298.953222) (xy 384.271971 -298.927721) (xy 384.324755 -298.909714)
			(xy 384.379598 -298.899584) (xy 384.435332 -298.897547) (xy 384.490769 -298.903647) (xy 384.544726 -298.917753)
			(xy 384.596055 -298.939565) (xy 384.643661 -298.968619) (xy 384.686529 -299.004294) (xy 384.723746 -299.045831)
			(xy 384.754519 -299.092344) (xy 384.762249 -299.108833) (xy 387.935718 -299.108833) (xy 387.935718 -299.044911)
			(xy 387.943729 -298.981493) (xy 387.959626 -298.919579) (xy 387.983158 -298.860146) (xy 388.013952 -298.804131)
			(xy 388.051525 -298.752416) (xy 388.095282 -298.705819) (xy 388.144535 -298.665074) (xy 388.198506 -298.630823)
			(xy 388.256345 -298.603606) (xy 388.317138 -298.583853) (xy 388.379928 -298.571875) (xy 388.443724 -298.567862)
			(xy 388.50752 -298.571875) (xy 388.57031 -298.583853) (xy 388.631103 -298.603606) (xy 388.688942 -298.630823)
			(xy 388.742913 -298.665074) (xy 388.792166 -298.705819) (xy 388.835923 -298.752416) (xy 388.873496 -298.804131)
			(xy 388.90429 -298.860146) (xy 388.927822 -298.919579) (xy 388.943719 -298.981493) (xy 388.95173 -299.044911)
			(xy 388.952232 -299.076872) (xy 388.95173 -299.108833) (xy 388.943719 -299.172251) (xy 388.927822 -299.234165)
			(xy 388.90429 -299.293598) (xy 388.873496 -299.349613) (xy 388.835923 -299.401328) (xy 388.792166 -299.447925)
			(xy 388.742913 -299.48867) (xy 388.688942 -299.522921) (xy 388.631103 -299.550138) (xy 388.57031 -299.569891)
			(xy 388.50752 -299.581869) (xy 388.443724 -299.585883) (xy 388.379928 -299.581869) (xy 388.317138 -299.569891)
			(xy 388.256345 -299.550138) (xy 388.198506 -299.522921) (xy 388.144535 -299.48867) (xy 388.095282 -299.447925)
			(xy 388.051525 -299.401328) (xy 388.013952 -299.349613) (xy 387.983158 -299.293598) (xy 387.959626 -299.234165)
			(xy 387.943729 -299.172251) (xy 387.935718 -299.108833) (xy 384.762249 -299.108833) (xy 384.778191 -299.142841)
			(xy 384.794259 -299.196248) (xy 384.802379 -299.251424) (xy 384.802888 -299.27931) (xy 384.802379 -299.307196)
			(xy 384.794259 -299.362372) (xy 384.778191 -299.415779) (xy 384.754519 -299.466276) (xy 384.723746 -299.512789)
			(xy 384.686529 -299.554326) (xy 384.643661 -299.590001) (xy 384.596055 -299.619055) (xy 384.544726 -299.640867)
			(xy 384.490769 -299.654973) (xy 384.435332 -299.661073) (xy 384.379598 -299.659036) (xy 384.324755 -299.648906)
			(xy 384.271971 -299.630899) (xy 384.222371 -299.605398) (xy 384.177013 -299.572947) (xy 384.136864 -299.534238)
			(xy 384.102778 -299.490095) (xy 384.075482 -299.44146) (xy 384.055559 -299.389369) (xy 384.043433 -299.334932)
			(xy 384.039362 -299.27931) (xy 382.516888 -299.27931) (xy 382.516379 -299.307196) (xy 382.508259 -299.362372)
			(xy 382.492191 -299.415779) (xy 382.468519 -299.466276) (xy 382.437746 -299.512789) (xy 382.400529 -299.554326)
			(xy 382.357661 -299.590001) (xy 382.310055 -299.619055) (xy 382.258726 -299.640867) (xy 382.204769 -299.654973)
			(xy 382.149332 -299.661073) (xy 382.093598 -299.659036) (xy 382.038755 -299.648906) (xy 381.985971 -299.630899)
			(xy 381.936371 -299.605398) (xy 381.891013 -299.572947) (xy 381.850864 -299.534238) (xy 381.816778 -299.490095)
			(xy 381.789482 -299.44146) (xy 381.769559 -299.389369) (xy 381.757433 -299.334932) (xy 381.753362 -299.27931)
			(xy 379.935442 -299.27931) (xy 379.947249 -299.31953) (xy 379.955001 -299.373473) (xy 379.955552 -299.400722)
			(xy 379.955002 -299.430199) (xy 379.945931 -299.48845) (xy 379.928008 -299.544613) (xy 379.90166 -299.59735)
			(xy 379.867514 -299.645408) (xy 379.847348 -299.666914) (xy 379.840639 -299.67435) (xy 379.833162 -299.692915)
			(xy 379.833369 -299.712927) (xy 379.836934 -299.722286) (xy 379.873256 -299.808392) (xy 379.876629 -299.815579)
			(xy 379.886965 -299.827619) (xy 379.893576 -299.832014) (xy 379.906022 -299.83938)
		)
		(stroke
			(width 0)
			(type solid)
		)
		(fill yes)
		(layer "In15.Cu")
		(net "PVDD11_S3_P0")
	)
	(gr_poly
		(pts
			(xy 58.648346 -319.35166) (xy 58.658337 -319.351131) (xy 58.676779 -319.343427) (xy 58.68416 -319.336674)
			(xy 61.425328 -316.595506) (xy 61.432183 -316.588111) (xy 61.439931 -316.569513) (xy 61.440314 -316.559438)
			(xy 61.440314 -200.576688) (xy 61.439889 -200.566618) (xy 61.432173 -200.548016) (xy 61.425328 -200.54062)
			(xy 59.664854 -198.780146) (xy 59.657455 -198.773302) (xy 59.638857 -198.765577) (xy 59.628786 -198.76516)
			(xy 52.295806 -198.76516) (xy 52.283251 -198.765803) (xy 52.261123 -198.777664) (xy 52.253642 -198.787766)
			(xy 52.19954 -198.868284) (xy 52.197 -198.89343) (xy 52.201826 -198.905368) (xy 52.209942 -198.926078)
			(xy 52.221364 -198.969069) (xy 52.227128 -199.013175) (xy 52.22748 -199.035416) (xy 52.227 -199.061115)
			(xy 52.219339 -199.111939) (xy 52.20419 -199.161053) (xy 52.181889 -199.207361) (xy 52.152936 -199.249828)
			(xy 52.117976 -199.287505) (xy 52.077792 -199.319551) (xy 52.03328 -199.34525) (xy 51.985435 -199.364027)
			(xy 51.935326 -199.375465) (xy 51.884072 -199.379306) (xy 51.832818 -199.375465) (xy 51.782709 -199.364027)
			(xy 51.734864 -199.34525) (xy 51.690352 -199.319551) (xy 51.650168 -199.287505) (xy 51.615208 -199.249828)
			(xy 51.586255 -199.207361) (xy 51.563954 -199.161053) (xy 51.548805 -199.111939) (xy 51.541144 -199.061115)
			(xy 51.540664 -199.035416) (xy 51.541032 -199.013176) (xy 51.546801 -198.969072) (xy 51.558206 -198.926079)
			(xy 51.566318 -198.905368) (xy 51.571144 -198.89343) (xy 51.568604 -198.868284) (xy 51.514502 -198.787766)
			(xy 51.506987 -198.777702) (xy 51.484879 -198.765843) (xy 51.472338 -198.76516) (xy 44.751752 -198.76516)
			(xy 44.739204 -198.765815) (xy 44.717096 -198.777688) (xy 44.709588 -198.787766) (xy 44.655486 -198.868284)
			(xy 44.652946 -198.89343) (xy 44.657772 -198.905368) (xy 44.665889 -198.926078) (xy 44.677312 -198.969068)
			(xy 44.683078 -199.013175) (xy 44.683426 -199.035416) (xy 44.682946 -199.061115) (xy 44.675285 -199.111939)
			(xy 44.660136 -199.161053) (xy 44.637835 -199.207361) (xy 44.608882 -199.249828) (xy 44.573922 -199.287505)
			(xy 44.533738 -199.319551) (xy 44.489226 -199.34525) (xy 44.441381 -199.364027) (xy 44.391272 -199.375465)
			(xy 44.340018 -199.379306) (xy 44.288764 -199.375465) (xy 44.238655 -199.364027) (xy 44.19081 -199.34525)
			(xy 44.146298 -199.319551) (xy 44.106114 -199.287505) (xy 44.071154 -199.249828) (xy 44.042201 -199.207361)
			(xy 44.0199 -199.161053) (xy 44.004751 -199.111939) (xy 43.99709 -199.061115) (xy 43.99661 -199.035416)
			(xy 43.996978 -199.013176) (xy 44.002746 -198.969071) (xy 44.01415 -198.926078) (xy 44.022264 -198.905368)
			(xy 44.02709 -198.89343) (xy 44.02455 -198.868284) (xy 43.970448 -198.787766) (xy 43.962929 -198.777711)
			(xy 43.94082 -198.765875) (xy 43.928284 -198.76516) (xy 37.207698 -198.76516) (xy 37.195144 -198.765805)
			(xy 37.173019 -198.777667) (xy 37.165534 -198.787766) (xy 37.111432 -198.868284) (xy 37.108892 -198.89343)
			(xy 37.113718 -198.905368) (xy 37.121834 -198.926078) (xy 37.133256 -198.969069) (xy 37.139021 -199.013175)
			(xy 37.139372 -199.035416) (xy 37.138892 -199.061115) (xy 37.131231 -199.111939) (xy 37.116082 -199.161053)
			(xy 37.093781 -199.207361) (xy 37.064828 -199.249828) (xy 37.029868 -199.287505) (xy 36.989684 -199.319551)
			(xy 36.945172 -199.34525) (xy 36.897327 -199.364027) (xy 36.847218 -199.375465) (xy 36.795964 -199.379306)
			(xy 36.74471 -199.375465) (xy 36.694601 -199.364027) (xy 36.646756 -199.34525) (xy 36.602244 -199.319551)
			(xy 36.56206 -199.287505) (xy 36.5271 -199.249828) (xy 36.498147 -199.207361) (xy 36.475846 -199.161053)
			(xy 36.460697 -199.111939) (xy 36.453036 -199.061115) (xy 36.452556 -199.035416) (xy 36.452924 -199.013176)
			(xy 36.458693 -198.969072) (xy 36.470098 -198.926079) (xy 36.47821 -198.905368) (xy 36.483036 -198.89343)
			(xy 36.480496 -198.868284) (xy 36.426394 -198.787766) (xy 36.418878 -198.777703) (xy 36.39677 -198.765847)
			(xy 36.38423 -198.76516) (xy 29.663898 -198.76516) (xy 29.651344 -198.765805) (xy 29.629219 -198.777667)
			(xy 29.621734 -198.787766) (xy 29.567632 -198.868284) (xy 29.565092 -198.89343) (xy 29.569918 -198.905368)
			(xy 29.578034 -198.926078) (xy 29.589456 -198.969069) (xy 29.595221 -199.013175) (xy 29.595572 -199.035416)
			(xy 29.595092 -199.061115) (xy 29.587431 -199.111939) (xy 29.572282 -199.161053) (xy 29.549981 -199.207361)
			(xy 29.521028 -199.249828) (xy 29.486068 -199.287505) (xy 29.445884 -199.319551) (xy 29.401372 -199.34525)
			(xy 29.353527 -199.364027) (xy 29.303418 -199.375465) (xy 29.252164 -199.379306) (xy 29.20091 -199.375465)
			(xy 29.150801 -199.364027) (xy 29.102956 -199.34525) (xy 29.058444 -199.319551) (xy 29.01826 -199.287505)
			(xy 28.9833 -199.249828) (xy 28.954347 -199.207361) (xy 28.932046 -199.161053) (xy 28.916897 -199.111939)
			(xy 28.909236 -199.061115) (xy 28.908756 -199.035416) (xy 28.909124 -199.013176) (xy 28.914893 -198.969072)
			(xy 28.926298 -198.926079) (xy 28.93441 -198.905368) (xy 28.939236 -198.89343) (xy 28.936696 -198.868284)
			(xy 28.882594 -198.787766) (xy 28.875078 -198.777703) (xy 28.85297 -198.765847) (xy 28.84043 -198.76516)
			(xy 22.119844 -198.76516) (xy 22.107297 -198.765817) (xy 22.085192 -198.777692) (xy 22.07768 -198.787766)
			(xy 22.023578 -198.868284) (xy 22.021038 -198.89343) (xy 22.025864 -198.905368) (xy 22.033981 -198.926078)
			(xy 22.045405 -198.969068) (xy 22.05117 -199.013175) (xy 22.051518 -199.035416) (xy 22.051038 -199.061115)
			(xy 22.043377 -199.111939) (xy 22.028228 -199.161053) (xy 22.005927 -199.207361) (xy 21.976974 -199.249828)
			(xy 21.942014 -199.287505) (xy 21.90183 -199.319551) (xy 21.857318 -199.34525) (xy 21.809473 -199.364027)
			(xy 21.759364 -199.375465) (xy 21.70811 -199.379306) (xy 21.656856 -199.375465) (xy 21.606747 -199.364027)
			(xy 21.558902 -199.34525) (xy 21.51439 -199.319551) (xy 21.474206 -199.287505) (xy 21.439246 -199.249828)
			(xy 21.410293 -199.207361) (xy 21.387992 -199.161053) (xy 21.372843 -199.111939) (xy 21.365182 -199.061115)
			(xy 21.364702 -199.035416) (xy 21.36507 -199.013176) (xy 21.370838 -198.969071) (xy 21.382241 -198.926078)
			(xy 21.390356 -198.905368) (xy 21.395182 -198.89343) (xy 21.392642 -198.868284) (xy 21.33854 -198.787766)
			(xy 21.331028 -198.777696) (xy 21.30892 -198.76582) (xy 21.296376 -198.76516) (xy 17.071086 -198.76516)
			(xy 17.061018 -198.765587) (xy 17.042423 -198.773312) (xy 17.035018 -198.780146) (xy 16.10106 -199.714104)
			(xy 16.094208 -199.7215) (xy 16.086465 -199.740098) (xy 16.086074 -199.750172) (xy 16.086074 -199.8853)
			(xy 17.264129 -199.8853) (xy 17.268159 -199.832802) (xy 17.280156 -199.781534) (xy 17.299839 -199.732699)
			(xy 17.326745 -199.68744) (xy 17.360245 -199.646819) (xy 17.399553 -199.611788) (xy 17.443748 -199.583168)
			(xy 17.491793 -199.561629) (xy 17.542564 -199.547677) (xy 17.594869 -199.541639) (xy 17.647483 -199.543656)
			(xy 17.699173 -199.55368) (xy 17.748726 -199.571478) (xy 17.794982 -199.596631) (xy 17.836856 -199.62855)
			(xy 17.873368 -199.666488) (xy 17.90366 -199.709554) (xy 17.927023 -199.756739) (xy 17.942909 -199.806938)
			(xy 17.950946 -199.858974) (xy 17.95145 -199.8853) (xy 24.808183 -199.8853) (xy 24.812213 -199.832802)
			(xy 24.82421 -199.781534) (xy 24.843893 -199.732699) (xy 24.870799 -199.68744) (xy 24.904299 -199.646819)
			(xy 24.943607 -199.611788) (xy 24.987802 -199.583168) (xy 25.035847 -199.561629) (xy 25.086618 -199.547677)
			(xy 25.138923 -199.541639) (xy 25.191537 -199.543656) (xy 25.243227 -199.55368) (xy 25.29278 -199.571478)
			(xy 25.339036 -199.596631) (xy 25.38091 -199.62855) (xy 25.417422 -199.666488) (xy 25.447714 -199.709554)
			(xy 25.471077 -199.756739) (xy 25.486963 -199.806938) (xy 25.495 -199.858974) (xy 25.495504 -199.8853)
			(xy 32.351983 -199.8853) (xy 32.356013 -199.832802) (xy 32.36801 -199.781534) (xy 32.387693 -199.732699)
			(xy 32.414599 -199.68744) (xy 32.448099 -199.646819) (xy 32.487407 -199.611788) (xy 32.531602 -199.583168)
			(xy 32.579647 -199.561629) (xy 32.630418 -199.547677) (xy 32.682723 -199.541639) (xy 32.735337 -199.543656)
			(xy 32.787027 -199.55368) (xy 32.83658 -199.571478) (xy 32.882836 -199.596631) (xy 32.92471 -199.62855)
			(xy 32.961222 -199.666488) (xy 32.991514 -199.709554) (xy 33.014877 -199.756739) (xy 33.030763 -199.806938)
			(xy 33.0388 -199.858974) (xy 33.039304 -199.8853) (xy 39.896037 -199.8853) (xy 39.900067 -199.832802)
			(xy 39.912064 -199.781534) (xy 39.931747 -199.732699) (xy 39.958653 -199.68744) (xy 39.992153 -199.646819)
			(xy 40.031461 -199.611788) (xy 40.075656 -199.583168) (xy 40.123701 -199.561629) (xy 40.174472 -199.547677)
			(xy 40.226777 -199.541639) (xy 40.279391 -199.543656) (xy 40.331081 -199.55368) (xy 40.380634 -199.571478)
			(xy 40.42689 -199.596631) (xy 40.468764 -199.62855) (xy 40.505276 -199.666488) (xy 40.535568 -199.709554)
			(xy 40.558931 -199.756739) (xy 40.574817 -199.806938) (xy 40.582854 -199.858974) (xy 40.583358 -199.8853)
			(xy 47.440091 -199.8853) (xy 47.444121 -199.832802) (xy 47.456118 -199.781534) (xy 47.475801 -199.732699)
			(xy 47.502707 -199.68744) (xy 47.536207 -199.646819) (xy 47.575515 -199.611788) (xy 47.61971 -199.583168)
			(xy 47.667755 -199.561629) (xy 47.718526 -199.547677) (xy 47.770831 -199.541639) (xy 47.823445 -199.543656)
			(xy 47.875135 -199.55368) (xy 47.924688 -199.571478) (xy 47.970944 -199.596631) (xy 48.012818 -199.62855)
			(xy 48.04933 -199.666488) (xy 48.079622 -199.709554) (xy 48.102985 -199.756739) (xy 48.118871 -199.806938)
			(xy 48.126908 -199.858974) (xy 48.127412 -199.8853) (xy 48.126908 -199.911626) (xy 48.118871 -199.963662)
			(xy 48.102985 -200.013861) (xy 48.079622 -200.061046) (xy 48.04933 -200.104112) (xy 48.012818 -200.14205)
			(xy 47.970944 -200.173969) (xy 47.924688 -200.199122) (xy 47.875135 -200.21692) (xy 47.823445 -200.226944)
			(xy 47.770831 -200.228961) (xy 47.718526 -200.222923) (xy 47.667755 -200.208971) (xy 47.61971 -200.187432)
			(xy 47.575515 -200.158812) (xy 47.536207 -200.123781) (xy 47.502707 -200.08316) (xy 47.475801 -200.037901)
			(xy 47.456118 -199.989066) (xy 47.444121 -199.937798) (xy 47.440091 -199.8853) (xy 40.583358 -199.8853)
			(xy 40.582854 -199.911626) (xy 40.574817 -199.963662) (xy 40.558931 -200.013861) (xy 40.535568 -200.061046)
			(xy 40.505276 -200.104112) (xy 40.468764 -200.14205) (xy 40.42689 -200.173969) (xy 40.380634 -200.199122)
			(xy 40.331081 -200.21692) (xy 40.279391 -200.226944) (xy 40.226777 -200.228961) (xy 40.174472 -200.222923)
			(xy 40.123701 -200.208971) (xy 40.075656 -200.187432) (xy 40.031461 -200.158812) (xy 39.992153 -200.123781)
			(xy 39.958653 -200.08316) (xy 39.931747 -200.037901) (xy 39.912064 -199.989066) (xy 39.900067 -199.937798)
			(xy 39.896037 -199.8853) (xy 33.039304 -199.8853) (xy 33.0388 -199.911626) (xy 33.030763 -199.963662)
			(xy 33.014877 -200.013861) (xy 32.991514 -200.061046) (xy 32.961222 -200.104112) (xy 32.92471 -200.14205)
			(xy 32.882836 -200.173969) (xy 32.83658 -200.199122) (xy 32.787027 -200.21692) (xy 32.735337 -200.226944)
			(xy 32.682723 -200.228961) (xy 32.630418 -200.222923) (xy 32.579647 -200.208971) (xy 32.531602 -200.187432)
			(xy 32.487407 -200.158812) (xy 32.448099 -200.123781) (xy 32.414599 -200.08316) (xy 32.387693 -200.037901)
			(xy 32.36801 -199.989066) (xy 32.356013 -199.937798) (xy 32.351983 -199.8853) (xy 25.495504 -199.8853)
			(xy 25.495 -199.911626) (xy 25.486963 -199.963662) (xy 25.471077 -200.013861) (xy 25.447714 -200.061046)
			(xy 25.417422 -200.104112) (xy 25.38091 -200.14205) (xy 25.339036 -200.173969) (xy 25.29278 -200.199122)
			(xy 25.243227 -200.21692) (xy 25.191537 -200.226944) (xy 25.138923 -200.228961) (xy 25.086618 -200.222923)
			(xy 25.035847 -200.208971) (xy 24.987802 -200.187432) (xy 24.943607 -200.158812) (xy 24.904299 -200.123781)
			(xy 24.870799 -200.08316) (xy 24.843893 -200.037901) (xy 24.82421 -199.989066) (xy 24.812213 -199.937798)
			(xy 24.808183 -199.8853) (xy 17.95145 -199.8853) (xy 17.950946 -199.911626) (xy 17.942909 -199.963662)
			(xy 17.927023 -200.013861) (xy 17.90366 -200.061046) (xy 17.873368 -200.104112) (xy 17.836856 -200.14205)
			(xy 17.794982 -200.173969) (xy 17.748726 -200.199122) (xy 17.699173 -200.21692) (xy 17.647483 -200.226944)
			(xy 17.594869 -200.228961) (xy 17.542564 -200.222923) (xy 17.491793 -200.208971) (xy 17.443748 -200.187432)
			(xy 17.399553 -200.158812) (xy 17.360245 -200.123781) (xy 17.326745 -200.08316) (xy 17.299839 -200.037901)
			(xy 17.280156 -199.989066) (xy 17.268159 -199.937798) (xy 17.264129 -199.8853) (xy 16.086074 -199.8853)
			(xy 16.086074 -200.735438) (xy 21.364197 -200.735438) (xy 21.368227 -200.68294) (xy 21.380224 -200.631672)
			(xy 21.399907 -200.582837) (xy 21.426813 -200.537578) (xy 21.460313 -200.496957) (xy 21.499621 -200.461926)
			(xy 21.543816 -200.433306) (xy 21.591861 -200.411767) (xy 21.642632 -200.397815) (xy 21.694937 -200.391777)
			(xy 21.747551 -200.393794) (xy 21.799241 -200.403818) (xy 21.848794 -200.421616) (xy 21.89505 -200.446769)
			(xy 21.936924 -200.478688) (xy 21.973436 -200.516626) (xy 22.003728 -200.559692) (xy 22.027091 -200.606877)
			(xy 22.042977 -200.657076) (xy 22.051014 -200.709112) (xy 22.051518 -200.735438) (xy 28.908251 -200.735438)
			(xy 28.912281 -200.68294) (xy 28.924278 -200.631672) (xy 28.943961 -200.582837) (xy 28.970867 -200.537578)
			(xy 29.004367 -200.496957) (xy 29.043675 -200.461926) (xy 29.08787 -200.433306) (xy 29.135915 -200.411767)
			(xy 29.186686 -200.397815) (xy 29.238991 -200.391777) (xy 29.291605 -200.393794) (xy 29.343295 -200.403818)
			(xy 29.392848 -200.421616) (xy 29.439104 -200.446769) (xy 29.480978 -200.478688) (xy 29.51749 -200.516626)
			(xy 29.547782 -200.559692) (xy 29.571145 -200.606877) (xy 29.587031 -200.657076) (xy 29.595068 -200.709112)
			(xy 29.595572 -200.735438) (xy 36.452051 -200.735438) (xy 36.456081 -200.68294) (xy 36.468078 -200.631672)
			(xy 36.487761 -200.582837) (xy 36.514667 -200.537578) (xy 36.548167 -200.496957) (xy 36.587475 -200.461926)
			(xy 36.63167 -200.433306) (xy 36.679715 -200.411767) (xy 36.730486 -200.397815) (xy 36.782791 -200.391777)
			(xy 36.835405 -200.393794) (xy 36.887095 -200.403818) (xy 36.936648 -200.421616) (xy 36.982904 -200.446769)
			(xy 37.024778 -200.478688) (xy 37.06129 -200.516626) (xy 37.091582 -200.559692) (xy 37.114945 -200.606877)
			(xy 37.130831 -200.657076) (xy 37.138868 -200.709112) (xy 37.139372 -200.735438) (xy 43.996105 -200.735438)
			(xy 44.000135 -200.68294) (xy 44.012132 -200.631672) (xy 44.031815 -200.582837) (xy 44.058721 -200.537578)
			(xy 44.092221 -200.496957) (xy 44.131529 -200.461926) (xy 44.175724 -200.433306) (xy 44.223769 -200.411767)
			(xy 44.27454 -200.397815) (xy 44.326845 -200.391777) (xy 44.379459 -200.393794) (xy 44.431149 -200.403818)
			(xy 44.480702 -200.421616) (xy 44.526958 -200.446769) (xy 44.568832 -200.478688) (xy 44.605344 -200.516626)
			(xy 44.635636 -200.559692) (xy 44.658999 -200.606877) (xy 44.674885 -200.657076) (xy 44.682922 -200.709112)
			(xy 44.683426 -200.735438) (xy 51.540159 -200.735438) (xy 51.544189 -200.68294) (xy 51.556186 -200.631672)
			(xy 51.575869 -200.582837) (xy 51.602775 -200.537578) (xy 51.636275 -200.496957) (xy 51.675583 -200.461926)
			(xy 51.719778 -200.433306) (xy 51.767823 -200.411767) (xy 51.818594 -200.397815) (xy 51.870899 -200.391777)
			(xy 51.923513 -200.393794) (xy 51.975203 -200.403818) (xy 52.024756 -200.421616) (xy 52.071012 -200.446769)
			(xy 52.112886 -200.478688) (xy 52.149398 -200.516626) (xy 52.17969 -200.559692) (xy 52.203053 -200.606877)
			(xy 52.218939 -200.657076) (xy 52.226976 -200.709112) (xy 52.22748 -200.735438) (xy 52.226976 -200.761764)
			(xy 52.218939 -200.8138) (xy 52.203053 -200.863999) (xy 52.17969 -200.911184) (xy 52.149398 -200.95425)
			(xy 52.112886 -200.992188) (xy 52.071012 -201.024107) (xy 52.024756 -201.04926) (xy 51.975203 -201.067058)
			(xy 51.923513 -201.077082) (xy 51.870899 -201.079099) (xy 51.818594 -201.073061) (xy 51.767823 -201.059109)
			(xy 51.719778 -201.03757) (xy 51.675583 -201.00895) (xy 51.636275 -200.973919) (xy 51.602775 -200.933298)
			(xy 51.575869 -200.888039) (xy 51.556186 -200.839204) (xy 51.544189 -200.787936) (xy 51.540159 -200.735438)
			(xy 44.683426 -200.735438) (xy 44.682922 -200.761764) (xy 44.674885 -200.8138) (xy 44.658999 -200.863999)
			(xy 44.635636 -200.911184) (xy 44.605344 -200.95425) (xy 44.568832 -200.992188) (xy 44.526958 -201.024107)
			(xy 44.480702 -201.04926) (xy 44.431149 -201.067058) (xy 44.379459 -201.077082) (xy 44.326845 -201.079099)
			(xy 44.27454 -201.073061) (xy 44.223769 -201.059109) (xy 44.175724 -201.03757) (xy 44.131529 -201.00895)
			(xy 44.092221 -200.973919) (xy 44.058721 -200.933298) (xy 44.031815 -200.888039) (xy 44.012132 -200.839204)
			(xy 44.000135 -200.787936) (xy 43.996105 -200.735438) (xy 37.139372 -200.735438) (xy 37.138868 -200.761764)
			(xy 37.130831 -200.8138) (xy 37.114945 -200.863999) (xy 37.091582 -200.911184) (xy 37.06129 -200.95425)
			(xy 37.024778 -200.992188) (xy 36.982904 -201.024107) (xy 36.936648 -201.04926) (xy 36.887095 -201.067058)
			(xy 36.835405 -201.077082) (xy 36.782791 -201.079099) (xy 36.730486 -201.073061) (xy 36.679715 -201.059109)
			(xy 36.63167 -201.03757) (xy 36.587475 -201.00895) (xy 36.548167 -200.973919) (xy 36.514667 -200.933298)
			(xy 36.487761 -200.888039) (xy 36.468078 -200.839204) (xy 36.456081 -200.787936) (xy 36.452051 -200.735438)
			(xy 29.595572 -200.735438) (xy 29.595068 -200.761764) (xy 29.587031 -200.8138) (xy 29.571145 -200.863999)
			(xy 29.547782 -200.911184) (xy 29.51749 -200.95425) (xy 29.480978 -200.992188) (xy 29.439104 -201.024107)
			(xy 29.392848 -201.04926) (xy 29.343295 -201.067058) (xy 29.291605 -201.077082) (xy 29.238991 -201.079099)
			(xy 29.186686 -201.073061) (xy 29.135915 -201.059109) (xy 29.08787 -201.03757) (xy 29.043675 -201.00895)
			(xy 29.004367 -200.973919) (xy 28.970867 -200.933298) (xy 28.943961 -200.888039) (xy 28.924278 -200.839204)
			(xy 28.912281 -200.787936) (xy 28.908251 -200.735438) (xy 22.051518 -200.735438) (xy 22.051014 -200.761764)
			(xy 22.042977 -200.8138) (xy 22.027091 -200.863999) (xy 22.003728 -200.911184) (xy 21.973436 -200.95425)
			(xy 21.936924 -200.992188) (xy 21.89505 -201.024107) (xy 21.848794 -201.04926) (xy 21.799241 -201.067058)
			(xy 21.747551 -201.077082) (xy 21.694937 -201.079099) (xy 21.642632 -201.073061) (xy 21.591861 -201.059109)
			(xy 21.543816 -201.03757) (xy 21.499621 -201.00895) (xy 21.460313 -200.973919) (xy 21.426813 -200.933298)
			(xy 21.399907 -200.888039) (xy 21.380224 -200.839204) (xy 21.368227 -200.787936) (xy 21.364197 -200.735438)
			(xy 16.086074 -200.735438) (xy 16.086074 -201.585322) (xy 17.264129 -201.585322) (xy 17.268159 -201.532824)
			(xy 17.280156 -201.481556) (xy 17.299839 -201.432721) (xy 17.326745 -201.387462) (xy 17.360245 -201.346841)
			(xy 17.399553 -201.31181) (xy 17.443748 -201.28319) (xy 17.491793 -201.261651) (xy 17.542564 -201.247699)
			(xy 17.594869 -201.241661) (xy 17.647483 -201.243678) (xy 17.699173 -201.253702) (xy 17.748726 -201.2715)
			(xy 17.794982 -201.296653) (xy 17.836856 -201.328572) (xy 17.873368 -201.36651) (xy 17.90366 -201.409576)
			(xy 17.927023 -201.456761) (xy 17.942909 -201.50696) (xy 17.950946 -201.558996) (xy 17.95145 -201.585322)
			(xy 21.364197 -201.585322) (xy 21.368227 -201.532824) (xy 21.380224 -201.481556) (xy 21.399907 -201.432721)
			(xy 21.426813 -201.387462) (xy 21.460313 -201.346841) (xy 21.499621 -201.31181) (xy 21.543816 -201.28319)
			(xy 21.591861 -201.261651) (xy 21.642632 -201.247699) (xy 21.694937 -201.241661) (xy 21.747551 -201.243678)
			(xy 21.799241 -201.253702) (xy 21.848794 -201.2715) (xy 21.89505 -201.296653) (xy 21.936924 -201.328572)
			(xy 21.973436 -201.36651) (xy 22.003728 -201.409576) (xy 22.027091 -201.456761) (xy 22.042977 -201.50696)
			(xy 22.051014 -201.558996) (xy 22.051518 -201.585322) (xy 24.808183 -201.585322) (xy 24.812213 -201.532824)
			(xy 24.82421 -201.481556) (xy 24.843893 -201.432721) (xy 24.870799 -201.387462) (xy 24.904299 -201.346841)
			(xy 24.943607 -201.31181) (xy 24.987802 -201.28319) (xy 25.035847 -201.261651) (xy 25.086618 -201.247699)
			(xy 25.138923 -201.241661) (xy 25.191537 -201.243678) (xy 25.243227 -201.253702) (xy 25.29278 -201.2715)
			(xy 25.339036 -201.296653) (xy 25.38091 -201.328572) (xy 25.417422 -201.36651) (xy 25.447714 -201.409576)
			(xy 25.471077 -201.456761) (xy 25.486963 -201.50696) (xy 25.495 -201.558996) (xy 25.495504 -201.585322)
			(xy 28.908251 -201.585322) (xy 28.912281 -201.532824) (xy 28.924278 -201.481556) (xy 28.943961 -201.432721)
			(xy 28.970867 -201.387462) (xy 29.004367 -201.346841) (xy 29.043675 -201.31181) (xy 29.08787 -201.28319)
			(xy 29.135915 -201.261651) (xy 29.186686 -201.247699) (xy 29.238991 -201.241661) (xy 29.291605 -201.243678)
			(xy 29.343295 -201.253702) (xy 29.392848 -201.2715) (xy 29.439104 -201.296653) (xy 29.480978 -201.328572)
			(xy 29.51749 -201.36651) (xy 29.547782 -201.409576) (xy 29.571145 -201.456761) (xy 29.587031 -201.50696)
			(xy 29.595068 -201.558996) (xy 29.595572 -201.585322) (xy 32.351983 -201.585322) (xy 32.356013 -201.532824)
			(xy 32.36801 -201.481556) (xy 32.387693 -201.432721) (xy 32.414599 -201.387462) (xy 32.448099 -201.346841)
			(xy 32.487407 -201.31181) (xy 32.531602 -201.28319) (xy 32.579647 -201.261651) (xy 32.630418 -201.247699)
			(xy 32.682723 -201.241661) (xy 32.735337 -201.243678) (xy 32.787027 -201.253702) (xy 32.83658 -201.2715)
			(xy 32.882836 -201.296653) (xy 32.92471 -201.328572) (xy 32.961222 -201.36651) (xy 32.991514 -201.409576)
			(xy 33.014877 -201.456761) (xy 33.030763 -201.50696) (xy 33.0388 -201.558996) (xy 33.039304 -201.585322)
			(xy 36.452051 -201.585322) (xy 36.456081 -201.532824) (xy 36.468078 -201.481556) (xy 36.487761 -201.432721)
			(xy 36.514667 -201.387462) (xy 36.548167 -201.346841) (xy 36.587475 -201.31181) (xy 36.63167 -201.28319)
			(xy 36.679715 -201.261651) (xy 36.730486 -201.247699) (xy 36.782791 -201.241661) (xy 36.835405 -201.243678)
			(xy 36.887095 -201.253702) (xy 36.936648 -201.2715) (xy 36.982904 -201.296653) (xy 37.024778 -201.328572)
			(xy 37.06129 -201.36651) (xy 37.091582 -201.409576) (xy 37.114945 -201.456761) (xy 37.130831 -201.50696)
			(xy 37.138868 -201.558996) (xy 37.139372 -201.585322) (xy 39.896037 -201.585322) (xy 39.900067 -201.532824)
			(xy 39.912064 -201.481556) (xy 39.931747 -201.432721) (xy 39.958653 -201.387462) (xy 39.992153 -201.346841)
			(xy 40.031461 -201.31181) (xy 40.075656 -201.28319) (xy 40.123701 -201.261651) (xy 40.174472 -201.247699)
			(xy 40.226777 -201.241661) (xy 40.279391 -201.243678) (xy 40.331081 -201.253702) (xy 40.380634 -201.2715)
			(xy 40.42689 -201.296653) (xy 40.468764 -201.328572) (xy 40.505276 -201.36651) (xy 40.535568 -201.409576)
			(xy 40.558931 -201.456761) (xy 40.574817 -201.50696) (xy 40.582854 -201.558996) (xy 40.583358 -201.585322)
			(xy 43.996105 -201.585322) (xy 44.000135 -201.532824) (xy 44.012132 -201.481556) (xy 44.031815 -201.432721)
			(xy 44.058721 -201.387462) (xy 44.092221 -201.346841) (xy 44.131529 -201.31181) (xy 44.175724 -201.28319)
			(xy 44.223769 -201.261651) (xy 44.27454 -201.247699) (xy 44.326845 -201.241661) (xy 44.379459 -201.243678)
			(xy 44.431149 -201.253702) (xy 44.480702 -201.2715) (xy 44.526958 -201.296653) (xy 44.568832 -201.328572)
			(xy 44.605344 -201.36651) (xy 44.635636 -201.409576) (xy 44.658999 -201.456761) (xy 44.674885 -201.50696)
			(xy 44.682922 -201.558996) (xy 44.683426 -201.585322) (xy 47.440091 -201.585322) (xy 47.444121 -201.532824)
			(xy 47.456118 -201.481556) (xy 47.475801 -201.432721) (xy 47.502707 -201.387462) (xy 47.536207 -201.346841)
			(xy 47.575515 -201.31181) (xy 47.61971 -201.28319) (xy 47.667755 -201.261651) (xy 47.718526 -201.247699)
			(xy 47.770831 -201.241661) (xy 47.823445 -201.243678) (xy 47.875135 -201.253702) (xy 47.924688 -201.2715)
			(xy 47.970944 -201.296653) (xy 48.012818 -201.328572) (xy 48.04933 -201.36651) (xy 48.079622 -201.409576)
			(xy 48.102985 -201.456761) (xy 48.118871 -201.50696) (xy 48.126908 -201.558996) (xy 48.127412 -201.585322)
			(xy 51.540159 -201.585322) (xy 51.544189 -201.532824) (xy 51.556186 -201.481556) (xy 51.575869 -201.432721)
			(xy 51.602775 -201.387462) (xy 51.636275 -201.346841) (xy 51.675583 -201.31181) (xy 51.719778 -201.28319)
			(xy 51.767823 -201.261651) (xy 51.818594 -201.247699) (xy 51.870899 -201.241661) (xy 51.923513 -201.243678)
			(xy 51.975203 -201.253702) (xy 52.024756 -201.2715) (xy 52.071012 -201.296653) (xy 52.112886 -201.328572)
			(xy 52.149398 -201.36651) (xy 52.17969 -201.409576) (xy 52.203053 -201.456761) (xy 52.218939 -201.50696)
			(xy 52.226976 -201.558996) (xy 52.22748 -201.585322) (xy 52.226976 -201.611648) (xy 52.218939 -201.663684)
			(xy 52.203053 -201.713883) (xy 52.17969 -201.761068) (xy 52.149398 -201.804134) (xy 52.112886 -201.842072)
			(xy 52.071012 -201.873991) (xy 52.024756 -201.899144) (xy 51.975203 -201.916942) (xy 51.923513 -201.926966)
			(xy 51.870899 -201.928983) (xy 51.818594 -201.922945) (xy 51.767823 -201.908993) (xy 51.719778 -201.887454)
			(xy 51.675583 -201.858834) (xy 51.636275 -201.823803) (xy 51.602775 -201.783182) (xy 51.575869 -201.737923)
			(xy 51.556186 -201.689088) (xy 51.544189 -201.63782) (xy 51.540159 -201.585322) (xy 48.127412 -201.585322)
			(xy 48.126908 -201.611648) (xy 48.118871 -201.663684) (xy 48.102985 -201.713883) (xy 48.079622 -201.761068)
			(xy 48.04933 -201.804134) (xy 48.012818 -201.842072) (xy 47.970944 -201.873991) (xy 47.924688 -201.899144)
			(xy 47.875135 -201.916942) (xy 47.823445 -201.926966) (xy 47.770831 -201.928983) (xy 47.718526 -201.922945)
			(xy 47.667755 -201.908993) (xy 47.61971 -201.887454) (xy 47.575515 -201.858834) (xy 47.536207 -201.823803)
			(xy 47.502707 -201.783182) (xy 47.475801 -201.737923) (xy 47.456118 -201.689088) (xy 47.444121 -201.63782)
			(xy 47.440091 -201.585322) (xy 44.683426 -201.585322) (xy 44.682922 -201.611648) (xy 44.674885 -201.663684)
			(xy 44.658999 -201.713883) (xy 44.635636 -201.761068) (xy 44.605344 -201.804134) (xy 44.568832 -201.842072)
			(xy 44.526958 -201.873991) (xy 44.480702 -201.899144) (xy 44.431149 -201.916942) (xy 44.379459 -201.926966)
			(xy 44.326845 -201.928983) (xy 44.27454 -201.922945) (xy 44.223769 -201.908993) (xy 44.175724 -201.887454)
			(xy 44.131529 -201.858834) (xy 44.092221 -201.823803) (xy 44.058721 -201.783182) (xy 44.031815 -201.737923)
			(xy 44.012132 -201.689088) (xy 44.000135 -201.63782) (xy 43.996105 -201.585322) (xy 40.583358 -201.585322)
			(xy 40.582854 -201.611648) (xy 40.574817 -201.663684) (xy 40.558931 -201.713883) (xy 40.535568 -201.761068)
			(xy 40.505276 -201.804134) (xy 40.468764 -201.842072) (xy 40.42689 -201.873991) (xy 40.380634 -201.899144)
			(xy 40.331081 -201.916942) (xy 40.279391 -201.926966) (xy 40.226777 -201.928983) (xy 40.174472 -201.922945)
			(xy 40.123701 -201.908993) (xy 40.075656 -201.887454) (xy 40.031461 -201.858834) (xy 39.992153 -201.823803)
			(xy 39.958653 -201.783182) (xy 39.931747 -201.737923) (xy 39.912064 -201.689088) (xy 39.900067 -201.63782)
			(xy 39.896037 -201.585322) (xy 37.139372 -201.585322) (xy 37.138868 -201.611648) (xy 37.130831 -201.663684)
			(xy 37.114945 -201.713883) (xy 37.091582 -201.761068) (xy 37.06129 -201.804134) (xy 37.024778 -201.842072)
			(xy 36.982904 -201.873991) (xy 36.936648 -201.899144) (xy 36.887095 -201.916942) (xy 36.835405 -201.926966)
			(xy 36.782791 -201.928983) (xy 36.730486 -201.922945) (xy 36.679715 -201.908993) (xy 36.63167 -201.887454)
			(xy 36.587475 -201.858834) (xy 36.548167 -201.823803) (xy 36.514667 -201.783182) (xy 36.487761 -201.737923)
			(xy 36.468078 -201.689088) (xy 36.456081 -201.63782) (xy 36.452051 -201.585322) (xy 33.039304 -201.585322)
			(xy 33.0388 -201.611648) (xy 33.030763 -201.663684) (xy 33.014877 -201.713883) (xy 32.991514 -201.761068)
			(xy 32.961222 -201.804134) (xy 32.92471 -201.842072) (xy 32.882836 -201.873991) (xy 32.83658 -201.899144)
			(xy 32.787027 -201.916942) (xy 32.735337 -201.926966) (xy 32.682723 -201.928983) (xy 32.630418 -201.922945)
			(xy 32.579647 -201.908993) (xy 32.531602 -201.887454) (xy 32.487407 -201.858834) (xy 32.448099 -201.823803)
			(xy 32.414599 -201.783182) (xy 32.387693 -201.737923) (xy 32.36801 -201.689088) (xy 32.356013 -201.63782)
			(xy 32.351983 -201.585322) (xy 29.595572 -201.585322) (xy 29.595068 -201.611648) (xy 29.587031 -201.663684)
			(xy 29.571145 -201.713883) (xy 29.547782 -201.761068) (xy 29.51749 -201.804134) (xy 29.480978 -201.842072)
			(xy 29.439104 -201.873991) (xy 29.392848 -201.899144) (xy 29.343295 -201.916942) (xy 29.291605 -201.926966)
			(xy 29.238991 -201.928983) (xy 29.186686 -201.922945) (xy 29.135915 -201.908993) (xy 29.08787 -201.887454)
			(xy 29.043675 -201.858834) (xy 29.004367 -201.823803) (xy 28.970867 -201.783182) (xy 28.943961 -201.737923)
			(xy 28.924278 -201.689088) (xy 28.912281 -201.63782) (xy 28.908251 -201.585322) (xy 25.495504 -201.585322)
			(xy 25.495 -201.611648) (xy 25.486963 -201.663684) (xy 25.471077 -201.713883) (xy 25.447714 -201.761068)
			(xy 25.417422 -201.804134) (xy 25.38091 -201.842072) (xy 25.339036 -201.873991) (xy 25.29278 -201.899144)
			(xy 25.243227 -201.916942) (xy 25.191537 -201.926966) (xy 25.138923 -201.928983) (xy 25.086618 -201.922945)
			(xy 25.035847 -201.908993) (xy 24.987802 -201.887454) (xy 24.943607 -201.858834) (xy 24.904299 -201.823803)
			(xy 24.870799 -201.783182) (xy 24.843893 -201.737923) (xy 24.82421 -201.689088) (xy 24.812213 -201.63782)
			(xy 24.808183 -201.585322) (xy 22.051518 -201.585322) (xy 22.051014 -201.611648) (xy 22.042977 -201.663684)
			(xy 22.027091 -201.713883) (xy 22.003728 -201.761068) (xy 21.973436 -201.804134) (xy 21.936924 -201.842072)
			(xy 21.89505 -201.873991) (xy 21.848794 -201.899144) (xy 21.799241 -201.916942) (xy 21.747551 -201.926966)
			(xy 21.694937 -201.928983) (xy 21.642632 -201.922945) (xy 21.591861 -201.908993) (xy 21.543816 -201.887454)
			(xy 21.499621 -201.858834) (xy 21.460313 -201.823803) (xy 21.426813 -201.783182) (xy 21.399907 -201.737923)
			(xy 21.380224 -201.689088) (xy 21.368227 -201.63782) (xy 21.364197 -201.585322) (xy 17.95145 -201.585322)
			(xy 17.950946 -201.611648) (xy 17.942909 -201.663684) (xy 17.927023 -201.713883) (xy 17.90366 -201.761068)
			(xy 17.873368 -201.804134) (xy 17.836856 -201.842072) (xy 17.794982 -201.873991) (xy 17.748726 -201.899144)
			(xy 17.699173 -201.916942) (xy 17.647483 -201.926966) (xy 17.594869 -201.928983) (xy 17.542564 -201.922945)
			(xy 17.491793 -201.908993) (xy 17.443748 -201.887454) (xy 17.399553 -201.858834) (xy 17.360245 -201.823803)
			(xy 17.326745 -201.783182) (xy 17.299839 -201.737923) (xy 17.280156 -201.689088) (xy 17.268159 -201.63782)
			(xy 17.264129 -201.585322) (xy 16.086074 -201.585322) (xy 16.086074 -202.435206) (xy 17.264129 -202.435206)
			(xy 17.268159 -202.382708) (xy 17.280156 -202.33144) (xy 17.299839 -202.282605) (xy 17.326745 -202.237346)
			(xy 17.360245 -202.196725) (xy 17.399553 -202.161694) (xy 17.443748 -202.133074) (xy 17.491793 -202.111535)
			(xy 17.542564 -202.097583) (xy 17.594869 -202.091545) (xy 17.647483 -202.093562) (xy 17.699173 -202.103586)
			(xy 17.748726 -202.121384) (xy 17.794982 -202.146537) (xy 17.836856 -202.178456) (xy 17.873368 -202.216394)
			(xy 17.90366 -202.25946) (xy 17.927023 -202.306645) (xy 17.942909 -202.356844) (xy 17.950946 -202.40888)
			(xy 17.95145 -202.435206) (xy 24.808183 -202.435206) (xy 24.812213 -202.382708) (xy 24.82421 -202.33144)
			(xy 24.843893 -202.282605) (xy 24.870799 -202.237346) (xy 24.904299 -202.196725) (xy 24.943607 -202.161694)
			(xy 24.987802 -202.133074) (xy 25.035847 -202.111535) (xy 25.086618 -202.097583) (xy 25.138923 -202.091545)
			(xy 25.191537 -202.093562) (xy 25.243227 -202.103586) (xy 25.29278 -202.121384) (xy 25.339036 -202.146537)
			(xy 25.38091 -202.178456) (xy 25.417422 -202.216394) (xy 25.447714 -202.25946) (xy 25.471077 -202.306645)
			(xy 25.486963 -202.356844) (xy 25.495 -202.40888) (xy 25.495504 -202.435206) (xy 32.351983 -202.435206)
			(xy 32.356013 -202.382708) (xy 32.36801 -202.33144) (xy 32.387693 -202.282605) (xy 32.414599 -202.237346)
			(xy 32.448099 -202.196725) (xy 32.487407 -202.161694) (xy 32.531602 -202.133074) (xy 32.579647 -202.111535)
			(xy 32.630418 -202.097583) (xy 32.682723 -202.091545) (xy 32.735337 -202.093562) (xy 32.787027 -202.103586)
			(xy 32.83658 -202.121384) (xy 32.882836 -202.146537) (xy 32.92471 -202.178456) (xy 32.961222 -202.216394)
			(xy 32.991514 -202.25946) (xy 33.014877 -202.306645) (xy 33.030763 -202.356844) (xy 33.0388 -202.40888)
			(xy 33.039304 -202.435206) (xy 39.896037 -202.435206) (xy 39.900067 -202.382708) (xy 39.912064 -202.33144)
			(xy 39.931747 -202.282605) (xy 39.958653 -202.237346) (xy 39.992153 -202.196725) (xy 40.031461 -202.161694)
			(xy 40.075656 -202.133074) (xy 40.123701 -202.111535) (xy 40.174472 -202.097583) (xy 40.226777 -202.091545)
			(xy 40.279391 -202.093562) (xy 40.331081 -202.103586) (xy 40.380634 -202.121384) (xy 40.42689 -202.146537)
			(xy 40.468764 -202.178456) (xy 40.505276 -202.216394) (xy 40.535568 -202.25946) (xy 40.558931 -202.306645)
			(xy 40.574817 -202.356844) (xy 40.582854 -202.40888) (xy 40.583358 -202.435206) (xy 47.440091 -202.435206)
			(xy 47.444121 -202.382708) (xy 47.456118 -202.33144) (xy 47.475801 -202.282605) (xy 47.502707 -202.237346)
			(xy 47.536207 -202.196725) (xy 47.575515 -202.161694) (xy 47.61971 -202.133074) (xy 47.667755 -202.111535)
			(xy 47.718526 -202.097583) (xy 47.770831 -202.091545) (xy 47.823445 -202.093562) (xy 47.875135 -202.103586)
			(xy 47.924688 -202.121384) (xy 47.970944 -202.146537) (xy 48.012818 -202.178456) (xy 48.04933 -202.216394)
			(xy 48.079622 -202.25946) (xy 48.102985 -202.306645) (xy 48.118871 -202.356844) (xy 48.126908 -202.40888)
			(xy 48.127412 -202.435206) (xy 48.126908 -202.461532) (xy 48.118871 -202.513568) (xy 48.102985 -202.563767)
			(xy 48.079622 -202.610952) (xy 48.04933 -202.654018) (xy 48.012818 -202.691956) (xy 47.970944 -202.723875)
			(xy 47.924688 -202.749028) (xy 47.875135 -202.766826) (xy 47.823445 -202.77685) (xy 47.770831 -202.778867)
			(xy 47.718526 -202.772829) (xy 47.667755 -202.758877) (xy 47.61971 -202.737338) (xy 47.575515 -202.708718)
			(xy 47.536207 -202.673687) (xy 47.502707 -202.633066) (xy 47.475801 -202.587807) (xy 47.456118 -202.538972)
			(xy 47.444121 -202.487704) (xy 47.440091 -202.435206) (xy 40.583358 -202.435206) (xy 40.582854 -202.461532)
			(xy 40.574817 -202.513568) (xy 40.558931 -202.563767) (xy 40.535568 -202.610952) (xy 40.505276 -202.654018)
			(xy 40.468764 -202.691956) (xy 40.42689 -202.723875) (xy 40.380634 -202.749028) (xy 40.331081 -202.766826)
			(xy 40.279391 -202.77685) (xy 40.226777 -202.778867) (xy 40.174472 -202.772829) (xy 40.123701 -202.758877)
			(xy 40.075656 -202.737338) (xy 40.031461 -202.708718) (xy 39.992153 -202.673687) (xy 39.958653 -202.633066)
			(xy 39.931747 -202.587807) (xy 39.912064 -202.538972) (xy 39.900067 -202.487704) (xy 39.896037 -202.435206)
			(xy 33.039304 -202.435206) (xy 33.0388 -202.461532) (xy 33.030763 -202.513568) (xy 33.014877 -202.563767)
			(xy 32.991514 -202.610952) (xy 32.961222 -202.654018) (xy 32.92471 -202.691956) (xy 32.882836 -202.723875)
			(xy 32.83658 -202.749028) (xy 32.787027 -202.766826) (xy 32.735337 -202.77685) (xy 32.682723 -202.778867)
			(xy 32.630418 -202.772829) (xy 32.579647 -202.758877) (xy 32.531602 -202.737338) (xy 32.487407 -202.708718)
			(xy 32.448099 -202.673687) (xy 32.414599 -202.633066) (xy 32.387693 -202.587807) (xy 32.36801 -202.538972)
			(xy 32.356013 -202.487704) (xy 32.351983 -202.435206) (xy 25.495504 -202.435206) (xy 25.495 -202.461532)
			(xy 25.486963 -202.513568) (xy 25.471077 -202.563767) (xy 25.447714 -202.610952) (xy 25.417422 -202.654018)
			(xy 25.38091 -202.691956) (xy 25.339036 -202.723875) (xy 25.29278 -202.749028) (xy 25.243227 -202.766826)
			(xy 25.191537 -202.77685) (xy 25.138923 -202.778867) (xy 25.086618 -202.772829) (xy 25.035847 -202.758877)
			(xy 24.987802 -202.737338) (xy 24.943607 -202.708718) (xy 24.904299 -202.673687) (xy 24.870799 -202.633066)
			(xy 24.843893 -202.587807) (xy 24.82421 -202.538972) (xy 24.812213 -202.487704) (xy 24.808183 -202.435206)
			(xy 17.95145 -202.435206) (xy 17.950946 -202.461532) (xy 17.942909 -202.513568) (xy 17.927023 -202.563767)
			(xy 17.90366 -202.610952) (xy 17.873368 -202.654018) (xy 17.836856 -202.691956) (xy 17.794982 -202.723875)
			(xy 17.748726 -202.749028) (xy 17.699173 -202.766826) (xy 17.647483 -202.77685) (xy 17.594869 -202.778867)
			(xy 17.542564 -202.772829) (xy 17.491793 -202.758877) (xy 17.443748 -202.737338) (xy 17.399553 -202.708718)
			(xy 17.360245 -202.673687) (xy 17.326745 -202.633066) (xy 17.299839 -202.587807) (xy 17.280156 -202.538972)
			(xy 17.268159 -202.487704) (xy 17.264129 -202.435206) (xy 16.086074 -202.435206) (xy 16.086074 -203.285344)
			(xy 21.364197 -203.285344) (xy 21.368227 -203.232846) (xy 21.380224 -203.181578) (xy 21.399907 -203.132743)
			(xy 21.426813 -203.087484) (xy 21.460313 -203.046863) (xy 21.499621 -203.011832) (xy 21.543816 -202.983212)
			(xy 21.591861 -202.961673) (xy 21.642632 -202.947721) (xy 21.694937 -202.941683) (xy 21.747551 -202.9437)
			(xy 21.799241 -202.953724) (xy 21.848794 -202.971522) (xy 21.89505 -202.996675) (xy 21.936924 -203.028594)
			(xy 21.973436 -203.066532) (xy 22.003728 -203.109598) (xy 22.027091 -203.156783) (xy 22.042977 -203.206982)
			(xy 22.051014 -203.259018) (xy 22.051518 -203.285344) (xy 28.908251 -203.285344) (xy 28.912281 -203.232846)
			(xy 28.924278 -203.181578) (xy 28.943961 -203.132743) (xy 28.970867 -203.087484) (xy 29.004367 -203.046863)
			(xy 29.043675 -203.011832) (xy 29.08787 -202.983212) (xy 29.135915 -202.961673) (xy 29.186686 -202.947721)
			(xy 29.238991 -202.941683) (xy 29.291605 -202.9437) (xy 29.343295 -202.953724) (xy 29.392848 -202.971522)
			(xy 29.439104 -202.996675) (xy 29.480978 -203.028594) (xy 29.51749 -203.066532) (xy 29.547782 -203.109598)
			(xy 29.571145 -203.156783) (xy 29.587031 -203.206982) (xy 29.595068 -203.259018) (xy 29.595572 -203.285344)
			(xy 36.452051 -203.285344) (xy 36.456081 -203.232846) (xy 36.468078 -203.181578) (xy 36.487761 -203.132743)
			(xy 36.514667 -203.087484) (xy 36.548167 -203.046863) (xy 36.587475 -203.011832) (xy 36.63167 -202.983212)
			(xy 36.679715 -202.961673) (xy 36.730486 -202.947721) (xy 36.782791 -202.941683) (xy 36.835405 -202.9437)
			(xy 36.887095 -202.953724) (xy 36.936648 -202.971522) (xy 36.982904 -202.996675) (xy 37.024778 -203.028594)
			(xy 37.06129 -203.066532) (xy 37.091582 -203.109598) (xy 37.114945 -203.156783) (xy 37.130831 -203.206982)
			(xy 37.138868 -203.259018) (xy 37.139372 -203.285344) (xy 43.996105 -203.285344) (xy 44.000135 -203.232846)
			(xy 44.012132 -203.181578) (xy 44.031815 -203.132743) (xy 44.058721 -203.087484) (xy 44.092221 -203.046863)
			(xy 44.131529 -203.011832) (xy 44.175724 -202.983212) (xy 44.223769 -202.961673) (xy 44.27454 -202.947721)
			(xy 44.326845 -202.941683) (xy 44.379459 -202.9437) (xy 44.431149 -202.953724) (xy 44.480702 -202.971522)
			(xy 44.526958 -202.996675) (xy 44.568832 -203.028594) (xy 44.605344 -203.066532) (xy 44.635636 -203.109598)
			(xy 44.658999 -203.156783) (xy 44.674885 -203.206982) (xy 44.682922 -203.259018) (xy 44.683426 -203.285344)
			(xy 51.540159 -203.285344) (xy 51.544189 -203.232846) (xy 51.556186 -203.181578) (xy 51.575869 -203.132743)
			(xy 51.602775 -203.087484) (xy 51.636275 -203.046863) (xy 51.675583 -203.011832) (xy 51.719778 -202.983212)
			(xy 51.767823 -202.961673) (xy 51.818594 -202.947721) (xy 51.870899 -202.941683) (xy 51.923513 -202.9437)
			(xy 51.975203 -202.953724) (xy 52.024756 -202.971522) (xy 52.071012 -202.996675) (xy 52.112886 -203.028594)
			(xy 52.149398 -203.066532) (xy 52.17969 -203.109598) (xy 52.203053 -203.156783) (xy 52.218939 -203.206982)
			(xy 52.226976 -203.259018) (xy 52.22748 -203.285344) (xy 52.226976 -203.31167) (xy 52.218939 -203.363706)
			(xy 52.203053 -203.413905) (xy 52.17969 -203.46109) (xy 52.149398 -203.504156) (xy 52.112886 -203.542094)
			(xy 52.071012 -203.574013) (xy 52.024756 -203.599166) (xy 51.975203 -203.616964) (xy 51.923513 -203.626988)
			(xy 51.870899 -203.629005) (xy 51.818594 -203.622967) (xy 51.767823 -203.609015) (xy 51.719778 -203.587476)
			(xy 51.675583 -203.558856) (xy 51.636275 -203.523825) (xy 51.602775 -203.483204) (xy 51.575869 -203.437945)
			(xy 51.556186 -203.38911) (xy 51.544189 -203.337842) (xy 51.540159 -203.285344) (xy 44.683426 -203.285344)
			(xy 44.682922 -203.31167) (xy 44.674885 -203.363706) (xy 44.658999 -203.413905) (xy 44.635636 -203.46109)
			(xy 44.605344 -203.504156) (xy 44.568832 -203.542094) (xy 44.526958 -203.574013) (xy 44.480702 -203.599166)
			(xy 44.431149 -203.616964) (xy 44.379459 -203.626988) (xy 44.326845 -203.629005) (xy 44.27454 -203.622967)
			(xy 44.223769 -203.609015) (xy 44.175724 -203.587476) (xy 44.131529 -203.558856) (xy 44.092221 -203.523825)
			(xy 44.058721 -203.483204) (xy 44.031815 -203.437945) (xy 44.012132 -203.38911) (xy 44.000135 -203.337842)
			(xy 43.996105 -203.285344) (xy 37.139372 -203.285344) (xy 37.138868 -203.31167) (xy 37.130831 -203.363706)
			(xy 37.114945 -203.413905) (xy 37.091582 -203.46109) (xy 37.06129 -203.504156) (xy 37.024778 -203.542094)
			(xy 36.982904 -203.574013) (xy 36.936648 -203.599166) (xy 36.887095 -203.616964) (xy 36.835405 -203.626988)
			(xy 36.782791 -203.629005) (xy 36.730486 -203.622967) (xy 36.679715 -203.609015) (xy 36.63167 -203.587476)
			(xy 36.587475 -203.558856) (xy 36.548167 -203.523825) (xy 36.514667 -203.483204) (xy 36.487761 -203.437945)
			(xy 36.468078 -203.38911) (xy 36.456081 -203.337842) (xy 36.452051 -203.285344) (xy 29.595572 -203.285344)
			(xy 29.595068 -203.31167) (xy 29.587031 -203.363706) (xy 29.571145 -203.413905) (xy 29.547782 -203.46109)
			(xy 29.51749 -203.504156) (xy 29.480978 -203.542094) (xy 29.439104 -203.574013) (xy 29.392848 -203.599166)
			(xy 29.343295 -203.616964) (xy 29.291605 -203.626988) (xy 29.238991 -203.629005) (xy 29.186686 -203.622967)
			(xy 29.135915 -203.609015) (xy 29.08787 -203.587476) (xy 29.043675 -203.558856) (xy 29.004367 -203.523825)
			(xy 28.970867 -203.483204) (xy 28.943961 -203.437945) (xy 28.924278 -203.38911) (xy 28.912281 -203.337842)
			(xy 28.908251 -203.285344) (xy 22.051518 -203.285344) (xy 22.051014 -203.31167) (xy 22.042977 -203.363706)
			(xy 22.027091 -203.413905) (xy 22.003728 -203.46109) (xy 21.973436 -203.504156) (xy 21.936924 -203.542094)
			(xy 21.89505 -203.574013) (xy 21.848794 -203.599166) (xy 21.799241 -203.616964) (xy 21.747551 -203.626988)
			(xy 21.694937 -203.629005) (xy 21.642632 -203.622967) (xy 21.591861 -203.609015) (xy 21.543816 -203.587476)
			(xy 21.499621 -203.558856) (xy 21.460313 -203.523825) (xy 21.426813 -203.483204) (xy 21.399907 -203.437945)
			(xy 21.380224 -203.38911) (xy 21.368227 -203.337842) (xy 21.364197 -203.285344) (xy 16.086074 -203.285344)
			(xy 16.086074 -204.135228) (xy 17.264129 -204.135228) (xy 17.268159 -204.08273) (xy 17.280156 -204.031462)
			(xy 17.299839 -203.982627) (xy 17.326745 -203.937368) (xy 17.360245 -203.896747) (xy 17.399553 -203.861716)
			(xy 17.443748 -203.833096) (xy 17.491793 -203.811557) (xy 17.542564 -203.797605) (xy 17.594869 -203.791567)
			(xy 17.647483 -203.793584) (xy 17.699173 -203.803608) (xy 17.748726 -203.821406) (xy 17.794982 -203.846559)
			(xy 17.836856 -203.878478) (xy 17.873368 -203.916416) (xy 17.90366 -203.959482) (xy 17.927023 -204.006667)
			(xy 17.942909 -204.056866) (xy 17.950946 -204.108902) (xy 17.95145 -204.135228) (xy 24.808183 -204.135228)
			(xy 24.812213 -204.08273) (xy 24.82421 -204.031462) (xy 24.843893 -203.982627) (xy 24.870799 -203.937368)
			(xy 24.904299 -203.896747) (xy 24.943607 -203.861716) (xy 24.987802 -203.833096) (xy 25.035847 -203.811557)
			(xy 25.086618 -203.797605) (xy 25.138923 -203.791567) (xy 25.191537 -203.793584) (xy 25.243227 -203.803608)
			(xy 25.29278 -203.821406) (xy 25.339036 -203.846559) (xy 25.38091 -203.878478) (xy 25.417422 -203.916416)
			(xy 25.447714 -203.959482) (xy 25.471077 -204.006667) (xy 25.486963 -204.056866) (xy 25.495 -204.108902)
			(xy 25.495504 -204.135228) (xy 32.351983 -204.135228) (xy 32.356013 -204.08273) (xy 32.36801 -204.031462)
			(xy 32.387693 -203.982627) (xy 32.414599 -203.937368) (xy 32.448099 -203.896747) (xy 32.487407 -203.861716)
			(xy 32.531602 -203.833096) (xy 32.579647 -203.811557) (xy 32.630418 -203.797605) (xy 32.682723 -203.791567)
			(xy 32.735337 -203.793584) (xy 32.787027 -203.803608) (xy 32.83658 -203.821406) (xy 32.882836 -203.846559)
			(xy 32.92471 -203.878478) (xy 32.961222 -203.916416) (xy 32.991514 -203.959482) (xy 33.014877 -204.006667)
			(xy 33.030763 -204.056866) (xy 33.0388 -204.108902) (xy 33.039304 -204.135228) (xy 39.896037 -204.135228)
			(xy 39.900067 -204.08273) (xy 39.912064 -204.031462) (xy 39.931747 -203.982627) (xy 39.958653 -203.937368)
			(xy 39.992153 -203.896747) (xy 40.031461 -203.861716) (xy 40.075656 -203.833096) (xy 40.123701 -203.811557)
			(xy 40.174472 -203.797605) (xy 40.226777 -203.791567) (xy 40.279391 -203.793584) (xy 40.331081 -203.803608)
			(xy 40.380634 -203.821406) (xy 40.42689 -203.846559) (xy 40.468764 -203.878478) (xy 40.505276 -203.916416)
			(xy 40.535568 -203.959482) (xy 40.558931 -204.006667) (xy 40.574817 -204.056866) (xy 40.582854 -204.108902)
			(xy 40.583358 -204.135228) (xy 47.440091 -204.135228) (xy 47.444121 -204.08273) (xy 47.456118 -204.031462)
			(xy 47.475801 -203.982627) (xy 47.502707 -203.937368) (xy 47.536207 -203.896747) (xy 47.575515 -203.861716)
			(xy 47.61971 -203.833096) (xy 47.667755 -203.811557) (xy 47.718526 -203.797605) (xy 47.770831 -203.791567)
			(xy 47.823445 -203.793584) (xy 47.875135 -203.803608) (xy 47.924688 -203.821406) (xy 47.970944 -203.846559)
			(xy 48.012818 -203.878478) (xy 48.04933 -203.916416) (xy 48.079622 -203.959482) (xy 48.102985 -204.006667)
			(xy 48.118871 -204.056866) (xy 48.126908 -204.108902) (xy 48.127412 -204.135228) (xy 48.126908 -204.161554)
			(xy 48.118871 -204.21359) (xy 48.102985 -204.263789) (xy 48.079622 -204.310974) (xy 48.04933 -204.35404)
			(xy 48.012818 -204.391978) (xy 47.970944 -204.423897) (xy 47.924688 -204.44905) (xy 47.875135 -204.466848)
			(xy 47.823445 -204.476872) (xy 47.770831 -204.478889) (xy 47.718526 -204.472851) (xy 47.667755 -204.458899)
			(xy 47.61971 -204.43736) (xy 47.575515 -204.40874) (xy 47.536207 -204.373709) (xy 47.502707 -204.333088)
			(xy 47.475801 -204.287829) (xy 47.456118 -204.238994) (xy 47.444121 -204.187726) (xy 47.440091 -204.135228)
			(xy 40.583358 -204.135228) (xy 40.582854 -204.161554) (xy 40.574817 -204.21359) (xy 40.558931 -204.263789)
			(xy 40.535568 -204.310974) (xy 40.505276 -204.35404) (xy 40.468764 -204.391978) (xy 40.42689 -204.423897)
			(xy 40.380634 -204.44905) (xy 40.331081 -204.466848) (xy 40.279391 -204.476872) (xy 40.226777 -204.478889)
			(xy 40.174472 -204.472851) (xy 40.123701 -204.458899) (xy 40.075656 -204.43736) (xy 40.031461 -204.40874)
			(xy 39.992153 -204.373709) (xy 39.958653 -204.333088) (xy 39.931747 -204.287829) (xy 39.912064 -204.238994)
			(xy 39.900067 -204.187726) (xy 39.896037 -204.135228) (xy 33.039304 -204.135228) (xy 33.0388 -204.161554)
			(xy 33.030763 -204.21359) (xy 33.014877 -204.263789) (xy 32.991514 -204.310974) (xy 32.961222 -204.35404)
			(xy 32.92471 -204.391978) (xy 32.882836 -204.423897) (xy 32.83658 -204.44905) (xy 32.787027 -204.466848)
			(xy 32.735337 -204.476872) (xy 32.682723 -204.478889) (xy 32.630418 -204.472851) (xy 32.579647 -204.458899)
			(xy 32.531602 -204.43736) (xy 32.487407 -204.40874) (xy 32.448099 -204.373709) (xy 32.414599 -204.333088)
			(xy 32.387693 -204.287829) (xy 32.36801 -204.238994) (xy 32.356013 -204.187726) (xy 32.351983 -204.135228)
			(xy 25.495504 -204.135228) (xy 25.495 -204.161554) (xy 25.486963 -204.21359) (xy 25.471077 -204.263789)
			(xy 25.447714 -204.310974) (xy 25.417422 -204.35404) (xy 25.38091 -204.391978) (xy 25.339036 -204.423897)
			(xy 25.29278 -204.44905) (xy 25.243227 -204.466848) (xy 25.191537 -204.476872) (xy 25.138923 -204.478889)
			(xy 25.086618 -204.472851) (xy 25.035847 -204.458899) (xy 24.987802 -204.43736) (xy 24.943607 -204.40874)
			(xy 24.904299 -204.373709) (xy 24.870799 -204.333088) (xy 24.843893 -204.287829) (xy 24.82421 -204.238994)
			(xy 24.812213 -204.187726) (xy 24.808183 -204.135228) (xy 17.95145 -204.135228) (xy 17.950946 -204.161554)
			(xy 17.942909 -204.21359) (xy 17.927023 -204.263789) (xy 17.90366 -204.310974) (xy 17.873368 -204.35404)
			(xy 17.836856 -204.391978) (xy 17.794982 -204.423897) (xy 17.748726 -204.44905) (xy 17.699173 -204.466848)
			(xy 17.647483 -204.476872) (xy 17.594869 -204.478889) (xy 17.542564 -204.472851) (xy 17.491793 -204.458899)
			(xy 17.443748 -204.43736) (xy 17.399553 -204.40874) (xy 17.360245 -204.373709) (xy 17.326745 -204.333088)
			(xy 17.299839 -204.287829) (xy 17.280156 -204.238994) (xy 17.268159 -204.187726) (xy 17.264129 -204.135228)
			(xy 16.086074 -204.135228) (xy 16.086074 -204.985366) (xy 21.364197 -204.985366) (xy 21.368227 -204.932868)
			(xy 21.380224 -204.8816) (xy 21.399907 -204.832765) (xy 21.426813 -204.787506) (xy 21.460313 -204.746885)
			(xy 21.499621 -204.711854) (xy 21.543816 -204.683234) (xy 21.591861 -204.661695) (xy 21.642632 -204.647743)
			(xy 21.694937 -204.641705) (xy 21.747551 -204.643722) (xy 21.799241 -204.653746) (xy 21.848794 -204.671544)
			(xy 21.89505 -204.696697) (xy 21.936924 -204.728616) (xy 21.973436 -204.766554) (xy 22.003728 -204.80962)
			(xy 22.027091 -204.856805) (xy 22.042977 -204.907004) (xy 22.051014 -204.95904) (xy 22.051518 -204.985366)
			(xy 28.908251 -204.985366) (xy 28.912281 -204.932868) (xy 28.924278 -204.8816) (xy 28.943961 -204.832765)
			(xy 28.970867 -204.787506) (xy 29.004367 -204.746885) (xy 29.043675 -204.711854) (xy 29.08787 -204.683234)
			(xy 29.135915 -204.661695) (xy 29.186686 -204.647743) (xy 29.238991 -204.641705) (xy 29.291605 -204.643722)
			(xy 29.343295 -204.653746) (xy 29.392848 -204.671544) (xy 29.439104 -204.696697) (xy 29.480978 -204.728616)
			(xy 29.51749 -204.766554) (xy 29.547782 -204.80962) (xy 29.571145 -204.856805) (xy 29.587031 -204.907004)
			(xy 29.595068 -204.95904) (xy 29.595572 -204.985366) (xy 36.452051 -204.985366) (xy 36.456081 -204.932868)
			(xy 36.468078 -204.8816) (xy 36.487761 -204.832765) (xy 36.514667 -204.787506) (xy 36.548167 -204.746885)
			(xy 36.587475 -204.711854) (xy 36.63167 -204.683234) (xy 36.679715 -204.661695) (xy 36.730486 -204.647743)
			(xy 36.782791 -204.641705) (xy 36.835405 -204.643722) (xy 36.887095 -204.653746) (xy 36.936648 -204.671544)
			(xy 36.982904 -204.696697) (xy 37.024778 -204.728616) (xy 37.06129 -204.766554) (xy 37.091582 -204.80962)
			(xy 37.114945 -204.856805) (xy 37.130831 -204.907004) (xy 37.138868 -204.95904) (xy 37.139372 -204.985366)
			(xy 43.996105 -204.985366) (xy 44.000135 -204.932868) (xy 44.012132 -204.8816) (xy 44.031815 -204.832765)
			(xy 44.058721 -204.787506) (xy 44.092221 -204.746885) (xy 44.131529 -204.711854) (xy 44.175724 -204.683234)
			(xy 44.223769 -204.661695) (xy 44.27454 -204.647743) (xy 44.326845 -204.641705) (xy 44.379459 -204.643722)
			(xy 44.431149 -204.653746) (xy 44.480702 -204.671544) (xy 44.526958 -204.696697) (xy 44.568832 -204.728616)
			(xy 44.605344 -204.766554) (xy 44.635636 -204.80962) (xy 44.658999 -204.856805) (xy 44.674885 -204.907004)
			(xy 44.682922 -204.95904) (xy 44.683426 -204.985366) (xy 51.540159 -204.985366) (xy 51.544189 -204.932868)
			(xy 51.556186 -204.8816) (xy 51.575869 -204.832765) (xy 51.602775 -204.787506) (xy 51.636275 -204.746885)
			(xy 51.675583 -204.711854) (xy 51.719778 -204.683234) (xy 51.767823 -204.661695) (xy 51.818594 -204.647743)
			(xy 51.870899 -204.641705) (xy 51.923513 -204.643722) (xy 51.975203 -204.653746) (xy 52.024756 -204.671544)
			(xy 52.071012 -204.696697) (xy 52.112886 -204.728616) (xy 52.149398 -204.766554) (xy 52.17969 -204.80962)
			(xy 52.203053 -204.856805) (xy 52.218939 -204.907004) (xy 52.226976 -204.95904) (xy 52.22748 -204.985366)
			(xy 52.226976 -205.011692) (xy 52.218939 -205.063728) (xy 52.203053 -205.113927) (xy 52.17969 -205.161112)
			(xy 52.149398 -205.204178) (xy 52.112886 -205.242116) (xy 52.071012 -205.274035) (xy 52.024756 -205.299188)
			(xy 51.975203 -205.316986) (xy 51.923513 -205.32701) (xy 51.870899 -205.329027) (xy 51.818594 -205.322989)
			(xy 51.767823 -205.309037) (xy 51.719778 -205.287498) (xy 51.675583 -205.258878) (xy 51.636275 -205.223847)
			(xy 51.602775 -205.183226) (xy 51.575869 -205.137967) (xy 51.556186 -205.089132) (xy 51.544189 -205.037864)
			(xy 51.540159 -204.985366) (xy 44.683426 -204.985366) (xy 44.682922 -205.011692) (xy 44.674885 -205.063728)
			(xy 44.658999 -205.113927) (xy 44.635636 -205.161112) (xy 44.605344 -205.204178) (xy 44.568832 -205.242116)
			(xy 44.526958 -205.274035) (xy 44.480702 -205.299188) (xy 44.431149 -205.316986) (xy 44.379459 -205.32701)
			(xy 44.326845 -205.329027) (xy 44.27454 -205.322989) (xy 44.223769 -205.309037) (xy 44.175724 -205.287498)
			(xy 44.131529 -205.258878) (xy 44.092221 -205.223847) (xy 44.058721 -205.183226) (xy 44.031815 -205.137967)
			(xy 44.012132 -205.089132) (xy 44.000135 -205.037864) (xy 43.996105 -204.985366) (xy 37.139372 -204.985366)
			(xy 37.138868 -205.011692) (xy 37.130831 -205.063728) (xy 37.114945 -205.113927) (xy 37.091582 -205.161112)
			(xy 37.06129 -205.204178) (xy 37.024778 -205.242116) (xy 36.982904 -205.274035) (xy 36.936648 -205.299188)
			(xy 36.887095 -205.316986) (xy 36.835405 -205.32701) (xy 36.782791 -205.329027) (xy 36.730486 -205.322989)
			(xy 36.679715 -205.309037) (xy 36.63167 -205.287498) (xy 36.587475 -205.258878) (xy 36.548167 -205.223847)
			(xy 36.514667 -205.183226) (xy 36.487761 -205.137967) (xy 36.468078 -205.089132) (xy 36.456081 -205.037864)
			(xy 36.452051 -204.985366) (xy 29.595572 -204.985366) (xy 29.595068 -205.011692) (xy 29.587031 -205.063728)
			(xy 29.571145 -205.113927) (xy 29.547782 -205.161112) (xy 29.51749 -205.204178) (xy 29.480978 -205.242116)
			(xy 29.439104 -205.274035) (xy 29.392848 -205.299188) (xy 29.343295 -205.316986) (xy 29.291605 -205.32701)
			(xy 29.238991 -205.329027) (xy 29.186686 -205.322989) (xy 29.135915 -205.309037) (xy 29.08787 -205.287498)
			(xy 29.043675 -205.258878) (xy 29.004367 -205.223847) (xy 28.970867 -205.183226) (xy 28.943961 -205.137967)
			(xy 28.924278 -205.089132) (xy 28.912281 -205.037864) (xy 28.908251 -204.985366) (xy 22.051518 -204.985366)
			(xy 22.051014 -205.011692) (xy 22.042977 -205.063728) (xy 22.027091 -205.113927) (xy 22.003728 -205.161112)
			(xy 21.973436 -205.204178) (xy 21.936924 -205.242116) (xy 21.89505 -205.274035) (xy 21.848794 -205.299188)
			(xy 21.799241 -205.316986) (xy 21.747551 -205.32701) (xy 21.694937 -205.329027) (xy 21.642632 -205.322989)
			(xy 21.591861 -205.309037) (xy 21.543816 -205.287498) (xy 21.499621 -205.258878) (xy 21.460313 -205.223847)
			(xy 21.426813 -205.183226) (xy 21.399907 -205.137967) (xy 21.380224 -205.089132) (xy 21.368227 -205.037864)
			(xy 21.364197 -204.985366) (xy 16.086074 -204.985366) (xy 16.086074 -205.83525) (xy 17.264129 -205.83525)
			(xy 17.268159 -205.782752) (xy 17.280156 -205.731484) (xy 17.299839 -205.682649) (xy 17.326745 -205.63739)
			(xy 17.360245 -205.596769) (xy 17.399553 -205.561738) (xy 17.443748 -205.533118) (xy 17.491793 -205.511579)
			(xy 17.542564 -205.497627) (xy 17.594869 -205.491589) (xy 17.647483 -205.493606) (xy 17.699173 -205.50363)
			(xy 17.748726 -205.521428) (xy 17.794982 -205.546581) (xy 17.836856 -205.5785) (xy 17.873368 -205.616438)
			(xy 17.90366 -205.659504) (xy 17.927023 -205.706689) (xy 17.942909 -205.756888) (xy 17.950946 -205.808924)
			(xy 17.95145 -205.83525) (xy 24.808183 -205.83525) (xy 24.812213 -205.782752) (xy 24.82421 -205.731484)
			(xy 24.843893 -205.682649) (xy 24.870799 -205.63739) (xy 24.904299 -205.596769) (xy 24.943607 -205.561738)
			(xy 24.987802 -205.533118) (xy 25.035847 -205.511579) (xy 25.086618 -205.497627) (xy 25.138923 -205.491589)
			(xy 25.191537 -205.493606) (xy 25.243227 -205.50363) (xy 25.29278 -205.521428) (xy 25.339036 -205.546581)
			(xy 25.38091 -205.5785) (xy 25.417422 -205.616438) (xy 25.447714 -205.659504) (xy 25.471077 -205.706689)
			(xy 25.486963 -205.756888) (xy 25.495 -205.808924) (xy 25.495504 -205.83525) (xy 32.351983 -205.83525)
			(xy 32.356013 -205.782752) (xy 32.36801 -205.731484) (xy 32.387693 -205.682649) (xy 32.414599 -205.63739)
			(xy 32.448099 -205.596769) (xy 32.487407 -205.561738) (xy 32.531602 -205.533118) (xy 32.579647 -205.511579)
			(xy 32.630418 -205.497627) (xy 32.682723 -205.491589) (xy 32.735337 -205.493606) (xy 32.787027 -205.50363)
			(xy 32.83658 -205.521428) (xy 32.882836 -205.546581) (xy 32.92471 -205.5785) (xy 32.961222 -205.616438)
			(xy 32.991514 -205.659504) (xy 33.014877 -205.706689) (xy 33.030763 -205.756888) (xy 33.0388 -205.808924)
			(xy 33.039304 -205.83525) (xy 39.896037 -205.83525) (xy 39.900067 -205.782752) (xy 39.912064 -205.731484)
			(xy 39.931747 -205.682649) (xy 39.958653 -205.63739) (xy 39.992153 -205.596769) (xy 40.031461 -205.561738)
			(xy 40.075656 -205.533118) (xy 40.123701 -205.511579) (xy 40.174472 -205.497627) (xy 40.226777 -205.491589)
			(xy 40.279391 -205.493606) (xy 40.331081 -205.50363) (xy 40.380634 -205.521428) (xy 40.42689 -205.546581)
			(xy 40.468764 -205.5785) (xy 40.505276 -205.616438) (xy 40.535568 -205.659504) (xy 40.558931 -205.706689)
			(xy 40.574817 -205.756888) (xy 40.582854 -205.808924) (xy 40.583358 -205.83525) (xy 47.440091 -205.83525)
			(xy 47.444121 -205.782752) (xy 47.456118 -205.731484) (xy 47.475801 -205.682649) (xy 47.502707 -205.63739)
			(xy 47.536207 -205.596769) (xy 47.575515 -205.561738) (xy 47.61971 -205.533118) (xy 47.667755 -205.511579)
			(xy 47.718526 -205.497627) (xy 47.770831 -205.491589) (xy 47.823445 -205.493606) (xy 47.875135 -205.50363)
			(xy 47.924688 -205.521428) (xy 47.970944 -205.546581) (xy 48.012818 -205.5785) (xy 48.04933 -205.616438)
			(xy 48.079622 -205.659504) (xy 48.102985 -205.706689) (xy 48.118871 -205.756888) (xy 48.126908 -205.808924)
			(xy 48.127412 -205.83525) (xy 48.126908 -205.861576) (xy 48.118871 -205.913612) (xy 48.102985 -205.963811)
			(xy 48.079622 -206.010996) (xy 48.04933 -206.054062) (xy 48.012818 -206.092) (xy 47.970944 -206.123919)
			(xy 47.924688 -206.149072) (xy 47.875135 -206.16687) (xy 47.823445 -206.176894) (xy 47.770831 -206.178911)
			(xy 47.718526 -206.172873) (xy 47.667755 -206.158921) (xy 47.61971 -206.137382) (xy 47.575515 -206.108762)
			(xy 47.536207 -206.073731) (xy 47.502707 -206.03311) (xy 47.475801 -205.987851) (xy 47.456118 -205.939016)
			(xy 47.444121 -205.887748) (xy 47.440091 -205.83525) (xy 40.583358 -205.83525) (xy 40.582854 -205.861576)
			(xy 40.574817 -205.913612) (xy 40.558931 -205.963811) (xy 40.535568 -206.010996) (xy 40.505276 -206.054062)
			(xy 40.468764 -206.092) (xy 40.42689 -206.123919) (xy 40.380634 -206.149072) (xy 40.331081 -206.16687)
			(xy 40.279391 -206.176894) (xy 40.226777 -206.178911) (xy 40.174472 -206.172873) (xy 40.123701 -206.158921)
			(xy 40.075656 -206.137382) (xy 40.031461 -206.108762) (xy 39.992153 -206.073731) (xy 39.958653 -206.03311)
			(xy 39.931747 -205.987851) (xy 39.912064 -205.939016) (xy 39.900067 -205.887748) (xy 39.896037 -205.83525)
			(xy 33.039304 -205.83525) (xy 33.0388 -205.861576) (xy 33.030763 -205.913612) (xy 33.014877 -205.963811)
			(xy 32.991514 -206.010996) (xy 32.961222 -206.054062) (xy 32.92471 -206.092) (xy 32.882836 -206.123919)
			(xy 32.83658 -206.149072) (xy 32.787027 -206.16687) (xy 32.735337 -206.176894) (xy 32.682723 -206.178911)
			(xy 32.630418 -206.172873) (xy 32.579647 -206.158921) (xy 32.531602 -206.137382) (xy 32.487407 -206.108762)
			(xy 32.448099 -206.073731) (xy 32.414599 -206.03311) (xy 32.387693 -205.987851) (xy 32.36801 -205.939016)
			(xy 32.356013 -205.887748) (xy 32.351983 -205.83525) (xy 25.495504 -205.83525) (xy 25.495 -205.861576)
			(xy 25.486963 -205.913612) (xy 25.471077 -205.963811) (xy 25.447714 -206.010996) (xy 25.417422 -206.054062)
			(xy 25.38091 -206.092) (xy 25.339036 -206.123919) (xy 25.29278 -206.149072) (xy 25.243227 -206.16687)
			(xy 25.191537 -206.176894) (xy 25.138923 -206.178911) (xy 25.086618 -206.172873) (xy 25.035847 -206.158921)
			(xy 24.987802 -206.137382) (xy 24.943607 -206.108762) (xy 24.904299 -206.073731) (xy 24.870799 -206.03311)
			(xy 24.843893 -205.987851) (xy 24.82421 -205.939016) (xy 24.812213 -205.887748) (xy 24.808183 -205.83525)
			(xy 17.95145 -205.83525) (xy 17.950946 -205.861576) (xy 17.942909 -205.913612) (xy 17.927023 -205.963811)
			(xy 17.90366 -206.010996) (xy 17.873368 -206.054062) (xy 17.836856 -206.092) (xy 17.794982 -206.123919)
			(xy 17.748726 -206.149072) (xy 17.699173 -206.16687) (xy 17.647483 -206.176894) (xy 17.594869 -206.178911)
			(xy 17.542564 -206.172873) (xy 17.491793 -206.158921) (xy 17.443748 -206.137382) (xy 17.399553 -206.108762)
			(xy 17.360245 -206.073731) (xy 17.326745 -206.03311) (xy 17.299839 -205.987851) (xy 17.280156 -205.939016)
			(xy 17.268159 -205.887748) (xy 17.264129 -205.83525) (xy 16.086074 -205.83525) (xy 16.086074 -206.685388)
			(xy 21.364197 -206.685388) (xy 21.368227 -206.63289) (xy 21.380224 -206.581622) (xy 21.399907 -206.532787)
			(xy 21.426813 -206.487528) (xy 21.460313 -206.446907) (xy 21.499621 -206.411876) (xy 21.543816 -206.383256)
			(xy 21.591861 -206.361717) (xy 21.642632 -206.347765) (xy 21.694937 -206.341727) (xy 21.747551 -206.343744)
			(xy 21.799241 -206.353768) (xy 21.848794 -206.371566) (xy 21.89505 -206.396719) (xy 21.936924 -206.428638)
			(xy 21.973436 -206.466576) (xy 22.003728 -206.509642) (xy 22.027091 -206.556827) (xy 22.042977 -206.607026)
			(xy 22.051014 -206.659062) (xy 22.051518 -206.685388) (xy 28.908251 -206.685388) (xy 28.912281 -206.63289)
			(xy 28.924278 -206.581622) (xy 28.943961 -206.532787) (xy 28.970867 -206.487528) (xy 29.004367 -206.446907)
			(xy 29.043675 -206.411876) (xy 29.08787 -206.383256) (xy 29.135915 -206.361717) (xy 29.186686 -206.347765)
			(xy 29.238991 -206.341727) (xy 29.291605 -206.343744) (xy 29.343295 -206.353768) (xy 29.392848 -206.371566)
			(xy 29.439104 -206.396719) (xy 29.480978 -206.428638) (xy 29.51749 -206.466576) (xy 29.547782 -206.509642)
			(xy 29.571145 -206.556827) (xy 29.587031 -206.607026) (xy 29.595068 -206.659062) (xy 29.595572 -206.685388)
			(xy 36.452051 -206.685388) (xy 36.456081 -206.63289) (xy 36.468078 -206.581622) (xy 36.487761 -206.532787)
			(xy 36.514667 -206.487528) (xy 36.548167 -206.446907) (xy 36.587475 -206.411876) (xy 36.63167 -206.383256)
			(xy 36.679715 -206.361717) (xy 36.730486 -206.347765) (xy 36.782791 -206.341727) (xy 36.835405 -206.343744)
			(xy 36.887095 -206.353768) (xy 36.936648 -206.371566) (xy 36.982904 -206.396719) (xy 37.024778 -206.428638)
			(xy 37.06129 -206.466576) (xy 37.091582 -206.509642) (xy 37.114945 -206.556827) (xy 37.130831 -206.607026)
			(xy 37.138868 -206.659062) (xy 37.139372 -206.685388) (xy 43.996105 -206.685388) (xy 44.000135 -206.63289)
			(xy 44.012132 -206.581622) (xy 44.031815 -206.532787) (xy 44.058721 -206.487528) (xy 44.092221 -206.446907)
			(xy 44.131529 -206.411876) (xy 44.175724 -206.383256) (xy 44.223769 -206.361717) (xy 44.27454 -206.347765)
			(xy 44.326845 -206.341727) (xy 44.379459 -206.343744) (xy 44.431149 -206.353768) (xy 44.480702 -206.371566)
			(xy 44.526958 -206.396719) (xy 44.568832 -206.428638) (xy 44.605344 -206.466576) (xy 44.635636 -206.509642)
			(xy 44.658999 -206.556827) (xy 44.674885 -206.607026) (xy 44.682922 -206.659062) (xy 44.683426 -206.685388)
			(xy 51.540159 -206.685388) (xy 51.544189 -206.63289) (xy 51.556186 -206.581622) (xy 51.575869 -206.532787)
			(xy 51.602775 -206.487528) (xy 51.636275 -206.446907) (xy 51.675583 -206.411876) (xy 51.719778 -206.383256)
			(xy 51.767823 -206.361717) (xy 51.818594 -206.347765) (xy 51.870899 -206.341727) (xy 51.923513 -206.343744)
			(xy 51.975203 -206.353768) (xy 52.024756 -206.371566) (xy 52.071012 -206.396719) (xy 52.112886 -206.428638)
			(xy 52.149398 -206.466576) (xy 52.17969 -206.509642) (xy 52.203053 -206.556827) (xy 52.218939 -206.607026)
			(xy 52.226976 -206.659062) (xy 52.22748 -206.685388) (xy 52.226976 -206.711714) (xy 52.218939 -206.76375)
			(xy 52.203053 -206.813949) (xy 52.17969 -206.861134) (xy 52.149398 -206.9042) (xy 52.112886 -206.942138)
			(xy 52.071012 -206.974057) (xy 52.024756 -206.99921) (xy 51.975203 -207.017008) (xy 51.923513 -207.027032)
			(xy 51.870899 -207.029049) (xy 51.818594 -207.023011) (xy 51.767823 -207.009059) (xy 51.719778 -206.98752)
			(xy 51.675583 -206.9589) (xy 51.636275 -206.923869) (xy 51.602775 -206.883248) (xy 51.575869 -206.837989)
			(xy 51.556186 -206.789154) (xy 51.544189 -206.737886) (xy 51.540159 -206.685388) (xy 44.683426 -206.685388)
			(xy 44.682922 -206.711714) (xy 44.674885 -206.76375) (xy 44.658999 -206.813949) (xy 44.635636 -206.861134)
			(xy 44.605344 -206.9042) (xy 44.568832 -206.942138) (xy 44.526958 -206.974057) (xy 44.480702 -206.99921)
			(xy 44.431149 -207.017008) (xy 44.379459 -207.027032) (xy 44.326845 -207.029049) (xy 44.27454 -207.023011)
			(xy 44.223769 -207.009059) (xy 44.175724 -206.98752) (xy 44.131529 -206.9589) (xy 44.092221 -206.923869)
			(xy 44.058721 -206.883248) (xy 44.031815 -206.837989) (xy 44.012132 -206.789154) (xy 44.000135 -206.737886)
			(xy 43.996105 -206.685388) (xy 37.139372 -206.685388) (xy 37.138868 -206.711714) (xy 37.130831 -206.76375)
			(xy 37.114945 -206.813949) (xy 37.091582 -206.861134) (xy 37.06129 -206.9042) (xy 37.024778 -206.942138)
			(xy 36.982904 -206.974057) (xy 36.936648 -206.99921) (xy 36.887095 -207.017008) (xy 36.835405 -207.027032)
			(xy 36.782791 -207.029049) (xy 36.730486 -207.023011) (xy 36.679715 -207.009059) (xy 36.63167 -206.98752)
			(xy 36.587475 -206.9589) (xy 36.548167 -206.923869) (xy 36.514667 -206.883248) (xy 36.487761 -206.837989)
			(xy 36.468078 -206.789154) (xy 36.456081 -206.737886) (xy 36.452051 -206.685388) (xy 29.595572 -206.685388)
			(xy 29.595068 -206.711714) (xy 29.587031 -206.76375) (xy 29.571145 -206.813949) (xy 29.547782 -206.861134)
			(xy 29.51749 -206.9042) (xy 29.480978 -206.942138) (xy 29.439104 -206.974057) (xy 29.392848 -206.99921)
			(xy 29.343295 -207.017008) (xy 29.291605 -207.027032) (xy 29.238991 -207.029049) (xy 29.186686 -207.023011)
			(xy 29.135915 -207.009059) (xy 29.08787 -206.98752) (xy 29.043675 -206.9589) (xy 29.004367 -206.923869)
			(xy 28.970867 -206.883248) (xy 28.943961 -206.837989) (xy 28.924278 -206.789154) (xy 28.912281 -206.737886)
			(xy 28.908251 -206.685388) (xy 22.051518 -206.685388) (xy 22.051014 -206.711714) (xy 22.042977 -206.76375)
			(xy 22.027091 -206.813949) (xy 22.003728 -206.861134) (xy 21.973436 -206.9042) (xy 21.936924 -206.942138)
			(xy 21.89505 -206.974057) (xy 21.848794 -206.99921) (xy 21.799241 -207.017008) (xy 21.747551 -207.027032)
			(xy 21.694937 -207.029049) (xy 21.642632 -207.023011) (xy 21.591861 -207.009059) (xy 21.543816 -206.98752)
			(xy 21.499621 -206.9589) (xy 21.460313 -206.923869) (xy 21.426813 -206.883248) (xy 21.399907 -206.837989)
			(xy 21.380224 -206.789154) (xy 21.368227 -206.737886) (xy 21.364197 -206.685388) (xy 16.086074 -206.685388)
			(xy 16.086074 -207.535272) (xy 17.264129 -207.535272) (xy 17.268159 -207.482774) (xy 17.280156 -207.431506)
			(xy 17.299839 -207.382671) (xy 17.326745 -207.337412) (xy 17.360245 -207.296791) (xy 17.399553 -207.26176)
			(xy 17.443748 -207.23314) (xy 17.491793 -207.211601) (xy 17.542564 -207.197649) (xy 17.594869 -207.191611)
			(xy 17.647483 -207.193628) (xy 17.699173 -207.203652) (xy 17.748726 -207.22145) (xy 17.794982 -207.246603)
			(xy 17.836856 -207.278522) (xy 17.873368 -207.31646) (xy 17.90366 -207.359526) (xy 17.927023 -207.406711)
			(xy 17.942909 -207.45691) (xy 17.950946 -207.508946) (xy 17.95145 -207.535272) (xy 24.808183 -207.535272)
			(xy 24.812213 -207.482774) (xy 24.82421 -207.431506) (xy 24.843893 -207.382671) (xy 24.870799 -207.337412)
			(xy 24.904299 -207.296791) (xy 24.943607 -207.26176) (xy 24.987802 -207.23314) (xy 25.035847 -207.211601)
			(xy 25.086618 -207.197649) (xy 25.138923 -207.191611) (xy 25.191537 -207.193628) (xy 25.243227 -207.203652)
			(xy 25.29278 -207.22145) (xy 25.339036 -207.246603) (xy 25.38091 -207.278522) (xy 25.417422 -207.31646)
			(xy 25.447714 -207.359526) (xy 25.471077 -207.406711) (xy 25.486963 -207.45691) (xy 25.495 -207.508946)
			(xy 25.495504 -207.535272) (xy 32.351983 -207.535272) (xy 32.356013 -207.482774) (xy 32.36801 -207.431506)
			(xy 32.387693 -207.382671) (xy 32.414599 -207.337412) (xy 32.448099 -207.296791) (xy 32.487407 -207.26176)
			(xy 32.531602 -207.23314) (xy 32.579647 -207.211601) (xy 32.630418 -207.197649) (xy 32.682723 -207.191611)
			(xy 32.735337 -207.193628) (xy 32.787027 -207.203652) (xy 32.83658 -207.22145) (xy 32.882836 -207.246603)
			(xy 32.92471 -207.278522) (xy 32.961222 -207.31646) (xy 32.991514 -207.359526) (xy 33.014877 -207.406711)
			(xy 33.030763 -207.45691) (xy 33.0388 -207.508946) (xy 33.039304 -207.535272) (xy 39.896037 -207.535272)
			(xy 39.900067 -207.482774) (xy 39.912064 -207.431506) (xy 39.931747 -207.382671) (xy 39.958653 -207.337412)
			(xy 39.992153 -207.296791) (xy 40.031461 -207.26176) (xy 40.075656 -207.23314) (xy 40.123701 -207.211601)
			(xy 40.174472 -207.197649) (xy 40.226777 -207.191611) (xy 40.279391 -207.193628) (xy 40.331081 -207.203652)
			(xy 40.380634 -207.22145) (xy 40.42689 -207.246603) (xy 40.468764 -207.278522) (xy 40.505276 -207.31646)
			(xy 40.535568 -207.359526) (xy 40.558931 -207.406711) (xy 40.574817 -207.45691) (xy 40.582854 -207.508946)
			(xy 40.583358 -207.535272) (xy 47.440091 -207.535272) (xy 47.444121 -207.482774) (xy 47.456118 -207.431506)
			(xy 47.475801 -207.382671) (xy 47.502707 -207.337412) (xy 47.536207 -207.296791) (xy 47.575515 -207.26176)
			(xy 47.61971 -207.23314) (xy 47.667755 -207.211601) (xy 47.718526 -207.197649) (xy 47.770831 -207.191611)
			(xy 47.823445 -207.193628) (xy 47.875135 -207.203652) (xy 47.924688 -207.22145) (xy 47.970944 -207.246603)
			(xy 48.012818 -207.278522) (xy 48.04933 -207.31646) (xy 48.079622 -207.359526) (xy 48.102985 -207.406711)
			(xy 48.118871 -207.45691) (xy 48.126908 -207.508946) (xy 48.127412 -207.535272) (xy 48.126908 -207.561598)
			(xy 48.118871 -207.613634) (xy 48.102985 -207.663833) (xy 48.079622 -207.711018) (xy 48.04933 -207.754084)
			(xy 48.012818 -207.792022) (xy 47.970944 -207.823941) (xy 47.924688 -207.849094) (xy 47.875135 -207.866892)
			(xy 47.823445 -207.876916) (xy 47.770831 -207.878933) (xy 47.718526 -207.872895) (xy 47.667755 -207.858943)
			(xy 47.61971 -207.837404) (xy 47.575515 -207.808784) (xy 47.536207 -207.773753) (xy 47.502707 -207.733132)
			(xy 47.475801 -207.687873) (xy 47.456118 -207.639038) (xy 47.444121 -207.58777) (xy 47.440091 -207.535272)
			(xy 40.583358 -207.535272) (xy 40.582854 -207.561598) (xy 40.574817 -207.613634) (xy 40.558931 -207.663833)
			(xy 40.535568 -207.711018) (xy 40.505276 -207.754084) (xy 40.468764 -207.792022) (xy 40.42689 -207.823941)
			(xy 40.380634 -207.849094) (xy 40.331081 -207.866892) (xy 40.279391 -207.876916) (xy 40.226777 -207.878933)
			(xy 40.174472 -207.872895) (xy 40.123701 -207.858943) (xy 40.075656 -207.837404) (xy 40.031461 -207.808784)
			(xy 39.992153 -207.773753) (xy 39.958653 -207.733132) (xy 39.931747 -207.687873) (xy 39.912064 -207.639038)
			(xy 39.900067 -207.58777) (xy 39.896037 -207.535272) (xy 33.039304 -207.535272) (xy 33.0388 -207.561598)
			(xy 33.030763 -207.613634) (xy 33.014877 -207.663833) (xy 32.991514 -207.711018) (xy 32.961222 -207.754084)
			(xy 32.92471 -207.792022) (xy 32.882836 -207.823941) (xy 32.83658 -207.849094) (xy 32.787027 -207.866892)
			(xy 32.735337 -207.876916) (xy 32.682723 -207.878933) (xy 32.630418 -207.872895) (xy 32.579647 -207.858943)
			(xy 32.531602 -207.837404) (xy 32.487407 -207.808784) (xy 32.448099 -207.773753) (xy 32.414599 -207.733132)
			(xy 32.387693 -207.687873) (xy 32.36801 -207.639038) (xy 32.356013 -207.58777) (xy 32.351983 -207.535272)
			(xy 25.495504 -207.535272) (xy 25.495 -207.561598) (xy 25.486963 -207.613634) (xy 25.471077 -207.663833)
			(xy 25.447714 -207.711018) (xy 25.417422 -207.754084) (xy 25.38091 -207.792022) (xy 25.339036 -207.823941)
			(xy 25.29278 -207.849094) (xy 25.243227 -207.866892) (xy 25.191537 -207.876916) (xy 25.138923 -207.878933)
			(xy 25.086618 -207.872895) (xy 25.035847 -207.858943) (xy 24.987802 -207.837404) (xy 24.943607 -207.808784)
			(xy 24.904299 -207.773753) (xy 24.870799 -207.733132) (xy 24.843893 -207.687873) (xy 24.82421 -207.639038)
			(xy 24.812213 -207.58777) (xy 24.808183 -207.535272) (xy 17.95145 -207.535272) (xy 17.950946 -207.561598)
			(xy 17.942909 -207.613634) (xy 17.927023 -207.663833) (xy 17.90366 -207.711018) (xy 17.873368 -207.754084)
			(xy 17.836856 -207.792022) (xy 17.794982 -207.823941) (xy 17.748726 -207.849094) (xy 17.699173 -207.866892)
			(xy 17.647483 -207.876916) (xy 17.594869 -207.878933) (xy 17.542564 -207.872895) (xy 17.491793 -207.858943)
			(xy 17.443748 -207.837404) (xy 17.399553 -207.808784) (xy 17.360245 -207.773753) (xy 17.326745 -207.733132)
			(xy 17.299839 -207.687873) (xy 17.280156 -207.639038) (xy 17.268159 -207.58777) (xy 17.264129 -207.535272)
			(xy 16.086074 -207.535272) (xy 16.086074 -208.38541) (xy 21.364197 -208.38541) (xy 21.368227 -208.332912)
			(xy 21.380224 -208.281644) (xy 21.399907 -208.232809) (xy 21.426813 -208.18755) (xy 21.460313 -208.146929)
			(xy 21.499621 -208.111898) (xy 21.543816 -208.083278) (xy 21.591861 -208.061739) (xy 21.642632 -208.047787)
			(xy 21.694937 -208.041749) (xy 21.747551 -208.043766) (xy 21.799241 -208.05379) (xy 21.848794 -208.071588)
			(xy 21.89505 -208.096741) (xy 21.936924 -208.12866) (xy 21.973436 -208.166598) (xy 22.003728 -208.209664)
			(xy 22.027091 -208.256849) (xy 22.042977 -208.307048) (xy 22.051014 -208.359084) (xy 22.051518 -208.38541)
			(xy 28.908251 -208.38541) (xy 28.912281 -208.332912) (xy 28.924278 -208.281644) (xy 28.943961 -208.232809)
			(xy 28.970867 -208.18755) (xy 29.004367 -208.146929) (xy 29.043675 -208.111898) (xy 29.08787 -208.083278)
			(xy 29.135915 -208.061739) (xy 29.186686 -208.047787) (xy 29.238991 -208.041749) (xy 29.291605 -208.043766)
			(xy 29.343295 -208.05379) (xy 29.392848 -208.071588) (xy 29.439104 -208.096741) (xy 29.480978 -208.12866)
			(xy 29.51749 -208.166598) (xy 29.547782 -208.209664) (xy 29.571145 -208.256849) (xy 29.587031 -208.307048)
			(xy 29.595068 -208.359084) (xy 29.595572 -208.38541) (xy 36.452051 -208.38541) (xy 36.456081 -208.332912)
			(xy 36.468078 -208.281644) (xy 36.487761 -208.232809) (xy 36.514667 -208.18755) (xy 36.548167 -208.146929)
			(xy 36.587475 -208.111898) (xy 36.63167 -208.083278) (xy 36.679715 -208.061739) (xy 36.730486 -208.047787)
			(xy 36.782791 -208.041749) (xy 36.835405 -208.043766) (xy 36.887095 -208.05379) (xy 36.936648 -208.071588)
			(xy 36.982904 -208.096741) (xy 37.024778 -208.12866) (xy 37.06129 -208.166598) (xy 37.091582 -208.209664)
			(xy 37.114945 -208.256849) (xy 37.130831 -208.307048) (xy 37.138868 -208.359084) (xy 37.139372 -208.38541)
			(xy 43.996105 -208.38541) (xy 44.000135 -208.332912) (xy 44.012132 -208.281644) (xy 44.031815 -208.232809)
			(xy 44.058721 -208.18755) (xy 44.092221 -208.146929) (xy 44.131529 -208.111898) (xy 44.175724 -208.083278)
			(xy 44.223769 -208.061739) (xy 44.27454 -208.047787) (xy 44.326845 -208.041749) (xy 44.379459 -208.043766)
			(xy 44.431149 -208.05379) (xy 44.480702 -208.071588) (xy 44.526958 -208.096741) (xy 44.568832 -208.12866)
			(xy 44.605344 -208.166598) (xy 44.635636 -208.209664) (xy 44.658999 -208.256849) (xy 44.674885 -208.307048)
			(xy 44.682922 -208.359084) (xy 44.683426 -208.38541) (xy 51.540159 -208.38541) (xy 51.544189 -208.332912)
			(xy 51.556186 -208.281644) (xy 51.575869 -208.232809) (xy 51.602775 -208.18755) (xy 51.636275 -208.146929)
			(xy 51.675583 -208.111898) (xy 51.719778 -208.083278) (xy 51.767823 -208.061739) (xy 51.818594 -208.047787)
			(xy 51.870899 -208.041749) (xy 51.923513 -208.043766) (xy 51.975203 -208.05379) (xy 52.024756 -208.071588)
			(xy 52.071012 -208.096741) (xy 52.112886 -208.12866) (xy 52.149398 -208.166598) (xy 52.17969 -208.209664)
			(xy 52.203053 -208.256849) (xy 52.218939 -208.307048) (xy 52.226976 -208.359084) (xy 52.22748 -208.38541)
			(xy 52.226976 -208.411736) (xy 52.218939 -208.463772) (xy 52.203053 -208.513971) (xy 52.17969 -208.561156)
			(xy 52.149398 -208.604222) (xy 52.112886 -208.64216) (xy 52.071012 -208.674079) (xy 52.024756 -208.699232)
			(xy 51.975203 -208.71703) (xy 51.923513 -208.727054) (xy 51.870899 -208.729071) (xy 51.818594 -208.723033)
			(xy 51.767823 -208.709081) (xy 51.719778 -208.687542) (xy 51.675583 -208.658922) (xy 51.636275 -208.623891)
			(xy 51.602775 -208.58327) (xy 51.575869 -208.538011) (xy 51.556186 -208.489176) (xy 51.544189 -208.437908)
			(xy 51.540159 -208.38541) (xy 44.683426 -208.38541) (xy 44.682922 -208.411736) (xy 44.674885 -208.463772)
			(xy 44.658999 -208.513971) (xy 44.635636 -208.561156) (xy 44.605344 -208.604222) (xy 44.568832 -208.64216)
			(xy 44.526958 -208.674079) (xy 44.480702 -208.699232) (xy 44.431149 -208.71703) (xy 44.379459 -208.727054)
			(xy 44.326845 -208.729071) (xy 44.27454 -208.723033) (xy 44.223769 -208.709081) (xy 44.175724 -208.687542)
			(xy 44.131529 -208.658922) (xy 44.092221 -208.623891) (xy 44.058721 -208.58327) (xy 44.031815 -208.538011)
			(xy 44.012132 -208.489176) (xy 44.000135 -208.437908) (xy 43.996105 -208.38541) (xy 37.139372 -208.38541)
			(xy 37.138868 -208.411736) (xy 37.130831 -208.463772) (xy 37.114945 -208.513971) (xy 37.091582 -208.561156)
			(xy 37.06129 -208.604222) (xy 37.024778 -208.64216) (xy 36.982904 -208.674079) (xy 36.936648 -208.699232)
			(xy 36.887095 -208.71703) (xy 36.835405 -208.727054) (xy 36.782791 -208.729071) (xy 36.730486 -208.723033)
			(xy 36.679715 -208.709081) (xy 36.63167 -208.687542) (xy 36.587475 -208.658922) (xy 36.548167 -208.623891)
			(xy 36.514667 -208.58327) (xy 36.487761 -208.538011) (xy 36.468078 -208.489176) (xy 36.456081 -208.437908)
			(xy 36.452051 -208.38541) (xy 29.595572 -208.38541) (xy 29.595068 -208.411736) (xy 29.587031 -208.463772)
			(xy 29.571145 -208.513971) (xy 29.547782 -208.561156) (xy 29.51749 -208.604222) (xy 29.480978 -208.64216)
			(xy 29.439104 -208.674079) (xy 29.392848 -208.699232) (xy 29.343295 -208.71703) (xy 29.291605 -208.727054)
			(xy 29.238991 -208.729071) (xy 29.186686 -208.723033) (xy 29.135915 -208.709081) (xy 29.08787 -208.687542)
			(xy 29.043675 -208.658922) (xy 29.004367 -208.623891) (xy 28.970867 -208.58327) (xy 28.943961 -208.538011)
			(xy 28.924278 -208.489176) (xy 28.912281 -208.437908) (xy 28.908251 -208.38541) (xy 22.051518 -208.38541)
			(xy 22.051014 -208.411736) (xy 22.042977 -208.463772) (xy 22.027091 -208.513971) (xy 22.003728 -208.561156)
			(xy 21.973436 -208.604222) (xy 21.936924 -208.64216) (xy 21.89505 -208.674079) (xy 21.848794 -208.699232)
			(xy 21.799241 -208.71703) (xy 21.747551 -208.727054) (xy 21.694937 -208.729071) (xy 21.642632 -208.723033)
			(xy 21.591861 -208.709081) (xy 21.543816 -208.687542) (xy 21.499621 -208.658922) (xy 21.460313 -208.623891)
			(xy 21.426813 -208.58327) (xy 21.399907 -208.538011) (xy 21.380224 -208.489176) (xy 21.368227 -208.437908)
			(xy 21.364197 -208.38541) (xy 16.086074 -208.38541) (xy 16.086074 -209.235294) (xy 17.264129 -209.235294)
			(xy 17.268159 -209.182796) (xy 17.280156 -209.131528) (xy 17.299839 -209.082693) (xy 17.326745 -209.037434)
			(xy 17.360245 -208.996813) (xy 17.399553 -208.961782) (xy 17.443748 -208.933162) (xy 17.491793 -208.911623)
			(xy 17.542564 -208.897671) (xy 17.594869 -208.891633) (xy 17.647483 -208.89365) (xy 17.699173 -208.903674)
			(xy 17.748726 -208.921472) (xy 17.794982 -208.946625) (xy 17.836856 -208.978544) (xy 17.873368 -209.016482)
			(xy 17.90366 -209.059548) (xy 17.927023 -209.106733) (xy 17.942909 -209.156932) (xy 17.950946 -209.208968)
			(xy 17.95145 -209.235294) (xy 24.808183 -209.235294) (xy 24.812213 -209.182796) (xy 24.82421 -209.131528)
			(xy 24.843893 -209.082693) (xy 24.870799 -209.037434) (xy 24.904299 -208.996813) (xy 24.943607 -208.961782)
			(xy 24.987802 -208.933162) (xy 25.035847 -208.911623) (xy 25.086618 -208.897671) (xy 25.138923 -208.891633)
			(xy 25.191537 -208.89365) (xy 25.243227 -208.903674) (xy 25.29278 -208.921472) (xy 25.339036 -208.946625)
			(xy 25.38091 -208.978544) (xy 25.417422 -209.016482) (xy 25.447714 -209.059548) (xy 25.471077 -209.106733)
			(xy 25.486963 -209.156932) (xy 25.495 -209.208968) (xy 25.495504 -209.235294) (xy 32.351983 -209.235294)
			(xy 32.356013 -209.182796) (xy 32.36801 -209.131528) (xy 32.387693 -209.082693) (xy 32.414599 -209.037434)
			(xy 32.448099 -208.996813) (xy 32.487407 -208.961782) (xy 32.531602 -208.933162) (xy 32.579647 -208.911623)
			(xy 32.630418 -208.897671) (xy 32.682723 -208.891633) (xy 32.735337 -208.89365) (xy 32.787027 -208.903674)
			(xy 32.83658 -208.921472) (xy 32.882836 -208.946625) (xy 32.92471 -208.978544) (xy 32.961222 -209.016482)
			(xy 32.991514 -209.059548) (xy 33.014877 -209.106733) (xy 33.030763 -209.156932) (xy 33.0388 -209.208968)
			(xy 33.039304 -209.235294) (xy 39.896037 -209.235294) (xy 39.900067 -209.182796) (xy 39.912064 -209.131528)
			(xy 39.931747 -209.082693) (xy 39.958653 -209.037434) (xy 39.992153 -208.996813) (xy 40.031461 -208.961782)
			(xy 40.075656 -208.933162) (xy 40.123701 -208.911623) (xy 40.174472 -208.897671) (xy 40.226777 -208.891633)
			(xy 40.279391 -208.89365) (xy 40.331081 -208.903674) (xy 40.380634 -208.921472) (xy 40.42689 -208.946625)
			(xy 40.468764 -208.978544) (xy 40.505276 -209.016482) (xy 40.535568 -209.059548) (xy 40.558931 -209.106733)
			(xy 40.574817 -209.156932) (xy 40.582854 -209.208968) (xy 40.583358 -209.235294) (xy 47.440091 -209.235294)
			(xy 47.444121 -209.182796) (xy 47.456118 -209.131528) (xy 47.475801 -209.082693) (xy 47.502707 -209.037434)
			(xy 47.536207 -208.996813) (xy 47.575515 -208.961782) (xy 47.61971 -208.933162) (xy 47.667755 -208.911623)
			(xy 47.718526 -208.897671) (xy 47.770831 -208.891633) (xy 47.823445 -208.89365) (xy 47.875135 -208.903674)
			(xy 47.924688 -208.921472) (xy 47.970944 -208.946625) (xy 48.012818 -208.978544) (xy 48.04933 -209.016482)
			(xy 48.079622 -209.059548) (xy 48.102985 -209.106733) (xy 48.118871 -209.156932) (xy 48.126908 -209.208968)
			(xy 48.127412 -209.235294) (xy 48.126908 -209.26162) (xy 48.118871 -209.313656) (xy 48.102985 -209.363855)
			(xy 48.079622 -209.41104) (xy 48.04933 -209.454106) (xy 48.012818 -209.492044) (xy 47.970944 -209.523963)
			(xy 47.924688 -209.549116) (xy 47.875135 -209.566914) (xy 47.823445 -209.576938) (xy 47.770831 -209.578955)
			(xy 47.718526 -209.572917) (xy 47.667755 -209.558965) (xy 47.61971 -209.537426) (xy 47.575515 -209.508806)
			(xy 47.536207 -209.473775) (xy 47.502707 -209.433154) (xy 47.475801 -209.387895) (xy 47.456118 -209.33906)
			(xy 47.444121 -209.287792) (xy 47.440091 -209.235294) (xy 40.583358 -209.235294) (xy 40.582854 -209.26162)
			(xy 40.574817 -209.313656) (xy 40.558931 -209.363855) (xy 40.535568 -209.41104) (xy 40.505276 -209.454106)
			(xy 40.468764 -209.492044) (xy 40.42689 -209.523963) (xy 40.380634 -209.549116) (xy 40.331081 -209.566914)
			(xy 40.279391 -209.576938) (xy 40.226777 -209.578955) (xy 40.174472 -209.572917) (xy 40.123701 -209.558965)
			(xy 40.075656 -209.537426) (xy 40.031461 -209.508806) (xy 39.992153 -209.473775) (xy 39.958653 -209.433154)
			(xy 39.931747 -209.387895) (xy 39.912064 -209.33906) (xy 39.900067 -209.287792) (xy 39.896037 -209.235294)
			(xy 33.039304 -209.235294) (xy 33.0388 -209.26162) (xy 33.030763 -209.313656) (xy 33.014877 -209.363855)
			(xy 32.991514 -209.41104) (xy 32.961222 -209.454106) (xy 32.92471 -209.492044) (xy 32.882836 -209.523963)
			(xy 32.83658 -209.549116) (xy 32.787027 -209.566914) (xy 32.735337 -209.576938) (xy 32.682723 -209.578955)
			(xy 32.630418 -209.572917) (xy 32.579647 -209.558965) (xy 32.531602 -209.537426) (xy 32.487407 -209.508806)
			(xy 32.448099 -209.473775) (xy 32.414599 -209.433154) (xy 32.387693 -209.387895) (xy 32.36801 -209.33906)
			(xy 32.356013 -209.287792) (xy 32.351983 -209.235294) (xy 25.495504 -209.235294) (xy 25.495 -209.26162)
			(xy 25.486963 -209.313656) (xy 25.471077 -209.363855) (xy 25.447714 -209.41104) (xy 25.417422 -209.454106)
			(xy 25.38091 -209.492044) (xy 25.339036 -209.523963) (xy 25.29278 -209.549116) (xy 25.243227 -209.566914)
			(xy 25.191537 -209.576938) (xy 25.138923 -209.578955) (xy 25.086618 -209.572917) (xy 25.035847 -209.558965)
			(xy 24.987802 -209.537426) (xy 24.943607 -209.508806) (xy 24.904299 -209.473775) (xy 24.870799 -209.433154)
			(xy 24.843893 -209.387895) (xy 24.82421 -209.33906) (xy 24.812213 -209.287792) (xy 24.808183 -209.235294)
			(xy 17.95145 -209.235294) (xy 17.950946 -209.26162) (xy 17.942909 -209.313656) (xy 17.927023 -209.363855)
			(xy 17.90366 -209.41104) (xy 17.873368 -209.454106) (xy 17.836856 -209.492044) (xy 17.794982 -209.523963)
			(xy 17.748726 -209.549116) (xy 17.699173 -209.566914) (xy 17.647483 -209.576938) (xy 17.594869 -209.578955)
			(xy 17.542564 -209.572917) (xy 17.491793 -209.558965) (xy 17.443748 -209.537426) (xy 17.399553 -209.508806)
			(xy 17.360245 -209.473775) (xy 17.326745 -209.433154) (xy 17.299839 -209.387895) (xy 17.280156 -209.33906)
			(xy 17.268159 -209.287792) (xy 17.264129 -209.235294) (xy 16.086074 -209.235294) (xy 16.086074 -210.085432)
			(xy 21.364197 -210.085432) (xy 21.368227 -210.032934) (xy 21.380224 -209.981666) (xy 21.399907 -209.932831)
			(xy 21.426813 -209.887572) (xy 21.460313 -209.846951) (xy 21.499621 -209.81192) (xy 21.543816 -209.7833)
			(xy 21.591861 -209.761761) (xy 21.642632 -209.747809) (xy 21.694937 -209.741771) (xy 21.747551 -209.743788)
			(xy 21.799241 -209.753812) (xy 21.848794 -209.77161) (xy 21.89505 -209.796763) (xy 21.936924 -209.828682)
			(xy 21.973436 -209.86662) (xy 22.003728 -209.909686) (xy 22.027091 -209.956871) (xy 22.042977 -210.00707)
			(xy 22.051014 -210.059106) (xy 22.051518 -210.085432) (xy 28.908251 -210.085432) (xy 28.912281 -210.032934)
			(xy 28.924278 -209.981666) (xy 28.943961 -209.932831) (xy 28.970867 -209.887572) (xy 29.004367 -209.846951)
			(xy 29.043675 -209.81192) (xy 29.08787 -209.7833) (xy 29.135915 -209.761761) (xy 29.186686 -209.747809)
			(xy 29.238991 -209.741771) (xy 29.291605 -209.743788) (xy 29.343295 -209.753812) (xy 29.392848 -209.77161)
			(xy 29.439104 -209.796763) (xy 29.480978 -209.828682) (xy 29.51749 -209.86662) (xy 29.547782 -209.909686)
			(xy 29.571145 -209.956871) (xy 29.587031 -210.00707) (xy 29.595068 -210.059106) (xy 29.595572 -210.085432)
			(xy 36.452051 -210.085432) (xy 36.456081 -210.032934) (xy 36.468078 -209.981666) (xy 36.487761 -209.932831)
			(xy 36.514667 -209.887572) (xy 36.548167 -209.846951) (xy 36.587475 -209.81192) (xy 36.63167 -209.7833)
			(xy 36.679715 -209.761761) (xy 36.730486 -209.747809) (xy 36.782791 -209.741771) (xy 36.835405 -209.743788)
			(xy 36.887095 -209.753812) (xy 36.936648 -209.77161) (xy 36.982904 -209.796763) (xy 37.024778 -209.828682)
			(xy 37.06129 -209.86662) (xy 37.091582 -209.909686) (xy 37.114945 -209.956871) (xy 37.130831 -210.00707)
			(xy 37.138868 -210.059106) (xy 37.139372 -210.085432) (xy 43.996105 -210.085432) (xy 44.000135 -210.032934)
			(xy 44.012132 -209.981666) (xy 44.031815 -209.932831) (xy 44.058721 -209.887572) (xy 44.092221 -209.846951)
			(xy 44.131529 -209.81192) (xy 44.175724 -209.7833) (xy 44.223769 -209.761761) (xy 44.27454 -209.747809)
			(xy 44.326845 -209.741771) (xy 44.379459 -209.743788) (xy 44.431149 -209.753812) (xy 44.480702 -209.77161)
			(xy 44.526958 -209.796763) (xy 44.568832 -209.828682) (xy 44.605344 -209.86662) (xy 44.635636 -209.909686)
			(xy 44.658999 -209.956871) (xy 44.674885 -210.00707) (xy 44.682922 -210.059106) (xy 44.683426 -210.085432)
			(xy 51.540159 -210.085432) (xy 51.544189 -210.032934) (xy 51.556186 -209.981666) (xy 51.575869 -209.932831)
			(xy 51.602775 -209.887572) (xy 51.636275 -209.846951) (xy 51.675583 -209.81192) (xy 51.719778 -209.7833)
			(xy 51.767823 -209.761761) (xy 51.818594 -209.747809) (xy 51.870899 -209.741771) (xy 51.923513 -209.743788)
			(xy 51.975203 -209.753812) (xy 52.024756 -209.77161) (xy 52.071012 -209.796763) (xy 52.112886 -209.828682)
			(xy 52.149398 -209.86662) (xy 52.17969 -209.909686) (xy 52.203053 -209.956871) (xy 52.218939 -210.00707)
			(xy 52.226976 -210.059106) (xy 52.22748 -210.085432) (xy 52.226976 -210.111758) (xy 52.218939 -210.163794)
			(xy 52.203053 -210.213993) (xy 52.17969 -210.261178) (xy 52.149398 -210.304244) (xy 52.112886 -210.342182)
			(xy 52.071012 -210.374101) (xy 52.024756 -210.399254) (xy 51.975203 -210.417052) (xy 51.923513 -210.427076)
			(xy 51.870899 -210.429093) (xy 51.818594 -210.423055) (xy 51.767823 -210.409103) (xy 51.719778 -210.387564)
			(xy 51.675583 -210.358944) (xy 51.636275 -210.323913) (xy 51.602775 -210.283292) (xy 51.575869 -210.238033)
			(xy 51.556186 -210.189198) (xy 51.544189 -210.13793) (xy 51.540159 -210.085432) (xy 44.683426 -210.085432)
			(xy 44.682922 -210.111758) (xy 44.674885 -210.163794) (xy 44.658999 -210.213993) (xy 44.635636 -210.261178)
			(xy 44.605344 -210.304244) (xy 44.568832 -210.342182) (xy 44.526958 -210.374101) (xy 44.480702 -210.399254)
			(xy 44.431149 -210.417052) (xy 44.379459 -210.427076) (xy 44.326845 -210.429093) (xy 44.27454 -210.423055)
			(xy 44.223769 -210.409103) (xy 44.175724 -210.387564) (xy 44.131529 -210.358944) (xy 44.092221 -210.323913)
			(xy 44.058721 -210.283292) (xy 44.031815 -210.238033) (xy 44.012132 -210.189198) (xy 44.000135 -210.13793)
			(xy 43.996105 -210.085432) (xy 37.139372 -210.085432) (xy 37.138868 -210.111758) (xy 37.130831 -210.163794)
			(xy 37.114945 -210.213993) (xy 37.091582 -210.261178) (xy 37.06129 -210.304244) (xy 37.024778 -210.342182)
			(xy 36.982904 -210.374101) (xy 36.936648 -210.399254) (xy 36.887095 -210.417052) (xy 36.835405 -210.427076)
			(xy 36.782791 -210.429093) (xy 36.730486 -210.423055) (xy 36.679715 -210.409103) (xy 36.63167 -210.387564)
			(xy 36.587475 -210.358944) (xy 36.548167 -210.323913) (xy 36.514667 -210.283292) (xy 36.487761 -210.238033)
			(xy 36.468078 -210.189198) (xy 36.456081 -210.13793) (xy 36.452051 -210.085432) (xy 29.595572 -210.085432)
			(xy 29.595068 -210.111758) (xy 29.587031 -210.163794) (xy 29.571145 -210.213993) (xy 29.547782 -210.261178)
			(xy 29.51749 -210.304244) (xy 29.480978 -210.342182) (xy 29.439104 -210.374101) (xy 29.392848 -210.399254)
			(xy 29.343295 -210.417052) (xy 29.291605 -210.427076) (xy 29.238991 -210.429093) (xy 29.186686 -210.423055)
			(xy 29.135915 -210.409103) (xy 29.08787 -210.387564) (xy 29.043675 -210.358944) (xy 29.004367 -210.323913)
			(xy 28.970867 -210.283292) (xy 28.943961 -210.238033) (xy 28.924278 -210.189198) (xy 28.912281 -210.13793)
			(xy 28.908251 -210.085432) (xy 22.051518 -210.085432) (xy 22.051014 -210.111758) (xy 22.042977 -210.163794)
			(xy 22.027091 -210.213993) (xy 22.003728 -210.261178) (xy 21.973436 -210.304244) (xy 21.936924 -210.342182)
			(xy 21.89505 -210.374101) (xy 21.848794 -210.399254) (xy 21.799241 -210.417052) (xy 21.747551 -210.427076)
			(xy 21.694937 -210.429093) (xy 21.642632 -210.423055) (xy 21.591861 -210.409103) (xy 21.543816 -210.387564)
			(xy 21.499621 -210.358944) (xy 21.460313 -210.323913) (xy 21.426813 -210.283292) (xy 21.399907 -210.238033)
			(xy 21.380224 -210.189198) (xy 21.368227 -210.13793) (xy 21.364197 -210.085432) (xy 16.086074 -210.085432)
			(xy 16.086074 -210.935316) (xy 17.264129 -210.935316) (xy 17.268159 -210.882818) (xy 17.280156 -210.83155)
			(xy 17.299839 -210.782715) (xy 17.326745 -210.737456) (xy 17.360245 -210.696835) (xy 17.399553 -210.661804)
			(xy 17.443748 -210.633184) (xy 17.491793 -210.611645) (xy 17.542564 -210.597693) (xy 17.594869 -210.591655)
			(xy 17.647483 -210.593672) (xy 17.699173 -210.603696) (xy 17.748726 -210.621494) (xy 17.794982 -210.646647)
			(xy 17.836856 -210.678566) (xy 17.873368 -210.716504) (xy 17.90366 -210.75957) (xy 17.927023 -210.806755)
			(xy 17.942909 -210.856954) (xy 17.950946 -210.90899) (xy 17.95145 -210.935316) (xy 21.364197 -210.935316)
			(xy 21.368227 -210.882818) (xy 21.380224 -210.83155) (xy 21.399907 -210.782715) (xy 21.426813 -210.737456)
			(xy 21.460313 -210.696835) (xy 21.499621 -210.661804) (xy 21.543816 -210.633184) (xy 21.591861 -210.611645)
			(xy 21.642632 -210.597693) (xy 21.694937 -210.591655) (xy 21.747551 -210.593672) (xy 21.799241 -210.603696)
			(xy 21.848794 -210.621494) (xy 21.89505 -210.646647) (xy 21.936924 -210.678566) (xy 21.973436 -210.716504)
			(xy 22.003728 -210.75957) (xy 22.027091 -210.806755) (xy 22.042977 -210.856954) (xy 22.051014 -210.90899)
			(xy 22.051518 -210.935316) (xy 24.808183 -210.935316) (xy 24.812213 -210.882818) (xy 24.82421 -210.83155)
			(xy 24.843893 -210.782715) (xy 24.870799 -210.737456) (xy 24.904299 -210.696835) (xy 24.943607 -210.661804)
			(xy 24.987802 -210.633184) (xy 25.035847 -210.611645) (xy 25.086618 -210.597693) (xy 25.138923 -210.591655)
			(xy 25.191537 -210.593672) (xy 25.243227 -210.603696) (xy 25.29278 -210.621494) (xy 25.339036 -210.646647)
			(xy 25.38091 -210.678566) (xy 25.417422 -210.716504) (xy 25.447714 -210.75957) (xy 25.471077 -210.806755)
			(xy 25.486963 -210.856954) (xy 25.495 -210.90899) (xy 25.495504 -210.935316) (xy 28.908251 -210.935316)
			(xy 28.912281 -210.882818) (xy 28.924278 -210.83155) (xy 28.943961 -210.782715) (xy 28.970867 -210.737456)
			(xy 29.004367 -210.696835) (xy 29.043675 -210.661804) (xy 29.08787 -210.633184) (xy 29.135915 -210.611645)
			(xy 29.186686 -210.597693) (xy 29.238991 -210.591655) (xy 29.291605 -210.593672) (xy 29.343295 -210.603696)
			(xy 29.392848 -210.621494) (xy 29.439104 -210.646647) (xy 29.480978 -210.678566) (xy 29.51749 -210.716504)
			(xy 29.547782 -210.75957) (xy 29.571145 -210.806755) (xy 29.587031 -210.856954) (xy 29.595068 -210.90899)
			(xy 29.595572 -210.935316) (xy 32.351983 -210.935316) (xy 32.356013 -210.882818) (xy 32.36801 -210.83155)
			(xy 32.387693 -210.782715) (xy 32.414599 -210.737456) (xy 32.448099 -210.696835) (xy 32.487407 -210.661804)
			(xy 32.531602 -210.633184) (xy 32.579647 -210.611645) (xy 32.630418 -210.597693) (xy 32.682723 -210.591655)
			(xy 32.735337 -210.593672) (xy 32.787027 -210.603696) (xy 32.83658 -210.621494) (xy 32.882836 -210.646647)
			(xy 32.92471 -210.678566) (xy 32.961222 -210.716504) (xy 32.991514 -210.75957) (xy 33.014877 -210.806755)
			(xy 33.030763 -210.856954) (xy 33.0388 -210.90899) (xy 33.039304 -210.935316) (xy 36.452051 -210.935316)
			(xy 36.456081 -210.882818) (xy 36.468078 -210.83155) (xy 36.487761 -210.782715) (xy 36.514667 -210.737456)
			(xy 36.548167 -210.696835) (xy 36.587475 -210.661804) (xy 36.63167 -210.633184) (xy 36.679715 -210.611645)
			(xy 36.730486 -210.597693) (xy 36.782791 -210.591655) (xy 36.835405 -210.593672) (xy 36.887095 -210.603696)
			(xy 36.936648 -210.621494) (xy 36.982904 -210.646647) (xy 37.024778 -210.678566) (xy 37.06129 -210.716504)
			(xy 37.091582 -210.75957) (xy 37.114945 -210.806755) (xy 37.130831 -210.856954) (xy 37.138868 -210.90899)
			(xy 37.139372 -210.935316) (xy 39.896037 -210.935316) (xy 39.900067 -210.882818) (xy 39.912064 -210.83155)
			(xy 39.931747 -210.782715) (xy 39.958653 -210.737456) (xy 39.992153 -210.696835) (xy 40.031461 -210.661804)
			(xy 40.075656 -210.633184) (xy 40.123701 -210.611645) (xy 40.174472 -210.597693) (xy 40.226777 -210.591655)
			(xy 40.279391 -210.593672) (xy 40.331081 -210.603696) (xy 40.380634 -210.621494) (xy 40.42689 -210.646647)
			(xy 40.468764 -210.678566) (xy 40.505276 -210.716504) (xy 40.535568 -210.75957) (xy 40.558931 -210.806755)
			(xy 40.574817 -210.856954) (xy 40.582854 -210.90899) (xy 40.583358 -210.935316) (xy 43.996105 -210.935316)
			(xy 44.000135 -210.882818) (xy 44.012132 -210.83155) (xy 44.031815 -210.782715) (xy 44.058721 -210.737456)
			(xy 44.092221 -210.696835) (xy 44.131529 -210.661804) (xy 44.175724 -210.633184) (xy 44.223769 -210.611645)
			(xy 44.27454 -210.597693) (xy 44.326845 -210.591655) (xy 44.379459 -210.593672) (xy 44.431149 -210.603696)
			(xy 44.480702 -210.621494) (xy 44.526958 -210.646647) (xy 44.568832 -210.678566) (xy 44.605344 -210.716504)
			(xy 44.635636 -210.75957) (xy 44.658999 -210.806755) (xy 44.674885 -210.856954) (xy 44.682922 -210.90899)
			(xy 44.683426 -210.935316) (xy 47.440091 -210.935316) (xy 47.444121 -210.882818) (xy 47.456118 -210.83155)
			(xy 47.475801 -210.782715) (xy 47.502707 -210.737456) (xy 47.536207 -210.696835) (xy 47.575515 -210.661804)
			(xy 47.61971 -210.633184) (xy 47.667755 -210.611645) (xy 47.718526 -210.597693) (xy 47.770831 -210.591655)
			(xy 47.823445 -210.593672) (xy 47.875135 -210.603696) (xy 47.924688 -210.621494) (xy 47.970944 -210.646647)
			(xy 48.012818 -210.678566) (xy 48.04933 -210.716504) (xy 48.079622 -210.75957) (xy 48.102985 -210.806755)
			(xy 48.118871 -210.856954) (xy 48.126908 -210.90899) (xy 48.127412 -210.935316) (xy 51.540159 -210.935316)
			(xy 51.544189 -210.882818) (xy 51.556186 -210.83155) (xy 51.575869 -210.782715) (xy 51.602775 -210.737456)
			(xy 51.636275 -210.696835) (xy 51.675583 -210.661804) (xy 51.719778 -210.633184) (xy 51.767823 -210.611645)
			(xy 51.818594 -210.597693) (xy 51.870899 -210.591655) (xy 51.923513 -210.593672) (xy 51.975203 -210.603696)
			(xy 52.024756 -210.621494) (xy 52.071012 -210.646647) (xy 52.112886 -210.678566) (xy 52.149398 -210.716504)
			(xy 52.17969 -210.75957) (xy 52.203053 -210.806755) (xy 52.218939 -210.856954) (xy 52.226976 -210.90899)
			(xy 52.22748 -210.935316) (xy 52.226976 -210.961642) (xy 52.218939 -211.013678) (xy 52.203053 -211.063877)
			(xy 52.17969 -211.111062) (xy 52.149398 -211.154128) (xy 52.112886 -211.192066) (xy 52.071012 -211.223985)
			(xy 52.024756 -211.249138) (xy 51.975203 -211.266936) (xy 51.923513 -211.27696) (xy 51.870899 -211.278977)
			(xy 51.818594 -211.272939) (xy 51.767823 -211.258987) (xy 51.719778 -211.237448) (xy 51.675583 -211.208828)
			(xy 51.636275 -211.173797) (xy 51.602775 -211.133176) (xy 51.575869 -211.087917) (xy 51.556186 -211.039082)
			(xy 51.544189 -210.987814) (xy 51.540159 -210.935316) (xy 48.127412 -210.935316) (xy 48.126908 -210.961642)
			(xy 48.118871 -211.013678) (xy 48.102985 -211.063877) (xy 48.079622 -211.111062) (xy 48.04933 -211.154128)
			(xy 48.012818 -211.192066) (xy 47.970944 -211.223985) (xy 47.924688 -211.249138) (xy 47.875135 -211.266936)
			(xy 47.823445 -211.27696) (xy 47.770831 -211.278977) (xy 47.718526 -211.272939) (xy 47.667755 -211.258987)
			(xy 47.61971 -211.237448) (xy 47.575515 -211.208828) (xy 47.536207 -211.173797) (xy 47.502707 -211.133176)
			(xy 47.475801 -211.087917) (xy 47.456118 -211.039082) (xy 47.444121 -210.987814) (xy 47.440091 -210.935316)
			(xy 44.683426 -210.935316) (xy 44.682922 -210.961642) (xy 44.674885 -211.013678) (xy 44.658999 -211.063877)
			(xy 44.635636 -211.111062) (xy 44.605344 -211.154128) (xy 44.568832 -211.192066) (xy 44.526958 -211.223985)
			(xy 44.480702 -211.249138) (xy 44.431149 -211.266936) (xy 44.379459 -211.27696) (xy 44.326845 -211.278977)
			(xy 44.27454 -211.272939) (xy 44.223769 -211.258987) (xy 44.175724 -211.237448) (xy 44.131529 -211.208828)
			(xy 44.092221 -211.173797) (xy 44.058721 -211.133176) (xy 44.031815 -211.087917) (xy 44.012132 -211.039082)
			(xy 44.000135 -210.987814) (xy 43.996105 -210.935316) (xy 40.583358 -210.935316) (xy 40.582854 -210.961642)
			(xy 40.574817 -211.013678) (xy 40.558931 -211.063877) (xy 40.535568 -211.111062) (xy 40.505276 -211.154128)
			(xy 40.468764 -211.192066) (xy 40.42689 -211.223985) (xy 40.380634 -211.249138) (xy 40.331081 -211.266936)
			(xy 40.279391 -211.27696) (xy 40.226777 -211.278977) (xy 40.174472 -211.272939) (xy 40.123701 -211.258987)
			(xy 40.075656 -211.237448) (xy 40.031461 -211.208828) (xy 39.992153 -211.173797) (xy 39.958653 -211.133176)
			(xy 39.931747 -211.087917) (xy 39.912064 -211.039082) (xy 39.900067 -210.987814) (xy 39.896037 -210.935316)
			(xy 37.139372 -210.935316) (xy 37.138868 -210.961642) (xy 37.130831 -211.013678) (xy 37.114945 -211.063877)
			(xy 37.091582 -211.111062) (xy 37.06129 -211.154128) (xy 37.024778 -211.192066) (xy 36.982904 -211.223985)
			(xy 36.936648 -211.249138) (xy 36.887095 -211.266936) (xy 36.835405 -211.27696) (xy 36.782791 -211.278977)
			(xy 36.730486 -211.272939) (xy 36.679715 -211.258987) (xy 36.63167 -211.237448) (xy 36.587475 -211.208828)
			(xy 36.548167 -211.173797) (xy 36.514667 -211.133176) (xy 36.487761 -211.087917) (xy 36.468078 -211.039082)
			(xy 36.456081 -210.987814) (xy 36.452051 -210.935316) (xy 33.039304 -210.935316) (xy 33.0388 -210.961642)
			(xy 33.030763 -211.013678) (xy 33.014877 -211.063877) (xy 32.991514 -211.111062) (xy 32.961222 -211.154128)
			(xy 32.92471 -211.192066) (xy 32.882836 -211.223985) (xy 32.83658 -211.249138) (xy 32.787027 -211.266936)
			(xy 32.735337 -211.27696) (xy 32.682723 -211.278977) (xy 32.630418 -211.272939) (xy 32.579647 -211.258987)
			(xy 32.531602 -211.237448) (xy 32.487407 -211.208828) (xy 32.448099 -211.173797) (xy 32.414599 -211.133176)
			(xy 32.387693 -211.087917) (xy 32.36801 -211.039082) (xy 32.356013 -210.987814) (xy 32.351983 -210.935316)
			(xy 29.595572 -210.935316) (xy 29.595068 -210.961642) (xy 29.587031 -211.013678) (xy 29.571145 -211.063877)
			(xy 29.547782 -211.111062) (xy 29.51749 -211.154128) (xy 29.480978 -211.192066) (xy 29.439104 -211.223985)
			(xy 29.392848 -211.249138) (xy 29.343295 -211.266936) (xy 29.291605 -211.27696) (xy 29.238991 -211.278977)
			(xy 29.186686 -211.272939) (xy 29.135915 -211.258987) (xy 29.08787 -211.237448) (xy 29.043675 -211.208828)
			(xy 29.004367 -211.173797) (xy 28.970867 -211.133176) (xy 28.943961 -211.087917) (xy 28.924278 -211.039082)
			(xy 28.912281 -210.987814) (xy 28.908251 -210.935316) (xy 25.495504 -210.935316) (xy 25.495 -210.961642)
			(xy 25.486963 -211.013678) (xy 25.471077 -211.063877) (xy 25.447714 -211.111062) (xy 25.417422 -211.154128)
			(xy 25.38091 -211.192066) (xy 25.339036 -211.223985) (xy 25.29278 -211.249138) (xy 25.243227 -211.266936)
			(xy 25.191537 -211.27696) (xy 25.138923 -211.278977) (xy 25.086618 -211.272939) (xy 25.035847 -211.258987)
			(xy 24.987802 -211.237448) (xy 24.943607 -211.208828) (xy 24.904299 -211.173797) (xy 24.870799 -211.133176)
			(xy 24.843893 -211.087917) (xy 24.82421 -211.039082) (xy 24.812213 -210.987814) (xy 24.808183 -210.935316)
			(xy 22.051518 -210.935316) (xy 22.051014 -210.961642) (xy 22.042977 -211.013678) (xy 22.027091 -211.063877)
			(xy 22.003728 -211.111062) (xy 21.973436 -211.154128) (xy 21.936924 -211.192066) (xy 21.89505 -211.223985)
			(xy 21.848794 -211.249138) (xy 21.799241 -211.266936) (xy 21.747551 -211.27696) (xy 21.694937 -211.278977)
			(xy 21.642632 -211.272939) (xy 21.591861 -211.258987) (xy 21.543816 -211.237448) (xy 21.499621 -211.208828)
			(xy 21.460313 -211.173797) (xy 21.426813 -211.133176) (xy 21.399907 -211.087917) (xy 21.380224 -211.039082)
			(xy 21.368227 -210.987814) (xy 21.364197 -210.935316) (xy 17.95145 -210.935316) (xy 17.950946 -210.961642)
			(xy 17.942909 -211.013678) (xy 17.927023 -211.063877) (xy 17.90366 -211.111062) (xy 17.873368 -211.154128)
			(xy 17.836856 -211.192066) (xy 17.794982 -211.223985) (xy 17.748726 -211.249138) (xy 17.699173 -211.266936)
			(xy 17.647483 -211.27696) (xy 17.594869 -211.278977) (xy 17.542564 -211.272939) (xy 17.491793 -211.258987)
			(xy 17.443748 -211.237448) (xy 17.399553 -211.208828) (xy 17.360245 -211.173797) (xy 17.326745 -211.133176)
			(xy 17.299839 -211.087917) (xy 17.280156 -211.039082) (xy 17.268159 -210.987814) (xy 17.264129 -210.935316)
			(xy 16.086074 -210.935316) (xy 16.086074 -211.7852) (xy 17.264129 -211.7852) (xy 17.268159 -211.732702)
			(xy 17.280156 -211.681434) (xy 17.299839 -211.632599) (xy 17.326745 -211.58734) (xy 17.360245 -211.546719)
			(xy 17.399553 -211.511688) (xy 17.443748 -211.483068) (xy 17.491793 -211.461529) (xy 17.542564 -211.447577)
			(xy 17.594869 -211.441539) (xy 17.647483 -211.443556) (xy 17.699173 -211.45358) (xy 17.748726 -211.471378)
			(xy 17.794982 -211.496531) (xy 17.836856 -211.52845) (xy 17.873368 -211.566388) (xy 17.90366 -211.609454)
			(xy 17.927023 -211.656639) (xy 17.942909 -211.706838) (xy 17.950946 -211.758874) (xy 17.95145 -211.7852)
			(xy 24.808183 -211.7852) (xy 24.812213 -211.732702) (xy 24.82421 -211.681434) (xy 24.843893 -211.632599)
			(xy 24.870799 -211.58734) (xy 24.904299 -211.546719) (xy 24.943607 -211.511688) (xy 24.987802 -211.483068)
			(xy 25.035847 -211.461529) (xy 25.086618 -211.447577) (xy 25.138923 -211.441539) (xy 25.191537 -211.443556)
			(xy 25.243227 -211.45358) (xy 25.29278 -211.471378) (xy 25.339036 -211.496531) (xy 25.38091 -211.52845)
			(xy 25.417422 -211.566388) (xy 25.447714 -211.609454) (xy 25.471077 -211.656639) (xy 25.486963 -211.706838)
			(xy 25.495 -211.758874) (xy 25.495504 -211.7852) (xy 32.351983 -211.7852) (xy 32.356013 -211.732702)
			(xy 32.36801 -211.681434) (xy 32.387693 -211.632599) (xy 32.414599 -211.58734) (xy 32.448099 -211.546719)
			(xy 32.487407 -211.511688) (xy 32.531602 -211.483068) (xy 32.579647 -211.461529) (xy 32.630418 -211.447577)
			(xy 32.682723 -211.441539) (xy 32.735337 -211.443556) (xy 32.787027 -211.45358) (xy 32.83658 -211.471378)
			(xy 32.882836 -211.496531) (xy 32.92471 -211.52845) (xy 32.961222 -211.566388) (xy 32.991514 -211.609454)
			(xy 33.014877 -211.656639) (xy 33.030763 -211.706838) (xy 33.0388 -211.758874) (xy 33.039304 -211.7852)
			(xy 39.896037 -211.7852) (xy 39.900067 -211.732702) (xy 39.912064 -211.681434) (xy 39.931747 -211.632599)
			(xy 39.958653 -211.58734) (xy 39.992153 -211.546719) (xy 40.031461 -211.511688) (xy 40.075656 -211.483068)
			(xy 40.123701 -211.461529) (xy 40.174472 -211.447577) (xy 40.226777 -211.441539) (xy 40.279391 -211.443556)
			(xy 40.331081 -211.45358) (xy 40.380634 -211.471378) (xy 40.42689 -211.496531) (xy 40.468764 -211.52845)
			(xy 40.505276 -211.566388) (xy 40.535568 -211.609454) (xy 40.558931 -211.656639) (xy 40.574817 -211.706838)
			(xy 40.582854 -211.758874) (xy 40.583358 -211.7852) (xy 47.440091 -211.7852) (xy 47.444121 -211.732702)
			(xy 47.456118 -211.681434) (xy 47.475801 -211.632599) (xy 47.502707 -211.58734) (xy 47.536207 -211.546719)
			(xy 47.575515 -211.511688) (xy 47.61971 -211.483068) (xy 47.667755 -211.461529) (xy 47.718526 -211.447577)
			(xy 47.770831 -211.441539) (xy 47.823445 -211.443556) (xy 47.875135 -211.45358) (xy 47.924688 -211.471378)
			(xy 47.970944 -211.496531) (xy 48.012818 -211.52845) (xy 48.04933 -211.566388) (xy 48.079622 -211.609454)
			(xy 48.102985 -211.656639) (xy 48.118871 -211.706838) (xy 48.126908 -211.758874) (xy 48.127412 -211.7852)
			(xy 48.126908 -211.811526) (xy 48.118871 -211.863562) (xy 48.102985 -211.913761) (xy 48.079622 -211.960946)
			(xy 48.04933 -212.004012) (xy 48.012818 -212.04195) (xy 47.970944 -212.073869) (xy 47.924688 -212.099022)
			(xy 47.875135 -212.11682) (xy 47.823445 -212.126844) (xy 47.770831 -212.128861) (xy 47.718526 -212.122823)
			(xy 47.667755 -212.108871) (xy 47.61971 -212.087332) (xy 47.575515 -212.058712) (xy 47.536207 -212.023681)
			(xy 47.502707 -211.98306) (xy 47.475801 -211.937801) (xy 47.456118 -211.888966) (xy 47.444121 -211.837698)
			(xy 47.440091 -211.7852) (xy 40.583358 -211.7852) (xy 40.582854 -211.811526) (xy 40.574817 -211.863562)
			(xy 40.558931 -211.913761) (xy 40.535568 -211.960946) (xy 40.505276 -212.004012) (xy 40.468764 -212.04195)
			(xy 40.42689 -212.073869) (xy 40.380634 -212.099022) (xy 40.331081 -212.11682) (xy 40.279391 -212.126844)
			(xy 40.226777 -212.128861) (xy 40.174472 -212.122823) (xy 40.123701 -212.108871) (xy 40.075656 -212.087332)
			(xy 40.031461 -212.058712) (xy 39.992153 -212.023681) (xy 39.958653 -211.98306) (xy 39.931747 -211.937801)
			(xy 39.912064 -211.888966) (xy 39.900067 -211.837698) (xy 39.896037 -211.7852) (xy 33.039304 -211.7852)
			(xy 33.0388 -211.811526) (xy 33.030763 -211.863562) (xy 33.014877 -211.913761) (xy 32.991514 -211.960946)
			(xy 32.961222 -212.004012) (xy 32.92471 -212.04195) (xy 32.882836 -212.073869) (xy 32.83658 -212.099022)
			(xy 32.787027 -212.11682) (xy 32.735337 -212.126844) (xy 32.682723 -212.128861) (xy 32.630418 -212.122823)
			(xy 32.579647 -212.108871) (xy 32.531602 -212.087332) (xy 32.487407 -212.058712) (xy 32.448099 -212.023681)
			(xy 32.414599 -211.98306) (xy 32.387693 -211.937801) (xy 32.36801 -211.888966) (xy 32.356013 -211.837698)
			(xy 32.351983 -211.7852) (xy 25.495504 -211.7852) (xy 25.495 -211.811526) (xy 25.486963 -211.863562)
			(xy 25.471077 -211.913761) (xy 25.447714 -211.960946) (xy 25.417422 -212.004012) (xy 25.38091 -212.04195)
			(xy 25.339036 -212.073869) (xy 25.29278 -212.099022) (xy 25.243227 -212.11682) (xy 25.191537 -212.126844)
			(xy 25.138923 -212.128861) (xy 25.086618 -212.122823) (xy 25.035847 -212.108871) (xy 24.987802 -212.087332)
			(xy 24.943607 -212.058712) (xy 24.904299 -212.023681) (xy 24.870799 -211.98306) (xy 24.843893 -211.937801)
			(xy 24.82421 -211.888966) (xy 24.812213 -211.837698) (xy 24.808183 -211.7852) (xy 17.95145 -211.7852)
			(xy 17.950946 -211.811526) (xy 17.942909 -211.863562) (xy 17.927023 -211.913761) (xy 17.90366 -211.960946)
			(xy 17.873368 -212.004012) (xy 17.836856 -212.04195) (xy 17.794982 -212.073869) (xy 17.748726 -212.099022)
			(xy 17.699173 -212.11682) (xy 17.647483 -212.126844) (xy 17.594869 -212.128861) (xy 17.542564 -212.122823)
			(xy 17.491793 -212.108871) (xy 17.443748 -212.087332) (xy 17.399553 -212.058712) (xy 17.360245 -212.023681)
			(xy 17.326745 -211.98306) (xy 17.299839 -211.937801) (xy 17.280156 -211.888966) (xy 17.268159 -211.837698)
			(xy 17.264129 -211.7852) (xy 16.086074 -211.7852) (xy 16.086074 -212.635338) (xy 21.364197 -212.635338)
			(xy 21.368227 -212.58284) (xy 21.380224 -212.531572) (xy 21.399907 -212.482737) (xy 21.426813 -212.437478)
			(xy 21.460313 -212.396857) (xy 21.499621 -212.361826) (xy 21.543816 -212.333206) (xy 21.591861 -212.311667)
			(xy 21.642632 -212.297715) (xy 21.694937 -212.291677) (xy 21.747551 -212.293694) (xy 21.799241 -212.303718)
			(xy 21.848794 -212.321516) (xy 21.89505 -212.346669) (xy 21.936924 -212.378588) (xy 21.973436 -212.416526)
			(xy 22.003728 -212.459592) (xy 22.027091 -212.506777) (xy 22.042977 -212.556976) (xy 22.051014 -212.609012)
			(xy 22.051518 -212.635338) (xy 28.908251 -212.635338) (xy 28.912281 -212.58284) (xy 28.924278 -212.531572)
			(xy 28.943961 -212.482737) (xy 28.970867 -212.437478) (xy 29.004367 -212.396857) (xy 29.043675 -212.361826)
			(xy 29.08787 -212.333206) (xy 29.135915 -212.311667) (xy 29.186686 -212.297715) (xy 29.238991 -212.291677)
			(xy 29.291605 -212.293694) (xy 29.343295 -212.303718) (xy 29.392848 -212.321516) (xy 29.439104 -212.346669)
			(xy 29.480978 -212.378588) (xy 29.51749 -212.416526) (xy 29.547782 -212.459592) (xy 29.571145 -212.506777)
			(xy 29.587031 -212.556976) (xy 29.595068 -212.609012) (xy 29.595572 -212.635338) (xy 36.452051 -212.635338)
			(xy 36.456081 -212.58284) (xy 36.468078 -212.531572) (xy 36.487761 -212.482737) (xy 36.514667 -212.437478)
			(xy 36.548167 -212.396857) (xy 36.587475 -212.361826) (xy 36.63167 -212.333206) (xy 36.679715 -212.311667)
			(xy 36.730486 -212.297715) (xy 36.782791 -212.291677) (xy 36.835405 -212.293694) (xy 36.887095 -212.303718)
			(xy 36.936648 -212.321516) (xy 36.982904 -212.346669) (xy 37.024778 -212.378588) (xy 37.06129 -212.416526)
			(xy 37.091582 -212.459592) (xy 37.114945 -212.506777) (xy 37.130831 -212.556976) (xy 37.138868 -212.609012)
			(xy 37.139372 -212.635338) (xy 43.996105 -212.635338) (xy 44.000135 -212.58284) (xy 44.012132 -212.531572)
			(xy 44.031815 -212.482737) (xy 44.058721 -212.437478) (xy 44.092221 -212.396857) (xy 44.131529 -212.361826)
			(xy 44.175724 -212.333206) (xy 44.223769 -212.311667) (xy 44.27454 -212.297715) (xy 44.326845 -212.291677)
			(xy 44.379459 -212.293694) (xy 44.431149 -212.303718) (xy 44.480702 -212.321516) (xy 44.526958 -212.346669)
			(xy 44.568832 -212.378588) (xy 44.605344 -212.416526) (xy 44.635636 -212.459592) (xy 44.658999 -212.506777)
			(xy 44.674885 -212.556976) (xy 44.682922 -212.609012) (xy 44.683426 -212.635338) (xy 51.540159 -212.635338)
			(xy 51.544189 -212.58284) (xy 51.556186 -212.531572) (xy 51.575869 -212.482737) (xy 51.602775 -212.437478)
			(xy 51.636275 -212.396857) (xy 51.675583 -212.361826) (xy 51.719778 -212.333206) (xy 51.767823 -212.311667)
			(xy 51.818594 -212.297715) (xy 51.870899 -212.291677) (xy 51.923513 -212.293694) (xy 51.975203 -212.303718)
			(xy 52.024756 -212.321516) (xy 52.071012 -212.346669) (xy 52.112886 -212.378588) (xy 52.149398 -212.416526)
			(xy 52.17969 -212.459592) (xy 52.203053 -212.506777) (xy 52.218939 -212.556976) (xy 52.226976 -212.609012)
			(xy 52.22748 -212.635338) (xy 52.226976 -212.661664) (xy 52.218939 -212.7137) (xy 52.203053 -212.763899)
			(xy 52.17969 -212.811084) (xy 52.149398 -212.85415) (xy 52.112886 -212.892088) (xy 52.071012 -212.924007)
			(xy 52.024756 -212.94916) (xy 51.975203 -212.966958) (xy 51.923513 -212.976982) (xy 51.870899 -212.978999)
			(xy 51.818594 -212.972961) (xy 51.767823 -212.959009) (xy 51.719778 -212.93747) (xy 51.675583 -212.90885)
			(xy 51.636275 -212.873819) (xy 51.602775 -212.833198) (xy 51.575869 -212.787939) (xy 51.556186 -212.739104)
			(xy 51.544189 -212.687836) (xy 51.540159 -212.635338) (xy 44.683426 -212.635338) (xy 44.682922 -212.661664)
			(xy 44.674885 -212.7137) (xy 44.658999 -212.763899) (xy 44.635636 -212.811084) (xy 44.605344 -212.85415)
			(xy 44.568832 -212.892088) (xy 44.526958 -212.924007) (xy 44.480702 -212.94916) (xy 44.431149 -212.966958)
			(xy 44.379459 -212.976982) (xy 44.326845 -212.978999) (xy 44.27454 -212.972961) (xy 44.223769 -212.959009)
			(xy 44.175724 -212.93747) (xy 44.131529 -212.90885) (xy 44.092221 -212.873819) (xy 44.058721 -212.833198)
			(xy 44.031815 -212.787939) (xy 44.012132 -212.739104) (xy 44.000135 -212.687836) (xy 43.996105 -212.635338)
			(xy 37.139372 -212.635338) (xy 37.138868 -212.661664) (xy 37.130831 -212.7137) (xy 37.114945 -212.763899)
			(xy 37.091582 -212.811084) (xy 37.06129 -212.85415) (xy 37.024778 -212.892088) (xy 36.982904 -212.924007)
			(xy 36.936648 -212.94916) (xy 36.887095 -212.966958) (xy 36.835405 -212.976982) (xy 36.782791 -212.978999)
			(xy 36.730486 -212.972961) (xy 36.679715 -212.959009) (xy 36.63167 -212.93747) (xy 36.587475 -212.90885)
			(xy 36.548167 -212.873819) (xy 36.514667 -212.833198) (xy 36.487761 -212.787939) (xy 36.468078 -212.739104)
			(xy 36.456081 -212.687836) (xy 36.452051 -212.635338) (xy 29.595572 -212.635338) (xy 29.595068 -212.661664)
			(xy 29.587031 -212.7137) (xy 29.571145 -212.763899) (xy 29.547782 -212.811084) (xy 29.51749 -212.85415)
			(xy 29.480978 -212.892088) (xy 29.439104 -212.924007) (xy 29.392848 -212.94916) (xy 29.343295 -212.966958)
			(xy 29.291605 -212.976982) (xy 29.238991 -212.978999) (xy 29.186686 -212.972961) (xy 29.135915 -212.959009)
			(xy 29.08787 -212.93747) (xy 29.043675 -212.90885) (xy 29.004367 -212.873819) (xy 28.970867 -212.833198)
			(xy 28.943961 -212.787939) (xy 28.924278 -212.739104) (xy 28.912281 -212.687836) (xy 28.908251 -212.635338)
			(xy 22.051518 -212.635338) (xy 22.051014 -212.661664) (xy 22.042977 -212.7137) (xy 22.027091 -212.763899)
			(xy 22.003728 -212.811084) (xy 21.973436 -212.85415) (xy 21.936924 -212.892088) (xy 21.89505 -212.924007)
			(xy 21.848794 -212.94916) (xy 21.799241 -212.966958) (xy 21.747551 -212.976982) (xy 21.694937 -212.978999)
			(xy 21.642632 -212.972961) (xy 21.591861 -212.959009) (xy 21.543816 -212.93747) (xy 21.499621 -212.90885)
			(xy 21.460313 -212.873819) (xy 21.426813 -212.833198) (xy 21.399907 -212.787939) (xy 21.380224 -212.739104)
			(xy 21.368227 -212.687836) (xy 21.364197 -212.635338) (xy 16.086074 -212.635338) (xy 16.086074 -213.485222)
			(xy 17.264129 -213.485222) (xy 17.268159 -213.432724) (xy 17.280156 -213.381456) (xy 17.299839 -213.332621)
			(xy 17.326745 -213.287362) (xy 17.360245 -213.246741) (xy 17.399553 -213.21171) (xy 17.443748 -213.18309)
			(xy 17.491793 -213.161551) (xy 17.542564 -213.147599) (xy 17.594869 -213.141561) (xy 17.647483 -213.143578)
			(xy 17.699173 -213.153602) (xy 17.748726 -213.1714) (xy 17.794982 -213.196553) (xy 17.836856 -213.228472)
			(xy 17.873368 -213.26641) (xy 17.90366 -213.309476) (xy 17.927023 -213.356661) (xy 17.942909 -213.40686)
			(xy 17.950946 -213.458896) (xy 17.95145 -213.485222) (xy 24.808183 -213.485222) (xy 24.812213 -213.432724)
			(xy 24.82421 -213.381456) (xy 24.843893 -213.332621) (xy 24.870799 -213.287362) (xy 24.904299 -213.246741)
			(xy 24.943607 -213.21171) (xy 24.987802 -213.18309) (xy 25.035847 -213.161551) (xy 25.086618 -213.147599)
			(xy 25.138923 -213.141561) (xy 25.191537 -213.143578) (xy 25.243227 -213.153602) (xy 25.29278 -213.1714)
			(xy 25.339036 -213.196553) (xy 25.38091 -213.228472) (xy 25.417422 -213.26641) (xy 25.447714 -213.309476)
			(xy 25.471077 -213.356661) (xy 25.486963 -213.40686) (xy 25.495 -213.458896) (xy 25.495504 -213.485222)
			(xy 32.351983 -213.485222) (xy 32.356013 -213.432724) (xy 32.36801 -213.381456) (xy 32.387693 -213.332621)
			(xy 32.414599 -213.287362) (xy 32.448099 -213.246741) (xy 32.487407 -213.21171) (xy 32.531602 -213.18309)
			(xy 32.579647 -213.161551) (xy 32.630418 -213.147599) (xy 32.682723 -213.141561) (xy 32.735337 -213.143578)
			(xy 32.787027 -213.153602) (xy 32.83658 -213.1714) (xy 32.882836 -213.196553) (xy 32.92471 -213.228472)
			(xy 32.961222 -213.26641) (xy 32.991514 -213.309476) (xy 33.014877 -213.356661) (xy 33.030763 -213.40686)
			(xy 33.0388 -213.458896) (xy 33.039304 -213.485222) (xy 39.896037 -213.485222) (xy 39.900067 -213.432724)
			(xy 39.912064 -213.381456) (xy 39.931747 -213.332621) (xy 39.958653 -213.287362) (xy 39.992153 -213.246741)
			(xy 40.031461 -213.21171) (xy 40.075656 -213.18309) (xy 40.123701 -213.161551) (xy 40.174472 -213.147599)
			(xy 40.226777 -213.141561) (xy 40.279391 -213.143578) (xy 40.331081 -213.153602) (xy 40.380634 -213.1714)
			(xy 40.42689 -213.196553) (xy 40.468764 -213.228472) (xy 40.505276 -213.26641) (xy 40.535568 -213.309476)
			(xy 40.558931 -213.356661) (xy 40.574817 -213.40686) (xy 40.582854 -213.458896) (xy 40.583358 -213.485222)
			(xy 47.440091 -213.485222) (xy 47.444121 -213.432724) (xy 47.456118 -213.381456) (xy 47.475801 -213.332621)
			(xy 47.502707 -213.287362) (xy 47.536207 -213.246741) (xy 47.575515 -213.21171) (xy 47.61971 -213.18309)
			(xy 47.667755 -213.161551) (xy 47.718526 -213.147599) (xy 47.770831 -213.141561) (xy 47.823445 -213.143578)
			(xy 47.875135 -213.153602) (xy 47.924688 -213.1714) (xy 47.970944 -213.196553) (xy 48.012818 -213.228472)
			(xy 48.04933 -213.26641) (xy 48.079622 -213.309476) (xy 48.102985 -213.356661) (xy 48.118871 -213.40686)
			(xy 48.126908 -213.458896) (xy 48.127412 -213.485222) (xy 48.126908 -213.511548) (xy 48.118871 -213.563584)
			(xy 48.102985 -213.613783) (xy 48.079622 -213.660968) (xy 48.04933 -213.704034) (xy 48.012818 -213.741972)
			(xy 47.970944 -213.773891) (xy 47.924688 -213.799044) (xy 47.875135 -213.816842) (xy 47.823445 -213.826866)
			(xy 47.770831 -213.828883) (xy 47.718526 -213.822845) (xy 47.667755 -213.808893) (xy 47.61971 -213.787354)
			(xy 47.575515 -213.758734) (xy 47.536207 -213.723703) (xy 47.502707 -213.683082) (xy 47.475801 -213.637823)
			(xy 47.456118 -213.588988) (xy 47.444121 -213.53772) (xy 47.440091 -213.485222) (xy 40.583358 -213.485222)
			(xy 40.582854 -213.511548) (xy 40.574817 -213.563584) (xy 40.558931 -213.613783) (xy 40.535568 -213.660968)
			(xy 40.505276 -213.704034) (xy 40.468764 -213.741972) (xy 40.42689 -213.773891) (xy 40.380634 -213.799044)
			(xy 40.331081 -213.816842) (xy 40.279391 -213.826866) (xy 40.226777 -213.828883) (xy 40.174472 -213.822845)
			(xy 40.123701 -213.808893) (xy 40.075656 -213.787354) (xy 40.031461 -213.758734) (xy 39.992153 -213.723703)
			(xy 39.958653 -213.683082) (xy 39.931747 -213.637823) (xy 39.912064 -213.588988) (xy 39.900067 -213.53772)
			(xy 39.896037 -213.485222) (xy 33.039304 -213.485222) (xy 33.0388 -213.511548) (xy 33.030763 -213.563584)
			(xy 33.014877 -213.613783) (xy 32.991514 -213.660968) (xy 32.961222 -213.704034) (xy 32.92471 -213.741972)
			(xy 32.882836 -213.773891) (xy 32.83658 -213.799044) (xy 32.787027 -213.816842) (xy 32.735337 -213.826866)
			(xy 32.682723 -213.828883) (xy 32.630418 -213.822845) (xy 32.579647 -213.808893) (xy 32.531602 -213.787354)
			(xy 32.487407 -213.758734) (xy 32.448099 -213.723703) (xy 32.414599 -213.683082) (xy 32.387693 -213.637823)
			(xy 32.36801 -213.588988) (xy 32.356013 -213.53772) (xy 32.351983 -213.485222) (xy 25.495504 -213.485222)
			(xy 25.495 -213.511548) (xy 25.486963 -213.563584) (xy 25.471077 -213.613783) (xy 25.447714 -213.660968)
			(xy 25.417422 -213.704034) (xy 25.38091 -213.741972) (xy 25.339036 -213.773891) (xy 25.29278 -213.799044)
			(xy 25.243227 -213.816842) (xy 25.191537 -213.826866) (xy 25.138923 -213.828883) (xy 25.086618 -213.822845)
			(xy 25.035847 -213.808893) (xy 24.987802 -213.787354) (xy 24.943607 -213.758734) (xy 24.904299 -213.723703)
			(xy 24.870799 -213.683082) (xy 24.843893 -213.637823) (xy 24.82421 -213.588988) (xy 24.812213 -213.53772)
			(xy 24.808183 -213.485222) (xy 17.95145 -213.485222) (xy 17.950946 -213.511548) (xy 17.942909 -213.563584)
			(xy 17.927023 -213.613783) (xy 17.90366 -213.660968) (xy 17.873368 -213.704034) (xy 17.836856 -213.741972)
			(xy 17.794982 -213.773891) (xy 17.748726 -213.799044) (xy 17.699173 -213.816842) (xy 17.647483 -213.826866)
			(xy 17.594869 -213.828883) (xy 17.542564 -213.822845) (xy 17.491793 -213.808893) (xy 17.443748 -213.787354)
			(xy 17.399553 -213.758734) (xy 17.360245 -213.723703) (xy 17.326745 -213.683082) (xy 17.299839 -213.637823)
			(xy 17.280156 -213.588988) (xy 17.268159 -213.53772) (xy 17.264129 -213.485222) (xy 16.086074 -213.485222)
			(xy 16.086074 -214.33536) (xy 21.364197 -214.33536) (xy 21.368227 -214.282862) (xy 21.380224 -214.231594)
			(xy 21.399907 -214.182759) (xy 21.426813 -214.1375) (xy 21.460313 -214.096879) (xy 21.499621 -214.061848)
			(xy 21.543816 -214.033228) (xy 21.591861 -214.011689) (xy 21.642632 -213.997737) (xy 21.694937 -213.991699)
			(xy 21.747551 -213.993716) (xy 21.799241 -214.00374) (xy 21.848794 -214.021538) (xy 21.89505 -214.046691)
			(xy 21.936924 -214.07861) (xy 21.973436 -214.116548) (xy 22.003728 -214.159614) (xy 22.027091 -214.206799)
			(xy 22.042977 -214.256998) (xy 22.051014 -214.309034) (xy 22.051518 -214.33536) (xy 28.908251 -214.33536)
			(xy 28.912281 -214.282862) (xy 28.924278 -214.231594) (xy 28.943961 -214.182759) (xy 28.970867 -214.1375)
			(xy 29.004367 -214.096879) (xy 29.043675 -214.061848) (xy 29.08787 -214.033228) (xy 29.135915 -214.011689)
			(xy 29.186686 -213.997737) (xy 29.238991 -213.991699) (xy 29.291605 -213.993716) (xy 29.343295 -214.00374)
			(xy 29.392848 -214.021538) (xy 29.439104 -214.046691) (xy 29.480978 -214.07861) (xy 29.51749 -214.116548)
			(xy 29.547782 -214.159614) (xy 29.571145 -214.206799) (xy 29.587031 -214.256998) (xy 29.595068 -214.309034)
			(xy 29.595572 -214.33536) (xy 36.452051 -214.33536) (xy 36.456081 -214.282862) (xy 36.468078 -214.231594)
			(xy 36.487761 -214.182759) (xy 36.514667 -214.1375) (xy 36.548167 -214.096879) (xy 36.587475 -214.061848)
			(xy 36.63167 -214.033228) (xy 36.679715 -214.011689) (xy 36.730486 -213.997737) (xy 36.782791 -213.991699)
			(xy 36.835405 -213.993716) (xy 36.887095 -214.00374) (xy 36.936648 -214.021538) (xy 36.982904 -214.046691)
			(xy 37.024778 -214.07861) (xy 37.06129 -214.116548) (xy 37.091582 -214.159614) (xy 37.114945 -214.206799)
			(xy 37.130831 -214.256998) (xy 37.138868 -214.309034) (xy 37.139372 -214.33536) (xy 43.996105 -214.33536)
			(xy 44.000135 -214.282862) (xy 44.012132 -214.231594) (xy 44.031815 -214.182759) (xy 44.058721 -214.1375)
			(xy 44.092221 -214.096879) (xy 44.131529 -214.061848) (xy 44.175724 -214.033228) (xy 44.223769 -214.011689)
			(xy 44.27454 -213.997737) (xy 44.326845 -213.991699) (xy 44.379459 -213.993716) (xy 44.431149 -214.00374)
			(xy 44.480702 -214.021538) (xy 44.526958 -214.046691) (xy 44.568832 -214.07861) (xy 44.605344 -214.116548)
			(xy 44.635636 -214.159614) (xy 44.658999 -214.206799) (xy 44.674885 -214.256998) (xy 44.682922 -214.309034)
			(xy 44.683426 -214.33536) (xy 51.540159 -214.33536) (xy 51.544189 -214.282862) (xy 51.556186 -214.231594)
			(xy 51.575869 -214.182759) (xy 51.602775 -214.1375) (xy 51.636275 -214.096879) (xy 51.675583 -214.061848)
			(xy 51.719778 -214.033228) (xy 51.767823 -214.011689) (xy 51.818594 -213.997737) (xy 51.870899 -213.991699)
			(xy 51.923513 -213.993716) (xy 51.975203 -214.00374) (xy 52.024756 -214.021538) (xy 52.071012 -214.046691)
			(xy 52.112886 -214.07861) (xy 52.149398 -214.116548) (xy 52.17969 -214.159614) (xy 52.203053 -214.206799)
			(xy 52.218939 -214.256998) (xy 52.226976 -214.309034) (xy 52.22748 -214.33536) (xy 52.226976 -214.361686)
			(xy 52.218939 -214.413722) (xy 52.203053 -214.463921) (xy 52.17969 -214.511106) (xy 52.149398 -214.554172)
			(xy 52.112886 -214.59211) (xy 52.071012 -214.624029) (xy 52.024756 -214.649182) (xy 51.975203 -214.66698)
			(xy 51.923513 -214.677004) (xy 51.870899 -214.679021) (xy 51.818594 -214.672983) (xy 51.767823 -214.659031)
			(xy 51.719778 -214.637492) (xy 51.675583 -214.608872) (xy 51.636275 -214.573841) (xy 51.602775 -214.53322)
			(xy 51.575869 -214.487961) (xy 51.556186 -214.439126) (xy 51.544189 -214.387858) (xy 51.540159 -214.33536)
			(xy 44.683426 -214.33536) (xy 44.682922 -214.361686) (xy 44.674885 -214.413722) (xy 44.658999 -214.463921)
			(xy 44.635636 -214.511106) (xy 44.605344 -214.554172) (xy 44.568832 -214.59211) (xy 44.526958 -214.624029)
			(xy 44.480702 -214.649182) (xy 44.431149 -214.66698) (xy 44.379459 -214.677004) (xy 44.326845 -214.679021)
			(xy 44.27454 -214.672983) (xy 44.223769 -214.659031) (xy 44.175724 -214.637492) (xy 44.131529 -214.608872)
			(xy 44.092221 -214.573841) (xy 44.058721 -214.53322) (xy 44.031815 -214.487961) (xy 44.012132 -214.439126)
			(xy 44.000135 -214.387858) (xy 43.996105 -214.33536) (xy 37.139372 -214.33536) (xy 37.138868 -214.361686)
			(xy 37.130831 -214.413722) (xy 37.114945 -214.463921) (xy 37.091582 -214.511106) (xy 37.06129 -214.554172)
			(xy 37.024778 -214.59211) (xy 36.982904 -214.624029) (xy 36.936648 -214.649182) (xy 36.887095 -214.66698)
			(xy 36.835405 -214.677004) (xy 36.782791 -214.679021) (xy 36.730486 -214.672983) (xy 36.679715 -214.659031)
			(xy 36.63167 -214.637492) (xy 36.587475 -214.608872) (xy 36.548167 -214.573841) (xy 36.514667 -214.53322)
			(xy 36.487761 -214.487961) (xy 36.468078 -214.439126) (xy 36.456081 -214.387858) (xy 36.452051 -214.33536)
			(xy 29.595572 -214.33536) (xy 29.595068 -214.361686) (xy 29.587031 -214.413722) (xy 29.571145 -214.463921)
			(xy 29.547782 -214.511106) (xy 29.51749 -214.554172) (xy 29.480978 -214.59211) (xy 29.439104 -214.624029)
			(xy 29.392848 -214.649182) (xy 29.343295 -214.66698) (xy 29.291605 -214.677004) (xy 29.238991 -214.679021)
			(xy 29.186686 -214.672983) (xy 29.135915 -214.659031) (xy 29.08787 -214.637492) (xy 29.043675 -214.608872)
			(xy 29.004367 -214.573841) (xy 28.970867 -214.53322) (xy 28.943961 -214.487961) (xy 28.924278 -214.439126)
			(xy 28.912281 -214.387858) (xy 28.908251 -214.33536) (xy 22.051518 -214.33536) (xy 22.051014 -214.361686)
			(xy 22.042977 -214.413722) (xy 22.027091 -214.463921) (xy 22.003728 -214.511106) (xy 21.973436 -214.554172)
			(xy 21.936924 -214.59211) (xy 21.89505 -214.624029) (xy 21.848794 -214.649182) (xy 21.799241 -214.66698)
			(xy 21.747551 -214.677004) (xy 21.694937 -214.679021) (xy 21.642632 -214.672983) (xy 21.591861 -214.659031)
			(xy 21.543816 -214.637492) (xy 21.499621 -214.608872) (xy 21.460313 -214.573841) (xy 21.426813 -214.53322)
			(xy 21.399907 -214.487961) (xy 21.380224 -214.439126) (xy 21.368227 -214.387858) (xy 21.364197 -214.33536)
			(xy 16.086074 -214.33536) (xy 16.086074 -215.185244) (xy 17.264129 -215.185244) (xy 17.268159 -215.132746)
			(xy 17.280156 -215.081478) (xy 17.299839 -215.032643) (xy 17.326745 -214.987384) (xy 17.360245 -214.946763)
			(xy 17.399553 -214.911732) (xy 17.443748 -214.883112) (xy 17.491793 -214.861573) (xy 17.542564 -214.847621)
			(xy 17.594869 -214.841583) (xy 17.647483 -214.8436) (xy 17.699173 -214.853624) (xy 17.748726 -214.871422)
			(xy 17.794982 -214.896575) (xy 17.836856 -214.928494) (xy 17.873368 -214.966432) (xy 17.90366 -215.009498)
			(xy 17.927023 -215.056683) (xy 17.942909 -215.106882) (xy 17.950946 -215.158918) (xy 17.95145 -215.185244)
			(xy 24.808183 -215.185244) (xy 24.812213 -215.132746) (xy 24.82421 -215.081478) (xy 24.843893 -215.032643)
			(xy 24.870799 -214.987384) (xy 24.904299 -214.946763) (xy 24.943607 -214.911732) (xy 24.987802 -214.883112)
			(xy 25.035847 -214.861573) (xy 25.086618 -214.847621) (xy 25.138923 -214.841583) (xy 25.191537 -214.8436)
			(xy 25.243227 -214.853624) (xy 25.29278 -214.871422) (xy 25.339036 -214.896575) (xy 25.38091 -214.928494)
			(xy 25.417422 -214.966432) (xy 25.447714 -215.009498) (xy 25.471077 -215.056683) (xy 25.486963 -215.106882)
			(xy 25.495 -215.158918) (xy 25.495504 -215.185244) (xy 32.351983 -215.185244) (xy 32.356013 -215.132746)
			(xy 32.36801 -215.081478) (xy 32.387693 -215.032643) (xy 32.414599 -214.987384) (xy 32.448099 -214.946763)
			(xy 32.487407 -214.911732) (xy 32.531602 -214.883112) (xy 32.579647 -214.861573) (xy 32.630418 -214.847621)
			(xy 32.682723 -214.841583) (xy 32.735337 -214.8436) (xy 32.787027 -214.853624) (xy 32.83658 -214.871422)
			(xy 32.882836 -214.896575) (xy 32.92471 -214.928494) (xy 32.961222 -214.966432) (xy 32.991514 -215.009498)
			(xy 33.014877 -215.056683) (xy 33.030763 -215.106882) (xy 33.0388 -215.158918) (xy 33.039304 -215.185244)
			(xy 39.896037 -215.185244) (xy 39.900067 -215.132746) (xy 39.912064 -215.081478) (xy 39.931747 -215.032643)
			(xy 39.958653 -214.987384) (xy 39.992153 -214.946763) (xy 40.031461 -214.911732) (xy 40.075656 -214.883112)
			(xy 40.123701 -214.861573) (xy 40.174472 -214.847621) (xy 40.226777 -214.841583) (xy 40.279391 -214.8436)
			(xy 40.331081 -214.853624) (xy 40.380634 -214.871422) (xy 40.42689 -214.896575) (xy 40.468764 -214.928494)
			(xy 40.505276 -214.966432) (xy 40.535568 -215.009498) (xy 40.558931 -215.056683) (xy 40.574817 -215.106882)
			(xy 40.582854 -215.158918) (xy 40.583358 -215.185244) (xy 47.440091 -215.185244) (xy 47.444121 -215.132746)
			(xy 47.456118 -215.081478) (xy 47.475801 -215.032643) (xy 47.502707 -214.987384) (xy 47.536207 -214.946763)
			(xy 47.575515 -214.911732) (xy 47.61971 -214.883112) (xy 47.667755 -214.861573) (xy 47.718526 -214.847621)
			(xy 47.770831 -214.841583) (xy 47.823445 -214.8436) (xy 47.875135 -214.853624) (xy 47.924688 -214.871422)
			(xy 47.970944 -214.896575) (xy 48.012818 -214.928494) (xy 48.04933 -214.966432) (xy 48.079622 -215.009498)
			(xy 48.102985 -215.056683) (xy 48.118871 -215.106882) (xy 48.126908 -215.158918) (xy 48.127412 -215.185244)
			(xy 48.126908 -215.21157) (xy 48.118871 -215.263606) (xy 48.102985 -215.313805) (xy 48.079622 -215.36099)
			(xy 48.04933 -215.404056) (xy 48.012818 -215.441994) (xy 47.970944 -215.473913) (xy 47.924688 -215.499066)
			(xy 47.875135 -215.516864) (xy 47.823445 -215.526888) (xy 47.770831 -215.528905) (xy 47.718526 -215.522867)
			(xy 47.667755 -215.508915) (xy 47.61971 -215.487376) (xy 47.575515 -215.458756) (xy 47.536207 -215.423725)
			(xy 47.502707 -215.383104) (xy 47.475801 -215.337845) (xy 47.456118 -215.28901) (xy 47.444121 -215.237742)
			(xy 47.440091 -215.185244) (xy 40.583358 -215.185244) (xy 40.582854 -215.21157) (xy 40.574817 -215.263606)
			(xy 40.558931 -215.313805) (xy 40.535568 -215.36099) (xy 40.505276 -215.404056) (xy 40.468764 -215.441994)
			(xy 40.42689 -215.473913) (xy 40.380634 -215.499066) (xy 40.331081 -215.516864) (xy 40.279391 -215.526888)
			(xy 40.226777 -215.528905) (xy 40.174472 -215.522867) (xy 40.123701 -215.508915) (xy 40.075656 -215.487376)
			(xy 40.031461 -215.458756) (xy 39.992153 -215.423725) (xy 39.958653 -215.383104) (xy 39.931747 -215.337845)
			(xy 39.912064 -215.28901) (xy 39.900067 -215.237742) (xy 39.896037 -215.185244) (xy 33.039304 -215.185244)
			(xy 33.0388 -215.21157) (xy 33.030763 -215.263606) (xy 33.014877 -215.313805) (xy 32.991514 -215.36099)
			(xy 32.961222 -215.404056) (xy 32.92471 -215.441994) (xy 32.882836 -215.473913) (xy 32.83658 -215.499066)
			(xy 32.787027 -215.516864) (xy 32.735337 -215.526888) (xy 32.682723 -215.528905) (xy 32.630418 -215.522867)
			(xy 32.579647 -215.508915) (xy 32.531602 -215.487376) (xy 32.487407 -215.458756) (xy 32.448099 -215.423725)
			(xy 32.414599 -215.383104) (xy 32.387693 -215.337845) (xy 32.36801 -215.28901) (xy 32.356013 -215.237742)
			(xy 32.351983 -215.185244) (xy 25.495504 -215.185244) (xy 25.495 -215.21157) (xy 25.486963 -215.263606)
			(xy 25.471077 -215.313805) (xy 25.447714 -215.36099) (xy 25.417422 -215.404056) (xy 25.38091 -215.441994)
			(xy 25.339036 -215.473913) (xy 25.29278 -215.499066) (xy 25.243227 -215.516864) (xy 25.191537 -215.526888)
			(xy 25.138923 -215.528905) (xy 25.086618 -215.522867) (xy 25.035847 -215.508915) (xy 24.987802 -215.487376)
			(xy 24.943607 -215.458756) (xy 24.904299 -215.423725) (xy 24.870799 -215.383104) (xy 24.843893 -215.337845)
			(xy 24.82421 -215.28901) (xy 24.812213 -215.237742) (xy 24.808183 -215.185244) (xy 17.95145 -215.185244)
			(xy 17.950946 -215.21157) (xy 17.942909 -215.263606) (xy 17.927023 -215.313805) (xy 17.90366 -215.36099)
			(xy 17.873368 -215.404056) (xy 17.836856 -215.441994) (xy 17.794982 -215.473913) (xy 17.748726 -215.499066)
			(xy 17.699173 -215.516864) (xy 17.647483 -215.526888) (xy 17.594869 -215.528905) (xy 17.542564 -215.522867)
			(xy 17.491793 -215.508915) (xy 17.443748 -215.487376) (xy 17.399553 -215.458756) (xy 17.360245 -215.423725)
			(xy 17.326745 -215.383104) (xy 17.299839 -215.337845) (xy 17.280156 -215.28901) (xy 17.268159 -215.237742)
			(xy 17.264129 -215.185244) (xy 16.086074 -215.185244) (xy 16.086074 -216.035382) (xy 21.364197 -216.035382)
			(xy 21.368227 -215.982884) (xy 21.380224 -215.931616) (xy 21.399907 -215.882781) (xy 21.426813 -215.837522)
			(xy 21.460313 -215.796901) (xy 21.499621 -215.76187) (xy 21.543816 -215.73325) (xy 21.591861 -215.711711)
			(xy 21.642632 -215.697759) (xy 21.694937 -215.691721) (xy 21.747551 -215.693738) (xy 21.799241 -215.703762)
			(xy 21.848794 -215.72156) (xy 21.89505 -215.746713) (xy 21.936924 -215.778632) (xy 21.973436 -215.81657)
			(xy 22.003728 -215.859636) (xy 22.027091 -215.906821) (xy 22.042977 -215.95702) (xy 22.051014 -216.009056)
			(xy 22.051518 -216.035382) (xy 28.908251 -216.035382) (xy 28.912281 -215.982884) (xy 28.924278 -215.931616)
			(xy 28.943961 -215.882781) (xy 28.970867 -215.837522) (xy 29.004367 -215.796901) (xy 29.043675 -215.76187)
			(xy 29.08787 -215.73325) (xy 29.135915 -215.711711) (xy 29.186686 -215.697759) (xy 29.238991 -215.691721)
			(xy 29.291605 -215.693738) (xy 29.343295 -215.703762) (xy 29.392848 -215.72156) (xy 29.439104 -215.746713)
			(xy 29.480978 -215.778632) (xy 29.51749 -215.81657) (xy 29.547782 -215.859636) (xy 29.571145 -215.906821)
			(xy 29.587031 -215.95702) (xy 29.595068 -216.009056) (xy 29.595572 -216.035382) (xy 36.452051 -216.035382)
			(xy 36.456081 -215.982884) (xy 36.468078 -215.931616) (xy 36.487761 -215.882781) (xy 36.514667 -215.837522)
			(xy 36.548167 -215.796901) (xy 36.587475 -215.76187) (xy 36.63167 -215.73325) (xy 36.679715 -215.711711)
			(xy 36.730486 -215.697759) (xy 36.782791 -215.691721) (xy 36.835405 -215.693738) (xy 36.887095 -215.703762)
			(xy 36.936648 -215.72156) (xy 36.982904 -215.746713) (xy 37.024778 -215.778632) (xy 37.06129 -215.81657)
			(xy 37.091582 -215.859636) (xy 37.114945 -215.906821) (xy 37.130831 -215.95702) (xy 37.138868 -216.009056)
			(xy 37.139372 -216.035382) (xy 43.996105 -216.035382) (xy 44.000135 -215.982884) (xy 44.012132 -215.931616)
			(xy 44.031815 -215.882781) (xy 44.058721 -215.837522) (xy 44.092221 -215.796901) (xy 44.131529 -215.76187)
			(xy 44.175724 -215.73325) (xy 44.223769 -215.711711) (xy 44.27454 -215.697759) (xy 44.326845 -215.691721)
			(xy 44.379459 -215.693738) (xy 44.431149 -215.703762) (xy 44.480702 -215.72156) (xy 44.526958 -215.746713)
			(xy 44.568832 -215.778632) (xy 44.605344 -215.81657) (xy 44.635636 -215.859636) (xy 44.658999 -215.906821)
			(xy 44.674885 -215.95702) (xy 44.682922 -216.009056) (xy 44.683426 -216.035382) (xy 51.540159 -216.035382)
			(xy 51.544189 -215.982884) (xy 51.556186 -215.931616) (xy 51.575869 -215.882781) (xy 51.602775 -215.837522)
			(xy 51.636275 -215.796901) (xy 51.675583 -215.76187) (xy 51.719778 -215.73325) (xy 51.767823 -215.711711)
			(xy 51.818594 -215.697759) (xy 51.870899 -215.691721) (xy 51.923513 -215.693738) (xy 51.975203 -215.703762)
			(xy 52.024756 -215.72156) (xy 52.071012 -215.746713) (xy 52.112886 -215.778632) (xy 52.149398 -215.81657)
			(xy 52.17969 -215.859636) (xy 52.203053 -215.906821) (xy 52.218939 -215.95702) (xy 52.226976 -216.009056)
			(xy 52.22748 -216.035382) (xy 52.226976 -216.061708) (xy 52.218939 -216.113744) (xy 52.203053 -216.163943)
			(xy 52.17969 -216.211128) (xy 52.149398 -216.254194) (xy 52.112886 -216.292132) (xy 52.071012 -216.324051)
			(xy 52.024756 -216.349204) (xy 51.975203 -216.367002) (xy 51.923513 -216.377026) (xy 51.870899 -216.379043)
			(xy 51.818594 -216.373005) (xy 51.767823 -216.359053) (xy 51.719778 -216.337514) (xy 51.675583 -216.308894)
			(xy 51.636275 -216.273863) (xy 51.602775 -216.233242) (xy 51.575869 -216.187983) (xy 51.556186 -216.139148)
			(xy 51.544189 -216.08788) (xy 51.540159 -216.035382) (xy 44.683426 -216.035382) (xy 44.682922 -216.061708)
			(xy 44.674885 -216.113744) (xy 44.658999 -216.163943) (xy 44.635636 -216.211128) (xy 44.605344 -216.254194)
			(xy 44.568832 -216.292132) (xy 44.526958 -216.324051) (xy 44.480702 -216.349204) (xy 44.431149 -216.367002)
			(xy 44.379459 -216.377026) (xy 44.326845 -216.379043) (xy 44.27454 -216.373005) (xy 44.223769 -216.359053)
			(xy 44.175724 -216.337514) (xy 44.131529 -216.308894) (xy 44.092221 -216.273863) (xy 44.058721 -216.233242)
			(xy 44.031815 -216.187983) (xy 44.012132 -216.139148) (xy 44.000135 -216.08788) (xy 43.996105 -216.035382)
			(xy 37.139372 -216.035382) (xy 37.138868 -216.061708) (xy 37.130831 -216.113744) (xy 37.114945 -216.163943)
			(xy 37.091582 -216.211128) (xy 37.06129 -216.254194) (xy 37.024778 -216.292132) (xy 36.982904 -216.324051)
			(xy 36.936648 -216.349204) (xy 36.887095 -216.367002) (xy 36.835405 -216.377026) (xy 36.782791 -216.379043)
			(xy 36.730486 -216.373005) (xy 36.679715 -216.359053) (xy 36.63167 -216.337514) (xy 36.587475 -216.308894)
			(xy 36.548167 -216.273863) (xy 36.514667 -216.233242) (xy 36.487761 -216.187983) (xy 36.468078 -216.139148)
			(xy 36.456081 -216.08788) (xy 36.452051 -216.035382) (xy 29.595572 -216.035382) (xy 29.595068 -216.061708)
			(xy 29.587031 -216.113744) (xy 29.571145 -216.163943) (xy 29.547782 -216.211128) (xy 29.51749 -216.254194)
			(xy 29.480978 -216.292132) (xy 29.439104 -216.324051) (xy 29.392848 -216.349204) (xy 29.343295 -216.367002)
			(xy 29.291605 -216.377026) (xy 29.238991 -216.379043) (xy 29.186686 -216.373005) (xy 29.135915 -216.359053)
			(xy 29.08787 -216.337514) (xy 29.043675 -216.308894) (xy 29.004367 -216.273863) (xy 28.970867 -216.233242)
			(xy 28.943961 -216.187983) (xy 28.924278 -216.139148) (xy 28.912281 -216.08788) (xy 28.908251 -216.035382)
			(xy 22.051518 -216.035382) (xy 22.051014 -216.061708) (xy 22.042977 -216.113744) (xy 22.027091 -216.163943)
			(xy 22.003728 -216.211128) (xy 21.973436 -216.254194) (xy 21.936924 -216.292132) (xy 21.89505 -216.324051)
			(xy 21.848794 -216.349204) (xy 21.799241 -216.367002) (xy 21.747551 -216.377026) (xy 21.694937 -216.379043)
			(xy 21.642632 -216.373005) (xy 21.591861 -216.359053) (xy 21.543816 -216.337514) (xy 21.499621 -216.308894)
			(xy 21.460313 -216.273863) (xy 21.426813 -216.233242) (xy 21.399907 -216.187983) (xy 21.380224 -216.139148)
			(xy 21.368227 -216.08788) (xy 21.364197 -216.035382) (xy 16.086074 -216.035382) (xy 16.086074 -216.885266)
			(xy 17.264129 -216.885266) (xy 17.268159 -216.832768) (xy 17.280156 -216.7815) (xy 17.299839 -216.732665)
			(xy 17.326745 -216.687406) (xy 17.360245 -216.646785) (xy 17.399553 -216.611754) (xy 17.443748 -216.583134)
			(xy 17.491793 -216.561595) (xy 17.542564 -216.547643) (xy 17.594869 -216.541605) (xy 17.647483 -216.543622)
			(xy 17.699173 -216.553646) (xy 17.748726 -216.571444) (xy 17.794982 -216.596597) (xy 17.836856 -216.628516)
			(xy 17.873368 -216.666454) (xy 17.90366 -216.70952) (xy 17.927023 -216.756705) (xy 17.942909 -216.806904)
			(xy 17.950946 -216.85894) (xy 17.95145 -216.885266) (xy 24.808183 -216.885266) (xy 24.812213 -216.832768)
			(xy 24.82421 -216.7815) (xy 24.843893 -216.732665) (xy 24.870799 -216.687406) (xy 24.904299 -216.646785)
			(xy 24.943607 -216.611754) (xy 24.987802 -216.583134) (xy 25.035847 -216.561595) (xy 25.086618 -216.547643)
			(xy 25.138923 -216.541605) (xy 25.191537 -216.543622) (xy 25.243227 -216.553646) (xy 25.29278 -216.571444)
			(xy 25.339036 -216.596597) (xy 25.38091 -216.628516) (xy 25.417422 -216.666454) (xy 25.447714 -216.70952)
			(xy 25.471077 -216.756705) (xy 25.486963 -216.806904) (xy 25.495 -216.85894) (xy 25.495504 -216.885266)
			(xy 32.351983 -216.885266) (xy 32.356013 -216.832768) (xy 32.36801 -216.7815) (xy 32.387693 -216.732665)
			(xy 32.414599 -216.687406) (xy 32.448099 -216.646785) (xy 32.487407 -216.611754) (xy 32.531602 -216.583134)
			(xy 32.579647 -216.561595) (xy 32.630418 -216.547643) (xy 32.682723 -216.541605) (xy 32.735337 -216.543622)
			(xy 32.787027 -216.553646) (xy 32.83658 -216.571444) (xy 32.882836 -216.596597) (xy 32.92471 -216.628516)
			(xy 32.961222 -216.666454) (xy 32.991514 -216.70952) (xy 33.014877 -216.756705) (xy 33.030763 -216.806904)
			(xy 33.0388 -216.85894) (xy 33.039304 -216.885266) (xy 39.896037 -216.885266) (xy 39.900067 -216.832768)
			(xy 39.912064 -216.7815) (xy 39.931747 -216.732665) (xy 39.958653 -216.687406) (xy 39.992153 -216.646785)
			(xy 40.031461 -216.611754) (xy 40.075656 -216.583134) (xy 40.123701 -216.561595) (xy 40.174472 -216.547643)
			(xy 40.226777 -216.541605) (xy 40.279391 -216.543622) (xy 40.331081 -216.553646) (xy 40.380634 -216.571444)
			(xy 40.42689 -216.596597) (xy 40.468764 -216.628516) (xy 40.505276 -216.666454) (xy 40.535568 -216.70952)
			(xy 40.558931 -216.756705) (xy 40.574817 -216.806904) (xy 40.582854 -216.85894) (xy 40.583358 -216.885266)
			(xy 47.440091 -216.885266) (xy 47.444121 -216.832768) (xy 47.456118 -216.7815) (xy 47.475801 -216.732665)
			(xy 47.502707 -216.687406) (xy 47.536207 -216.646785) (xy 47.575515 -216.611754) (xy 47.61971 -216.583134)
			(xy 47.667755 -216.561595) (xy 47.718526 -216.547643) (xy 47.770831 -216.541605) (xy 47.823445 -216.543622)
			(xy 47.875135 -216.553646) (xy 47.924688 -216.571444) (xy 47.970944 -216.596597) (xy 48.012818 -216.628516)
			(xy 48.04933 -216.666454) (xy 48.079622 -216.70952) (xy 48.102985 -216.756705) (xy 48.118871 -216.806904)
			(xy 48.126908 -216.85894) (xy 48.127412 -216.885266) (xy 48.126908 -216.911592) (xy 48.118871 -216.963628)
			(xy 48.102985 -217.013827) (xy 48.079622 -217.061012) (xy 48.04933 -217.104078) (xy 48.012818 -217.142016)
			(xy 47.970944 -217.173935) (xy 47.924688 -217.199088) (xy 47.875135 -217.216886) (xy 47.823445 -217.22691)
			(xy 47.770831 -217.228927) (xy 47.718526 -217.222889) (xy 47.667755 -217.208937) (xy 47.61971 -217.187398)
			(xy 47.575515 -217.158778) (xy 47.536207 -217.123747) (xy 47.502707 -217.083126) (xy 47.475801 -217.037867)
			(xy 47.456118 -216.989032) (xy 47.444121 -216.937764) (xy 47.440091 -216.885266) (xy 40.583358 -216.885266)
			(xy 40.582854 -216.911592) (xy 40.574817 -216.963628) (xy 40.558931 -217.013827) (xy 40.535568 -217.061012)
			(xy 40.505276 -217.104078) (xy 40.468764 -217.142016) (xy 40.42689 -217.173935) (xy 40.380634 -217.199088)
			(xy 40.331081 -217.216886) (xy 40.279391 -217.22691) (xy 40.226777 -217.228927) (xy 40.174472 -217.222889)
			(xy 40.123701 -217.208937) (xy 40.075656 -217.187398) (xy 40.031461 -217.158778) (xy 39.992153 -217.123747)
			(xy 39.958653 -217.083126) (xy 39.931747 -217.037867) (xy 39.912064 -216.989032) (xy 39.900067 -216.937764)
			(xy 39.896037 -216.885266) (xy 33.039304 -216.885266) (xy 33.0388 -216.911592) (xy 33.030763 -216.963628)
			(xy 33.014877 -217.013827) (xy 32.991514 -217.061012) (xy 32.961222 -217.104078) (xy 32.92471 -217.142016)
			(xy 32.882836 -217.173935) (xy 32.83658 -217.199088) (xy 32.787027 -217.216886) (xy 32.735337 -217.22691)
			(xy 32.682723 -217.228927) (xy 32.630418 -217.222889) (xy 32.579647 -217.208937) (xy 32.531602 -217.187398)
			(xy 32.487407 -217.158778) (xy 32.448099 -217.123747) (xy 32.414599 -217.083126) (xy 32.387693 -217.037867)
			(xy 32.36801 -216.989032) (xy 32.356013 -216.937764) (xy 32.351983 -216.885266) (xy 25.495504 -216.885266)
			(xy 25.495 -216.911592) (xy 25.486963 -216.963628) (xy 25.471077 -217.013827) (xy 25.447714 -217.061012)
			(xy 25.417422 -217.104078) (xy 25.38091 -217.142016) (xy 25.339036 -217.173935) (xy 25.29278 -217.199088)
			(xy 25.243227 -217.216886) (xy 25.191537 -217.22691) (xy 25.138923 -217.228927) (xy 25.086618 -217.222889)
			(xy 25.035847 -217.208937) (xy 24.987802 -217.187398) (xy 24.943607 -217.158778) (xy 24.904299 -217.123747)
			(xy 24.870799 -217.083126) (xy 24.843893 -217.037867) (xy 24.82421 -216.989032) (xy 24.812213 -216.937764)
			(xy 24.808183 -216.885266) (xy 17.95145 -216.885266) (xy 17.950946 -216.911592) (xy 17.942909 -216.963628)
			(xy 17.927023 -217.013827) (xy 17.90366 -217.061012) (xy 17.873368 -217.104078) (xy 17.836856 -217.142016)
			(xy 17.794982 -217.173935) (xy 17.748726 -217.199088) (xy 17.699173 -217.216886) (xy 17.647483 -217.22691)
			(xy 17.594869 -217.228927) (xy 17.542564 -217.222889) (xy 17.491793 -217.208937) (xy 17.443748 -217.187398)
			(xy 17.399553 -217.158778) (xy 17.360245 -217.123747) (xy 17.326745 -217.083126) (xy 17.299839 -217.037867)
			(xy 17.280156 -216.989032) (xy 17.268159 -216.937764) (xy 17.264129 -216.885266) (xy 16.086074 -216.885266)
			(xy 16.086074 -217.735404) (xy 21.364197 -217.735404) (xy 21.368227 -217.682906) (xy 21.380224 -217.631638)
			(xy 21.399907 -217.582803) (xy 21.426813 -217.537544) (xy 21.460313 -217.496923) (xy 21.499621 -217.461892)
			(xy 21.543816 -217.433272) (xy 21.591861 -217.411733) (xy 21.642632 -217.397781) (xy 21.694937 -217.391743)
			(xy 21.747551 -217.39376) (xy 21.799241 -217.403784) (xy 21.848794 -217.421582) (xy 21.89505 -217.446735)
			(xy 21.936924 -217.478654) (xy 21.973436 -217.516592) (xy 22.003728 -217.559658) (xy 22.027091 -217.606843)
			(xy 22.042977 -217.657042) (xy 22.051014 -217.709078) (xy 22.051518 -217.735404) (xy 28.908251 -217.735404)
			(xy 28.912281 -217.682906) (xy 28.924278 -217.631638) (xy 28.943961 -217.582803) (xy 28.970867 -217.537544)
			(xy 29.004367 -217.496923) (xy 29.043675 -217.461892) (xy 29.08787 -217.433272) (xy 29.135915 -217.411733)
			(xy 29.186686 -217.397781) (xy 29.238991 -217.391743) (xy 29.291605 -217.39376) (xy 29.343295 -217.403784)
			(xy 29.392848 -217.421582) (xy 29.439104 -217.446735) (xy 29.480978 -217.478654) (xy 29.51749 -217.516592)
			(xy 29.547782 -217.559658) (xy 29.571145 -217.606843) (xy 29.587031 -217.657042) (xy 29.595068 -217.709078)
			(xy 29.595572 -217.735404) (xy 36.452051 -217.735404) (xy 36.456081 -217.682906) (xy 36.468078 -217.631638)
			(xy 36.487761 -217.582803) (xy 36.514667 -217.537544) (xy 36.548167 -217.496923) (xy 36.587475 -217.461892)
			(xy 36.63167 -217.433272) (xy 36.679715 -217.411733) (xy 36.730486 -217.397781) (xy 36.782791 -217.391743)
			(xy 36.835405 -217.39376) (xy 36.887095 -217.403784) (xy 36.936648 -217.421582) (xy 36.982904 -217.446735)
			(xy 37.024778 -217.478654) (xy 37.06129 -217.516592) (xy 37.091582 -217.559658) (xy 37.114945 -217.606843)
			(xy 37.130831 -217.657042) (xy 37.138868 -217.709078) (xy 37.139372 -217.735404) (xy 43.996105 -217.735404)
			(xy 44.000135 -217.682906) (xy 44.012132 -217.631638) (xy 44.031815 -217.582803) (xy 44.058721 -217.537544)
			(xy 44.092221 -217.496923) (xy 44.131529 -217.461892) (xy 44.175724 -217.433272) (xy 44.223769 -217.411733)
			(xy 44.27454 -217.397781) (xy 44.326845 -217.391743) (xy 44.379459 -217.39376) (xy 44.431149 -217.403784)
			(xy 44.480702 -217.421582) (xy 44.526958 -217.446735) (xy 44.568832 -217.478654) (xy 44.605344 -217.516592)
			(xy 44.635636 -217.559658) (xy 44.658999 -217.606843) (xy 44.674885 -217.657042) (xy 44.682922 -217.709078)
			(xy 44.683426 -217.735404) (xy 51.540159 -217.735404) (xy 51.544189 -217.682906) (xy 51.556186 -217.631638)
			(xy 51.575869 -217.582803) (xy 51.602775 -217.537544) (xy 51.636275 -217.496923) (xy 51.675583 -217.461892)
			(xy 51.719778 -217.433272) (xy 51.767823 -217.411733) (xy 51.818594 -217.397781) (xy 51.870899 -217.391743)
			(xy 51.923513 -217.39376) (xy 51.975203 -217.403784) (xy 52.024756 -217.421582) (xy 52.071012 -217.446735)
			(xy 52.112886 -217.478654) (xy 52.149398 -217.516592) (xy 52.17969 -217.559658) (xy 52.203053 -217.606843)
			(xy 52.218939 -217.657042) (xy 52.226976 -217.709078) (xy 52.22748 -217.735404) (xy 52.226976 -217.76173)
			(xy 52.218939 -217.813766) (xy 52.203053 -217.863965) (xy 52.17969 -217.91115) (xy 52.149398 -217.954216)
			(xy 52.112886 -217.992154) (xy 52.071012 -218.024073) (xy 52.024756 -218.049226) (xy 51.975203 -218.067024)
			(xy 51.923513 -218.077048) (xy 51.870899 -218.079065) (xy 51.818594 -218.073027) (xy 51.767823 -218.059075)
			(xy 51.719778 -218.037536) (xy 51.675583 -218.008916) (xy 51.636275 -217.973885) (xy 51.602775 -217.933264)
			(xy 51.575869 -217.888005) (xy 51.556186 -217.83917) (xy 51.544189 -217.787902) (xy 51.540159 -217.735404)
			(xy 44.683426 -217.735404) (xy 44.682922 -217.76173) (xy 44.674885 -217.813766) (xy 44.658999 -217.863965)
			(xy 44.635636 -217.91115) (xy 44.605344 -217.954216) (xy 44.568832 -217.992154) (xy 44.526958 -218.024073)
			(xy 44.480702 -218.049226) (xy 44.431149 -218.067024) (xy 44.379459 -218.077048) (xy 44.326845 -218.079065)
			(xy 44.27454 -218.073027) (xy 44.223769 -218.059075) (xy 44.175724 -218.037536) (xy 44.131529 -218.008916)
			(xy 44.092221 -217.973885) (xy 44.058721 -217.933264) (xy 44.031815 -217.888005) (xy 44.012132 -217.83917)
			(xy 44.000135 -217.787902) (xy 43.996105 -217.735404) (xy 37.139372 -217.735404) (xy 37.138868 -217.76173)
			(xy 37.130831 -217.813766) (xy 37.114945 -217.863965) (xy 37.091582 -217.91115) (xy 37.06129 -217.954216)
			(xy 37.024778 -217.992154) (xy 36.982904 -218.024073) (xy 36.936648 -218.049226) (xy 36.887095 -218.067024)
			(xy 36.835405 -218.077048) (xy 36.782791 -218.079065) (xy 36.730486 -218.073027) (xy 36.679715 -218.059075)
			(xy 36.63167 -218.037536) (xy 36.587475 -218.008916) (xy 36.548167 -217.973885) (xy 36.514667 -217.933264)
			(xy 36.487761 -217.888005) (xy 36.468078 -217.83917) (xy 36.456081 -217.787902) (xy 36.452051 -217.735404)
			(xy 29.595572 -217.735404) (xy 29.595068 -217.76173) (xy 29.587031 -217.813766) (xy 29.571145 -217.863965)
			(xy 29.547782 -217.91115) (xy 29.51749 -217.954216) (xy 29.480978 -217.992154) (xy 29.439104 -218.024073)
			(xy 29.392848 -218.049226) (xy 29.343295 -218.067024) (xy 29.291605 -218.077048) (xy 29.238991 -218.079065)
			(xy 29.186686 -218.073027) (xy 29.135915 -218.059075) (xy 29.08787 -218.037536) (xy 29.043675 -218.008916)
			(xy 29.004367 -217.973885) (xy 28.970867 -217.933264) (xy 28.943961 -217.888005) (xy 28.924278 -217.83917)
			(xy 28.912281 -217.787902) (xy 28.908251 -217.735404) (xy 22.051518 -217.735404) (xy 22.051014 -217.76173)
			(xy 22.042977 -217.813766) (xy 22.027091 -217.863965) (xy 22.003728 -217.91115) (xy 21.973436 -217.954216)
			(xy 21.936924 -217.992154) (xy 21.89505 -218.024073) (xy 21.848794 -218.049226) (xy 21.799241 -218.067024)
			(xy 21.747551 -218.077048) (xy 21.694937 -218.079065) (xy 21.642632 -218.073027) (xy 21.591861 -218.059075)
			(xy 21.543816 -218.037536) (xy 21.499621 -218.008916) (xy 21.460313 -217.973885) (xy 21.426813 -217.933264)
			(xy 21.399907 -217.888005) (xy 21.380224 -217.83917) (xy 21.368227 -217.787902) (xy 21.364197 -217.735404)
			(xy 16.086074 -217.735404) (xy 16.086074 -218.585288) (xy 17.264129 -218.585288) (xy 17.268159 -218.53279)
			(xy 17.280156 -218.481522) (xy 17.299839 -218.432687) (xy 17.326745 -218.387428) (xy 17.360245 -218.346807)
			(xy 17.399553 -218.311776) (xy 17.443748 -218.283156) (xy 17.491793 -218.261617) (xy 17.542564 -218.247665)
			(xy 17.594869 -218.241627) (xy 17.647483 -218.243644) (xy 17.699173 -218.253668) (xy 17.748726 -218.271466)
			(xy 17.794982 -218.296619) (xy 17.836856 -218.328538) (xy 17.873368 -218.366476) (xy 17.90366 -218.409542)
			(xy 17.927023 -218.456727) (xy 17.942909 -218.506926) (xy 17.950946 -218.558962) (xy 17.95145 -218.585288)
			(xy 24.808183 -218.585288) (xy 24.812213 -218.53279) (xy 24.82421 -218.481522) (xy 24.843893 -218.432687)
			(xy 24.870799 -218.387428) (xy 24.904299 -218.346807) (xy 24.943607 -218.311776) (xy 24.987802 -218.283156)
			(xy 25.035847 -218.261617) (xy 25.086618 -218.247665) (xy 25.138923 -218.241627) (xy 25.191537 -218.243644)
			(xy 25.243227 -218.253668) (xy 25.29278 -218.271466) (xy 25.339036 -218.296619) (xy 25.38091 -218.328538)
			(xy 25.417422 -218.366476) (xy 25.447714 -218.409542) (xy 25.471077 -218.456727) (xy 25.486963 -218.506926)
			(xy 25.495 -218.558962) (xy 25.495504 -218.585288) (xy 32.351983 -218.585288) (xy 32.356013 -218.53279)
			(xy 32.36801 -218.481522) (xy 32.387693 -218.432687) (xy 32.414599 -218.387428) (xy 32.448099 -218.346807)
			(xy 32.487407 -218.311776) (xy 32.531602 -218.283156) (xy 32.579647 -218.261617) (xy 32.630418 -218.247665)
			(xy 32.682723 -218.241627) (xy 32.735337 -218.243644) (xy 32.787027 -218.253668) (xy 32.83658 -218.271466)
			(xy 32.882836 -218.296619) (xy 32.92471 -218.328538) (xy 32.961222 -218.366476) (xy 32.991514 -218.409542)
			(xy 33.014877 -218.456727) (xy 33.030763 -218.506926) (xy 33.0388 -218.558962) (xy 33.039304 -218.585288)
			(xy 39.896037 -218.585288) (xy 39.900067 -218.53279) (xy 39.912064 -218.481522) (xy 39.931747 -218.432687)
			(xy 39.958653 -218.387428) (xy 39.992153 -218.346807) (xy 40.031461 -218.311776) (xy 40.075656 -218.283156)
			(xy 40.123701 -218.261617) (xy 40.174472 -218.247665) (xy 40.226777 -218.241627) (xy 40.279391 -218.243644)
			(xy 40.331081 -218.253668) (xy 40.380634 -218.271466) (xy 40.42689 -218.296619) (xy 40.468764 -218.328538)
			(xy 40.505276 -218.366476) (xy 40.535568 -218.409542) (xy 40.558931 -218.456727) (xy 40.574817 -218.506926)
			(xy 40.582854 -218.558962) (xy 40.583358 -218.585288) (xy 47.440091 -218.585288) (xy 47.444121 -218.53279)
			(xy 47.456118 -218.481522) (xy 47.475801 -218.432687) (xy 47.502707 -218.387428) (xy 47.536207 -218.346807)
			(xy 47.575515 -218.311776) (xy 47.61971 -218.283156) (xy 47.667755 -218.261617) (xy 47.718526 -218.247665)
			(xy 47.770831 -218.241627) (xy 47.823445 -218.243644) (xy 47.875135 -218.253668) (xy 47.924688 -218.271466)
			(xy 47.970944 -218.296619) (xy 48.012818 -218.328538) (xy 48.04933 -218.366476) (xy 48.079622 -218.409542)
			(xy 48.102985 -218.456727) (xy 48.118871 -218.506926) (xy 48.126908 -218.558962) (xy 48.127412 -218.585288)
			(xy 48.126908 -218.611614) (xy 48.118871 -218.66365) (xy 48.102985 -218.713849) (xy 48.079622 -218.761034)
			(xy 48.04933 -218.8041) (xy 48.012818 -218.842038) (xy 47.970944 -218.873957) (xy 47.924688 -218.89911)
			(xy 47.875135 -218.916908) (xy 47.823445 -218.926932) (xy 47.770831 -218.928949) (xy 47.718526 -218.922911)
			(xy 47.667755 -218.908959) (xy 47.61971 -218.88742) (xy 47.575515 -218.8588) (xy 47.536207 -218.823769)
			(xy 47.502707 -218.783148) (xy 47.475801 -218.737889) (xy 47.456118 -218.689054) (xy 47.444121 -218.637786)
			(xy 47.440091 -218.585288) (xy 40.583358 -218.585288) (xy 40.582854 -218.611614) (xy 40.574817 -218.66365)
			(xy 40.558931 -218.713849) (xy 40.535568 -218.761034) (xy 40.505276 -218.8041) (xy 40.468764 -218.842038)
			(xy 40.42689 -218.873957) (xy 40.380634 -218.89911) (xy 40.331081 -218.916908) (xy 40.279391 -218.926932)
			(xy 40.226777 -218.928949) (xy 40.174472 -218.922911) (xy 40.123701 -218.908959) (xy 40.075656 -218.88742)
			(xy 40.031461 -218.8588) (xy 39.992153 -218.823769) (xy 39.958653 -218.783148) (xy 39.931747 -218.737889)
			(xy 39.912064 -218.689054) (xy 39.900067 -218.637786) (xy 39.896037 -218.585288) (xy 33.039304 -218.585288)
			(xy 33.0388 -218.611614) (xy 33.030763 -218.66365) (xy 33.014877 -218.713849) (xy 32.991514 -218.761034)
			(xy 32.961222 -218.8041) (xy 32.92471 -218.842038) (xy 32.882836 -218.873957) (xy 32.83658 -218.89911)
			(xy 32.787027 -218.916908) (xy 32.735337 -218.926932) (xy 32.682723 -218.928949) (xy 32.630418 -218.922911)
			(xy 32.579647 -218.908959) (xy 32.531602 -218.88742) (xy 32.487407 -218.8588) (xy 32.448099 -218.823769)
			(xy 32.414599 -218.783148) (xy 32.387693 -218.737889) (xy 32.36801 -218.689054) (xy 32.356013 -218.637786)
			(xy 32.351983 -218.585288) (xy 25.495504 -218.585288) (xy 25.495 -218.611614) (xy 25.486963 -218.66365)
			(xy 25.471077 -218.713849) (xy 25.447714 -218.761034) (xy 25.417422 -218.8041) (xy 25.38091 -218.842038)
			(xy 25.339036 -218.873957) (xy 25.29278 -218.89911) (xy 25.243227 -218.916908) (xy 25.191537 -218.926932)
			(xy 25.138923 -218.928949) (xy 25.086618 -218.922911) (xy 25.035847 -218.908959) (xy 24.987802 -218.88742)
			(xy 24.943607 -218.8588) (xy 24.904299 -218.823769) (xy 24.870799 -218.783148) (xy 24.843893 -218.737889)
			(xy 24.82421 -218.689054) (xy 24.812213 -218.637786) (xy 24.808183 -218.585288) (xy 17.95145 -218.585288)
			(xy 17.950946 -218.611614) (xy 17.942909 -218.66365) (xy 17.927023 -218.713849) (xy 17.90366 -218.761034)
			(xy 17.873368 -218.8041) (xy 17.836856 -218.842038) (xy 17.794982 -218.873957) (xy 17.748726 -218.89911)
			(xy 17.699173 -218.916908) (xy 17.647483 -218.926932) (xy 17.594869 -218.928949) (xy 17.542564 -218.922911)
			(xy 17.491793 -218.908959) (xy 17.443748 -218.88742) (xy 17.399553 -218.8588) (xy 17.360245 -218.823769)
			(xy 17.326745 -218.783148) (xy 17.299839 -218.737889) (xy 17.280156 -218.689054) (xy 17.268159 -218.637786)
			(xy 17.264129 -218.585288) (xy 16.086074 -218.585288) (xy 16.086074 -219.435426) (xy 21.364197 -219.435426)
			(xy 21.368227 -219.382928) (xy 21.380224 -219.33166) (xy 21.399907 -219.282825) (xy 21.426813 -219.237566)
			(xy 21.460313 -219.196945) (xy 21.499621 -219.161914) (xy 21.543816 -219.133294) (xy 21.591861 -219.111755)
			(xy 21.642632 -219.097803) (xy 21.694937 -219.091765) (xy 21.747551 -219.093782) (xy 21.799241 -219.103806)
			(xy 21.848794 -219.121604) (xy 21.89505 -219.146757) (xy 21.936924 -219.178676) (xy 21.973436 -219.216614)
			(xy 22.003728 -219.25968) (xy 22.027091 -219.306865) (xy 22.042977 -219.357064) (xy 22.051014 -219.4091)
			(xy 22.051518 -219.435426) (xy 28.908251 -219.435426) (xy 28.912281 -219.382928) (xy 28.924278 -219.33166)
			(xy 28.943961 -219.282825) (xy 28.970867 -219.237566) (xy 29.004367 -219.196945) (xy 29.043675 -219.161914)
			(xy 29.08787 -219.133294) (xy 29.135915 -219.111755) (xy 29.186686 -219.097803) (xy 29.238991 -219.091765)
			(xy 29.291605 -219.093782) (xy 29.343295 -219.103806) (xy 29.392848 -219.121604) (xy 29.439104 -219.146757)
			(xy 29.480978 -219.178676) (xy 29.51749 -219.216614) (xy 29.547782 -219.25968) (xy 29.571145 -219.306865)
			(xy 29.587031 -219.357064) (xy 29.595068 -219.4091) (xy 29.595572 -219.435426) (xy 36.452051 -219.435426)
			(xy 36.456081 -219.382928) (xy 36.468078 -219.33166) (xy 36.487761 -219.282825) (xy 36.514667 -219.237566)
			(xy 36.548167 -219.196945) (xy 36.587475 -219.161914) (xy 36.63167 -219.133294) (xy 36.679715 -219.111755)
			(xy 36.730486 -219.097803) (xy 36.782791 -219.091765) (xy 36.835405 -219.093782) (xy 36.887095 -219.103806)
			(xy 36.936648 -219.121604) (xy 36.982904 -219.146757) (xy 37.024778 -219.178676) (xy 37.06129 -219.216614)
			(xy 37.091582 -219.25968) (xy 37.114945 -219.306865) (xy 37.130831 -219.357064) (xy 37.138868 -219.4091)
			(xy 37.139372 -219.435426) (xy 43.996105 -219.435426) (xy 44.000135 -219.382928) (xy 44.012132 -219.33166)
			(xy 44.031815 -219.282825) (xy 44.058721 -219.237566) (xy 44.092221 -219.196945) (xy 44.131529 -219.161914)
			(xy 44.175724 -219.133294) (xy 44.223769 -219.111755) (xy 44.27454 -219.097803) (xy 44.326845 -219.091765)
			(xy 44.379459 -219.093782) (xy 44.431149 -219.103806) (xy 44.480702 -219.121604) (xy 44.526958 -219.146757)
			(xy 44.568832 -219.178676) (xy 44.605344 -219.216614) (xy 44.635636 -219.25968) (xy 44.658999 -219.306865)
			(xy 44.674885 -219.357064) (xy 44.682922 -219.4091) (xy 44.683426 -219.435426) (xy 51.540159 -219.435426)
			(xy 51.544189 -219.382928) (xy 51.556186 -219.33166) (xy 51.575869 -219.282825) (xy 51.602775 -219.237566)
			(xy 51.636275 -219.196945) (xy 51.675583 -219.161914) (xy 51.719778 -219.133294) (xy 51.767823 -219.111755)
			(xy 51.818594 -219.097803) (xy 51.870899 -219.091765) (xy 51.923513 -219.093782) (xy 51.975203 -219.103806)
			(xy 52.024756 -219.121604) (xy 52.071012 -219.146757) (xy 52.112886 -219.178676) (xy 52.149398 -219.216614)
			(xy 52.17969 -219.25968) (xy 52.203053 -219.306865) (xy 52.218939 -219.357064) (xy 52.226976 -219.4091)
			(xy 52.22748 -219.435426) (xy 52.226976 -219.461752) (xy 52.218939 -219.513788) (xy 52.203053 -219.563987)
			(xy 52.17969 -219.611172) (xy 52.149398 -219.654238) (xy 52.112886 -219.692176) (xy 52.071012 -219.724095)
			(xy 52.024756 -219.749248) (xy 51.975203 -219.767046) (xy 51.923513 -219.77707) (xy 51.870899 -219.779087)
			(xy 51.818594 -219.773049) (xy 51.767823 -219.759097) (xy 51.719778 -219.737558) (xy 51.675583 -219.708938)
			(xy 51.636275 -219.673907) (xy 51.602775 -219.633286) (xy 51.575869 -219.588027) (xy 51.556186 -219.539192)
			(xy 51.544189 -219.487924) (xy 51.540159 -219.435426) (xy 44.683426 -219.435426) (xy 44.682922 -219.461752)
			(xy 44.674885 -219.513788) (xy 44.658999 -219.563987) (xy 44.635636 -219.611172) (xy 44.605344 -219.654238)
			(xy 44.568832 -219.692176) (xy 44.526958 -219.724095) (xy 44.480702 -219.749248) (xy 44.431149 -219.767046)
			(xy 44.379459 -219.77707) (xy 44.326845 -219.779087) (xy 44.27454 -219.773049) (xy 44.223769 -219.759097)
			(xy 44.175724 -219.737558) (xy 44.131529 -219.708938) (xy 44.092221 -219.673907) (xy 44.058721 -219.633286)
			(xy 44.031815 -219.588027) (xy 44.012132 -219.539192) (xy 44.000135 -219.487924) (xy 43.996105 -219.435426)
			(xy 37.139372 -219.435426) (xy 37.138868 -219.461752) (xy 37.130831 -219.513788) (xy 37.114945 -219.563987)
			(xy 37.091582 -219.611172) (xy 37.06129 -219.654238) (xy 37.024778 -219.692176) (xy 36.982904 -219.724095)
			(xy 36.936648 -219.749248) (xy 36.887095 -219.767046) (xy 36.835405 -219.77707) (xy 36.782791 -219.779087)
			(xy 36.730486 -219.773049) (xy 36.679715 -219.759097) (xy 36.63167 -219.737558) (xy 36.587475 -219.708938)
			(xy 36.548167 -219.673907) (xy 36.514667 -219.633286) (xy 36.487761 -219.588027) (xy 36.468078 -219.539192)
			(xy 36.456081 -219.487924) (xy 36.452051 -219.435426) (xy 29.595572 -219.435426) (xy 29.595068 -219.461752)
			(xy 29.587031 -219.513788) (xy 29.571145 -219.563987) (xy 29.547782 -219.611172) (xy 29.51749 -219.654238)
			(xy 29.480978 -219.692176) (xy 29.439104 -219.724095) (xy 29.392848 -219.749248) (xy 29.343295 -219.767046)
			(xy 29.291605 -219.77707) (xy 29.238991 -219.779087) (xy 29.186686 -219.773049) (xy 29.135915 -219.759097)
			(xy 29.08787 -219.737558) (xy 29.043675 -219.708938) (xy 29.004367 -219.673907) (xy 28.970867 -219.633286)
			(xy 28.943961 -219.588027) (xy 28.924278 -219.539192) (xy 28.912281 -219.487924) (xy 28.908251 -219.435426)
			(xy 22.051518 -219.435426) (xy 22.051014 -219.461752) (xy 22.042977 -219.513788) (xy 22.027091 -219.563987)
			(xy 22.003728 -219.611172) (xy 21.973436 -219.654238) (xy 21.936924 -219.692176) (xy 21.89505 -219.724095)
			(xy 21.848794 -219.749248) (xy 21.799241 -219.767046) (xy 21.747551 -219.77707) (xy 21.694937 -219.779087)
			(xy 21.642632 -219.773049) (xy 21.591861 -219.759097) (xy 21.543816 -219.737558) (xy 21.499621 -219.708938)
			(xy 21.460313 -219.673907) (xy 21.426813 -219.633286) (xy 21.399907 -219.588027) (xy 21.380224 -219.539192)
			(xy 21.368227 -219.487924) (xy 21.364197 -219.435426) (xy 16.086074 -219.435426) (xy 16.086074 -220.28531)
			(xy 17.264129 -220.28531) (xy 17.268159 -220.232812) (xy 17.280156 -220.181544) (xy 17.299839 -220.132709)
			(xy 17.326745 -220.08745) (xy 17.360245 -220.046829) (xy 17.399553 -220.011798) (xy 17.443748 -219.983178)
			(xy 17.491793 -219.961639) (xy 17.542564 -219.947687) (xy 17.594869 -219.941649) (xy 17.647483 -219.943666)
			(xy 17.699173 -219.95369) (xy 17.748726 -219.971488) (xy 17.794982 -219.996641) (xy 17.836856 -220.02856)
			(xy 17.873368 -220.066498) (xy 17.90366 -220.109564) (xy 17.927023 -220.156749) (xy 17.942909 -220.206948)
			(xy 17.950946 -220.258984) (xy 17.95145 -220.28531) (xy 21.364197 -220.28531) (xy 21.368227 -220.232812)
			(xy 21.380224 -220.181544) (xy 21.399907 -220.132709) (xy 21.426813 -220.08745) (xy 21.460313 -220.046829)
			(xy 21.499621 -220.011798) (xy 21.543816 -219.983178) (xy 21.591861 -219.961639) (xy 21.642632 -219.947687)
			(xy 21.694937 -219.941649) (xy 21.747551 -219.943666) (xy 21.799241 -219.95369) (xy 21.848794 -219.971488)
			(xy 21.89505 -219.996641) (xy 21.936924 -220.02856) (xy 21.973436 -220.066498) (xy 22.003728 -220.109564)
			(xy 22.027091 -220.156749) (xy 22.042977 -220.206948) (xy 22.051014 -220.258984) (xy 22.051518 -220.28531)
			(xy 24.808183 -220.28531) (xy 24.812213 -220.232812) (xy 24.82421 -220.181544) (xy 24.843893 -220.132709)
			(xy 24.870799 -220.08745) (xy 24.904299 -220.046829) (xy 24.943607 -220.011798) (xy 24.987802 -219.983178)
			(xy 25.035847 -219.961639) (xy 25.086618 -219.947687) (xy 25.138923 -219.941649) (xy 25.191537 -219.943666)
			(xy 25.243227 -219.95369) (xy 25.29278 -219.971488) (xy 25.339036 -219.996641) (xy 25.38091 -220.02856)
			(xy 25.417422 -220.066498) (xy 25.447714 -220.109564) (xy 25.471077 -220.156749) (xy 25.486963 -220.206948)
			(xy 25.495 -220.258984) (xy 25.495504 -220.28531) (xy 28.908251 -220.28531) (xy 28.912281 -220.232812)
			(xy 28.924278 -220.181544) (xy 28.943961 -220.132709) (xy 28.970867 -220.08745) (xy 29.004367 -220.046829)
			(xy 29.043675 -220.011798) (xy 29.08787 -219.983178) (xy 29.135915 -219.961639) (xy 29.186686 -219.947687)
			(xy 29.238991 -219.941649) (xy 29.291605 -219.943666) (xy 29.343295 -219.95369) (xy 29.392848 -219.971488)
			(xy 29.439104 -219.996641) (xy 29.480978 -220.02856) (xy 29.51749 -220.066498) (xy 29.547782 -220.109564)
			(xy 29.571145 -220.156749) (xy 29.587031 -220.206948) (xy 29.595068 -220.258984) (xy 29.595572 -220.28531)
			(xy 32.351983 -220.28531) (xy 32.356013 -220.232812) (xy 32.36801 -220.181544) (xy 32.387693 -220.132709)
			(xy 32.414599 -220.08745) (xy 32.448099 -220.046829) (xy 32.487407 -220.011798) (xy 32.531602 -219.983178)
			(xy 32.579647 -219.961639) (xy 32.630418 -219.947687) (xy 32.682723 -219.941649) (xy 32.735337 -219.943666)
			(xy 32.787027 -219.95369) (xy 32.83658 -219.971488) (xy 32.882836 -219.996641) (xy 32.92471 -220.02856)
			(xy 32.961222 -220.066498) (xy 32.991514 -220.109564) (xy 33.014877 -220.156749) (xy 33.030763 -220.206948)
			(xy 33.0388 -220.258984) (xy 33.039304 -220.28531) (xy 36.452051 -220.28531) (xy 36.456081 -220.232812)
			(xy 36.468078 -220.181544) (xy 36.487761 -220.132709) (xy 36.514667 -220.08745) (xy 36.548167 -220.046829)
			(xy 36.587475 -220.011798) (xy 36.63167 -219.983178) (xy 36.679715 -219.961639) (xy 36.730486 -219.947687)
			(xy 36.782791 -219.941649) (xy 36.835405 -219.943666) (xy 36.887095 -219.95369) (xy 36.936648 -219.971488)
			(xy 36.982904 -219.996641) (xy 37.024778 -220.02856) (xy 37.06129 -220.066498) (xy 37.091582 -220.109564)
			(xy 37.114945 -220.156749) (xy 37.130831 -220.206948) (xy 37.138868 -220.258984) (xy 37.139372 -220.28531)
			(xy 39.896037 -220.28531) (xy 39.900067 -220.232812) (xy 39.912064 -220.181544) (xy 39.931747 -220.132709)
			(xy 39.958653 -220.08745) (xy 39.992153 -220.046829) (xy 40.031461 -220.011798) (xy 40.075656 -219.983178)
			(xy 40.123701 -219.961639) (xy 40.174472 -219.947687) (xy 40.226777 -219.941649) (xy 40.279391 -219.943666)
			(xy 40.331081 -219.95369) (xy 40.380634 -219.971488) (xy 40.42689 -219.996641) (xy 40.468764 -220.02856)
			(xy 40.505276 -220.066498) (xy 40.535568 -220.109564) (xy 40.558931 -220.156749) (xy 40.574817 -220.206948)
			(xy 40.582854 -220.258984) (xy 40.583358 -220.28531) (xy 43.996105 -220.28531) (xy 44.000135 -220.232812)
			(xy 44.012132 -220.181544) (xy 44.031815 -220.132709) (xy 44.058721 -220.08745) (xy 44.092221 -220.046829)
			(xy 44.131529 -220.011798) (xy 44.175724 -219.983178) (xy 44.223769 -219.961639) (xy 44.27454 -219.947687)
			(xy 44.326845 -219.941649) (xy 44.379459 -219.943666) (xy 44.431149 -219.95369) (xy 44.480702 -219.971488)
			(xy 44.526958 -219.996641) (xy 44.568832 -220.02856) (xy 44.605344 -220.066498) (xy 44.635636 -220.109564)
			(xy 44.658999 -220.156749) (xy 44.674885 -220.206948) (xy 44.682922 -220.258984) (xy 44.683426 -220.28531)
			(xy 47.440091 -220.28531) (xy 47.444121 -220.232812) (xy 47.456118 -220.181544) (xy 47.475801 -220.132709)
			(xy 47.502707 -220.08745) (xy 47.536207 -220.046829) (xy 47.575515 -220.011798) (xy 47.61971 -219.983178)
			(xy 47.667755 -219.961639) (xy 47.718526 -219.947687) (xy 47.770831 -219.941649) (xy 47.823445 -219.943666)
			(xy 47.875135 -219.95369) (xy 47.924688 -219.971488) (xy 47.970944 -219.996641) (xy 48.012818 -220.02856)
			(xy 48.04933 -220.066498) (xy 48.079622 -220.109564) (xy 48.102985 -220.156749) (xy 48.118871 -220.206948)
			(xy 48.126908 -220.258984) (xy 48.127412 -220.28531) (xy 51.540159 -220.28531) (xy 51.544189 -220.232812)
			(xy 51.556186 -220.181544) (xy 51.575869 -220.132709) (xy 51.602775 -220.08745) (xy 51.636275 -220.046829)
			(xy 51.675583 -220.011798) (xy 51.719778 -219.983178) (xy 51.767823 -219.961639) (xy 51.818594 -219.947687)
			(xy 51.870899 -219.941649) (xy 51.923513 -219.943666) (xy 51.975203 -219.95369) (xy 52.024756 -219.971488)
			(xy 52.071012 -219.996641) (xy 52.112886 -220.02856) (xy 52.149398 -220.066498) (xy 52.17969 -220.109564)
			(xy 52.203053 -220.156749) (xy 52.218939 -220.206948) (xy 52.226976 -220.258984) (xy 52.22748 -220.28531)
			(xy 52.226976 -220.311636) (xy 52.218939 -220.363672) (xy 52.203053 -220.413871) (xy 52.17969 -220.461056)
			(xy 52.149398 -220.504122) (xy 52.112886 -220.54206) (xy 52.071012 -220.573979) (xy 52.024756 -220.599132)
			(xy 51.975203 -220.61693) (xy 51.923513 -220.626954) (xy 51.870899 -220.628971) (xy 51.818594 -220.622933)
			(xy 51.767823 -220.608981) (xy 51.719778 -220.587442) (xy 51.675583 -220.558822) (xy 51.636275 -220.523791)
			(xy 51.602775 -220.48317) (xy 51.575869 -220.437911) (xy 51.556186 -220.389076) (xy 51.544189 -220.337808)
			(xy 51.540159 -220.28531) (xy 48.127412 -220.28531) (xy 48.126908 -220.311636) (xy 48.118871 -220.363672)
			(xy 48.102985 -220.413871) (xy 48.079622 -220.461056) (xy 48.04933 -220.504122) (xy 48.012818 -220.54206)
			(xy 47.970944 -220.573979) (xy 47.924688 -220.599132) (xy 47.875135 -220.61693) (xy 47.823445 -220.626954)
			(xy 47.770831 -220.628971) (xy 47.718526 -220.622933) (xy 47.667755 -220.608981) (xy 47.61971 -220.587442)
			(xy 47.575515 -220.558822) (xy 47.536207 -220.523791) (xy 47.502707 -220.48317) (xy 47.475801 -220.437911)
			(xy 47.456118 -220.389076) (xy 47.444121 -220.337808) (xy 47.440091 -220.28531) (xy 44.683426 -220.28531)
			(xy 44.682922 -220.311636) (xy 44.674885 -220.363672) (xy 44.658999 -220.413871) (xy 44.635636 -220.461056)
			(xy 44.605344 -220.504122) (xy 44.568832 -220.54206) (xy 44.526958 -220.573979) (xy 44.480702 -220.599132)
			(xy 44.431149 -220.61693) (xy 44.379459 -220.626954) (xy 44.326845 -220.628971) (xy 44.27454 -220.622933)
			(xy 44.223769 -220.608981) (xy 44.175724 -220.587442) (xy 44.131529 -220.558822) (xy 44.092221 -220.523791)
			(xy 44.058721 -220.48317) (xy 44.031815 -220.437911) (xy 44.012132 -220.389076) (xy 44.000135 -220.337808)
			(xy 43.996105 -220.28531) (xy 40.583358 -220.28531) (xy 40.582854 -220.311636) (xy 40.574817 -220.363672)
			(xy 40.558931 -220.413871) (xy 40.535568 -220.461056) (xy 40.505276 -220.504122) (xy 40.468764 -220.54206)
			(xy 40.42689 -220.573979) (xy 40.380634 -220.599132) (xy 40.331081 -220.61693) (xy 40.279391 -220.626954)
			(xy 40.226777 -220.628971) (xy 40.174472 -220.622933) (xy 40.123701 -220.608981) (xy 40.075656 -220.587442)
			(xy 40.031461 -220.558822) (xy 39.992153 -220.523791) (xy 39.958653 -220.48317) (xy 39.931747 -220.437911)
			(xy 39.912064 -220.389076) (xy 39.900067 -220.337808) (xy 39.896037 -220.28531) (xy 37.139372 -220.28531)
			(xy 37.138868 -220.311636) (xy 37.130831 -220.363672) (xy 37.114945 -220.413871) (xy 37.091582 -220.461056)
			(xy 37.06129 -220.504122) (xy 37.024778 -220.54206) (xy 36.982904 -220.573979) (xy 36.936648 -220.599132)
			(xy 36.887095 -220.61693) (xy 36.835405 -220.626954) (xy 36.782791 -220.628971) (xy 36.730486 -220.622933)
			(xy 36.679715 -220.608981) (xy 36.63167 -220.587442) (xy 36.587475 -220.558822) (xy 36.548167 -220.523791)
			(xy 36.514667 -220.48317) (xy 36.487761 -220.437911) (xy 36.468078 -220.389076) (xy 36.456081 -220.337808)
			(xy 36.452051 -220.28531) (xy 33.039304 -220.28531) (xy 33.0388 -220.311636) (xy 33.030763 -220.363672)
			(xy 33.014877 -220.413871) (xy 32.991514 -220.461056) (xy 32.961222 -220.504122) (xy 32.92471 -220.54206)
			(xy 32.882836 -220.573979) (xy 32.83658 -220.599132) (xy 32.787027 -220.61693) (xy 32.735337 -220.626954)
			(xy 32.682723 -220.628971) (xy 32.630418 -220.622933) (xy 32.579647 -220.608981) (xy 32.531602 -220.587442)
			(xy 32.487407 -220.558822) (xy 32.448099 -220.523791) (xy 32.414599 -220.48317) (xy 32.387693 -220.437911)
			(xy 32.36801 -220.389076) (xy 32.356013 -220.337808) (xy 32.351983 -220.28531) (xy 29.595572 -220.28531)
			(xy 29.595068 -220.311636) (xy 29.587031 -220.363672) (xy 29.571145 -220.413871) (xy 29.547782 -220.461056)
			(xy 29.51749 -220.504122) (xy 29.480978 -220.54206) (xy 29.439104 -220.573979) (xy 29.392848 -220.599132)
			(xy 29.343295 -220.61693) (xy 29.291605 -220.626954) (xy 29.238991 -220.628971) (xy 29.186686 -220.622933)
			(xy 29.135915 -220.608981) (xy 29.08787 -220.587442) (xy 29.043675 -220.558822) (xy 29.004367 -220.523791)
			(xy 28.970867 -220.48317) (xy 28.943961 -220.437911) (xy 28.924278 -220.389076) (xy 28.912281 -220.337808)
			(xy 28.908251 -220.28531) (xy 25.495504 -220.28531) (xy 25.495 -220.311636) (xy 25.486963 -220.363672)
			(xy 25.471077 -220.413871) (xy 25.447714 -220.461056) (xy 25.417422 -220.504122) (xy 25.38091 -220.54206)
			(xy 25.339036 -220.573979) (xy 25.29278 -220.599132) (xy 25.243227 -220.61693) (xy 25.191537 -220.626954)
			(xy 25.138923 -220.628971) (xy 25.086618 -220.622933) (xy 25.035847 -220.608981) (xy 24.987802 -220.587442)
			(xy 24.943607 -220.558822) (xy 24.904299 -220.523791) (xy 24.870799 -220.48317) (xy 24.843893 -220.437911)
			(xy 24.82421 -220.389076) (xy 24.812213 -220.337808) (xy 24.808183 -220.28531) (xy 22.051518 -220.28531)
			(xy 22.051014 -220.311636) (xy 22.042977 -220.363672) (xy 22.027091 -220.413871) (xy 22.003728 -220.461056)
			(xy 21.973436 -220.504122) (xy 21.936924 -220.54206) (xy 21.89505 -220.573979) (xy 21.848794 -220.599132)
			(xy 21.799241 -220.61693) (xy 21.747551 -220.626954) (xy 21.694937 -220.628971) (xy 21.642632 -220.622933)
			(xy 21.591861 -220.608981) (xy 21.543816 -220.587442) (xy 21.499621 -220.558822) (xy 21.460313 -220.523791)
			(xy 21.426813 -220.48317) (xy 21.399907 -220.437911) (xy 21.380224 -220.389076) (xy 21.368227 -220.337808)
			(xy 21.364197 -220.28531) (xy 17.95145 -220.28531) (xy 17.950946 -220.311636) (xy 17.942909 -220.363672)
			(xy 17.927023 -220.413871) (xy 17.90366 -220.461056) (xy 17.873368 -220.504122) (xy 17.836856 -220.54206)
			(xy 17.794982 -220.573979) (xy 17.748726 -220.599132) (xy 17.699173 -220.61693) (xy 17.647483 -220.626954)
			(xy 17.594869 -220.628971) (xy 17.542564 -220.622933) (xy 17.491793 -220.608981) (xy 17.443748 -220.587442)
			(xy 17.399553 -220.558822) (xy 17.360245 -220.523791) (xy 17.326745 -220.48317) (xy 17.299839 -220.437911)
			(xy 17.280156 -220.389076) (xy 17.268159 -220.337808) (xy 17.264129 -220.28531) (xy 16.086074 -220.28531)
			(xy 16.086074 -221.135194) (xy 17.264129 -221.135194) (xy 17.268159 -221.082696) (xy 17.280156 -221.031428)
			(xy 17.299839 -220.982593) (xy 17.326745 -220.937334) (xy 17.360245 -220.896713) (xy 17.399553 -220.861682)
			(xy 17.443748 -220.833062) (xy 17.491793 -220.811523) (xy 17.542564 -220.797571) (xy 17.594869 -220.791533)
			(xy 17.647483 -220.79355) (xy 17.699173 -220.803574) (xy 17.748726 -220.821372) (xy 17.794982 -220.846525)
			(xy 17.836856 -220.878444) (xy 17.873368 -220.916382) (xy 17.90366 -220.959448) (xy 17.927023 -221.006633)
			(xy 17.942909 -221.056832) (xy 17.950946 -221.108868) (xy 17.95145 -221.135194) (xy 24.808183 -221.135194)
			(xy 24.812213 -221.082696) (xy 24.82421 -221.031428) (xy 24.843893 -220.982593) (xy 24.870799 -220.937334)
			(xy 24.904299 -220.896713) (xy 24.943607 -220.861682) (xy 24.987802 -220.833062) (xy 25.035847 -220.811523)
			(xy 25.086618 -220.797571) (xy 25.138923 -220.791533) (xy 25.191537 -220.79355) (xy 25.243227 -220.803574)
			(xy 25.29278 -220.821372) (xy 25.339036 -220.846525) (xy 25.38091 -220.878444) (xy 25.417422 -220.916382)
			(xy 25.447714 -220.959448) (xy 25.471077 -221.006633) (xy 25.486963 -221.056832) (xy 25.495 -221.108868)
			(xy 25.495504 -221.135194) (xy 32.351983 -221.135194) (xy 32.356013 -221.082696) (xy 32.36801 -221.031428)
			(xy 32.387693 -220.982593) (xy 32.414599 -220.937334) (xy 32.448099 -220.896713) (xy 32.487407 -220.861682)
			(xy 32.531602 -220.833062) (xy 32.579647 -220.811523) (xy 32.630418 -220.797571) (xy 32.682723 -220.791533)
			(xy 32.735337 -220.79355) (xy 32.787027 -220.803574) (xy 32.83658 -220.821372) (xy 32.882836 -220.846525)
			(xy 32.92471 -220.878444) (xy 32.961222 -220.916382) (xy 32.991514 -220.959448) (xy 33.014877 -221.006633)
			(xy 33.030763 -221.056832) (xy 33.0388 -221.108868) (xy 33.039304 -221.135194) (xy 39.896037 -221.135194)
			(xy 39.900067 -221.082696) (xy 39.912064 -221.031428) (xy 39.931747 -220.982593) (xy 39.958653 -220.937334)
			(xy 39.992153 -220.896713) (xy 40.031461 -220.861682) (xy 40.075656 -220.833062) (xy 40.123701 -220.811523)
			(xy 40.174472 -220.797571) (xy 40.226777 -220.791533) (xy 40.279391 -220.79355) (xy 40.331081 -220.803574)
			(xy 40.380634 -220.821372) (xy 40.42689 -220.846525) (xy 40.468764 -220.878444) (xy 40.505276 -220.916382)
			(xy 40.535568 -220.959448) (xy 40.558931 -221.006633) (xy 40.574817 -221.056832) (xy 40.582854 -221.108868)
			(xy 40.583358 -221.135194) (xy 47.440091 -221.135194) (xy 47.444121 -221.082696) (xy 47.456118 -221.031428)
			(xy 47.475801 -220.982593) (xy 47.502707 -220.937334) (xy 47.536207 -220.896713) (xy 47.575515 -220.861682)
			(xy 47.61971 -220.833062) (xy 47.667755 -220.811523) (xy 47.718526 -220.797571) (xy 47.770831 -220.791533)
			(xy 47.823445 -220.79355) (xy 47.875135 -220.803574) (xy 47.924688 -220.821372) (xy 47.970944 -220.846525)
			(xy 48.012818 -220.878444) (xy 48.04933 -220.916382) (xy 48.079622 -220.959448) (xy 48.102985 -221.006633)
			(xy 48.118871 -221.056832) (xy 48.126908 -221.108868) (xy 48.127412 -221.135194) (xy 48.126908 -221.16152)
			(xy 48.118871 -221.213556) (xy 48.102985 -221.263755) (xy 48.079622 -221.31094) (xy 48.04933 -221.354006)
			(xy 48.012818 -221.391944) (xy 47.970944 -221.423863) (xy 47.924688 -221.449016) (xy 47.875135 -221.466814)
			(xy 47.823445 -221.476838) (xy 47.770831 -221.478855) (xy 47.718526 -221.472817) (xy 47.667755 -221.458865)
			(xy 47.61971 -221.437326) (xy 47.575515 -221.408706) (xy 47.536207 -221.373675) (xy 47.502707 -221.333054)
			(xy 47.475801 -221.287795) (xy 47.456118 -221.23896) (xy 47.444121 -221.187692) (xy 47.440091 -221.135194)
			(xy 40.583358 -221.135194) (xy 40.582854 -221.16152) (xy 40.574817 -221.213556) (xy 40.558931 -221.263755)
			(xy 40.535568 -221.31094) (xy 40.505276 -221.354006) (xy 40.468764 -221.391944) (xy 40.42689 -221.423863)
			(xy 40.380634 -221.449016) (xy 40.331081 -221.466814) (xy 40.279391 -221.476838) (xy 40.226777 -221.478855)
			(xy 40.174472 -221.472817) (xy 40.123701 -221.458865) (xy 40.075656 -221.437326) (xy 40.031461 -221.408706)
			(xy 39.992153 -221.373675) (xy 39.958653 -221.333054) (xy 39.931747 -221.287795) (xy 39.912064 -221.23896)
			(xy 39.900067 -221.187692) (xy 39.896037 -221.135194) (xy 33.039304 -221.135194) (xy 33.0388 -221.16152)
			(xy 33.030763 -221.213556) (xy 33.014877 -221.263755) (xy 32.991514 -221.31094) (xy 32.961222 -221.354006)
			(xy 32.92471 -221.391944) (xy 32.882836 -221.423863) (xy 32.83658 -221.449016) (xy 32.787027 -221.466814)
			(xy 32.735337 -221.476838) (xy 32.682723 -221.478855) (xy 32.630418 -221.472817) (xy 32.579647 -221.458865)
			(xy 32.531602 -221.437326) (xy 32.487407 -221.408706) (xy 32.448099 -221.373675) (xy 32.414599 -221.333054)
			(xy 32.387693 -221.287795) (xy 32.36801 -221.23896) (xy 32.356013 -221.187692) (xy 32.351983 -221.135194)
			(xy 25.495504 -221.135194) (xy 25.495 -221.16152) (xy 25.486963 -221.213556) (xy 25.471077 -221.263755)
			(xy 25.447714 -221.31094) (xy 25.417422 -221.354006) (xy 25.38091 -221.391944) (xy 25.339036 -221.423863)
			(xy 25.29278 -221.449016) (xy 25.243227 -221.466814) (xy 25.191537 -221.476838) (xy 25.138923 -221.478855)
			(xy 25.086618 -221.472817) (xy 25.035847 -221.458865) (xy 24.987802 -221.437326) (xy 24.943607 -221.408706)
			(xy 24.904299 -221.373675) (xy 24.870799 -221.333054) (xy 24.843893 -221.287795) (xy 24.82421 -221.23896)
			(xy 24.812213 -221.187692) (xy 24.808183 -221.135194) (xy 17.95145 -221.135194) (xy 17.950946 -221.16152)
			(xy 17.942909 -221.213556) (xy 17.927023 -221.263755) (xy 17.90366 -221.31094) (xy 17.873368 -221.354006)
			(xy 17.836856 -221.391944) (xy 17.794982 -221.423863) (xy 17.748726 -221.449016) (xy 17.699173 -221.466814)
			(xy 17.647483 -221.476838) (xy 17.594869 -221.478855) (xy 17.542564 -221.472817) (xy 17.491793 -221.458865)
			(xy 17.443748 -221.437326) (xy 17.399553 -221.408706) (xy 17.360245 -221.373675) (xy 17.326745 -221.333054)
			(xy 17.299839 -221.287795) (xy 17.280156 -221.23896) (xy 17.268159 -221.187692) (xy 17.264129 -221.135194)
			(xy 16.086074 -221.135194) (xy 16.086074 -221.985332) (xy 21.364197 -221.985332) (xy 21.368227 -221.932834)
			(xy 21.380224 -221.881566) (xy 21.399907 -221.832731) (xy 21.426813 -221.787472) (xy 21.460313 -221.746851)
			(xy 21.499621 -221.71182) (xy 21.543816 -221.6832) (xy 21.591861 -221.661661) (xy 21.642632 -221.647709)
			(xy 21.694937 -221.641671) (xy 21.747551 -221.643688) (xy 21.799241 -221.653712) (xy 21.848794 -221.67151)
			(xy 21.89505 -221.696663) (xy 21.936924 -221.728582) (xy 21.973436 -221.76652) (xy 22.003728 -221.809586)
			(xy 22.027091 -221.856771) (xy 22.042977 -221.90697) (xy 22.051014 -221.959006) (xy 22.051518 -221.985332)
			(xy 28.908251 -221.985332) (xy 28.912281 -221.932834) (xy 28.924278 -221.881566) (xy 28.943961 -221.832731)
			(xy 28.970867 -221.787472) (xy 29.004367 -221.746851) (xy 29.043675 -221.71182) (xy 29.08787 -221.6832)
			(xy 29.135915 -221.661661) (xy 29.186686 -221.647709) (xy 29.238991 -221.641671) (xy 29.291605 -221.643688)
			(xy 29.343295 -221.653712) (xy 29.392848 -221.67151) (xy 29.439104 -221.696663) (xy 29.480978 -221.728582)
			(xy 29.51749 -221.76652) (xy 29.547782 -221.809586) (xy 29.571145 -221.856771) (xy 29.587031 -221.90697)
			(xy 29.595068 -221.959006) (xy 29.595572 -221.985332) (xy 36.452051 -221.985332) (xy 36.456081 -221.932834)
			(xy 36.468078 -221.881566) (xy 36.487761 -221.832731) (xy 36.514667 -221.787472) (xy 36.548167 -221.746851)
			(xy 36.587475 -221.71182) (xy 36.63167 -221.6832) (xy 36.679715 -221.661661) (xy 36.730486 -221.647709)
			(xy 36.782791 -221.641671) (xy 36.835405 -221.643688) (xy 36.887095 -221.653712) (xy 36.936648 -221.67151)
			(xy 36.982904 -221.696663) (xy 37.024778 -221.728582) (xy 37.06129 -221.76652) (xy 37.091582 -221.809586)
			(xy 37.114945 -221.856771) (xy 37.130831 -221.90697) (xy 37.138868 -221.959006) (xy 37.139372 -221.985332)
			(xy 43.996105 -221.985332) (xy 44.000135 -221.932834) (xy 44.012132 -221.881566) (xy 44.031815 -221.832731)
			(xy 44.058721 -221.787472) (xy 44.092221 -221.746851) (xy 44.131529 -221.71182) (xy 44.175724 -221.6832)
			(xy 44.223769 -221.661661) (xy 44.27454 -221.647709) (xy 44.326845 -221.641671) (xy 44.379459 -221.643688)
			(xy 44.431149 -221.653712) (xy 44.480702 -221.67151) (xy 44.526958 -221.696663) (xy 44.568832 -221.728582)
			(xy 44.605344 -221.76652) (xy 44.635636 -221.809586) (xy 44.658999 -221.856771) (xy 44.674885 -221.90697)
			(xy 44.682922 -221.959006) (xy 44.683426 -221.985332) (xy 51.540159 -221.985332) (xy 51.544189 -221.932834)
			(xy 51.556186 -221.881566) (xy 51.575869 -221.832731) (xy 51.602775 -221.787472) (xy 51.636275 -221.746851)
			(xy 51.675583 -221.71182) (xy 51.719778 -221.6832) (xy 51.767823 -221.661661) (xy 51.818594 -221.647709)
			(xy 51.870899 -221.641671) (xy 51.923513 -221.643688) (xy 51.975203 -221.653712) (xy 52.024756 -221.67151)
			(xy 52.071012 -221.696663) (xy 52.112886 -221.728582) (xy 52.149398 -221.76652) (xy 52.17969 -221.809586)
			(xy 52.203053 -221.856771) (xy 52.218939 -221.90697) (xy 52.226976 -221.959006) (xy 52.22748 -221.985332)
			(xy 52.226976 -222.011658) (xy 52.218939 -222.063694) (xy 52.203053 -222.113893) (xy 52.17969 -222.161078)
			(xy 52.149398 -222.204144) (xy 52.112886 -222.242082) (xy 52.071012 -222.274001) (xy 52.024756 -222.299154)
			(xy 51.975203 -222.316952) (xy 51.923513 -222.326976) (xy 51.870899 -222.328993) (xy 51.818594 -222.322955)
			(xy 51.767823 -222.309003) (xy 51.719778 -222.287464) (xy 51.675583 -222.258844) (xy 51.636275 -222.223813)
			(xy 51.602775 -222.183192) (xy 51.575869 -222.137933) (xy 51.556186 -222.089098) (xy 51.544189 -222.03783)
			(xy 51.540159 -221.985332) (xy 44.683426 -221.985332) (xy 44.682922 -222.011658) (xy 44.674885 -222.063694)
			(xy 44.658999 -222.113893) (xy 44.635636 -222.161078) (xy 44.605344 -222.204144) (xy 44.568832 -222.242082)
			(xy 44.526958 -222.274001) (xy 44.480702 -222.299154) (xy 44.431149 -222.316952) (xy 44.379459 -222.326976)
			(xy 44.326845 -222.328993) (xy 44.27454 -222.322955) (xy 44.223769 -222.309003) (xy 44.175724 -222.287464)
			(xy 44.131529 -222.258844) (xy 44.092221 -222.223813) (xy 44.058721 -222.183192) (xy 44.031815 -222.137933)
			(xy 44.012132 -222.089098) (xy 44.000135 -222.03783) (xy 43.996105 -221.985332) (xy 37.139372 -221.985332)
			(xy 37.138868 -222.011658) (xy 37.130831 -222.063694) (xy 37.114945 -222.113893) (xy 37.091582 -222.161078)
			(xy 37.06129 -222.204144) (xy 37.024778 -222.242082) (xy 36.982904 -222.274001) (xy 36.936648 -222.299154)
			(xy 36.887095 -222.316952) (xy 36.835405 -222.326976) (xy 36.782791 -222.328993) (xy 36.730486 -222.322955)
			(xy 36.679715 -222.309003) (xy 36.63167 -222.287464) (xy 36.587475 -222.258844) (xy 36.548167 -222.223813)
			(xy 36.514667 -222.183192) (xy 36.487761 -222.137933) (xy 36.468078 -222.089098) (xy 36.456081 -222.03783)
			(xy 36.452051 -221.985332) (xy 29.595572 -221.985332) (xy 29.595068 -222.011658) (xy 29.587031 -222.063694)
			(xy 29.571145 -222.113893) (xy 29.547782 -222.161078) (xy 29.51749 -222.204144) (xy 29.480978 -222.242082)
			(xy 29.439104 -222.274001) (xy 29.392848 -222.299154) (xy 29.343295 -222.316952) (xy 29.291605 -222.326976)
			(xy 29.238991 -222.328993) (xy 29.186686 -222.322955) (xy 29.135915 -222.309003) (xy 29.08787 -222.287464)
			(xy 29.043675 -222.258844) (xy 29.004367 -222.223813) (xy 28.970867 -222.183192) (xy 28.943961 -222.137933)
			(xy 28.924278 -222.089098) (xy 28.912281 -222.03783) (xy 28.908251 -221.985332) (xy 22.051518 -221.985332)
			(xy 22.051014 -222.011658) (xy 22.042977 -222.063694) (xy 22.027091 -222.113893) (xy 22.003728 -222.161078)
			(xy 21.973436 -222.204144) (xy 21.936924 -222.242082) (xy 21.89505 -222.274001) (xy 21.848794 -222.299154)
			(xy 21.799241 -222.316952) (xy 21.747551 -222.326976) (xy 21.694937 -222.328993) (xy 21.642632 -222.322955)
			(xy 21.591861 -222.309003) (xy 21.543816 -222.287464) (xy 21.499621 -222.258844) (xy 21.460313 -222.223813)
			(xy 21.426813 -222.183192) (xy 21.399907 -222.137933) (xy 21.380224 -222.089098) (xy 21.368227 -222.03783)
			(xy 21.364197 -221.985332) (xy 16.086074 -221.985332) (xy 16.086074 -222.835216) (xy 17.264129 -222.835216)
			(xy 17.268159 -222.782718) (xy 17.280156 -222.73145) (xy 17.299839 -222.682615) (xy 17.326745 -222.637356)
			(xy 17.360245 -222.596735) (xy 17.399553 -222.561704) (xy 17.443748 -222.533084) (xy 17.491793 -222.511545)
			(xy 17.542564 -222.497593) (xy 17.594869 -222.491555) (xy 17.647483 -222.493572) (xy 17.699173 -222.503596)
			(xy 17.748726 -222.521394) (xy 17.794982 -222.546547) (xy 17.836856 -222.578466) (xy 17.873368 -222.616404)
			(xy 17.90366 -222.65947) (xy 17.927023 -222.706655) (xy 17.942909 -222.756854) (xy 17.950946 -222.80889)
			(xy 17.95145 -222.835216) (xy 24.808183 -222.835216) (xy 24.812213 -222.782718) (xy 24.82421 -222.73145)
			(xy 24.843893 -222.682615) (xy 24.870799 -222.637356) (xy 24.904299 -222.596735) (xy 24.943607 -222.561704)
			(xy 24.987802 -222.533084) (xy 25.035847 -222.511545) (xy 25.086618 -222.497593) (xy 25.138923 -222.491555)
			(xy 25.191537 -222.493572) (xy 25.243227 -222.503596) (xy 25.29278 -222.521394) (xy 25.339036 -222.546547)
			(xy 25.38091 -222.578466) (xy 25.417422 -222.616404) (xy 25.447714 -222.65947) (xy 25.471077 -222.706655)
			(xy 25.486963 -222.756854) (xy 25.495 -222.80889) (xy 25.495504 -222.835216) (xy 32.351983 -222.835216)
			(xy 32.356013 -222.782718) (xy 32.36801 -222.73145) (xy 32.387693 -222.682615) (xy 32.414599 -222.637356)
			(xy 32.448099 -222.596735) (xy 32.487407 -222.561704) (xy 32.531602 -222.533084) (xy 32.579647 -222.511545)
			(xy 32.630418 -222.497593) (xy 32.682723 -222.491555) (xy 32.735337 -222.493572) (xy 32.787027 -222.503596)
			(xy 32.83658 -222.521394) (xy 32.882836 -222.546547) (xy 32.92471 -222.578466) (xy 32.961222 -222.616404)
			(xy 32.991514 -222.65947) (xy 33.014877 -222.706655) (xy 33.030763 -222.756854) (xy 33.0388 -222.80889)
			(xy 33.039304 -222.835216) (xy 39.896037 -222.835216) (xy 39.900067 -222.782718) (xy 39.912064 -222.73145)
			(xy 39.931747 -222.682615) (xy 39.958653 -222.637356) (xy 39.992153 -222.596735) (xy 40.031461 -222.561704)
			(xy 40.075656 -222.533084) (xy 40.123701 -222.511545) (xy 40.174472 -222.497593) (xy 40.226777 -222.491555)
			(xy 40.279391 -222.493572) (xy 40.331081 -222.503596) (xy 40.380634 -222.521394) (xy 40.42689 -222.546547)
			(xy 40.468764 -222.578466) (xy 40.505276 -222.616404) (xy 40.535568 -222.65947) (xy 40.558931 -222.706655)
			(xy 40.574817 -222.756854) (xy 40.582854 -222.80889) (xy 40.583358 -222.835216) (xy 47.440091 -222.835216)
			(xy 47.444121 -222.782718) (xy 47.456118 -222.73145) (xy 47.475801 -222.682615) (xy 47.502707 -222.637356)
			(xy 47.536207 -222.596735) (xy 47.575515 -222.561704) (xy 47.61971 -222.533084) (xy 47.667755 -222.511545)
			(xy 47.718526 -222.497593) (xy 47.770831 -222.491555) (xy 47.823445 -222.493572) (xy 47.875135 -222.503596)
			(xy 47.924688 -222.521394) (xy 47.970944 -222.546547) (xy 48.012818 -222.578466) (xy 48.04933 -222.616404)
			(xy 48.079622 -222.65947) (xy 48.102985 -222.706655) (xy 48.118871 -222.756854) (xy 48.126908 -222.80889)
			(xy 48.127412 -222.835216) (xy 48.126908 -222.861542) (xy 48.118871 -222.913578) (xy 48.102985 -222.963777)
			(xy 48.079622 -223.010962) (xy 48.04933 -223.054028) (xy 48.012818 -223.091966) (xy 47.970944 -223.123885)
			(xy 47.924688 -223.149038) (xy 47.875135 -223.166836) (xy 47.823445 -223.17686) (xy 47.770831 -223.178877)
			(xy 47.718526 -223.172839) (xy 47.667755 -223.158887) (xy 47.61971 -223.137348) (xy 47.575515 -223.108728)
			(xy 47.536207 -223.073697) (xy 47.502707 -223.033076) (xy 47.475801 -222.987817) (xy 47.456118 -222.938982)
			(xy 47.444121 -222.887714) (xy 47.440091 -222.835216) (xy 40.583358 -222.835216) (xy 40.582854 -222.861542)
			(xy 40.574817 -222.913578) (xy 40.558931 -222.963777) (xy 40.535568 -223.010962) (xy 40.505276 -223.054028)
			(xy 40.468764 -223.091966) (xy 40.42689 -223.123885) (xy 40.380634 -223.149038) (xy 40.331081 -223.166836)
			(xy 40.279391 -223.17686) (xy 40.226777 -223.178877) (xy 40.174472 -223.172839) (xy 40.123701 -223.158887)
			(xy 40.075656 -223.137348) (xy 40.031461 -223.108728) (xy 39.992153 -223.073697) (xy 39.958653 -223.033076)
			(xy 39.931747 -222.987817) (xy 39.912064 -222.938982) (xy 39.900067 -222.887714) (xy 39.896037 -222.835216)
			(xy 33.039304 -222.835216) (xy 33.0388 -222.861542) (xy 33.030763 -222.913578) (xy 33.014877 -222.963777)
			(xy 32.991514 -223.010962) (xy 32.961222 -223.054028) (xy 32.92471 -223.091966) (xy 32.882836 -223.123885)
			(xy 32.83658 -223.149038) (xy 32.787027 -223.166836) (xy 32.735337 -223.17686) (xy 32.682723 -223.178877)
			(xy 32.630418 -223.172839) (xy 32.579647 -223.158887) (xy 32.531602 -223.137348) (xy 32.487407 -223.108728)
			(xy 32.448099 -223.073697) (xy 32.414599 -223.033076) (xy 32.387693 -222.987817) (xy 32.36801 -222.938982)
			(xy 32.356013 -222.887714) (xy 32.351983 -222.835216) (xy 25.495504 -222.835216) (xy 25.495 -222.861542)
			(xy 25.486963 -222.913578) (xy 25.471077 -222.963777) (xy 25.447714 -223.010962) (xy 25.417422 -223.054028)
			(xy 25.38091 -223.091966) (xy 25.339036 -223.123885) (xy 25.29278 -223.149038) (xy 25.243227 -223.166836)
			(xy 25.191537 -223.17686) (xy 25.138923 -223.178877) (xy 25.086618 -223.172839) (xy 25.035847 -223.158887)
			(xy 24.987802 -223.137348) (xy 24.943607 -223.108728) (xy 24.904299 -223.073697) (xy 24.870799 -223.033076)
			(xy 24.843893 -222.987817) (xy 24.82421 -222.938982) (xy 24.812213 -222.887714) (xy 24.808183 -222.835216)
			(xy 17.95145 -222.835216) (xy 17.950946 -222.861542) (xy 17.942909 -222.913578) (xy 17.927023 -222.963777)
			(xy 17.90366 -223.010962) (xy 17.873368 -223.054028) (xy 17.836856 -223.091966) (xy 17.794982 -223.123885)
			(xy 17.748726 -223.149038) (xy 17.699173 -223.166836) (xy 17.647483 -223.17686) (xy 17.594869 -223.178877)
			(xy 17.542564 -223.172839) (xy 17.491793 -223.158887) (xy 17.443748 -223.137348) (xy 17.399553 -223.108728)
			(xy 17.360245 -223.073697) (xy 17.326745 -223.033076) (xy 17.299839 -222.987817) (xy 17.280156 -222.938982)
			(xy 17.268159 -222.887714) (xy 17.264129 -222.835216) (xy 16.086074 -222.835216) (xy 16.086074 -223.685354)
			(xy 21.364197 -223.685354) (xy 21.368227 -223.632856) (xy 21.380224 -223.581588) (xy 21.399907 -223.532753)
			(xy 21.426813 -223.487494) (xy 21.460313 -223.446873) (xy 21.499621 -223.411842) (xy 21.543816 -223.383222)
			(xy 21.591861 -223.361683) (xy 21.642632 -223.347731) (xy 21.694937 -223.341693) (xy 21.747551 -223.34371)
			(xy 21.799241 -223.353734) (xy 21.848794 -223.371532) (xy 21.89505 -223.396685) (xy 21.936924 -223.428604)
			(xy 21.973436 -223.466542) (xy 22.003728 -223.509608) (xy 22.027091 -223.556793) (xy 22.042977 -223.606992)
			(xy 22.051014 -223.659028) (xy 22.051518 -223.685354) (xy 28.908251 -223.685354) (xy 28.912281 -223.632856)
			(xy 28.924278 -223.581588) (xy 28.943961 -223.532753) (xy 28.970867 -223.487494) (xy 29.004367 -223.446873)
			(xy 29.043675 -223.411842) (xy 29.08787 -223.383222) (xy 29.135915 -223.361683) (xy 29.186686 -223.347731)
			(xy 29.238991 -223.341693) (xy 29.291605 -223.34371) (xy 29.343295 -223.353734) (xy 29.392848 -223.371532)
			(xy 29.439104 -223.396685) (xy 29.480978 -223.428604) (xy 29.51749 -223.466542) (xy 29.547782 -223.509608)
			(xy 29.571145 -223.556793) (xy 29.587031 -223.606992) (xy 29.595068 -223.659028) (xy 29.595572 -223.685354)
			(xy 36.452051 -223.685354) (xy 36.456081 -223.632856) (xy 36.468078 -223.581588) (xy 36.487761 -223.532753)
			(xy 36.514667 -223.487494) (xy 36.548167 -223.446873) (xy 36.587475 -223.411842) (xy 36.63167 -223.383222)
			(xy 36.679715 -223.361683) (xy 36.730486 -223.347731) (xy 36.782791 -223.341693) (xy 36.835405 -223.34371)
			(xy 36.887095 -223.353734) (xy 36.936648 -223.371532) (xy 36.982904 -223.396685) (xy 37.024778 -223.428604)
			(xy 37.06129 -223.466542) (xy 37.091582 -223.509608) (xy 37.114945 -223.556793) (xy 37.130831 -223.606992)
			(xy 37.138868 -223.659028) (xy 37.139372 -223.685354) (xy 43.996105 -223.685354) (xy 44.000135 -223.632856)
			(xy 44.012132 -223.581588) (xy 44.031815 -223.532753) (xy 44.058721 -223.487494) (xy 44.092221 -223.446873)
			(xy 44.131529 -223.411842) (xy 44.175724 -223.383222) (xy 44.223769 -223.361683) (xy 44.27454 -223.347731)
			(xy 44.326845 -223.341693) (xy 44.379459 -223.34371) (xy 44.431149 -223.353734) (xy 44.480702 -223.371532)
			(xy 44.526958 -223.396685) (xy 44.568832 -223.428604) (xy 44.605344 -223.466542) (xy 44.635636 -223.509608)
			(xy 44.658999 -223.556793) (xy 44.674885 -223.606992) (xy 44.682922 -223.659028) (xy 44.683426 -223.685354)
			(xy 51.540159 -223.685354) (xy 51.544189 -223.632856) (xy 51.556186 -223.581588) (xy 51.575869 -223.532753)
			(xy 51.602775 -223.487494) (xy 51.636275 -223.446873) (xy 51.675583 -223.411842) (xy 51.719778 -223.383222)
			(xy 51.767823 -223.361683) (xy 51.818594 -223.347731) (xy 51.870899 -223.341693) (xy 51.923513 -223.34371)
			(xy 51.975203 -223.353734) (xy 52.024756 -223.371532) (xy 52.071012 -223.396685) (xy 52.112886 -223.428604)
			(xy 52.149398 -223.466542) (xy 52.17969 -223.509608) (xy 52.203053 -223.556793) (xy 52.218939 -223.606992)
			(xy 52.226976 -223.659028) (xy 52.22748 -223.685354) (xy 52.226976 -223.71168) (xy 52.218939 -223.763716)
			(xy 52.203053 -223.813915) (xy 52.17969 -223.8611) (xy 52.149398 -223.904166) (xy 52.112886 -223.942104)
			(xy 52.071012 -223.974023) (xy 52.024756 -223.999176) (xy 51.975203 -224.016974) (xy 51.923513 -224.026998)
			(xy 51.870899 -224.029015) (xy 51.818594 -224.022977) (xy 51.767823 -224.009025) (xy 51.719778 -223.987486)
			(xy 51.675583 -223.958866) (xy 51.636275 -223.923835) (xy 51.602775 -223.883214) (xy 51.575869 -223.837955)
			(xy 51.556186 -223.78912) (xy 51.544189 -223.737852) (xy 51.540159 -223.685354) (xy 44.683426 -223.685354)
			(xy 44.682922 -223.71168) (xy 44.674885 -223.763716) (xy 44.658999 -223.813915) (xy 44.635636 -223.8611)
			(xy 44.605344 -223.904166) (xy 44.568832 -223.942104) (xy 44.526958 -223.974023) (xy 44.480702 -223.999176)
			(xy 44.431149 -224.016974) (xy 44.379459 -224.026998) (xy 44.326845 -224.029015) (xy 44.27454 -224.022977)
			(xy 44.223769 -224.009025) (xy 44.175724 -223.987486) (xy 44.131529 -223.958866) (xy 44.092221 -223.923835)
			(xy 44.058721 -223.883214) (xy 44.031815 -223.837955) (xy 44.012132 -223.78912) (xy 44.000135 -223.737852)
			(xy 43.996105 -223.685354) (xy 37.139372 -223.685354) (xy 37.138868 -223.71168) (xy 37.130831 -223.763716)
			(xy 37.114945 -223.813915) (xy 37.091582 -223.8611) (xy 37.06129 -223.904166) (xy 37.024778 -223.942104)
			(xy 36.982904 -223.974023) (xy 36.936648 -223.999176) (xy 36.887095 -224.016974) (xy 36.835405 -224.026998)
			(xy 36.782791 -224.029015) (xy 36.730486 -224.022977) (xy 36.679715 -224.009025) (xy 36.63167 -223.987486)
			(xy 36.587475 -223.958866) (xy 36.548167 -223.923835) (xy 36.514667 -223.883214) (xy 36.487761 -223.837955)
			(xy 36.468078 -223.78912) (xy 36.456081 -223.737852) (xy 36.452051 -223.685354) (xy 29.595572 -223.685354)
			(xy 29.595068 -223.71168) (xy 29.587031 -223.763716) (xy 29.571145 -223.813915) (xy 29.547782 -223.8611)
			(xy 29.51749 -223.904166) (xy 29.480978 -223.942104) (xy 29.439104 -223.974023) (xy 29.392848 -223.999176)
			(xy 29.343295 -224.016974) (xy 29.291605 -224.026998) (xy 29.238991 -224.029015) (xy 29.186686 -224.022977)
			(xy 29.135915 -224.009025) (xy 29.08787 -223.987486) (xy 29.043675 -223.958866) (xy 29.004367 -223.923835)
			(xy 28.970867 -223.883214) (xy 28.943961 -223.837955) (xy 28.924278 -223.78912) (xy 28.912281 -223.737852)
			(xy 28.908251 -223.685354) (xy 22.051518 -223.685354) (xy 22.051014 -223.71168) (xy 22.042977 -223.763716)
			(xy 22.027091 -223.813915) (xy 22.003728 -223.8611) (xy 21.973436 -223.904166) (xy 21.936924 -223.942104)
			(xy 21.89505 -223.974023) (xy 21.848794 -223.999176) (xy 21.799241 -224.016974) (xy 21.747551 -224.026998)
			(xy 21.694937 -224.029015) (xy 21.642632 -224.022977) (xy 21.591861 -224.009025) (xy 21.543816 -223.987486)
			(xy 21.499621 -223.958866) (xy 21.460313 -223.923835) (xy 21.426813 -223.883214) (xy 21.399907 -223.837955)
			(xy 21.380224 -223.78912) (xy 21.368227 -223.737852) (xy 21.364197 -223.685354) (xy 16.086074 -223.685354)
			(xy 16.086074 -224.535238) (xy 17.264129 -224.535238) (xy 17.268159 -224.48274) (xy 17.280156 -224.431472)
			(xy 17.299839 -224.382637) (xy 17.326745 -224.337378) (xy 17.360245 -224.296757) (xy 17.399553 -224.261726)
			(xy 17.443748 -224.233106) (xy 17.491793 -224.211567) (xy 17.542564 -224.197615) (xy 17.594869 -224.191577)
			(xy 17.647483 -224.193594) (xy 17.699173 -224.203618) (xy 17.748726 -224.221416) (xy 17.794982 -224.246569)
			(xy 17.836856 -224.278488) (xy 17.873368 -224.316426) (xy 17.90366 -224.359492) (xy 17.927023 -224.406677)
			(xy 17.942909 -224.456876) (xy 17.950946 -224.508912) (xy 17.95145 -224.535238) (xy 24.808183 -224.535238)
			(xy 24.812213 -224.48274) (xy 24.82421 -224.431472) (xy 24.843893 -224.382637) (xy 24.870799 -224.337378)
			(xy 24.904299 -224.296757) (xy 24.943607 -224.261726) (xy 24.987802 -224.233106) (xy 25.035847 -224.211567)
			(xy 25.086618 -224.197615) (xy 25.138923 -224.191577) (xy 25.191537 -224.193594) (xy 25.243227 -224.203618)
			(xy 25.29278 -224.221416) (xy 25.339036 -224.246569) (xy 25.38091 -224.278488) (xy 25.417422 -224.316426)
			(xy 25.447714 -224.359492) (xy 25.471077 -224.406677) (xy 25.486963 -224.456876) (xy 25.495 -224.508912)
			(xy 25.495504 -224.535238) (xy 32.351983 -224.535238) (xy 32.356013 -224.48274) (xy 32.36801 -224.431472)
			(xy 32.387693 -224.382637) (xy 32.414599 -224.337378) (xy 32.448099 -224.296757) (xy 32.487407 -224.261726)
			(xy 32.531602 -224.233106) (xy 32.579647 -224.211567) (xy 32.630418 -224.197615) (xy 32.682723 -224.191577)
			(xy 32.735337 -224.193594) (xy 32.787027 -224.203618) (xy 32.83658 -224.221416) (xy 32.882836 -224.246569)
			(xy 32.92471 -224.278488) (xy 32.961222 -224.316426) (xy 32.991514 -224.359492) (xy 33.014877 -224.406677)
			(xy 33.030763 -224.456876) (xy 33.0388 -224.508912) (xy 33.039304 -224.535238) (xy 39.896037 -224.535238)
			(xy 39.900067 -224.48274) (xy 39.912064 -224.431472) (xy 39.931747 -224.382637) (xy 39.958653 -224.337378)
			(xy 39.992153 -224.296757) (xy 40.031461 -224.261726) (xy 40.075656 -224.233106) (xy 40.123701 -224.211567)
			(xy 40.174472 -224.197615) (xy 40.226777 -224.191577) (xy 40.279391 -224.193594) (xy 40.331081 -224.203618)
			(xy 40.380634 -224.221416) (xy 40.42689 -224.246569) (xy 40.468764 -224.278488) (xy 40.505276 -224.316426)
			(xy 40.535568 -224.359492) (xy 40.558931 -224.406677) (xy 40.574817 -224.456876) (xy 40.582854 -224.508912)
			(xy 40.583358 -224.535238) (xy 47.440091 -224.535238) (xy 47.444121 -224.48274) (xy 47.456118 -224.431472)
			(xy 47.475801 -224.382637) (xy 47.502707 -224.337378) (xy 47.536207 -224.296757) (xy 47.575515 -224.261726)
			(xy 47.61971 -224.233106) (xy 47.667755 -224.211567) (xy 47.718526 -224.197615) (xy 47.770831 -224.191577)
			(xy 47.823445 -224.193594) (xy 47.875135 -224.203618) (xy 47.924688 -224.221416) (xy 47.970944 -224.246569)
			(xy 48.012818 -224.278488) (xy 48.04933 -224.316426) (xy 48.079622 -224.359492) (xy 48.102985 -224.406677)
			(xy 48.118871 -224.456876) (xy 48.126908 -224.508912) (xy 48.127412 -224.535238) (xy 48.126908 -224.561564)
			(xy 48.118871 -224.6136) (xy 48.102985 -224.663799) (xy 48.079622 -224.710984) (xy 48.04933 -224.75405)
			(xy 48.012818 -224.791988) (xy 47.970944 -224.823907) (xy 47.924688 -224.84906) (xy 47.875135 -224.866858)
			(xy 47.823445 -224.876882) (xy 47.770831 -224.878899) (xy 47.718526 -224.872861) (xy 47.667755 -224.858909)
			(xy 47.61971 -224.83737) (xy 47.575515 -224.80875) (xy 47.536207 -224.773719) (xy 47.502707 -224.733098)
			(xy 47.475801 -224.687839) (xy 47.456118 -224.639004) (xy 47.444121 -224.587736) (xy 47.440091 -224.535238)
			(xy 40.583358 -224.535238) (xy 40.582854 -224.561564) (xy 40.574817 -224.6136) (xy 40.558931 -224.663799)
			(xy 40.535568 -224.710984) (xy 40.505276 -224.75405) (xy 40.468764 -224.791988) (xy 40.42689 -224.823907)
			(xy 40.380634 -224.84906) (xy 40.331081 -224.866858) (xy 40.279391 -224.876882) (xy 40.226777 -224.878899)
			(xy 40.174472 -224.872861) (xy 40.123701 -224.858909) (xy 40.075656 -224.83737) (xy 40.031461 -224.80875)
			(xy 39.992153 -224.773719) (xy 39.958653 -224.733098) (xy 39.931747 -224.687839) (xy 39.912064 -224.639004)
			(xy 39.900067 -224.587736) (xy 39.896037 -224.535238) (xy 33.039304 -224.535238) (xy 33.0388 -224.561564)
			(xy 33.030763 -224.6136) (xy 33.014877 -224.663799) (xy 32.991514 -224.710984) (xy 32.961222 -224.75405)
			(xy 32.92471 -224.791988) (xy 32.882836 -224.823907) (xy 32.83658 -224.84906) (xy 32.787027 -224.866858)
			(xy 32.735337 -224.876882) (xy 32.682723 -224.878899) (xy 32.630418 -224.872861) (xy 32.579647 -224.858909)
			(xy 32.531602 -224.83737) (xy 32.487407 -224.80875) (xy 32.448099 -224.773719) (xy 32.414599 -224.733098)
			(xy 32.387693 -224.687839) (xy 32.36801 -224.639004) (xy 32.356013 -224.587736) (xy 32.351983 -224.535238)
			(xy 25.495504 -224.535238) (xy 25.495 -224.561564) (xy 25.486963 -224.6136) (xy 25.471077 -224.663799)
			(xy 25.447714 -224.710984) (xy 25.417422 -224.75405) (xy 25.38091 -224.791988) (xy 25.339036 -224.823907)
			(xy 25.29278 -224.84906) (xy 25.243227 -224.866858) (xy 25.191537 -224.876882) (xy 25.138923 -224.878899)
			(xy 25.086618 -224.872861) (xy 25.035847 -224.858909) (xy 24.987802 -224.83737) (xy 24.943607 -224.80875)
			(xy 24.904299 -224.773719) (xy 24.870799 -224.733098) (xy 24.843893 -224.687839) (xy 24.82421 -224.639004)
			(xy 24.812213 -224.587736) (xy 24.808183 -224.535238) (xy 17.95145 -224.535238) (xy 17.950946 -224.561564)
			(xy 17.942909 -224.6136) (xy 17.927023 -224.663799) (xy 17.90366 -224.710984) (xy 17.873368 -224.75405)
			(xy 17.836856 -224.791988) (xy 17.794982 -224.823907) (xy 17.748726 -224.84906) (xy 17.699173 -224.866858)
			(xy 17.647483 -224.876882) (xy 17.594869 -224.878899) (xy 17.542564 -224.872861) (xy 17.491793 -224.858909)
			(xy 17.443748 -224.83737) (xy 17.399553 -224.80875) (xy 17.360245 -224.773719) (xy 17.326745 -224.733098)
			(xy 17.299839 -224.687839) (xy 17.280156 -224.639004) (xy 17.268159 -224.587736) (xy 17.264129 -224.535238)
			(xy 16.086074 -224.535238) (xy 16.086074 -225.385376) (xy 21.364197 -225.385376) (xy 21.368227 -225.332878)
			(xy 21.380224 -225.28161) (xy 21.399907 -225.232775) (xy 21.426813 -225.187516) (xy 21.460313 -225.146895)
			(xy 21.499621 -225.111864) (xy 21.543816 -225.083244) (xy 21.591861 -225.061705) (xy 21.642632 -225.047753)
			(xy 21.694937 -225.041715) (xy 21.747551 -225.043732) (xy 21.799241 -225.053756) (xy 21.848794 -225.071554)
			(xy 21.89505 -225.096707) (xy 21.936924 -225.128626) (xy 21.973436 -225.166564) (xy 22.003728 -225.20963)
			(xy 22.027091 -225.256815) (xy 22.042977 -225.307014) (xy 22.051014 -225.35905) (xy 22.051518 -225.385376)
			(xy 28.908251 -225.385376) (xy 28.912281 -225.332878) (xy 28.924278 -225.28161) (xy 28.943961 -225.232775)
			(xy 28.970867 -225.187516) (xy 29.004367 -225.146895) (xy 29.043675 -225.111864) (xy 29.08787 -225.083244)
			(xy 29.135915 -225.061705) (xy 29.186686 -225.047753) (xy 29.238991 -225.041715) (xy 29.291605 -225.043732)
			(xy 29.343295 -225.053756) (xy 29.392848 -225.071554) (xy 29.439104 -225.096707) (xy 29.480978 -225.128626)
			(xy 29.51749 -225.166564) (xy 29.547782 -225.20963) (xy 29.571145 -225.256815) (xy 29.587031 -225.307014)
			(xy 29.595068 -225.35905) (xy 29.595572 -225.385376) (xy 36.452051 -225.385376) (xy 36.456081 -225.332878)
			(xy 36.468078 -225.28161) (xy 36.487761 -225.232775) (xy 36.514667 -225.187516) (xy 36.548167 -225.146895)
			(xy 36.587475 -225.111864) (xy 36.63167 -225.083244) (xy 36.679715 -225.061705) (xy 36.730486 -225.047753)
			(xy 36.782791 -225.041715) (xy 36.835405 -225.043732) (xy 36.887095 -225.053756) (xy 36.936648 -225.071554)
			(xy 36.982904 -225.096707) (xy 37.024778 -225.128626) (xy 37.06129 -225.166564) (xy 37.091582 -225.20963)
			(xy 37.114945 -225.256815) (xy 37.130831 -225.307014) (xy 37.138868 -225.35905) (xy 37.139372 -225.385376)
			(xy 43.996105 -225.385376) (xy 44.000135 -225.332878) (xy 44.012132 -225.28161) (xy 44.031815 -225.232775)
			(xy 44.058721 -225.187516) (xy 44.092221 -225.146895) (xy 44.131529 -225.111864) (xy 44.175724 -225.083244)
			(xy 44.223769 -225.061705) (xy 44.27454 -225.047753) (xy 44.326845 -225.041715) (xy 44.379459 -225.043732)
			(xy 44.431149 -225.053756) (xy 44.480702 -225.071554) (xy 44.526958 -225.096707) (xy 44.568832 -225.128626)
			(xy 44.605344 -225.166564) (xy 44.635636 -225.20963) (xy 44.658999 -225.256815) (xy 44.674885 -225.307014)
			(xy 44.682922 -225.35905) (xy 44.683426 -225.385376) (xy 51.540159 -225.385376) (xy 51.544189 -225.332878)
			(xy 51.556186 -225.28161) (xy 51.575869 -225.232775) (xy 51.602775 -225.187516) (xy 51.636275 -225.146895)
			(xy 51.675583 -225.111864) (xy 51.719778 -225.083244) (xy 51.767823 -225.061705) (xy 51.818594 -225.047753)
			(xy 51.870899 -225.041715) (xy 51.923513 -225.043732) (xy 51.975203 -225.053756) (xy 52.024756 -225.071554)
			(xy 52.071012 -225.096707) (xy 52.112886 -225.128626) (xy 52.149398 -225.166564) (xy 52.17969 -225.20963)
			(xy 52.203053 -225.256815) (xy 52.218939 -225.307014) (xy 52.226976 -225.35905) (xy 52.22748 -225.385376)
			(xy 52.226976 -225.411702) (xy 52.218939 -225.463738) (xy 52.203053 -225.513937) (xy 52.17969 -225.561122)
			(xy 52.149398 -225.604188) (xy 52.112886 -225.642126) (xy 52.071012 -225.674045) (xy 52.024756 -225.699198)
			(xy 51.975203 -225.716996) (xy 51.923513 -225.72702) (xy 51.870899 -225.729037) (xy 51.818594 -225.722999)
			(xy 51.767823 -225.709047) (xy 51.719778 -225.687508) (xy 51.675583 -225.658888) (xy 51.636275 -225.623857)
			(xy 51.602775 -225.583236) (xy 51.575869 -225.537977) (xy 51.556186 -225.489142) (xy 51.544189 -225.437874)
			(xy 51.540159 -225.385376) (xy 44.683426 -225.385376) (xy 44.682922 -225.411702) (xy 44.674885 -225.463738)
			(xy 44.658999 -225.513937) (xy 44.635636 -225.561122) (xy 44.605344 -225.604188) (xy 44.568832 -225.642126)
			(xy 44.526958 -225.674045) (xy 44.480702 -225.699198) (xy 44.431149 -225.716996) (xy 44.379459 -225.72702)
			(xy 44.326845 -225.729037) (xy 44.27454 -225.722999) (xy 44.223769 -225.709047) (xy 44.175724 -225.687508)
			(xy 44.131529 -225.658888) (xy 44.092221 -225.623857) (xy 44.058721 -225.583236) (xy 44.031815 -225.537977)
			(xy 44.012132 -225.489142) (xy 44.000135 -225.437874) (xy 43.996105 -225.385376) (xy 37.139372 -225.385376)
			(xy 37.138868 -225.411702) (xy 37.130831 -225.463738) (xy 37.114945 -225.513937) (xy 37.091582 -225.561122)
			(xy 37.06129 -225.604188) (xy 37.024778 -225.642126) (xy 36.982904 -225.674045) (xy 36.936648 -225.699198)
			(xy 36.887095 -225.716996) (xy 36.835405 -225.72702) (xy 36.782791 -225.729037) (xy 36.730486 -225.722999)
			(xy 36.679715 -225.709047) (xy 36.63167 -225.687508) (xy 36.587475 -225.658888) (xy 36.548167 -225.623857)
			(xy 36.514667 -225.583236) (xy 36.487761 -225.537977) (xy 36.468078 -225.489142) (xy 36.456081 -225.437874)
			(xy 36.452051 -225.385376) (xy 29.595572 -225.385376) (xy 29.595068 -225.411702) (xy 29.587031 -225.463738)
			(xy 29.571145 -225.513937) (xy 29.547782 -225.561122) (xy 29.51749 -225.604188) (xy 29.480978 -225.642126)
			(xy 29.439104 -225.674045) (xy 29.392848 -225.699198) (xy 29.343295 -225.716996) (xy 29.291605 -225.72702)
			(xy 29.238991 -225.729037) (xy 29.186686 -225.722999) (xy 29.135915 -225.709047) (xy 29.08787 -225.687508)
			(xy 29.043675 -225.658888) (xy 29.004367 -225.623857) (xy 28.970867 -225.583236) (xy 28.943961 -225.537977)
			(xy 28.924278 -225.489142) (xy 28.912281 -225.437874) (xy 28.908251 -225.385376) (xy 22.051518 -225.385376)
			(xy 22.051014 -225.411702) (xy 22.042977 -225.463738) (xy 22.027091 -225.513937) (xy 22.003728 -225.561122)
			(xy 21.973436 -225.604188) (xy 21.936924 -225.642126) (xy 21.89505 -225.674045) (xy 21.848794 -225.699198)
			(xy 21.799241 -225.716996) (xy 21.747551 -225.72702) (xy 21.694937 -225.729037) (xy 21.642632 -225.722999)
			(xy 21.591861 -225.709047) (xy 21.543816 -225.687508) (xy 21.499621 -225.658888) (xy 21.460313 -225.623857)
			(xy 21.426813 -225.583236) (xy 21.399907 -225.537977) (xy 21.380224 -225.489142) (xy 21.368227 -225.437874)
			(xy 21.364197 -225.385376) (xy 16.086074 -225.385376) (xy 16.086074 -226.23526) (xy 17.264129 -226.23526)
			(xy 17.268159 -226.182762) (xy 17.280156 -226.131494) (xy 17.299839 -226.082659) (xy 17.326745 -226.0374)
			(xy 17.360245 -225.996779) (xy 17.399553 -225.961748) (xy 17.443748 -225.933128) (xy 17.491793 -225.911589)
			(xy 17.542564 -225.897637) (xy 17.594869 -225.891599) (xy 17.647483 -225.893616) (xy 17.699173 -225.90364)
			(xy 17.748726 -225.921438) (xy 17.794982 -225.946591) (xy 17.836856 -225.97851) (xy 17.873368 -226.016448)
			(xy 17.90366 -226.059514) (xy 17.927023 -226.106699) (xy 17.942909 -226.156898) (xy 17.950946 -226.208934)
			(xy 17.95145 -226.23526) (xy 24.808183 -226.23526) (xy 24.812213 -226.182762) (xy 24.82421 -226.131494)
			(xy 24.843893 -226.082659) (xy 24.870799 -226.0374) (xy 24.904299 -225.996779) (xy 24.943607 -225.961748)
			(xy 24.987802 -225.933128) (xy 25.035847 -225.911589) (xy 25.086618 -225.897637) (xy 25.138923 -225.891599)
			(xy 25.191537 -225.893616) (xy 25.243227 -225.90364) (xy 25.29278 -225.921438) (xy 25.339036 -225.946591)
			(xy 25.38091 -225.97851) (xy 25.417422 -226.016448) (xy 25.447714 -226.059514) (xy 25.471077 -226.106699)
			(xy 25.486963 -226.156898) (xy 25.495 -226.208934) (xy 25.495504 -226.23526) (xy 32.351983 -226.23526)
			(xy 32.356013 -226.182762) (xy 32.36801 -226.131494) (xy 32.387693 -226.082659) (xy 32.414599 -226.0374)
			(xy 32.448099 -225.996779) (xy 32.487407 -225.961748) (xy 32.531602 -225.933128) (xy 32.579647 -225.911589)
			(xy 32.630418 -225.897637) (xy 32.682723 -225.891599) (xy 32.735337 -225.893616) (xy 32.787027 -225.90364)
			(xy 32.83658 -225.921438) (xy 32.882836 -225.946591) (xy 32.92471 -225.97851) (xy 32.961222 -226.016448)
			(xy 32.991514 -226.059514) (xy 33.014877 -226.106699) (xy 33.030763 -226.156898) (xy 33.0388 -226.208934)
			(xy 33.039304 -226.23526) (xy 39.896037 -226.23526) (xy 39.900067 -226.182762) (xy 39.912064 -226.131494)
			(xy 39.931747 -226.082659) (xy 39.958653 -226.0374) (xy 39.992153 -225.996779) (xy 40.031461 -225.961748)
			(xy 40.075656 -225.933128) (xy 40.123701 -225.911589) (xy 40.174472 -225.897637) (xy 40.226777 -225.891599)
			(xy 40.279391 -225.893616) (xy 40.331081 -225.90364) (xy 40.380634 -225.921438) (xy 40.42689 -225.946591)
			(xy 40.468764 -225.97851) (xy 40.505276 -226.016448) (xy 40.535568 -226.059514) (xy 40.558931 -226.106699)
			(xy 40.574817 -226.156898) (xy 40.582854 -226.208934) (xy 40.583358 -226.23526) (xy 47.440091 -226.23526)
			(xy 47.444121 -226.182762) (xy 47.456118 -226.131494) (xy 47.475801 -226.082659) (xy 47.502707 -226.0374)
			(xy 47.536207 -225.996779) (xy 47.575515 -225.961748) (xy 47.61971 -225.933128) (xy 47.667755 -225.911589)
			(xy 47.718526 -225.897637) (xy 47.770831 -225.891599) (xy 47.823445 -225.893616) (xy 47.875135 -225.90364)
			(xy 47.924688 -225.921438) (xy 47.970944 -225.946591) (xy 48.012818 -225.97851) (xy 48.04933 -226.016448)
			(xy 48.079622 -226.059514) (xy 48.102985 -226.106699) (xy 48.118871 -226.156898) (xy 48.126908 -226.208934)
			(xy 48.127412 -226.23526) (xy 48.126908 -226.261586) (xy 48.118871 -226.313622) (xy 48.102985 -226.363821)
			(xy 48.079622 -226.411006) (xy 48.04933 -226.454072) (xy 48.012818 -226.49201) (xy 47.970944 -226.523929)
			(xy 47.924688 -226.549082) (xy 47.875135 -226.56688) (xy 47.823445 -226.576904) (xy 47.770831 -226.578921)
			(xy 47.718526 -226.572883) (xy 47.667755 -226.558931) (xy 47.61971 -226.537392) (xy 47.575515 -226.508772)
			(xy 47.536207 -226.473741) (xy 47.502707 -226.43312) (xy 47.475801 -226.387861) (xy 47.456118 -226.339026)
			(xy 47.444121 -226.287758) (xy 47.440091 -226.23526) (xy 40.583358 -226.23526) (xy 40.582854 -226.261586)
			(xy 40.574817 -226.313622) (xy 40.558931 -226.363821) (xy 40.535568 -226.411006) (xy 40.505276 -226.454072)
			(xy 40.468764 -226.49201) (xy 40.42689 -226.523929) (xy 40.380634 -226.549082) (xy 40.331081 -226.56688)
			(xy 40.279391 -226.576904) (xy 40.226777 -226.578921) (xy 40.174472 -226.572883) (xy 40.123701 -226.558931)
			(xy 40.075656 -226.537392) (xy 40.031461 -226.508772) (xy 39.992153 -226.473741) (xy 39.958653 -226.43312)
			(xy 39.931747 -226.387861) (xy 39.912064 -226.339026) (xy 39.900067 -226.287758) (xy 39.896037 -226.23526)
			(xy 33.039304 -226.23526) (xy 33.0388 -226.261586) (xy 33.030763 -226.313622) (xy 33.014877 -226.363821)
			(xy 32.991514 -226.411006) (xy 32.961222 -226.454072) (xy 32.92471 -226.49201) (xy 32.882836 -226.523929)
			(xy 32.83658 -226.549082) (xy 32.787027 -226.56688) (xy 32.735337 -226.576904) (xy 32.682723 -226.578921)
			(xy 32.630418 -226.572883) (xy 32.579647 -226.558931) (xy 32.531602 -226.537392) (xy 32.487407 -226.508772)
			(xy 32.448099 -226.473741) (xy 32.414599 -226.43312) (xy 32.387693 -226.387861) (xy 32.36801 -226.339026)
			(xy 32.356013 -226.287758) (xy 32.351983 -226.23526) (xy 25.495504 -226.23526) (xy 25.495 -226.261586)
			(xy 25.486963 -226.313622) (xy 25.471077 -226.363821) (xy 25.447714 -226.411006) (xy 25.417422 -226.454072)
			(xy 25.38091 -226.49201) (xy 25.339036 -226.523929) (xy 25.29278 -226.549082) (xy 25.243227 -226.56688)
			(xy 25.191537 -226.576904) (xy 25.138923 -226.578921) (xy 25.086618 -226.572883) (xy 25.035847 -226.558931)
			(xy 24.987802 -226.537392) (xy 24.943607 -226.508772) (xy 24.904299 -226.473741) (xy 24.870799 -226.43312)
			(xy 24.843893 -226.387861) (xy 24.82421 -226.339026) (xy 24.812213 -226.287758) (xy 24.808183 -226.23526)
			(xy 17.95145 -226.23526) (xy 17.950946 -226.261586) (xy 17.942909 -226.313622) (xy 17.927023 -226.363821)
			(xy 17.90366 -226.411006) (xy 17.873368 -226.454072) (xy 17.836856 -226.49201) (xy 17.794982 -226.523929)
			(xy 17.748726 -226.549082) (xy 17.699173 -226.56688) (xy 17.647483 -226.576904) (xy 17.594869 -226.578921)
			(xy 17.542564 -226.572883) (xy 17.491793 -226.558931) (xy 17.443748 -226.537392) (xy 17.399553 -226.508772)
			(xy 17.360245 -226.473741) (xy 17.326745 -226.43312) (xy 17.299839 -226.387861) (xy 17.280156 -226.339026)
			(xy 17.268159 -226.287758) (xy 17.264129 -226.23526) (xy 16.086074 -226.23526) (xy 16.086074 -227.085398)
			(xy 21.364197 -227.085398) (xy 21.368227 -227.0329) (xy 21.380224 -226.981632) (xy 21.399907 -226.932797)
			(xy 21.426813 -226.887538) (xy 21.460313 -226.846917) (xy 21.499621 -226.811886) (xy 21.543816 -226.783266)
			(xy 21.591861 -226.761727) (xy 21.642632 -226.747775) (xy 21.694937 -226.741737) (xy 21.747551 -226.743754)
			(xy 21.799241 -226.753778) (xy 21.848794 -226.771576) (xy 21.89505 -226.796729) (xy 21.936924 -226.828648)
			(xy 21.973436 -226.866586) (xy 22.003728 -226.909652) (xy 22.027091 -226.956837) (xy 22.042977 -227.007036)
			(xy 22.051014 -227.059072) (xy 22.051518 -227.085398) (xy 28.908251 -227.085398) (xy 28.912281 -227.0329)
			(xy 28.924278 -226.981632) (xy 28.943961 -226.932797) (xy 28.970867 -226.887538) (xy 29.004367 -226.846917)
			(xy 29.043675 -226.811886) (xy 29.08787 -226.783266) (xy 29.135915 -226.761727) (xy 29.186686 -226.747775)
			(xy 29.238991 -226.741737) (xy 29.291605 -226.743754) (xy 29.343295 -226.753778) (xy 29.392848 -226.771576)
			(xy 29.439104 -226.796729) (xy 29.480978 -226.828648) (xy 29.51749 -226.866586) (xy 29.547782 -226.909652)
			(xy 29.571145 -226.956837) (xy 29.587031 -227.007036) (xy 29.595068 -227.059072) (xy 29.595572 -227.085398)
			(xy 36.452051 -227.085398) (xy 36.456081 -227.0329) (xy 36.468078 -226.981632) (xy 36.487761 -226.932797)
			(xy 36.514667 -226.887538) (xy 36.548167 -226.846917) (xy 36.587475 -226.811886) (xy 36.63167 -226.783266)
			(xy 36.679715 -226.761727) (xy 36.730486 -226.747775) (xy 36.782791 -226.741737) (xy 36.835405 -226.743754)
			(xy 36.887095 -226.753778) (xy 36.936648 -226.771576) (xy 36.982904 -226.796729) (xy 37.024778 -226.828648)
			(xy 37.06129 -226.866586) (xy 37.091582 -226.909652) (xy 37.114945 -226.956837) (xy 37.130831 -227.007036)
			(xy 37.138868 -227.059072) (xy 37.139372 -227.085398) (xy 43.996105 -227.085398) (xy 44.000135 -227.0329)
			(xy 44.012132 -226.981632) (xy 44.031815 -226.932797) (xy 44.058721 -226.887538) (xy 44.092221 -226.846917)
			(xy 44.131529 -226.811886) (xy 44.175724 -226.783266) (xy 44.223769 -226.761727) (xy 44.27454 -226.747775)
			(xy 44.326845 -226.741737) (xy 44.379459 -226.743754) (xy 44.431149 -226.753778) (xy 44.480702 -226.771576)
			(xy 44.526958 -226.796729) (xy 44.568832 -226.828648) (xy 44.605344 -226.866586) (xy 44.635636 -226.909652)
			(xy 44.658999 -226.956837) (xy 44.674885 -227.007036) (xy 44.682922 -227.059072) (xy 44.683426 -227.085398)
			(xy 51.540159 -227.085398) (xy 51.544189 -227.0329) (xy 51.556186 -226.981632) (xy 51.575869 -226.932797)
			(xy 51.602775 -226.887538) (xy 51.636275 -226.846917) (xy 51.675583 -226.811886) (xy 51.719778 -226.783266)
			(xy 51.767823 -226.761727) (xy 51.818594 -226.747775) (xy 51.870899 -226.741737) (xy 51.923513 -226.743754)
			(xy 51.975203 -226.753778) (xy 52.024756 -226.771576) (xy 52.071012 -226.796729) (xy 52.112886 -226.828648)
			(xy 52.149398 -226.866586) (xy 52.17969 -226.909652) (xy 52.203053 -226.956837) (xy 52.218939 -227.007036)
			(xy 52.226976 -227.059072) (xy 52.22748 -227.085398) (xy 52.226976 -227.111724) (xy 52.218939 -227.16376)
			(xy 52.203053 -227.213959) (xy 52.17969 -227.261144) (xy 52.149398 -227.30421) (xy 52.112886 -227.342148)
			(xy 52.071012 -227.374067) (xy 52.024756 -227.39922) (xy 51.975203 -227.417018) (xy 51.923513 -227.427042)
			(xy 51.870899 -227.429059) (xy 51.818594 -227.423021) (xy 51.767823 -227.409069) (xy 51.719778 -227.38753)
			(xy 51.675583 -227.35891) (xy 51.636275 -227.323879) (xy 51.602775 -227.283258) (xy 51.575869 -227.237999)
			(xy 51.556186 -227.189164) (xy 51.544189 -227.137896) (xy 51.540159 -227.085398) (xy 44.683426 -227.085398)
			(xy 44.682922 -227.111724) (xy 44.674885 -227.16376) (xy 44.658999 -227.213959) (xy 44.635636 -227.261144)
			(xy 44.605344 -227.30421) (xy 44.568832 -227.342148) (xy 44.526958 -227.374067) (xy 44.480702 -227.39922)
			(xy 44.431149 -227.417018) (xy 44.379459 -227.427042) (xy 44.326845 -227.429059) (xy 44.27454 -227.423021)
			(xy 44.223769 -227.409069) (xy 44.175724 -227.38753) (xy 44.131529 -227.35891) (xy 44.092221 -227.323879)
			(xy 44.058721 -227.283258) (xy 44.031815 -227.237999) (xy 44.012132 -227.189164) (xy 44.000135 -227.137896)
			(xy 43.996105 -227.085398) (xy 37.139372 -227.085398) (xy 37.138868 -227.111724) (xy 37.130831 -227.16376)
			(xy 37.114945 -227.213959) (xy 37.091582 -227.261144) (xy 37.06129 -227.30421) (xy 37.024778 -227.342148)
			(xy 36.982904 -227.374067) (xy 36.936648 -227.39922) (xy 36.887095 -227.417018) (xy 36.835405 -227.427042)
			(xy 36.782791 -227.429059) (xy 36.730486 -227.423021) (xy 36.679715 -227.409069) (xy 36.63167 -227.38753)
			(xy 36.587475 -227.35891) (xy 36.548167 -227.323879) (xy 36.514667 -227.283258) (xy 36.487761 -227.237999)
			(xy 36.468078 -227.189164) (xy 36.456081 -227.137896) (xy 36.452051 -227.085398) (xy 29.595572 -227.085398)
			(xy 29.595068 -227.111724) (xy 29.587031 -227.16376) (xy 29.571145 -227.213959) (xy 29.547782 -227.261144)
			(xy 29.51749 -227.30421) (xy 29.480978 -227.342148) (xy 29.439104 -227.374067) (xy 29.392848 -227.39922)
			(xy 29.343295 -227.417018) (xy 29.291605 -227.427042) (xy 29.238991 -227.429059) (xy 29.186686 -227.423021)
			(xy 29.135915 -227.409069) (xy 29.08787 -227.38753) (xy 29.043675 -227.35891) (xy 29.004367 -227.323879)
			(xy 28.970867 -227.283258) (xy 28.943961 -227.237999) (xy 28.924278 -227.189164) (xy 28.912281 -227.137896)
			(xy 28.908251 -227.085398) (xy 22.051518 -227.085398) (xy 22.051014 -227.111724) (xy 22.042977 -227.16376)
			(xy 22.027091 -227.213959) (xy 22.003728 -227.261144) (xy 21.973436 -227.30421) (xy 21.936924 -227.342148)
			(xy 21.89505 -227.374067) (xy 21.848794 -227.39922) (xy 21.799241 -227.417018) (xy 21.747551 -227.427042)
			(xy 21.694937 -227.429059) (xy 21.642632 -227.423021) (xy 21.591861 -227.409069) (xy 21.543816 -227.38753)
			(xy 21.499621 -227.35891) (xy 21.460313 -227.323879) (xy 21.426813 -227.283258) (xy 21.399907 -227.237999)
			(xy 21.380224 -227.189164) (xy 21.368227 -227.137896) (xy 21.364197 -227.085398) (xy 16.086074 -227.085398)
			(xy 16.086074 -227.935282) (xy 17.264129 -227.935282) (xy 17.268159 -227.882784) (xy 17.280156 -227.831516)
			(xy 17.299839 -227.782681) (xy 17.326745 -227.737422) (xy 17.360245 -227.696801) (xy 17.399553 -227.66177)
			(xy 17.443748 -227.63315) (xy 17.491793 -227.611611) (xy 17.542564 -227.597659) (xy 17.594869 -227.591621)
			(xy 17.647483 -227.593638) (xy 17.699173 -227.603662) (xy 17.748726 -227.62146) (xy 17.794982 -227.646613)
			(xy 17.836856 -227.678532) (xy 17.873368 -227.71647) (xy 17.90366 -227.759536) (xy 17.927023 -227.806721)
			(xy 17.942909 -227.85692) (xy 17.950946 -227.908956) (xy 17.95145 -227.935282) (xy 24.808183 -227.935282)
			(xy 24.812213 -227.882784) (xy 24.82421 -227.831516) (xy 24.843893 -227.782681) (xy 24.870799 -227.737422)
			(xy 24.904299 -227.696801) (xy 24.943607 -227.66177) (xy 24.987802 -227.63315) (xy 25.035847 -227.611611)
			(xy 25.086618 -227.597659) (xy 25.138923 -227.591621) (xy 25.191537 -227.593638) (xy 25.243227 -227.603662)
			(xy 25.29278 -227.62146) (xy 25.339036 -227.646613) (xy 25.38091 -227.678532) (xy 25.417422 -227.71647)
			(xy 25.447714 -227.759536) (xy 25.471077 -227.806721) (xy 25.486963 -227.85692) (xy 25.495 -227.908956)
			(xy 25.495504 -227.935282) (xy 32.351983 -227.935282) (xy 32.356013 -227.882784) (xy 32.36801 -227.831516)
			(xy 32.387693 -227.782681) (xy 32.414599 -227.737422) (xy 32.448099 -227.696801) (xy 32.487407 -227.66177)
			(xy 32.531602 -227.63315) (xy 32.579647 -227.611611) (xy 32.630418 -227.597659) (xy 32.682723 -227.591621)
			(xy 32.735337 -227.593638) (xy 32.787027 -227.603662) (xy 32.83658 -227.62146) (xy 32.882836 -227.646613)
			(xy 32.92471 -227.678532) (xy 32.961222 -227.71647) (xy 32.991514 -227.759536) (xy 33.014877 -227.806721)
			(xy 33.030763 -227.85692) (xy 33.0388 -227.908956) (xy 33.039304 -227.935282) (xy 39.896037 -227.935282)
			(xy 39.900067 -227.882784) (xy 39.912064 -227.831516) (xy 39.931747 -227.782681) (xy 39.958653 -227.737422)
			(xy 39.992153 -227.696801) (xy 40.031461 -227.66177) (xy 40.075656 -227.63315) (xy 40.123701 -227.611611)
			(xy 40.174472 -227.597659) (xy 40.226777 -227.591621) (xy 40.279391 -227.593638) (xy 40.331081 -227.603662)
			(xy 40.380634 -227.62146) (xy 40.42689 -227.646613) (xy 40.468764 -227.678532) (xy 40.505276 -227.71647)
			(xy 40.535568 -227.759536) (xy 40.558931 -227.806721) (xy 40.574817 -227.85692) (xy 40.582854 -227.908956)
			(xy 40.583358 -227.935282) (xy 47.440091 -227.935282) (xy 47.444121 -227.882784) (xy 47.456118 -227.831516)
			(xy 47.475801 -227.782681) (xy 47.502707 -227.737422) (xy 47.536207 -227.696801) (xy 47.575515 -227.66177)
			(xy 47.61971 -227.63315) (xy 47.667755 -227.611611) (xy 47.718526 -227.597659) (xy 47.770831 -227.591621)
			(xy 47.823445 -227.593638) (xy 47.875135 -227.603662) (xy 47.924688 -227.62146) (xy 47.970944 -227.646613)
			(xy 48.012818 -227.678532) (xy 48.04933 -227.71647) (xy 48.079622 -227.759536) (xy 48.102985 -227.806721)
			(xy 48.118871 -227.85692) (xy 48.126908 -227.908956) (xy 48.127412 -227.935282) (xy 48.126908 -227.961608)
			(xy 48.118871 -228.013644) (xy 48.102985 -228.063843) (xy 48.079622 -228.111028) (xy 48.04933 -228.154094)
			(xy 48.012818 -228.192032) (xy 47.970944 -228.223951) (xy 47.924688 -228.249104) (xy 47.875135 -228.266902)
			(xy 47.823445 -228.276926) (xy 47.770831 -228.278943) (xy 47.718526 -228.272905) (xy 47.667755 -228.258953)
			(xy 47.61971 -228.237414) (xy 47.575515 -228.208794) (xy 47.536207 -228.173763) (xy 47.502707 -228.133142)
			(xy 47.475801 -228.087883) (xy 47.456118 -228.039048) (xy 47.444121 -227.98778) (xy 47.440091 -227.935282)
			(xy 40.583358 -227.935282) (xy 40.582854 -227.961608) (xy 40.574817 -228.013644) (xy 40.558931 -228.063843)
			(xy 40.535568 -228.111028) (xy 40.505276 -228.154094) (xy 40.468764 -228.192032) (xy 40.42689 -228.223951)
			(xy 40.380634 -228.249104) (xy 40.331081 -228.266902) (xy 40.279391 -228.276926) (xy 40.226777 -228.278943)
			(xy 40.174472 -228.272905) (xy 40.123701 -228.258953) (xy 40.075656 -228.237414) (xy 40.031461 -228.208794)
			(xy 39.992153 -228.173763) (xy 39.958653 -228.133142) (xy 39.931747 -228.087883) (xy 39.912064 -228.039048)
			(xy 39.900067 -227.98778) (xy 39.896037 -227.935282) (xy 33.039304 -227.935282) (xy 33.0388 -227.961608)
			(xy 33.030763 -228.013644) (xy 33.014877 -228.063843) (xy 32.991514 -228.111028) (xy 32.961222 -228.154094)
			(xy 32.92471 -228.192032) (xy 32.882836 -228.223951) (xy 32.83658 -228.249104) (xy 32.787027 -228.266902)
			(xy 32.735337 -228.276926) (xy 32.682723 -228.278943) (xy 32.630418 -228.272905) (xy 32.579647 -228.258953)
			(xy 32.531602 -228.237414) (xy 32.487407 -228.208794) (xy 32.448099 -228.173763) (xy 32.414599 -228.133142)
			(xy 32.387693 -228.087883) (xy 32.36801 -228.039048) (xy 32.356013 -227.98778) (xy 32.351983 -227.935282)
			(xy 25.495504 -227.935282) (xy 25.495 -227.961608) (xy 25.486963 -228.013644) (xy 25.471077 -228.063843)
			(xy 25.447714 -228.111028) (xy 25.417422 -228.154094) (xy 25.38091 -228.192032) (xy 25.339036 -228.223951)
			(xy 25.29278 -228.249104) (xy 25.243227 -228.266902) (xy 25.191537 -228.276926) (xy 25.138923 -228.278943)
			(xy 25.086618 -228.272905) (xy 25.035847 -228.258953) (xy 24.987802 -228.237414) (xy 24.943607 -228.208794)
			(xy 24.904299 -228.173763) (xy 24.870799 -228.133142) (xy 24.843893 -228.087883) (xy 24.82421 -228.039048)
			(xy 24.812213 -227.98778) (xy 24.808183 -227.935282) (xy 17.95145 -227.935282) (xy 17.950946 -227.961608)
			(xy 17.942909 -228.013644) (xy 17.927023 -228.063843) (xy 17.90366 -228.111028) (xy 17.873368 -228.154094)
			(xy 17.836856 -228.192032) (xy 17.794982 -228.223951) (xy 17.748726 -228.249104) (xy 17.699173 -228.266902)
			(xy 17.647483 -228.276926) (xy 17.594869 -228.278943) (xy 17.542564 -228.272905) (xy 17.491793 -228.258953)
			(xy 17.443748 -228.237414) (xy 17.399553 -228.208794) (xy 17.360245 -228.173763) (xy 17.326745 -228.133142)
			(xy 17.299839 -228.087883) (xy 17.280156 -228.039048) (xy 17.268159 -227.98778) (xy 17.264129 -227.935282)
			(xy 16.086074 -227.935282) (xy 16.086074 -228.78542) (xy 21.364197 -228.78542) (xy 21.368227 -228.732922)
			(xy 21.380224 -228.681654) (xy 21.399907 -228.632819) (xy 21.426813 -228.58756) (xy 21.460313 -228.546939)
			(xy 21.499621 -228.511908) (xy 21.543816 -228.483288) (xy 21.591861 -228.461749) (xy 21.642632 -228.447797)
			(xy 21.694937 -228.441759) (xy 21.747551 -228.443776) (xy 21.799241 -228.4538) (xy 21.848794 -228.471598)
			(xy 21.89505 -228.496751) (xy 21.936924 -228.52867) (xy 21.973436 -228.566608) (xy 22.003728 -228.609674)
			(xy 22.027091 -228.656859) (xy 22.042977 -228.707058) (xy 22.051014 -228.759094) (xy 22.051518 -228.78542)
			(xy 28.908251 -228.78542) (xy 28.912281 -228.732922) (xy 28.924278 -228.681654) (xy 28.943961 -228.632819)
			(xy 28.970867 -228.58756) (xy 29.004367 -228.546939) (xy 29.043675 -228.511908) (xy 29.08787 -228.483288)
			(xy 29.135915 -228.461749) (xy 29.186686 -228.447797) (xy 29.238991 -228.441759) (xy 29.291605 -228.443776)
			(xy 29.343295 -228.4538) (xy 29.392848 -228.471598) (xy 29.439104 -228.496751) (xy 29.480978 -228.52867)
			(xy 29.51749 -228.566608) (xy 29.547782 -228.609674) (xy 29.571145 -228.656859) (xy 29.587031 -228.707058)
			(xy 29.595068 -228.759094) (xy 29.595572 -228.78542) (xy 36.452051 -228.78542) (xy 36.456081 -228.732922)
			(xy 36.468078 -228.681654) (xy 36.487761 -228.632819) (xy 36.514667 -228.58756) (xy 36.548167 -228.546939)
			(xy 36.587475 -228.511908) (xy 36.63167 -228.483288) (xy 36.679715 -228.461749) (xy 36.730486 -228.447797)
			(xy 36.782791 -228.441759) (xy 36.835405 -228.443776) (xy 36.887095 -228.4538) (xy 36.936648 -228.471598)
			(xy 36.982904 -228.496751) (xy 37.024778 -228.52867) (xy 37.06129 -228.566608) (xy 37.091582 -228.609674)
			(xy 37.114945 -228.656859) (xy 37.130831 -228.707058) (xy 37.138868 -228.759094) (xy 37.139372 -228.78542)
			(xy 43.996105 -228.78542) (xy 44.000135 -228.732922) (xy 44.012132 -228.681654) (xy 44.031815 -228.632819)
			(xy 44.058721 -228.58756) (xy 44.092221 -228.546939) (xy 44.131529 -228.511908) (xy 44.175724 -228.483288)
			(xy 44.223769 -228.461749) (xy 44.27454 -228.447797) (xy 44.326845 -228.441759) (xy 44.379459 -228.443776)
			(xy 44.431149 -228.4538) (xy 44.480702 -228.471598) (xy 44.526958 -228.496751) (xy 44.568832 -228.52867)
			(xy 44.605344 -228.566608) (xy 44.635636 -228.609674) (xy 44.658999 -228.656859) (xy 44.674885 -228.707058)
			(xy 44.682922 -228.759094) (xy 44.683426 -228.78542) (xy 51.540159 -228.78542) (xy 51.544189 -228.732922)
			(xy 51.556186 -228.681654) (xy 51.575869 -228.632819) (xy 51.602775 -228.58756) (xy 51.636275 -228.546939)
			(xy 51.675583 -228.511908) (xy 51.719778 -228.483288) (xy 51.767823 -228.461749) (xy 51.818594 -228.447797)
			(xy 51.870899 -228.441759) (xy 51.923513 -228.443776) (xy 51.975203 -228.4538) (xy 52.024756 -228.471598)
			(xy 52.071012 -228.496751) (xy 52.112886 -228.52867) (xy 52.149398 -228.566608) (xy 52.17969 -228.609674)
			(xy 52.203053 -228.656859) (xy 52.218939 -228.707058) (xy 52.226976 -228.759094) (xy 52.22748 -228.78542)
			(xy 52.226976 -228.811746) (xy 52.218939 -228.863782) (xy 52.203053 -228.913981) (xy 52.17969 -228.961166)
			(xy 52.149398 -229.004232) (xy 52.112886 -229.04217) (xy 52.071012 -229.074089) (xy 52.024756 -229.099242)
			(xy 51.975203 -229.11704) (xy 51.923513 -229.127064) (xy 51.870899 -229.129081) (xy 51.818594 -229.123043)
			(xy 51.767823 -229.109091) (xy 51.719778 -229.087552) (xy 51.675583 -229.058932) (xy 51.636275 -229.023901)
			(xy 51.602775 -228.98328) (xy 51.575869 -228.938021) (xy 51.556186 -228.889186) (xy 51.544189 -228.837918)
			(xy 51.540159 -228.78542) (xy 44.683426 -228.78542) (xy 44.682922 -228.811746) (xy 44.674885 -228.863782)
			(xy 44.658999 -228.913981) (xy 44.635636 -228.961166) (xy 44.605344 -229.004232) (xy 44.568832 -229.04217)
			(xy 44.526958 -229.074089) (xy 44.480702 -229.099242) (xy 44.431149 -229.11704) (xy 44.379459 -229.127064)
			(xy 44.326845 -229.129081) (xy 44.27454 -229.123043) (xy 44.223769 -229.109091) (xy 44.175724 -229.087552)
			(xy 44.131529 -229.058932) (xy 44.092221 -229.023901) (xy 44.058721 -228.98328) (xy 44.031815 -228.938021)
			(xy 44.012132 -228.889186) (xy 44.000135 -228.837918) (xy 43.996105 -228.78542) (xy 37.139372 -228.78542)
			(xy 37.138868 -228.811746) (xy 37.130831 -228.863782) (xy 37.114945 -228.913981) (xy 37.091582 -228.961166)
			(xy 37.06129 -229.004232) (xy 37.024778 -229.04217) (xy 36.982904 -229.074089) (xy 36.936648 -229.099242)
			(xy 36.887095 -229.11704) (xy 36.835405 -229.127064) (xy 36.782791 -229.129081) (xy 36.730486 -229.123043)
			(xy 36.679715 -229.109091) (xy 36.63167 -229.087552) (xy 36.587475 -229.058932) (xy 36.548167 -229.023901)
			(xy 36.514667 -228.98328) (xy 36.487761 -228.938021) (xy 36.468078 -228.889186) (xy 36.456081 -228.837918)
			(xy 36.452051 -228.78542) (xy 29.595572 -228.78542) (xy 29.595068 -228.811746) (xy 29.587031 -228.863782)
			(xy 29.571145 -228.913981) (xy 29.547782 -228.961166) (xy 29.51749 -229.004232) (xy 29.480978 -229.04217)
			(xy 29.439104 -229.074089) (xy 29.392848 -229.099242) (xy 29.343295 -229.11704) (xy 29.291605 -229.127064)
			(xy 29.238991 -229.129081) (xy 29.186686 -229.123043) (xy 29.135915 -229.109091) (xy 29.08787 -229.087552)
			(xy 29.043675 -229.058932) (xy 29.004367 -229.023901) (xy 28.970867 -228.98328) (xy 28.943961 -228.938021)
			(xy 28.924278 -228.889186) (xy 28.912281 -228.837918) (xy 28.908251 -228.78542) (xy 22.051518 -228.78542)
			(xy 22.051014 -228.811746) (xy 22.042977 -228.863782) (xy 22.027091 -228.913981) (xy 22.003728 -228.961166)
			(xy 21.973436 -229.004232) (xy 21.936924 -229.04217) (xy 21.89505 -229.074089) (xy 21.848794 -229.099242)
			(xy 21.799241 -229.11704) (xy 21.747551 -229.127064) (xy 21.694937 -229.129081) (xy 21.642632 -229.123043)
			(xy 21.591861 -229.109091) (xy 21.543816 -229.087552) (xy 21.499621 -229.058932) (xy 21.460313 -229.023901)
			(xy 21.426813 -228.98328) (xy 21.399907 -228.938021) (xy 21.380224 -228.889186) (xy 21.368227 -228.837918)
			(xy 21.364197 -228.78542) (xy 16.086074 -228.78542) (xy 16.086074 -229.635304) (xy 17.264129 -229.635304)
			(xy 17.268159 -229.582806) (xy 17.280156 -229.531538) (xy 17.299839 -229.482703) (xy 17.326745 -229.437444)
			(xy 17.360245 -229.396823) (xy 17.399553 -229.361792) (xy 17.443748 -229.333172) (xy 17.491793 -229.311633)
			(xy 17.542564 -229.297681) (xy 17.594869 -229.291643) (xy 17.647483 -229.29366) (xy 17.699173 -229.303684)
			(xy 17.748726 -229.321482) (xy 17.794982 -229.346635) (xy 17.836856 -229.378554) (xy 17.873368 -229.416492)
			(xy 17.90366 -229.459558) (xy 17.927023 -229.506743) (xy 17.942909 -229.556942) (xy 17.950946 -229.608978)
			(xy 17.95145 -229.635304) (xy 21.364197 -229.635304) (xy 21.368227 -229.582806) (xy 21.380224 -229.531538)
			(xy 21.399907 -229.482703) (xy 21.426813 -229.437444) (xy 21.460313 -229.396823) (xy 21.499621 -229.361792)
			(xy 21.543816 -229.333172) (xy 21.591861 -229.311633) (xy 21.642632 -229.297681) (xy 21.694937 -229.291643)
			(xy 21.747551 -229.29366) (xy 21.799241 -229.303684) (xy 21.848794 -229.321482) (xy 21.89505 -229.346635)
			(xy 21.936924 -229.378554) (xy 21.973436 -229.416492) (xy 22.003728 -229.459558) (xy 22.027091 -229.506743)
			(xy 22.042977 -229.556942) (xy 22.051014 -229.608978) (xy 22.051518 -229.635304) (xy 24.808183 -229.635304)
			(xy 24.812213 -229.582806) (xy 24.82421 -229.531538) (xy 24.843893 -229.482703) (xy 24.870799 -229.437444)
			(xy 24.904299 -229.396823) (xy 24.943607 -229.361792) (xy 24.987802 -229.333172) (xy 25.035847 -229.311633)
			(xy 25.086618 -229.297681) (xy 25.138923 -229.291643) (xy 25.191537 -229.29366) (xy 25.243227 -229.303684)
			(xy 25.29278 -229.321482) (xy 25.339036 -229.346635) (xy 25.38091 -229.378554) (xy 25.417422 -229.416492)
			(xy 25.447714 -229.459558) (xy 25.471077 -229.506743) (xy 25.486963 -229.556942) (xy 25.495 -229.608978)
			(xy 25.495504 -229.635304) (xy 28.908251 -229.635304) (xy 28.912281 -229.582806) (xy 28.924278 -229.531538)
			(xy 28.943961 -229.482703) (xy 28.970867 -229.437444) (xy 29.004367 -229.396823) (xy 29.043675 -229.361792)
			(xy 29.08787 -229.333172) (xy 29.135915 -229.311633) (xy 29.186686 -229.297681) (xy 29.238991 -229.291643)
			(xy 29.291605 -229.29366) (xy 29.343295 -229.303684) (xy 29.392848 -229.321482) (xy 29.439104 -229.346635)
			(xy 29.480978 -229.378554) (xy 29.51749 -229.416492) (xy 29.547782 -229.459558) (xy 29.571145 -229.506743)
			(xy 29.587031 -229.556942) (xy 29.595068 -229.608978) (xy 29.595572 -229.635304) (xy 32.351983 -229.635304)
			(xy 32.356013 -229.582806) (xy 32.36801 -229.531538) (xy 32.387693 -229.482703) (xy 32.414599 -229.437444)
			(xy 32.448099 -229.396823) (xy 32.487407 -229.361792) (xy 32.531602 -229.333172) (xy 32.579647 -229.311633)
			(xy 32.630418 -229.297681) (xy 32.682723 -229.291643) (xy 32.735337 -229.29366) (xy 32.787027 -229.303684)
			(xy 32.83658 -229.321482) (xy 32.882836 -229.346635) (xy 32.92471 -229.378554) (xy 32.961222 -229.416492)
			(xy 32.991514 -229.459558) (xy 33.014877 -229.506743) (xy 33.030763 -229.556942) (xy 33.0388 -229.608978)
			(xy 33.039304 -229.635304) (xy 36.452051 -229.635304) (xy 36.456081 -229.582806) (xy 36.468078 -229.531538)
			(xy 36.487761 -229.482703) (xy 36.514667 -229.437444) (xy 36.548167 -229.396823) (xy 36.587475 -229.361792)
			(xy 36.63167 -229.333172) (xy 36.679715 -229.311633) (xy 36.730486 -229.297681) (xy 36.782791 -229.291643)
			(xy 36.835405 -229.29366) (xy 36.887095 -229.303684) (xy 36.936648 -229.321482) (xy 36.982904 -229.346635)
			(xy 37.024778 -229.378554) (xy 37.06129 -229.416492) (xy 37.091582 -229.459558) (xy 37.114945 -229.506743)
			(xy 37.130831 -229.556942) (xy 37.138868 -229.608978) (xy 37.139372 -229.635304) (xy 39.896037 -229.635304)
			(xy 39.900067 -229.582806) (xy 39.912064 -229.531538) (xy 39.931747 -229.482703) (xy 39.958653 -229.437444)
			(xy 39.992153 -229.396823) (xy 40.031461 -229.361792) (xy 40.075656 -229.333172) (xy 40.123701 -229.311633)
			(xy 40.174472 -229.297681) (xy 40.226777 -229.291643) (xy 40.279391 -229.29366) (xy 40.331081 -229.303684)
			(xy 40.380634 -229.321482) (xy 40.42689 -229.346635) (xy 40.468764 -229.378554) (xy 40.505276 -229.416492)
			(xy 40.535568 -229.459558) (xy 40.558931 -229.506743) (xy 40.574817 -229.556942) (xy 40.582854 -229.608978)
			(xy 40.583358 -229.635304) (xy 43.996105 -229.635304) (xy 44.000135 -229.582806) (xy 44.012132 -229.531538)
			(xy 44.031815 -229.482703) (xy 44.058721 -229.437444) (xy 44.092221 -229.396823) (xy 44.131529 -229.361792)
			(xy 44.175724 -229.333172) (xy 44.223769 -229.311633) (xy 44.27454 -229.297681) (xy 44.326845 -229.291643)
			(xy 44.379459 -229.29366) (xy 44.431149 -229.303684) (xy 44.480702 -229.321482) (xy 44.526958 -229.346635)
			(xy 44.568832 -229.378554) (xy 44.605344 -229.416492) (xy 44.635636 -229.459558) (xy 44.658999 -229.506743)
			(xy 44.674885 -229.556942) (xy 44.682922 -229.608978) (xy 44.683426 -229.635304) (xy 47.440091 -229.635304)
			(xy 47.444121 -229.582806) (xy 47.456118 -229.531538) (xy 47.475801 -229.482703) (xy 47.502707 -229.437444)
			(xy 47.536207 -229.396823) (xy 47.575515 -229.361792) (xy 47.61971 -229.333172) (xy 47.667755 -229.311633)
			(xy 47.718526 -229.297681) (xy 47.770831 -229.291643) (xy 47.823445 -229.29366) (xy 47.875135 -229.303684)
			(xy 47.924688 -229.321482) (xy 47.970944 -229.346635) (xy 48.012818 -229.378554) (xy 48.04933 -229.416492)
			(xy 48.079622 -229.459558) (xy 48.102985 -229.506743) (xy 48.118871 -229.556942) (xy 48.126908 -229.608978)
			(xy 48.127412 -229.635304) (xy 51.540159 -229.635304) (xy 51.544189 -229.582806) (xy 51.556186 -229.531538)
			(xy 51.575869 -229.482703) (xy 51.602775 -229.437444) (xy 51.636275 -229.396823) (xy 51.675583 -229.361792)
			(xy 51.719778 -229.333172) (xy 51.767823 -229.311633) (xy 51.818594 -229.297681) (xy 51.870899 -229.291643)
			(xy 51.923513 -229.29366) (xy 51.975203 -229.303684) (xy 52.024756 -229.321482) (xy 52.071012 -229.346635)
			(xy 52.112886 -229.378554) (xy 52.149398 -229.416492) (xy 52.17969 -229.459558) (xy 52.203053 -229.506743)
			(xy 52.218939 -229.556942) (xy 52.226976 -229.608978) (xy 52.22748 -229.635304) (xy 52.226976 -229.66163)
			(xy 52.218939 -229.713666) (xy 52.203053 -229.763865) (xy 52.17969 -229.81105) (xy 52.149398 -229.854116)
			(xy 52.112886 -229.892054) (xy 52.071012 -229.923973) (xy 52.024756 -229.949126) (xy 51.975203 -229.966924)
			(xy 51.923513 -229.976948) (xy 51.870899 -229.978965) (xy 51.818594 -229.972927) (xy 51.767823 -229.958975)
			(xy 51.719778 -229.937436) (xy 51.675583 -229.908816) (xy 51.636275 -229.873785) (xy 51.602775 -229.833164)
			(xy 51.575869 -229.787905) (xy 51.556186 -229.73907) (xy 51.544189 -229.687802) (xy 51.540159 -229.635304)
			(xy 48.127412 -229.635304) (xy 48.126908 -229.66163) (xy 48.118871 -229.713666) (xy 48.102985 -229.763865)
			(xy 48.079622 -229.81105) (xy 48.04933 -229.854116) (xy 48.012818 -229.892054) (xy 47.970944 -229.923973)
			(xy 47.924688 -229.949126) (xy 47.875135 -229.966924) (xy 47.823445 -229.976948) (xy 47.770831 -229.978965)
			(xy 47.718526 -229.972927) (xy 47.667755 -229.958975) (xy 47.61971 -229.937436) (xy 47.575515 -229.908816)
			(xy 47.536207 -229.873785) (xy 47.502707 -229.833164) (xy 47.475801 -229.787905) (xy 47.456118 -229.73907)
			(xy 47.444121 -229.687802) (xy 47.440091 -229.635304) (xy 44.683426 -229.635304) (xy 44.682922 -229.66163)
			(xy 44.674885 -229.713666) (xy 44.658999 -229.763865) (xy 44.635636 -229.81105) (xy 44.605344 -229.854116)
			(xy 44.568832 -229.892054) (xy 44.526958 -229.923973) (xy 44.480702 -229.949126) (xy 44.431149 -229.966924)
			(xy 44.379459 -229.976948) (xy 44.326845 -229.978965) (xy 44.27454 -229.972927) (xy 44.223769 -229.958975)
			(xy 44.175724 -229.937436) (xy 44.131529 -229.908816) (xy 44.092221 -229.873785) (xy 44.058721 -229.833164)
			(xy 44.031815 -229.787905) (xy 44.012132 -229.73907) (xy 44.000135 -229.687802) (xy 43.996105 -229.635304)
			(xy 40.583358 -229.635304) (xy 40.582854 -229.66163) (xy 40.574817 -229.713666) (xy 40.558931 -229.763865)
			(xy 40.535568 -229.81105) (xy 40.505276 -229.854116) (xy 40.468764 -229.892054) (xy 40.42689 -229.923973)
			(xy 40.380634 -229.949126) (xy 40.331081 -229.966924) (xy 40.279391 -229.976948) (xy 40.226777 -229.978965)
			(xy 40.174472 -229.972927) (xy 40.123701 -229.958975) (xy 40.075656 -229.937436) (xy 40.031461 -229.908816)
			(xy 39.992153 -229.873785) (xy 39.958653 -229.833164) (xy 39.931747 -229.787905) (xy 39.912064 -229.73907)
			(xy 39.900067 -229.687802) (xy 39.896037 -229.635304) (xy 37.139372 -229.635304) (xy 37.138868 -229.66163)
			(xy 37.130831 -229.713666) (xy 37.114945 -229.763865) (xy 37.091582 -229.81105) (xy 37.06129 -229.854116)
			(xy 37.024778 -229.892054) (xy 36.982904 -229.923973) (xy 36.936648 -229.949126) (xy 36.887095 -229.966924)
			(xy 36.835405 -229.976948) (xy 36.782791 -229.978965) (xy 36.730486 -229.972927) (xy 36.679715 -229.958975)
			(xy 36.63167 -229.937436) (xy 36.587475 -229.908816) (xy 36.548167 -229.873785) (xy 36.514667 -229.833164)
			(xy 36.487761 -229.787905) (xy 36.468078 -229.73907) (xy 36.456081 -229.687802) (xy 36.452051 -229.635304)
			(xy 33.039304 -229.635304) (xy 33.0388 -229.66163) (xy 33.030763 -229.713666) (xy 33.014877 -229.763865)
			(xy 32.991514 -229.81105) (xy 32.961222 -229.854116) (xy 32.92471 -229.892054) (xy 32.882836 -229.923973)
			(xy 32.83658 -229.949126) (xy 32.787027 -229.966924) (xy 32.735337 -229.976948) (xy 32.682723 -229.978965)
			(xy 32.630418 -229.972927) (xy 32.579647 -229.958975) (xy 32.531602 -229.937436) (xy 32.487407 -229.908816)
			(xy 32.448099 -229.873785) (xy 32.414599 -229.833164) (xy 32.387693 -229.787905) (xy 32.36801 -229.73907)
			(xy 32.356013 -229.687802) (xy 32.351983 -229.635304) (xy 29.595572 -229.635304) (xy 29.595068 -229.66163)
			(xy 29.587031 -229.713666) (xy 29.571145 -229.763865) (xy 29.547782 -229.81105) (xy 29.51749 -229.854116)
			(xy 29.480978 -229.892054) (xy 29.439104 -229.923973) (xy 29.392848 -229.949126) (xy 29.343295 -229.966924)
			(xy 29.291605 -229.976948) (xy 29.238991 -229.978965) (xy 29.186686 -229.972927) (xy 29.135915 -229.958975)
			(xy 29.08787 -229.937436) (xy 29.043675 -229.908816) (xy 29.004367 -229.873785) (xy 28.970867 -229.833164)
			(xy 28.943961 -229.787905) (xy 28.924278 -229.73907) (xy 28.912281 -229.687802) (xy 28.908251 -229.635304)
			(xy 25.495504 -229.635304) (xy 25.495 -229.66163) (xy 25.486963 -229.713666) (xy 25.471077 -229.763865)
			(xy 25.447714 -229.81105) (xy 25.417422 -229.854116) (xy 25.38091 -229.892054) (xy 25.339036 -229.923973)
			(xy 25.29278 -229.949126) (xy 25.243227 -229.966924) (xy 25.191537 -229.976948) (xy 25.138923 -229.978965)
			(xy 25.086618 -229.972927) (xy 25.035847 -229.958975) (xy 24.987802 -229.937436) (xy 24.943607 -229.908816)
			(xy 24.904299 -229.873785) (xy 24.870799 -229.833164) (xy 24.843893 -229.787905) (xy 24.82421 -229.73907)
			(xy 24.812213 -229.687802) (xy 24.808183 -229.635304) (xy 22.051518 -229.635304) (xy 22.051014 -229.66163)
			(xy 22.042977 -229.713666) (xy 22.027091 -229.763865) (xy 22.003728 -229.81105) (xy 21.973436 -229.854116)
			(xy 21.936924 -229.892054) (xy 21.89505 -229.923973) (xy 21.848794 -229.949126) (xy 21.799241 -229.966924)
			(xy 21.747551 -229.976948) (xy 21.694937 -229.978965) (xy 21.642632 -229.972927) (xy 21.591861 -229.958975)
			(xy 21.543816 -229.937436) (xy 21.499621 -229.908816) (xy 21.460313 -229.873785) (xy 21.426813 -229.833164)
			(xy 21.399907 -229.787905) (xy 21.380224 -229.73907) (xy 21.368227 -229.687802) (xy 21.364197 -229.635304)
			(xy 17.95145 -229.635304) (xy 17.950946 -229.66163) (xy 17.942909 -229.713666) (xy 17.927023 -229.763865)
			(xy 17.90366 -229.81105) (xy 17.873368 -229.854116) (xy 17.836856 -229.892054) (xy 17.794982 -229.923973)
			(xy 17.748726 -229.949126) (xy 17.699173 -229.966924) (xy 17.647483 -229.976948) (xy 17.594869 -229.978965)
			(xy 17.542564 -229.972927) (xy 17.491793 -229.958975) (xy 17.443748 -229.937436) (xy 17.399553 -229.908816)
			(xy 17.360245 -229.873785) (xy 17.326745 -229.833164) (xy 17.299839 -229.787905) (xy 17.280156 -229.73907)
			(xy 17.268159 -229.687802) (xy 17.264129 -229.635304) (xy 16.086074 -229.635304) (xy 16.086074 -230.485442)
			(xy 17.264129 -230.485442) (xy 17.268159 -230.432944) (xy 17.280156 -230.381676) (xy 17.299839 -230.332841)
			(xy 17.326745 -230.287582) (xy 17.360245 -230.246961) (xy 17.399553 -230.21193) (xy 17.443748 -230.18331)
			(xy 17.491793 -230.161771) (xy 17.542564 -230.147819) (xy 17.594869 -230.141781) (xy 17.647483 -230.143798)
			(xy 17.699173 -230.153822) (xy 17.748726 -230.17162) (xy 17.794982 -230.196773) (xy 17.836856 -230.228692)
			(xy 17.873368 -230.26663) (xy 17.90366 -230.309696) (xy 17.927023 -230.356881) (xy 17.942909 -230.40708)
			(xy 17.950946 -230.459116) (xy 17.95145 -230.485442) (xy 24.808183 -230.485442) (xy 24.812213 -230.432944)
			(xy 24.82421 -230.381676) (xy 24.843893 -230.332841) (xy 24.870799 -230.287582) (xy 24.904299 -230.246961)
			(xy 24.943607 -230.21193) (xy 24.987802 -230.18331) (xy 25.035847 -230.161771) (xy 25.086618 -230.147819)
			(xy 25.138923 -230.141781) (xy 25.191537 -230.143798) (xy 25.243227 -230.153822) (xy 25.29278 -230.17162)
			(xy 25.339036 -230.196773) (xy 25.38091 -230.228692) (xy 25.417422 -230.26663) (xy 25.447714 -230.309696)
			(xy 25.471077 -230.356881) (xy 25.486963 -230.40708) (xy 25.495 -230.459116) (xy 25.495504 -230.485442)
			(xy 32.351983 -230.485442) (xy 32.356013 -230.432944) (xy 32.36801 -230.381676) (xy 32.387693 -230.332841)
			(xy 32.414599 -230.287582) (xy 32.448099 -230.246961) (xy 32.487407 -230.21193) (xy 32.531602 -230.18331)
			(xy 32.579647 -230.161771) (xy 32.630418 -230.147819) (xy 32.682723 -230.141781) (xy 32.735337 -230.143798)
			(xy 32.787027 -230.153822) (xy 32.83658 -230.17162) (xy 32.882836 -230.196773) (xy 32.92471 -230.228692)
			(xy 32.961222 -230.26663) (xy 32.991514 -230.309696) (xy 33.014877 -230.356881) (xy 33.030763 -230.40708)
			(xy 33.0388 -230.459116) (xy 33.039304 -230.485442) (xy 39.896037 -230.485442) (xy 39.900067 -230.432944)
			(xy 39.912064 -230.381676) (xy 39.931747 -230.332841) (xy 39.958653 -230.287582) (xy 39.992153 -230.246961)
			(xy 40.031461 -230.21193) (xy 40.075656 -230.18331) (xy 40.123701 -230.161771) (xy 40.174472 -230.147819)
			(xy 40.226777 -230.141781) (xy 40.279391 -230.143798) (xy 40.331081 -230.153822) (xy 40.380634 -230.17162)
			(xy 40.42689 -230.196773) (xy 40.468764 -230.228692) (xy 40.505276 -230.26663) (xy 40.535568 -230.309696)
			(xy 40.558931 -230.356881) (xy 40.574817 -230.40708) (xy 40.582854 -230.459116) (xy 40.583358 -230.485442)
			(xy 47.440091 -230.485442) (xy 47.444121 -230.432944) (xy 47.456118 -230.381676) (xy 47.475801 -230.332841)
			(xy 47.502707 -230.287582) (xy 47.536207 -230.246961) (xy 47.575515 -230.21193) (xy 47.61971 -230.18331)
			(xy 47.667755 -230.161771) (xy 47.718526 -230.147819) (xy 47.770831 -230.141781) (xy 47.823445 -230.143798)
			(xy 47.875135 -230.153822) (xy 47.924688 -230.17162) (xy 47.970944 -230.196773) (xy 48.012818 -230.228692)
			(xy 48.04933 -230.26663) (xy 48.079622 -230.309696) (xy 48.102985 -230.356881) (xy 48.118871 -230.40708)
			(xy 48.126908 -230.459116) (xy 48.127412 -230.485442) (xy 48.126908 -230.511768) (xy 48.118871 -230.563804)
			(xy 48.102985 -230.614003) (xy 48.079622 -230.661188) (xy 48.04933 -230.704254) (xy 48.012818 -230.742192)
			(xy 47.970944 -230.774111) (xy 47.924688 -230.799264) (xy 47.875135 -230.817062) (xy 47.823445 -230.827086)
			(xy 47.770831 -230.829103) (xy 47.718526 -230.823065) (xy 47.667755 -230.809113) (xy 47.61971 -230.787574)
			(xy 47.575515 -230.758954) (xy 47.536207 -230.723923) (xy 47.502707 -230.683302) (xy 47.475801 -230.638043)
			(xy 47.456118 -230.589208) (xy 47.444121 -230.53794) (xy 47.440091 -230.485442) (xy 40.583358 -230.485442)
			(xy 40.582854 -230.511768) (xy 40.574817 -230.563804) (xy 40.558931 -230.614003) (xy 40.535568 -230.661188)
			(xy 40.505276 -230.704254) (xy 40.468764 -230.742192) (xy 40.42689 -230.774111) (xy 40.380634 -230.799264)
			(xy 40.331081 -230.817062) (xy 40.279391 -230.827086) (xy 40.226777 -230.829103) (xy 40.174472 -230.823065)
			(xy 40.123701 -230.809113) (xy 40.075656 -230.787574) (xy 40.031461 -230.758954) (xy 39.992153 -230.723923)
			(xy 39.958653 -230.683302) (xy 39.931747 -230.638043) (xy 39.912064 -230.589208) (xy 39.900067 -230.53794)
			(xy 39.896037 -230.485442) (xy 33.039304 -230.485442) (xy 33.0388 -230.511768) (xy 33.030763 -230.563804)
			(xy 33.014877 -230.614003) (xy 32.991514 -230.661188) (xy 32.961222 -230.704254) (xy 32.92471 -230.742192)
			(xy 32.882836 -230.774111) (xy 32.83658 -230.799264) (xy 32.787027 -230.817062) (xy 32.735337 -230.827086)
			(xy 32.682723 -230.829103) (xy 32.630418 -230.823065) (xy 32.579647 -230.809113) (xy 32.531602 -230.787574)
			(xy 32.487407 -230.758954) (xy 32.448099 -230.723923) (xy 32.414599 -230.683302) (xy 32.387693 -230.638043)
			(xy 32.36801 -230.589208) (xy 32.356013 -230.53794) (xy 32.351983 -230.485442) (xy 25.495504 -230.485442)
			(xy 25.495 -230.511768) (xy 25.486963 -230.563804) (xy 25.471077 -230.614003) (xy 25.447714 -230.661188)
			(xy 25.417422 -230.704254) (xy 25.38091 -230.742192) (xy 25.339036 -230.774111) (xy 25.29278 -230.799264)
			(xy 25.243227 -230.817062) (xy 25.191537 -230.827086) (xy 25.138923 -230.829103) (xy 25.086618 -230.823065)
			(xy 25.035847 -230.809113) (xy 24.987802 -230.787574) (xy 24.943607 -230.758954) (xy 24.904299 -230.723923)
			(xy 24.870799 -230.683302) (xy 24.843893 -230.638043) (xy 24.82421 -230.589208) (xy 24.812213 -230.53794)
			(xy 24.808183 -230.485442) (xy 17.95145 -230.485442) (xy 17.950946 -230.511768) (xy 17.942909 -230.563804)
			(xy 17.927023 -230.614003) (xy 17.90366 -230.661188) (xy 17.873368 -230.704254) (xy 17.836856 -230.742192)
			(xy 17.794982 -230.774111) (xy 17.748726 -230.799264) (xy 17.699173 -230.817062) (xy 17.647483 -230.827086)
			(xy 17.594869 -230.829103) (xy 17.542564 -230.823065) (xy 17.491793 -230.809113) (xy 17.443748 -230.787574)
			(xy 17.399553 -230.758954) (xy 17.360245 -230.723923) (xy 17.326745 -230.683302) (xy 17.299839 -230.638043)
			(xy 17.280156 -230.589208) (xy 17.268159 -230.53794) (xy 17.264129 -230.485442) (xy 16.086074 -230.485442)
			(xy 16.086074 -231.335326) (xy 21.364197 -231.335326) (xy 21.368227 -231.282828) (xy 21.380224 -231.23156)
			(xy 21.399907 -231.182725) (xy 21.426813 -231.137466) (xy 21.460313 -231.096845) (xy 21.499621 -231.061814)
			(xy 21.543816 -231.033194) (xy 21.591861 -231.011655) (xy 21.642632 -230.997703) (xy 21.694937 -230.991665)
			(xy 21.747551 -230.993682) (xy 21.799241 -231.003706) (xy 21.848794 -231.021504) (xy 21.89505 -231.046657)
			(xy 21.936924 -231.078576) (xy 21.973436 -231.116514) (xy 22.003728 -231.15958) (xy 22.027091 -231.206765)
			(xy 22.042977 -231.256964) (xy 22.051014 -231.309) (xy 22.051518 -231.335326) (xy 28.908251 -231.335326)
			(xy 28.912281 -231.282828) (xy 28.924278 -231.23156) (xy 28.943961 -231.182725) (xy 28.970867 -231.137466)
			(xy 29.004367 -231.096845) (xy 29.043675 -231.061814) (xy 29.08787 -231.033194) (xy 29.135915 -231.011655)
			(xy 29.186686 -230.997703) (xy 29.238991 -230.991665) (xy 29.291605 -230.993682) (xy 29.343295 -231.003706)
			(xy 29.392848 -231.021504) (xy 29.439104 -231.046657) (xy 29.480978 -231.078576) (xy 29.51749 -231.116514)
			(xy 29.547782 -231.15958) (xy 29.571145 -231.206765) (xy 29.587031 -231.256964) (xy 29.595068 -231.309)
			(xy 29.595572 -231.335326) (xy 36.452051 -231.335326) (xy 36.456081 -231.282828) (xy 36.468078 -231.23156)
			(xy 36.487761 -231.182725) (xy 36.514667 -231.137466) (xy 36.548167 -231.096845) (xy 36.587475 -231.061814)
			(xy 36.63167 -231.033194) (xy 36.679715 -231.011655) (xy 36.730486 -230.997703) (xy 36.782791 -230.991665)
			(xy 36.835405 -230.993682) (xy 36.887095 -231.003706) (xy 36.936648 -231.021504) (xy 36.982904 -231.046657)
			(xy 37.024778 -231.078576) (xy 37.06129 -231.116514) (xy 37.091582 -231.15958) (xy 37.114945 -231.206765)
			(xy 37.130831 -231.256964) (xy 37.138868 -231.309) (xy 37.139372 -231.335326) (xy 43.996105 -231.335326)
			(xy 44.000135 -231.282828) (xy 44.012132 -231.23156) (xy 44.031815 -231.182725) (xy 44.058721 -231.137466)
			(xy 44.092221 -231.096845) (xy 44.131529 -231.061814) (xy 44.175724 -231.033194) (xy 44.223769 -231.011655)
			(xy 44.27454 -230.997703) (xy 44.326845 -230.991665) (xy 44.379459 -230.993682) (xy 44.431149 -231.003706)
			(xy 44.480702 -231.021504) (xy 44.526958 -231.046657) (xy 44.568832 -231.078576) (xy 44.605344 -231.116514)
			(xy 44.635636 -231.15958) (xy 44.658999 -231.206765) (xy 44.674885 -231.256964) (xy 44.682922 -231.309)
			(xy 44.683426 -231.335326) (xy 51.540159 -231.335326) (xy 51.544189 -231.282828) (xy 51.556186 -231.23156)
			(xy 51.575869 -231.182725) (xy 51.602775 -231.137466) (xy 51.636275 -231.096845) (xy 51.675583 -231.061814)
			(xy 51.719778 -231.033194) (xy 51.767823 -231.011655) (xy 51.818594 -230.997703) (xy 51.870899 -230.991665)
			(xy 51.923513 -230.993682) (xy 51.975203 -231.003706) (xy 52.024756 -231.021504) (xy 52.071012 -231.046657)
			(xy 52.112886 -231.078576) (xy 52.149398 -231.116514) (xy 52.17969 -231.15958) (xy 52.203053 -231.206765)
			(xy 52.218939 -231.256964) (xy 52.226976 -231.309) (xy 52.22748 -231.335326) (xy 52.226976 -231.361652)
			(xy 52.218939 -231.413688) (xy 52.203053 -231.463887) (xy 52.17969 -231.511072) (xy 52.149398 -231.554138)
			(xy 52.112886 -231.592076) (xy 52.071012 -231.623995) (xy 52.024756 -231.649148) (xy 51.975203 -231.666946)
			(xy 51.923513 -231.67697) (xy 51.870899 -231.678987) (xy 51.818594 -231.672949) (xy 51.767823 -231.658997)
			(xy 51.719778 -231.637458) (xy 51.675583 -231.608838) (xy 51.636275 -231.573807) (xy 51.602775 -231.533186)
			(xy 51.575869 -231.487927) (xy 51.556186 -231.439092) (xy 51.544189 -231.387824) (xy 51.540159 -231.335326)
			(xy 44.683426 -231.335326) (xy 44.682922 -231.361652) (xy 44.674885 -231.413688) (xy 44.658999 -231.463887)
			(xy 44.635636 -231.511072) (xy 44.605344 -231.554138) (xy 44.568832 -231.592076) (xy 44.526958 -231.623995)
			(xy 44.480702 -231.649148) (xy 44.431149 -231.666946) (xy 44.379459 -231.67697) (xy 44.326845 -231.678987)
			(xy 44.27454 -231.672949) (xy 44.223769 -231.658997) (xy 44.175724 -231.637458) (xy 44.131529 -231.608838)
			(xy 44.092221 -231.573807) (xy 44.058721 -231.533186) (xy 44.031815 -231.487927) (xy 44.012132 -231.439092)
			(xy 44.000135 -231.387824) (xy 43.996105 -231.335326) (xy 37.139372 -231.335326) (xy 37.138868 -231.361652)
			(xy 37.130831 -231.413688) (xy 37.114945 -231.463887) (xy 37.091582 -231.511072) (xy 37.06129 -231.554138)
			(xy 37.024778 -231.592076) (xy 36.982904 -231.623995) (xy 36.936648 -231.649148) (xy 36.887095 -231.666946)
			(xy 36.835405 -231.67697) (xy 36.782791 -231.678987) (xy 36.730486 -231.672949) (xy 36.679715 -231.658997)
			(xy 36.63167 -231.637458) (xy 36.587475 -231.608838) (xy 36.548167 -231.573807) (xy 36.514667 -231.533186)
			(xy 36.487761 -231.487927) (xy 36.468078 -231.439092) (xy 36.456081 -231.387824) (xy 36.452051 -231.335326)
			(xy 29.595572 -231.335326) (xy 29.595068 -231.361652) (xy 29.587031 -231.413688) (xy 29.571145 -231.463887)
			(xy 29.547782 -231.511072) (xy 29.51749 -231.554138) (xy 29.480978 -231.592076) (xy 29.439104 -231.623995)
			(xy 29.392848 -231.649148) (xy 29.343295 -231.666946) (xy 29.291605 -231.67697) (xy 29.238991 -231.678987)
			(xy 29.186686 -231.672949) (xy 29.135915 -231.658997) (xy 29.08787 -231.637458) (xy 29.043675 -231.608838)
			(xy 29.004367 -231.573807) (xy 28.970867 -231.533186) (xy 28.943961 -231.487927) (xy 28.924278 -231.439092)
			(xy 28.912281 -231.387824) (xy 28.908251 -231.335326) (xy 22.051518 -231.335326) (xy 22.051014 -231.361652)
			(xy 22.042977 -231.413688) (xy 22.027091 -231.463887) (xy 22.003728 -231.511072) (xy 21.973436 -231.554138)
			(xy 21.936924 -231.592076) (xy 21.89505 -231.623995) (xy 21.848794 -231.649148) (xy 21.799241 -231.666946)
			(xy 21.747551 -231.67697) (xy 21.694937 -231.678987) (xy 21.642632 -231.672949) (xy 21.591861 -231.658997)
			(xy 21.543816 -231.637458) (xy 21.499621 -231.608838) (xy 21.460313 -231.573807) (xy 21.426813 -231.533186)
			(xy 21.399907 -231.487927) (xy 21.380224 -231.439092) (xy 21.368227 -231.387824) (xy 21.364197 -231.335326)
			(xy 16.086074 -231.335326) (xy 16.086074 -232.18521) (xy 17.264129 -232.18521) (xy 17.268159 -232.132712)
			(xy 17.280156 -232.081444) (xy 17.299839 -232.032609) (xy 17.326745 -231.98735) (xy 17.360245 -231.946729)
			(xy 17.399553 -231.911698) (xy 17.443748 -231.883078) (xy 17.491793 -231.861539) (xy 17.542564 -231.847587)
			(xy 17.594869 -231.841549) (xy 17.647483 -231.843566) (xy 17.699173 -231.85359) (xy 17.748726 -231.871388)
			(xy 17.794982 -231.896541) (xy 17.836856 -231.92846) (xy 17.873368 -231.966398) (xy 17.90366 -232.009464)
			(xy 17.927023 -232.056649) (xy 17.942909 -232.106848) (xy 17.950946 -232.158884) (xy 17.95145 -232.18521)
			(xy 24.808183 -232.18521) (xy 24.812213 -232.132712) (xy 24.82421 -232.081444) (xy 24.843893 -232.032609)
			(xy 24.870799 -231.98735) (xy 24.904299 -231.946729) (xy 24.943607 -231.911698) (xy 24.987802 -231.883078)
			(xy 25.035847 -231.861539) (xy 25.086618 -231.847587) (xy 25.138923 -231.841549) (xy 25.191537 -231.843566)
			(xy 25.243227 -231.85359) (xy 25.29278 -231.871388) (xy 25.339036 -231.896541) (xy 25.38091 -231.92846)
			(xy 25.417422 -231.966398) (xy 25.447714 -232.009464) (xy 25.471077 -232.056649) (xy 25.486963 -232.106848)
			(xy 25.495 -232.158884) (xy 25.495504 -232.18521) (xy 32.351983 -232.18521) (xy 32.356013 -232.132712)
			(xy 32.36801 -232.081444) (xy 32.387693 -232.032609) (xy 32.414599 -231.98735) (xy 32.448099 -231.946729)
			(xy 32.487407 -231.911698) (xy 32.531602 -231.883078) (xy 32.579647 -231.861539) (xy 32.630418 -231.847587)
			(xy 32.682723 -231.841549) (xy 32.735337 -231.843566) (xy 32.787027 -231.85359) (xy 32.83658 -231.871388)
			(xy 32.882836 -231.896541) (xy 32.92471 -231.92846) (xy 32.961222 -231.966398) (xy 32.991514 -232.009464)
			(xy 33.014877 -232.056649) (xy 33.030763 -232.106848) (xy 33.0388 -232.158884) (xy 33.039304 -232.18521)
			(xy 39.896037 -232.18521) (xy 39.900067 -232.132712) (xy 39.912064 -232.081444) (xy 39.931747 -232.032609)
			(xy 39.958653 -231.98735) (xy 39.992153 -231.946729) (xy 40.031461 -231.911698) (xy 40.075656 -231.883078)
			(xy 40.123701 -231.861539) (xy 40.174472 -231.847587) (xy 40.226777 -231.841549) (xy 40.279391 -231.843566)
			(xy 40.331081 -231.85359) (xy 40.380634 -231.871388) (xy 40.42689 -231.896541) (xy 40.468764 -231.92846)
			(xy 40.505276 -231.966398) (xy 40.535568 -232.009464) (xy 40.558931 -232.056649) (xy 40.574817 -232.106848)
			(xy 40.582854 -232.158884) (xy 40.583358 -232.18521) (xy 47.440091 -232.18521) (xy 47.444121 -232.132712)
			(xy 47.456118 -232.081444) (xy 47.475801 -232.032609) (xy 47.502707 -231.98735) (xy 47.536207 -231.946729)
			(xy 47.575515 -231.911698) (xy 47.61971 -231.883078) (xy 47.667755 -231.861539) (xy 47.718526 -231.847587)
			(xy 47.770831 -231.841549) (xy 47.823445 -231.843566) (xy 47.875135 -231.85359) (xy 47.924688 -231.871388)
			(xy 47.970944 -231.896541) (xy 48.012818 -231.92846) (xy 48.04933 -231.966398) (xy 48.079622 -232.009464)
			(xy 48.102985 -232.056649) (xy 48.118871 -232.106848) (xy 48.126908 -232.158884) (xy 48.127412 -232.18521)
			(xy 48.126908 -232.211536) (xy 48.118871 -232.263572) (xy 48.102985 -232.313771) (xy 48.079622 -232.360956)
			(xy 48.04933 -232.404022) (xy 48.012818 -232.44196) (xy 47.970944 -232.473879) (xy 47.924688 -232.499032)
			(xy 47.875135 -232.51683) (xy 47.823445 -232.526854) (xy 47.770831 -232.528871) (xy 47.718526 -232.522833)
			(xy 47.667755 -232.508881) (xy 47.61971 -232.487342) (xy 47.575515 -232.458722) (xy 47.536207 -232.423691)
			(xy 47.502707 -232.38307) (xy 47.475801 -232.337811) (xy 47.456118 -232.288976) (xy 47.444121 -232.237708)
			(xy 47.440091 -232.18521) (xy 40.583358 -232.18521) (xy 40.582854 -232.211536) (xy 40.574817 -232.263572)
			(xy 40.558931 -232.313771) (xy 40.535568 -232.360956) (xy 40.505276 -232.404022) (xy 40.468764 -232.44196)
			(xy 40.42689 -232.473879) (xy 40.380634 -232.499032) (xy 40.331081 -232.51683) (xy 40.279391 -232.526854)
			(xy 40.226777 -232.528871) (xy 40.174472 -232.522833) (xy 40.123701 -232.508881) (xy 40.075656 -232.487342)
			(xy 40.031461 -232.458722) (xy 39.992153 -232.423691) (xy 39.958653 -232.38307) (xy 39.931747 -232.337811)
			(xy 39.912064 -232.288976) (xy 39.900067 -232.237708) (xy 39.896037 -232.18521) (xy 33.039304 -232.18521)
			(xy 33.0388 -232.211536) (xy 33.030763 -232.263572) (xy 33.014877 -232.313771) (xy 32.991514 -232.360956)
			(xy 32.961222 -232.404022) (xy 32.92471 -232.44196) (xy 32.882836 -232.473879) (xy 32.83658 -232.499032)
			(xy 32.787027 -232.51683) (xy 32.735337 -232.526854) (xy 32.682723 -232.528871) (xy 32.630418 -232.522833)
			(xy 32.579647 -232.508881) (xy 32.531602 -232.487342) (xy 32.487407 -232.458722) (xy 32.448099 -232.423691)
			(xy 32.414599 -232.38307) (xy 32.387693 -232.337811) (xy 32.36801 -232.288976) (xy 32.356013 -232.237708)
			(xy 32.351983 -232.18521) (xy 25.495504 -232.18521) (xy 25.495 -232.211536) (xy 25.486963 -232.263572)
			(xy 25.471077 -232.313771) (xy 25.447714 -232.360956) (xy 25.417422 -232.404022) (xy 25.38091 -232.44196)
			(xy 25.339036 -232.473879) (xy 25.29278 -232.499032) (xy 25.243227 -232.51683) (xy 25.191537 -232.526854)
			(xy 25.138923 -232.528871) (xy 25.086618 -232.522833) (xy 25.035847 -232.508881) (xy 24.987802 -232.487342)
			(xy 24.943607 -232.458722) (xy 24.904299 -232.423691) (xy 24.870799 -232.38307) (xy 24.843893 -232.337811)
			(xy 24.82421 -232.288976) (xy 24.812213 -232.237708) (xy 24.808183 -232.18521) (xy 17.95145 -232.18521)
			(xy 17.950946 -232.211536) (xy 17.942909 -232.263572) (xy 17.927023 -232.313771) (xy 17.90366 -232.360956)
			(xy 17.873368 -232.404022) (xy 17.836856 -232.44196) (xy 17.794982 -232.473879) (xy 17.748726 -232.499032)
			(xy 17.699173 -232.51683) (xy 17.647483 -232.526854) (xy 17.594869 -232.528871) (xy 17.542564 -232.522833)
			(xy 17.491793 -232.508881) (xy 17.443748 -232.487342) (xy 17.399553 -232.458722) (xy 17.360245 -232.423691)
			(xy 17.326745 -232.38307) (xy 17.299839 -232.337811) (xy 17.280156 -232.288976) (xy 17.268159 -232.237708)
			(xy 17.264129 -232.18521) (xy 16.086074 -232.18521) (xy 16.086074 -233.035348) (xy 21.364197 -233.035348)
			(xy 21.368227 -232.98285) (xy 21.380224 -232.931582) (xy 21.399907 -232.882747) (xy 21.426813 -232.837488)
			(xy 21.460313 -232.796867) (xy 21.499621 -232.761836) (xy 21.543816 -232.733216) (xy 21.591861 -232.711677)
			(xy 21.642632 -232.697725) (xy 21.694937 -232.691687) (xy 21.747551 -232.693704) (xy 21.799241 -232.703728)
			(xy 21.848794 -232.721526) (xy 21.89505 -232.746679) (xy 21.936924 -232.778598) (xy 21.973436 -232.816536)
			(xy 22.003728 -232.859602) (xy 22.027091 -232.906787) (xy 22.042977 -232.956986) (xy 22.051014 -233.009022)
			(xy 22.051518 -233.035348) (xy 28.908251 -233.035348) (xy 28.912281 -232.98285) (xy 28.924278 -232.931582)
			(xy 28.943961 -232.882747) (xy 28.970867 -232.837488) (xy 29.004367 -232.796867) (xy 29.043675 -232.761836)
			(xy 29.08787 -232.733216) (xy 29.135915 -232.711677) (xy 29.186686 -232.697725) (xy 29.238991 -232.691687)
			(xy 29.291605 -232.693704) (xy 29.343295 -232.703728) (xy 29.392848 -232.721526) (xy 29.439104 -232.746679)
			(xy 29.480978 -232.778598) (xy 29.51749 -232.816536) (xy 29.547782 -232.859602) (xy 29.571145 -232.906787)
			(xy 29.587031 -232.956986) (xy 29.595068 -233.009022) (xy 29.595572 -233.035348) (xy 36.452051 -233.035348)
			(xy 36.456081 -232.98285) (xy 36.468078 -232.931582) (xy 36.487761 -232.882747) (xy 36.514667 -232.837488)
			(xy 36.548167 -232.796867) (xy 36.587475 -232.761836) (xy 36.63167 -232.733216) (xy 36.679715 -232.711677)
			(xy 36.730486 -232.697725) (xy 36.782791 -232.691687) (xy 36.835405 -232.693704) (xy 36.887095 -232.703728)
			(xy 36.936648 -232.721526) (xy 36.982904 -232.746679) (xy 37.024778 -232.778598) (xy 37.06129 -232.816536)
			(xy 37.091582 -232.859602) (xy 37.114945 -232.906787) (xy 37.130831 -232.956986) (xy 37.138868 -233.009022)
			(xy 37.139372 -233.035348) (xy 43.996105 -233.035348) (xy 44.000135 -232.98285) (xy 44.012132 -232.931582)
			(xy 44.031815 -232.882747) (xy 44.058721 -232.837488) (xy 44.092221 -232.796867) (xy 44.131529 -232.761836)
			(xy 44.175724 -232.733216) (xy 44.223769 -232.711677) (xy 44.27454 -232.697725) (xy 44.326845 -232.691687)
			(xy 44.379459 -232.693704) (xy 44.431149 -232.703728) (xy 44.480702 -232.721526) (xy 44.526958 -232.746679)
			(xy 44.568832 -232.778598) (xy 44.605344 -232.816536) (xy 44.635636 -232.859602) (xy 44.658999 -232.906787)
			(xy 44.674885 -232.956986) (xy 44.682922 -233.009022) (xy 44.683426 -233.035348) (xy 51.540159 -233.035348)
			(xy 51.544189 -232.98285) (xy 51.556186 -232.931582) (xy 51.575869 -232.882747) (xy 51.602775 -232.837488)
			(xy 51.636275 -232.796867) (xy 51.675583 -232.761836) (xy 51.719778 -232.733216) (xy 51.767823 -232.711677)
			(xy 51.818594 -232.697725) (xy 51.870899 -232.691687) (xy 51.923513 -232.693704) (xy 51.975203 -232.703728)
			(xy 52.024756 -232.721526) (xy 52.071012 -232.746679) (xy 52.112886 -232.778598) (xy 52.149398 -232.816536)
			(xy 52.17969 -232.859602) (xy 52.203053 -232.906787) (xy 52.218939 -232.956986) (xy 52.226976 -233.009022)
			(xy 52.22748 -233.035348) (xy 52.226976 -233.061674) (xy 52.218939 -233.11371) (xy 52.203053 -233.163909)
			(xy 52.17969 -233.211094) (xy 52.149398 -233.25416) (xy 52.112886 -233.292098) (xy 52.071012 -233.324017)
			(xy 52.024756 -233.34917) (xy 51.975203 -233.366968) (xy 51.923513 -233.376992) (xy 51.870899 -233.379009)
			(xy 51.818594 -233.372971) (xy 51.767823 -233.359019) (xy 51.719778 -233.33748) (xy 51.675583 -233.30886)
			(xy 51.636275 -233.273829) (xy 51.602775 -233.233208) (xy 51.575869 -233.187949) (xy 51.556186 -233.139114)
			(xy 51.544189 -233.087846) (xy 51.540159 -233.035348) (xy 44.683426 -233.035348) (xy 44.682922 -233.061674)
			(xy 44.674885 -233.11371) (xy 44.658999 -233.163909) (xy 44.635636 -233.211094) (xy 44.605344 -233.25416)
			(xy 44.568832 -233.292098) (xy 44.526958 -233.324017) (xy 44.480702 -233.34917) (xy 44.431149 -233.366968)
			(xy 44.379459 -233.376992) (xy 44.326845 -233.379009) (xy 44.27454 -233.372971) (xy 44.223769 -233.359019)
			(xy 44.175724 -233.33748) (xy 44.131529 -233.30886) (xy 44.092221 -233.273829) (xy 44.058721 -233.233208)
			(xy 44.031815 -233.187949) (xy 44.012132 -233.139114) (xy 44.000135 -233.087846) (xy 43.996105 -233.035348)
			(xy 37.139372 -233.035348) (xy 37.138868 -233.061674) (xy 37.130831 -233.11371) (xy 37.114945 -233.163909)
			(xy 37.091582 -233.211094) (xy 37.06129 -233.25416) (xy 37.024778 -233.292098) (xy 36.982904 -233.324017)
			(xy 36.936648 -233.34917) (xy 36.887095 -233.366968) (xy 36.835405 -233.376992) (xy 36.782791 -233.379009)
			(xy 36.730486 -233.372971) (xy 36.679715 -233.359019) (xy 36.63167 -233.33748) (xy 36.587475 -233.30886)
			(xy 36.548167 -233.273829) (xy 36.514667 -233.233208) (xy 36.487761 -233.187949) (xy 36.468078 -233.139114)
			(xy 36.456081 -233.087846) (xy 36.452051 -233.035348) (xy 29.595572 -233.035348) (xy 29.595068 -233.061674)
			(xy 29.587031 -233.11371) (xy 29.571145 -233.163909) (xy 29.547782 -233.211094) (xy 29.51749 -233.25416)
			(xy 29.480978 -233.292098) (xy 29.439104 -233.324017) (xy 29.392848 -233.34917) (xy 29.343295 -233.366968)
			(xy 29.291605 -233.376992) (xy 29.238991 -233.379009) (xy 29.186686 -233.372971) (xy 29.135915 -233.359019)
			(xy 29.08787 -233.33748) (xy 29.043675 -233.30886) (xy 29.004367 -233.273829) (xy 28.970867 -233.233208)
			(xy 28.943961 -233.187949) (xy 28.924278 -233.139114) (xy 28.912281 -233.087846) (xy 28.908251 -233.035348)
			(xy 22.051518 -233.035348) (xy 22.051014 -233.061674) (xy 22.042977 -233.11371) (xy 22.027091 -233.163909)
			(xy 22.003728 -233.211094) (xy 21.973436 -233.25416) (xy 21.936924 -233.292098) (xy 21.89505 -233.324017)
			(xy 21.848794 -233.34917) (xy 21.799241 -233.366968) (xy 21.747551 -233.376992) (xy 21.694937 -233.379009)
			(xy 21.642632 -233.372971) (xy 21.591861 -233.359019) (xy 21.543816 -233.33748) (xy 21.499621 -233.30886)
			(xy 21.460313 -233.273829) (xy 21.426813 -233.233208) (xy 21.399907 -233.187949) (xy 21.380224 -233.139114)
			(xy 21.368227 -233.087846) (xy 21.364197 -233.035348) (xy 16.086074 -233.035348) (xy 16.086074 -233.885232)
			(xy 17.264129 -233.885232) (xy 17.268159 -233.832734) (xy 17.280156 -233.781466) (xy 17.299839 -233.732631)
			(xy 17.326745 -233.687372) (xy 17.360245 -233.646751) (xy 17.399553 -233.61172) (xy 17.443748 -233.5831)
			(xy 17.491793 -233.561561) (xy 17.542564 -233.547609) (xy 17.594869 -233.541571) (xy 17.647483 -233.543588)
			(xy 17.699173 -233.553612) (xy 17.748726 -233.57141) (xy 17.794982 -233.596563) (xy 17.836856 -233.628482)
			(xy 17.873368 -233.66642) (xy 17.90366 -233.709486) (xy 17.927023 -233.756671) (xy 17.942909 -233.80687)
			(xy 17.950946 -233.858906) (xy 17.95145 -233.885232) (xy 24.808183 -233.885232) (xy 24.812213 -233.832734)
			(xy 24.82421 -233.781466) (xy 24.843893 -233.732631) (xy 24.870799 -233.687372) (xy 24.904299 -233.646751)
			(xy 24.943607 -233.61172) (xy 24.987802 -233.5831) (xy 25.035847 -233.561561) (xy 25.086618 -233.547609)
			(xy 25.138923 -233.541571) (xy 25.191537 -233.543588) (xy 25.243227 -233.553612) (xy 25.29278 -233.57141)
			(xy 25.339036 -233.596563) (xy 25.38091 -233.628482) (xy 25.417422 -233.66642) (xy 25.447714 -233.709486)
			(xy 25.471077 -233.756671) (xy 25.486963 -233.80687) (xy 25.495 -233.858906) (xy 25.495504 -233.885232)
			(xy 32.351983 -233.885232) (xy 32.356013 -233.832734) (xy 32.36801 -233.781466) (xy 32.387693 -233.732631)
			(xy 32.414599 -233.687372) (xy 32.448099 -233.646751) (xy 32.487407 -233.61172) (xy 32.531602 -233.5831)
			(xy 32.579647 -233.561561) (xy 32.630418 -233.547609) (xy 32.682723 -233.541571) (xy 32.735337 -233.543588)
			(xy 32.787027 -233.553612) (xy 32.83658 -233.57141) (xy 32.882836 -233.596563) (xy 32.92471 -233.628482)
			(xy 32.961222 -233.66642) (xy 32.991514 -233.709486) (xy 33.014877 -233.756671) (xy 33.030763 -233.80687)
			(xy 33.0388 -233.858906) (xy 33.039304 -233.885232) (xy 39.896037 -233.885232) (xy 39.900067 -233.832734)
			(xy 39.912064 -233.781466) (xy 39.931747 -233.732631) (xy 39.958653 -233.687372) (xy 39.992153 -233.646751)
			(xy 40.031461 -233.61172) (xy 40.075656 -233.5831) (xy 40.123701 -233.561561) (xy 40.174472 -233.547609)
			(xy 40.226777 -233.541571) (xy 40.279391 -233.543588) (xy 40.331081 -233.553612) (xy 40.380634 -233.57141)
			(xy 40.42689 -233.596563) (xy 40.468764 -233.628482) (xy 40.505276 -233.66642) (xy 40.535568 -233.709486)
			(xy 40.558931 -233.756671) (xy 40.574817 -233.80687) (xy 40.582854 -233.858906) (xy 40.583358 -233.885232)
			(xy 47.440091 -233.885232) (xy 47.444121 -233.832734) (xy 47.456118 -233.781466) (xy 47.475801 -233.732631)
			(xy 47.502707 -233.687372) (xy 47.536207 -233.646751) (xy 47.575515 -233.61172) (xy 47.61971 -233.5831)
			(xy 47.667755 -233.561561) (xy 47.718526 -233.547609) (xy 47.770831 -233.541571) (xy 47.823445 -233.543588)
			(xy 47.875135 -233.553612) (xy 47.924688 -233.57141) (xy 47.970944 -233.596563) (xy 48.012818 -233.628482)
			(xy 48.04933 -233.66642) (xy 48.079622 -233.709486) (xy 48.102985 -233.756671) (xy 48.118871 -233.80687)
			(xy 48.126908 -233.858906) (xy 48.127412 -233.885232) (xy 48.126908 -233.911558) (xy 48.118871 -233.963594)
			(xy 48.102985 -234.013793) (xy 48.079622 -234.060978) (xy 48.04933 -234.104044) (xy 48.012818 -234.141982)
			(xy 47.970944 -234.173901) (xy 47.924688 -234.199054) (xy 47.875135 -234.216852) (xy 47.823445 -234.226876)
			(xy 47.770831 -234.228893) (xy 47.718526 -234.222855) (xy 47.667755 -234.208903) (xy 47.61971 -234.187364)
			(xy 47.575515 -234.158744) (xy 47.536207 -234.123713) (xy 47.502707 -234.083092) (xy 47.475801 -234.037833)
			(xy 47.456118 -233.988998) (xy 47.444121 -233.93773) (xy 47.440091 -233.885232) (xy 40.583358 -233.885232)
			(xy 40.582854 -233.911558) (xy 40.574817 -233.963594) (xy 40.558931 -234.013793) (xy 40.535568 -234.060978)
			(xy 40.505276 -234.104044) (xy 40.468764 -234.141982) (xy 40.42689 -234.173901) (xy 40.380634 -234.199054)
			(xy 40.331081 -234.216852) (xy 40.279391 -234.226876) (xy 40.226777 -234.228893) (xy 40.174472 -234.222855)
			(xy 40.123701 -234.208903) (xy 40.075656 -234.187364) (xy 40.031461 -234.158744) (xy 39.992153 -234.123713)
			(xy 39.958653 -234.083092) (xy 39.931747 -234.037833) (xy 39.912064 -233.988998) (xy 39.900067 -233.93773)
			(xy 39.896037 -233.885232) (xy 33.039304 -233.885232) (xy 33.0388 -233.911558) (xy 33.030763 -233.963594)
			(xy 33.014877 -234.013793) (xy 32.991514 -234.060978) (xy 32.961222 -234.104044) (xy 32.92471 -234.141982)
			(xy 32.882836 -234.173901) (xy 32.83658 -234.199054) (xy 32.787027 -234.216852) (xy 32.735337 -234.226876)
			(xy 32.682723 -234.228893) (xy 32.630418 -234.222855) (xy 32.579647 -234.208903) (xy 32.531602 -234.187364)
			(xy 32.487407 -234.158744) (xy 32.448099 -234.123713) (xy 32.414599 -234.083092) (xy 32.387693 -234.037833)
			(xy 32.36801 -233.988998) (xy 32.356013 -233.93773) (xy 32.351983 -233.885232) (xy 25.495504 -233.885232)
			(xy 25.495 -233.911558) (xy 25.486963 -233.963594) (xy 25.471077 -234.013793) (xy 25.447714 -234.060978)
			(xy 25.417422 -234.104044) (xy 25.38091 -234.141982) (xy 25.339036 -234.173901) (xy 25.29278 -234.199054)
			(xy 25.243227 -234.216852) (xy 25.191537 -234.226876) (xy 25.138923 -234.228893) (xy 25.086618 -234.222855)
			(xy 25.035847 -234.208903) (xy 24.987802 -234.187364) (xy 24.943607 -234.158744) (xy 24.904299 -234.123713)
			(xy 24.870799 -234.083092) (xy 24.843893 -234.037833) (xy 24.82421 -233.988998) (xy 24.812213 -233.93773)
			(xy 24.808183 -233.885232) (xy 17.95145 -233.885232) (xy 17.950946 -233.911558) (xy 17.942909 -233.963594)
			(xy 17.927023 -234.013793) (xy 17.90366 -234.060978) (xy 17.873368 -234.104044) (xy 17.836856 -234.141982)
			(xy 17.794982 -234.173901) (xy 17.748726 -234.199054) (xy 17.699173 -234.216852) (xy 17.647483 -234.226876)
			(xy 17.594869 -234.228893) (xy 17.542564 -234.222855) (xy 17.491793 -234.208903) (xy 17.443748 -234.187364)
			(xy 17.399553 -234.158744) (xy 17.360245 -234.123713) (xy 17.326745 -234.083092) (xy 17.299839 -234.037833)
			(xy 17.280156 -233.988998) (xy 17.268159 -233.93773) (xy 17.264129 -233.885232) (xy 16.086074 -233.885232)
			(xy 16.086074 -234.73537) (xy 21.364197 -234.73537) (xy 21.368227 -234.682872) (xy 21.380224 -234.631604)
			(xy 21.399907 -234.582769) (xy 21.426813 -234.53751) (xy 21.460313 -234.496889) (xy 21.499621 -234.461858)
			(xy 21.543816 -234.433238) (xy 21.591861 -234.411699) (xy 21.642632 -234.397747) (xy 21.694937 -234.391709)
			(xy 21.747551 -234.393726) (xy 21.799241 -234.40375) (xy 21.848794 -234.421548) (xy 21.89505 -234.446701)
			(xy 21.936924 -234.47862) (xy 21.973436 -234.516558) (xy 22.003728 -234.559624) (xy 22.027091 -234.606809)
			(xy 22.042977 -234.657008) (xy 22.051014 -234.709044) (xy 22.051518 -234.73537) (xy 28.908251 -234.73537)
			(xy 28.912281 -234.682872) (xy 28.924278 -234.631604) (xy 28.943961 -234.582769) (xy 28.970867 -234.53751)
			(xy 29.004367 -234.496889) (xy 29.043675 -234.461858) (xy 29.08787 -234.433238) (xy 29.135915 -234.411699)
			(xy 29.186686 -234.397747) (xy 29.238991 -234.391709) (xy 29.291605 -234.393726) (xy 29.343295 -234.40375)
			(xy 29.392848 -234.421548) (xy 29.439104 -234.446701) (xy 29.480978 -234.47862) (xy 29.51749 -234.516558)
			(xy 29.547782 -234.559624) (xy 29.571145 -234.606809) (xy 29.587031 -234.657008) (xy 29.595068 -234.709044)
			(xy 29.595572 -234.73537) (xy 36.452051 -234.73537) (xy 36.456081 -234.682872) (xy 36.468078 -234.631604)
			(xy 36.487761 -234.582769) (xy 36.514667 -234.53751) (xy 36.548167 -234.496889) (xy 36.587475 -234.461858)
			(xy 36.63167 -234.433238) (xy 36.679715 -234.411699) (xy 36.730486 -234.397747) (xy 36.782791 -234.391709)
			(xy 36.835405 -234.393726) (xy 36.887095 -234.40375) (xy 36.936648 -234.421548) (xy 36.982904 -234.446701)
			(xy 37.024778 -234.47862) (xy 37.06129 -234.516558) (xy 37.091582 -234.559624) (xy 37.114945 -234.606809)
			(xy 37.130831 -234.657008) (xy 37.138868 -234.709044) (xy 37.139372 -234.73537) (xy 43.996105 -234.73537)
			(xy 44.000135 -234.682872) (xy 44.012132 -234.631604) (xy 44.031815 -234.582769) (xy 44.058721 -234.53751)
			(xy 44.092221 -234.496889) (xy 44.131529 -234.461858) (xy 44.175724 -234.433238) (xy 44.223769 -234.411699)
			(xy 44.27454 -234.397747) (xy 44.326845 -234.391709) (xy 44.379459 -234.393726) (xy 44.431149 -234.40375)
			(xy 44.480702 -234.421548) (xy 44.526958 -234.446701) (xy 44.568832 -234.47862) (xy 44.605344 -234.516558)
			(xy 44.635636 -234.559624) (xy 44.658999 -234.606809) (xy 44.674885 -234.657008) (xy 44.682922 -234.709044)
			(xy 44.683426 -234.73537) (xy 51.540159 -234.73537) (xy 51.544189 -234.682872) (xy 51.556186 -234.631604)
			(xy 51.575869 -234.582769) (xy 51.602775 -234.53751) (xy 51.636275 -234.496889) (xy 51.675583 -234.461858)
			(xy 51.719778 -234.433238) (xy 51.767823 -234.411699) (xy 51.818594 -234.397747) (xy 51.870899 -234.391709)
			(xy 51.923513 -234.393726) (xy 51.975203 -234.40375) (xy 52.024756 -234.421548) (xy 52.071012 -234.446701)
			(xy 52.112886 -234.47862) (xy 52.149398 -234.516558) (xy 52.17969 -234.559624) (xy 52.203053 -234.606809)
			(xy 52.218939 -234.657008) (xy 52.226976 -234.709044) (xy 52.22748 -234.73537) (xy 52.226976 -234.761696)
			(xy 52.218939 -234.813732) (xy 52.203053 -234.863931) (xy 52.17969 -234.911116) (xy 52.149398 -234.954182)
			(xy 52.112886 -234.99212) (xy 52.071012 -235.024039) (xy 52.024756 -235.049192) (xy 51.975203 -235.06699)
			(xy 51.923513 -235.077014) (xy 51.870899 -235.079031) (xy 51.818594 -235.072993) (xy 51.767823 -235.059041)
			(xy 51.719778 -235.037502) (xy 51.675583 -235.008882) (xy 51.636275 -234.973851) (xy 51.602775 -234.93323)
			(xy 51.575869 -234.887971) (xy 51.556186 -234.839136) (xy 51.544189 -234.787868) (xy 51.540159 -234.73537)
			(xy 44.683426 -234.73537) (xy 44.682922 -234.761696) (xy 44.674885 -234.813732) (xy 44.658999 -234.863931)
			(xy 44.635636 -234.911116) (xy 44.605344 -234.954182) (xy 44.568832 -234.99212) (xy 44.526958 -235.024039)
			(xy 44.480702 -235.049192) (xy 44.431149 -235.06699) (xy 44.379459 -235.077014) (xy 44.326845 -235.079031)
			(xy 44.27454 -235.072993) (xy 44.223769 -235.059041) (xy 44.175724 -235.037502) (xy 44.131529 -235.008882)
			(xy 44.092221 -234.973851) (xy 44.058721 -234.93323) (xy 44.031815 -234.887971) (xy 44.012132 -234.839136)
			(xy 44.000135 -234.787868) (xy 43.996105 -234.73537) (xy 37.139372 -234.73537) (xy 37.138868 -234.761696)
			(xy 37.130831 -234.813732) (xy 37.114945 -234.863931) (xy 37.091582 -234.911116) (xy 37.06129 -234.954182)
			(xy 37.024778 -234.99212) (xy 36.982904 -235.024039) (xy 36.936648 -235.049192) (xy 36.887095 -235.06699)
			(xy 36.835405 -235.077014) (xy 36.782791 -235.079031) (xy 36.730486 -235.072993) (xy 36.679715 -235.059041)
			(xy 36.63167 -235.037502) (xy 36.587475 -235.008882) (xy 36.548167 -234.973851) (xy 36.514667 -234.93323)
			(xy 36.487761 -234.887971) (xy 36.468078 -234.839136) (xy 36.456081 -234.787868) (xy 36.452051 -234.73537)
			(xy 29.595572 -234.73537) (xy 29.595068 -234.761696) (xy 29.587031 -234.813732) (xy 29.571145 -234.863931)
			(xy 29.547782 -234.911116) (xy 29.51749 -234.954182) (xy 29.480978 -234.99212) (xy 29.439104 -235.024039)
			(xy 29.392848 -235.049192) (xy 29.343295 -235.06699) (xy 29.291605 -235.077014) (xy 29.238991 -235.079031)
			(xy 29.186686 -235.072993) (xy 29.135915 -235.059041) (xy 29.08787 -235.037502) (xy 29.043675 -235.008882)
			(xy 29.004367 -234.973851) (xy 28.970867 -234.93323) (xy 28.943961 -234.887971) (xy 28.924278 -234.839136)
			(xy 28.912281 -234.787868) (xy 28.908251 -234.73537) (xy 22.051518 -234.73537) (xy 22.051014 -234.761696)
			(xy 22.042977 -234.813732) (xy 22.027091 -234.863931) (xy 22.003728 -234.911116) (xy 21.973436 -234.954182)
			(xy 21.936924 -234.99212) (xy 21.89505 -235.024039) (xy 21.848794 -235.049192) (xy 21.799241 -235.06699)
			(xy 21.747551 -235.077014) (xy 21.694937 -235.079031) (xy 21.642632 -235.072993) (xy 21.591861 -235.059041)
			(xy 21.543816 -235.037502) (xy 21.499621 -235.008882) (xy 21.460313 -234.973851) (xy 21.426813 -234.93323)
			(xy 21.399907 -234.887971) (xy 21.380224 -234.839136) (xy 21.368227 -234.787868) (xy 21.364197 -234.73537)
			(xy 16.086074 -234.73537) (xy 16.086074 -235.585254) (xy 17.264129 -235.585254) (xy 17.268159 -235.532756)
			(xy 17.280156 -235.481488) (xy 17.299839 -235.432653) (xy 17.326745 -235.387394) (xy 17.360245 -235.346773)
			(xy 17.399553 -235.311742) (xy 17.443748 -235.283122) (xy 17.491793 -235.261583) (xy 17.542564 -235.247631)
			(xy 17.594869 -235.241593) (xy 17.647483 -235.24361) (xy 17.699173 -235.253634) (xy 17.748726 -235.271432)
			(xy 17.794982 -235.296585) (xy 17.836856 -235.328504) (xy 17.873368 -235.366442) (xy 17.90366 -235.409508)
			(xy 17.927023 -235.456693) (xy 17.942909 -235.506892) (xy 17.950946 -235.558928) (xy 17.95145 -235.585254)
			(xy 24.808183 -235.585254) (xy 24.812213 -235.532756) (xy 24.82421 -235.481488) (xy 24.843893 -235.432653)
			(xy 24.870799 -235.387394) (xy 24.904299 -235.346773) (xy 24.943607 -235.311742) (xy 24.987802 -235.283122)
			(xy 25.035847 -235.261583) (xy 25.086618 -235.247631) (xy 25.138923 -235.241593) (xy 25.191537 -235.24361)
			(xy 25.243227 -235.253634) (xy 25.29278 -235.271432) (xy 25.339036 -235.296585) (xy 25.38091 -235.328504)
			(xy 25.417422 -235.366442) (xy 25.447714 -235.409508) (xy 25.471077 -235.456693) (xy 25.486963 -235.506892)
			(xy 25.495 -235.558928) (xy 25.495504 -235.585254) (xy 32.351983 -235.585254) (xy 32.356013 -235.532756)
			(xy 32.36801 -235.481488) (xy 32.387693 -235.432653) (xy 32.414599 -235.387394) (xy 32.448099 -235.346773)
			(xy 32.487407 -235.311742) (xy 32.531602 -235.283122) (xy 32.579647 -235.261583) (xy 32.630418 -235.247631)
			(xy 32.682723 -235.241593) (xy 32.735337 -235.24361) (xy 32.787027 -235.253634) (xy 32.83658 -235.271432)
			(xy 32.882836 -235.296585) (xy 32.92471 -235.328504) (xy 32.961222 -235.366442) (xy 32.991514 -235.409508)
			(xy 33.014877 -235.456693) (xy 33.030763 -235.506892) (xy 33.0388 -235.558928) (xy 33.039304 -235.585254)
			(xy 39.896037 -235.585254) (xy 39.900067 -235.532756) (xy 39.912064 -235.481488) (xy 39.931747 -235.432653)
			(xy 39.958653 -235.387394) (xy 39.992153 -235.346773) (xy 40.031461 -235.311742) (xy 40.075656 -235.283122)
			(xy 40.123701 -235.261583) (xy 40.174472 -235.247631) (xy 40.226777 -235.241593) (xy 40.279391 -235.24361)
			(xy 40.331081 -235.253634) (xy 40.380634 -235.271432) (xy 40.42689 -235.296585) (xy 40.468764 -235.328504)
			(xy 40.505276 -235.366442) (xy 40.535568 -235.409508) (xy 40.558931 -235.456693) (xy 40.574817 -235.506892)
			(xy 40.582854 -235.558928) (xy 40.583358 -235.585254) (xy 47.440091 -235.585254) (xy 47.444121 -235.532756)
			(xy 47.456118 -235.481488) (xy 47.475801 -235.432653) (xy 47.502707 -235.387394) (xy 47.536207 -235.346773)
			(xy 47.575515 -235.311742) (xy 47.61971 -235.283122) (xy 47.667755 -235.261583) (xy 47.718526 -235.247631)
			(xy 47.770831 -235.241593) (xy 47.823445 -235.24361) (xy 47.875135 -235.253634) (xy 47.924688 -235.271432)
			(xy 47.970944 -235.296585) (xy 48.012818 -235.328504) (xy 48.04933 -235.366442) (xy 48.079622 -235.409508)
			(xy 48.102985 -235.456693) (xy 48.118871 -235.506892) (xy 48.126908 -235.558928) (xy 48.127412 -235.585254)
			(xy 48.126908 -235.61158) (xy 48.118871 -235.663616) (xy 48.102985 -235.713815) (xy 48.079622 -235.761)
			(xy 48.04933 -235.804066) (xy 48.012818 -235.842004) (xy 47.970944 -235.873923) (xy 47.924688 -235.899076)
			(xy 47.875135 -235.916874) (xy 47.823445 -235.926898) (xy 47.770831 -235.928915) (xy 47.718526 -235.922877)
			(xy 47.667755 -235.908925) (xy 47.61971 -235.887386) (xy 47.575515 -235.858766) (xy 47.536207 -235.823735)
			(xy 47.502707 -235.783114) (xy 47.475801 -235.737855) (xy 47.456118 -235.68902) (xy 47.444121 -235.637752)
			(xy 47.440091 -235.585254) (xy 40.583358 -235.585254) (xy 40.582854 -235.61158) (xy 40.574817 -235.663616)
			(xy 40.558931 -235.713815) (xy 40.535568 -235.761) (xy 40.505276 -235.804066) (xy 40.468764 -235.842004)
			(xy 40.42689 -235.873923) (xy 40.380634 -235.899076) (xy 40.331081 -235.916874) (xy 40.279391 -235.926898)
			(xy 40.226777 -235.928915) (xy 40.174472 -235.922877) (xy 40.123701 -235.908925) (xy 40.075656 -235.887386)
			(xy 40.031461 -235.858766) (xy 39.992153 -235.823735) (xy 39.958653 -235.783114) (xy 39.931747 -235.737855)
			(xy 39.912064 -235.68902) (xy 39.900067 -235.637752) (xy 39.896037 -235.585254) (xy 33.039304 -235.585254)
			(xy 33.0388 -235.61158) (xy 33.030763 -235.663616) (xy 33.014877 -235.713815) (xy 32.991514 -235.761)
			(xy 32.961222 -235.804066) (xy 32.92471 -235.842004) (xy 32.882836 -235.873923) (xy 32.83658 -235.899076)
			(xy 32.787027 -235.916874) (xy 32.735337 -235.926898) (xy 32.682723 -235.928915) (xy 32.630418 -235.922877)
			(xy 32.579647 -235.908925) (xy 32.531602 -235.887386) (xy 32.487407 -235.858766) (xy 32.448099 -235.823735)
			(xy 32.414599 -235.783114) (xy 32.387693 -235.737855) (xy 32.36801 -235.68902) (xy 32.356013 -235.637752)
			(xy 32.351983 -235.585254) (xy 25.495504 -235.585254) (xy 25.495 -235.61158) (xy 25.486963 -235.663616)
			(xy 25.471077 -235.713815) (xy 25.447714 -235.761) (xy 25.417422 -235.804066) (xy 25.38091 -235.842004)
			(xy 25.339036 -235.873923) (xy 25.29278 -235.899076) (xy 25.243227 -235.916874) (xy 25.191537 -235.926898)
			(xy 25.138923 -235.928915) (xy 25.086618 -235.922877) (xy 25.035847 -235.908925) (xy 24.987802 -235.887386)
			(xy 24.943607 -235.858766) (xy 24.904299 -235.823735) (xy 24.870799 -235.783114) (xy 24.843893 -235.737855)
			(xy 24.82421 -235.68902) (xy 24.812213 -235.637752) (xy 24.808183 -235.585254) (xy 17.95145 -235.585254)
			(xy 17.950946 -235.61158) (xy 17.942909 -235.663616) (xy 17.927023 -235.713815) (xy 17.90366 -235.761)
			(xy 17.873368 -235.804066) (xy 17.836856 -235.842004) (xy 17.794982 -235.873923) (xy 17.748726 -235.899076)
			(xy 17.699173 -235.916874) (xy 17.647483 -235.926898) (xy 17.594869 -235.928915) (xy 17.542564 -235.922877)
			(xy 17.491793 -235.908925) (xy 17.443748 -235.887386) (xy 17.399553 -235.858766) (xy 17.360245 -235.823735)
			(xy 17.326745 -235.783114) (xy 17.299839 -235.737855) (xy 17.280156 -235.68902) (xy 17.268159 -235.637752)
			(xy 17.264129 -235.585254) (xy 16.086074 -235.585254) (xy 16.086074 -236.435392) (xy 21.364197 -236.435392)
			(xy 21.368227 -236.382894) (xy 21.380224 -236.331626) (xy 21.399907 -236.282791) (xy 21.426813 -236.237532)
			(xy 21.460313 -236.196911) (xy 21.499621 -236.16188) (xy 21.543816 -236.13326) (xy 21.591861 -236.111721)
			(xy 21.642632 -236.097769) (xy 21.694937 -236.091731) (xy 21.747551 -236.093748) (xy 21.799241 -236.103772)
			(xy 21.848794 -236.12157) (xy 21.89505 -236.146723) (xy 21.936924 -236.178642) (xy 21.973436 -236.21658)
			(xy 22.003728 -236.259646) (xy 22.027091 -236.306831) (xy 22.042977 -236.35703) (xy 22.051014 -236.409066)
			(xy 22.051518 -236.435392) (xy 28.908251 -236.435392) (xy 28.912281 -236.382894) (xy 28.924278 -236.331626)
			(xy 28.943961 -236.282791) (xy 28.970867 -236.237532) (xy 29.004367 -236.196911) (xy 29.043675 -236.16188)
			(xy 29.08787 -236.13326) (xy 29.135915 -236.111721) (xy 29.186686 -236.097769) (xy 29.238991 -236.091731)
			(xy 29.291605 -236.093748) (xy 29.343295 -236.103772) (xy 29.392848 -236.12157) (xy 29.439104 -236.146723)
			(xy 29.480978 -236.178642) (xy 29.51749 -236.21658) (xy 29.547782 -236.259646) (xy 29.571145 -236.306831)
			(xy 29.587031 -236.35703) (xy 29.595068 -236.409066) (xy 29.595572 -236.435392) (xy 36.452051 -236.435392)
			(xy 36.456081 -236.382894) (xy 36.468078 -236.331626) (xy 36.487761 -236.282791) (xy 36.514667 -236.237532)
			(xy 36.548167 -236.196911) (xy 36.587475 -236.16188) (xy 36.63167 -236.13326) (xy 36.679715 -236.111721)
			(xy 36.730486 -236.097769) (xy 36.782791 -236.091731) (xy 36.835405 -236.093748) (xy 36.887095 -236.103772)
			(xy 36.936648 -236.12157) (xy 36.982904 -236.146723) (xy 37.024778 -236.178642) (xy 37.06129 -236.21658)
			(xy 37.091582 -236.259646) (xy 37.114945 -236.306831) (xy 37.130831 -236.35703) (xy 37.138868 -236.409066)
			(xy 37.139372 -236.435392) (xy 43.996105 -236.435392) (xy 44.000135 -236.382894) (xy 44.012132 -236.331626)
			(xy 44.031815 -236.282791) (xy 44.058721 -236.237532) (xy 44.092221 -236.196911) (xy 44.131529 -236.16188)
			(xy 44.175724 -236.13326) (xy 44.223769 -236.111721) (xy 44.27454 -236.097769) (xy 44.326845 -236.091731)
			(xy 44.379459 -236.093748) (xy 44.431149 -236.103772) (xy 44.480702 -236.12157) (xy 44.526958 -236.146723)
			(xy 44.568832 -236.178642) (xy 44.605344 -236.21658) (xy 44.635636 -236.259646) (xy 44.658999 -236.306831)
			(xy 44.674885 -236.35703) (xy 44.682922 -236.409066) (xy 44.683426 -236.435392) (xy 51.540159 -236.435392)
			(xy 51.544189 -236.382894) (xy 51.556186 -236.331626) (xy 51.575869 -236.282791) (xy 51.602775 -236.237532)
			(xy 51.636275 -236.196911) (xy 51.675583 -236.16188) (xy 51.719778 -236.13326) (xy 51.767823 -236.111721)
			(xy 51.818594 -236.097769) (xy 51.870899 -236.091731) (xy 51.923513 -236.093748) (xy 51.975203 -236.103772)
			(xy 52.024756 -236.12157) (xy 52.071012 -236.146723) (xy 52.112886 -236.178642) (xy 52.149398 -236.21658)
			(xy 52.17969 -236.259646) (xy 52.203053 -236.306831) (xy 52.218939 -236.35703) (xy 52.226976 -236.409066)
			(xy 52.22748 -236.435392) (xy 52.226976 -236.461718) (xy 52.218939 -236.513754) (xy 52.203053 -236.563953)
			(xy 52.17969 -236.611138) (xy 52.149398 -236.654204) (xy 52.112886 -236.692142) (xy 52.071012 -236.724061)
			(xy 52.024756 -236.749214) (xy 51.975203 -236.767012) (xy 51.923513 -236.777036) (xy 51.870899 -236.779053)
			(xy 51.818594 -236.773015) (xy 51.767823 -236.759063) (xy 51.719778 -236.737524) (xy 51.675583 -236.708904)
			(xy 51.636275 -236.673873) (xy 51.602775 -236.633252) (xy 51.575869 -236.587993) (xy 51.556186 -236.539158)
			(xy 51.544189 -236.48789) (xy 51.540159 -236.435392) (xy 44.683426 -236.435392) (xy 44.682922 -236.461718)
			(xy 44.674885 -236.513754) (xy 44.658999 -236.563953) (xy 44.635636 -236.611138) (xy 44.605344 -236.654204)
			(xy 44.568832 -236.692142) (xy 44.526958 -236.724061) (xy 44.480702 -236.749214) (xy 44.431149 -236.767012)
			(xy 44.379459 -236.777036) (xy 44.326845 -236.779053) (xy 44.27454 -236.773015) (xy 44.223769 -236.759063)
			(xy 44.175724 -236.737524) (xy 44.131529 -236.708904) (xy 44.092221 -236.673873) (xy 44.058721 -236.633252)
			(xy 44.031815 -236.587993) (xy 44.012132 -236.539158) (xy 44.000135 -236.48789) (xy 43.996105 -236.435392)
			(xy 37.139372 -236.435392) (xy 37.138868 -236.461718) (xy 37.130831 -236.513754) (xy 37.114945 -236.563953)
			(xy 37.091582 -236.611138) (xy 37.06129 -236.654204) (xy 37.024778 -236.692142) (xy 36.982904 -236.724061)
			(xy 36.936648 -236.749214) (xy 36.887095 -236.767012) (xy 36.835405 -236.777036) (xy 36.782791 -236.779053)
			(xy 36.730486 -236.773015) (xy 36.679715 -236.759063) (xy 36.63167 -236.737524) (xy 36.587475 -236.708904)
			(xy 36.548167 -236.673873) (xy 36.514667 -236.633252) (xy 36.487761 -236.587993) (xy 36.468078 -236.539158)
			(xy 36.456081 -236.48789) (xy 36.452051 -236.435392) (xy 29.595572 -236.435392) (xy 29.595068 -236.461718)
			(xy 29.587031 -236.513754) (xy 29.571145 -236.563953) (xy 29.547782 -236.611138) (xy 29.51749 -236.654204)
			(xy 29.480978 -236.692142) (xy 29.439104 -236.724061) (xy 29.392848 -236.749214) (xy 29.343295 -236.767012)
			(xy 29.291605 -236.777036) (xy 29.238991 -236.779053) (xy 29.186686 -236.773015) (xy 29.135915 -236.759063)
			(xy 29.08787 -236.737524) (xy 29.043675 -236.708904) (xy 29.004367 -236.673873) (xy 28.970867 -236.633252)
			(xy 28.943961 -236.587993) (xy 28.924278 -236.539158) (xy 28.912281 -236.48789) (xy 28.908251 -236.435392)
			(xy 22.051518 -236.435392) (xy 22.051014 -236.461718) (xy 22.042977 -236.513754) (xy 22.027091 -236.563953)
			(xy 22.003728 -236.611138) (xy 21.973436 -236.654204) (xy 21.936924 -236.692142) (xy 21.89505 -236.724061)
			(xy 21.848794 -236.749214) (xy 21.799241 -236.767012) (xy 21.747551 -236.777036) (xy 21.694937 -236.779053)
			(xy 21.642632 -236.773015) (xy 21.591861 -236.759063) (xy 21.543816 -236.737524) (xy 21.499621 -236.708904)
			(xy 21.460313 -236.673873) (xy 21.426813 -236.633252) (xy 21.399907 -236.587993) (xy 21.380224 -236.539158)
			(xy 21.368227 -236.48789) (xy 21.364197 -236.435392) (xy 16.086074 -236.435392) (xy 16.086074 -237.285276)
			(xy 17.264129 -237.285276) (xy 17.268159 -237.232778) (xy 17.280156 -237.18151) (xy 17.299839 -237.132675)
			(xy 17.326745 -237.087416) (xy 17.360245 -237.046795) (xy 17.399553 -237.011764) (xy 17.443748 -236.983144)
			(xy 17.491793 -236.961605) (xy 17.542564 -236.947653) (xy 17.594869 -236.941615) (xy 17.647483 -236.943632)
			(xy 17.699173 -236.953656) (xy 17.748726 -236.971454) (xy 17.794982 -236.996607) (xy 17.836856 -237.028526)
			(xy 17.873368 -237.066464) (xy 17.90366 -237.10953) (xy 17.927023 -237.156715) (xy 17.942909 -237.206914)
			(xy 17.950946 -237.25895) (xy 17.95145 -237.285276) (xy 24.808183 -237.285276) (xy 24.812213 -237.232778)
			(xy 24.82421 -237.18151) (xy 24.843893 -237.132675) (xy 24.870799 -237.087416) (xy 24.904299 -237.046795)
			(xy 24.943607 -237.011764) (xy 24.987802 -236.983144) (xy 25.035847 -236.961605) (xy 25.086618 -236.947653)
			(xy 25.138923 -236.941615) (xy 25.191537 -236.943632) (xy 25.243227 -236.953656) (xy 25.29278 -236.971454)
			(xy 25.339036 -236.996607) (xy 25.38091 -237.028526) (xy 25.417422 -237.066464) (xy 25.447714 -237.10953)
			(xy 25.471077 -237.156715) (xy 25.486963 -237.206914) (xy 25.495 -237.25895) (xy 25.495504 -237.285276)
			(xy 32.351983 -237.285276) (xy 32.356013 -237.232778) (xy 32.36801 -237.18151) (xy 32.387693 -237.132675)
			(xy 32.414599 -237.087416) (xy 32.448099 -237.046795) (xy 32.487407 -237.011764) (xy 32.531602 -236.983144)
			(xy 32.579647 -236.961605) (xy 32.630418 -236.947653) (xy 32.682723 -236.941615) (xy 32.735337 -236.943632)
			(xy 32.787027 -236.953656) (xy 32.83658 -236.971454) (xy 32.882836 -236.996607) (xy 32.92471 -237.028526)
			(xy 32.961222 -237.066464) (xy 32.991514 -237.10953) (xy 33.014877 -237.156715) (xy 33.030763 -237.206914)
			(xy 33.0388 -237.25895) (xy 33.039304 -237.285276) (xy 39.896037 -237.285276) (xy 39.900067 -237.232778)
			(xy 39.912064 -237.18151) (xy 39.931747 -237.132675) (xy 39.958653 -237.087416) (xy 39.992153 -237.046795)
			(xy 40.031461 -237.011764) (xy 40.075656 -236.983144) (xy 40.123701 -236.961605) (xy 40.174472 -236.947653)
			(xy 40.226777 -236.941615) (xy 40.279391 -236.943632) (xy 40.331081 -236.953656) (xy 40.380634 -236.971454)
			(xy 40.42689 -236.996607) (xy 40.468764 -237.028526) (xy 40.505276 -237.066464) (xy 40.535568 -237.10953)
			(xy 40.558931 -237.156715) (xy 40.574817 -237.206914) (xy 40.582854 -237.25895) (xy 40.583358 -237.285276)
			(xy 47.440091 -237.285276) (xy 47.444121 -237.232778) (xy 47.456118 -237.18151) (xy 47.475801 -237.132675)
			(xy 47.502707 -237.087416) (xy 47.536207 -237.046795) (xy 47.575515 -237.011764) (xy 47.61971 -236.983144)
			(xy 47.667755 -236.961605) (xy 47.718526 -236.947653) (xy 47.770831 -236.941615) (xy 47.823445 -236.943632)
			(xy 47.875135 -236.953656) (xy 47.924688 -236.971454) (xy 47.970944 -236.996607) (xy 48.012818 -237.028526)
			(xy 48.04933 -237.066464) (xy 48.079622 -237.10953) (xy 48.102985 -237.156715) (xy 48.118871 -237.206914)
			(xy 48.126908 -237.25895) (xy 48.127412 -237.285276) (xy 48.126908 -237.311602) (xy 48.118871 -237.363638)
			(xy 48.102985 -237.413837) (xy 48.079622 -237.461022) (xy 48.04933 -237.504088) (xy 48.012818 -237.542026)
			(xy 47.970944 -237.573945) (xy 47.924688 -237.599098) (xy 47.875135 -237.616896) (xy 47.823445 -237.62692)
			(xy 47.770831 -237.628937) (xy 47.718526 -237.622899) (xy 47.667755 -237.608947) (xy 47.61971 -237.587408)
			(xy 47.575515 -237.558788) (xy 47.536207 -237.523757) (xy 47.502707 -237.483136) (xy 47.475801 -237.437877)
			(xy 47.456118 -237.389042) (xy 47.444121 -237.337774) (xy 47.440091 -237.285276) (xy 40.583358 -237.285276)
			(xy 40.582854 -237.311602) (xy 40.574817 -237.363638) (xy 40.558931 -237.413837) (xy 40.535568 -237.461022)
			(xy 40.505276 -237.504088) (xy 40.468764 -237.542026) (xy 40.42689 -237.573945) (xy 40.380634 -237.599098)
			(xy 40.331081 -237.616896) (xy 40.279391 -237.62692) (xy 40.226777 -237.628937) (xy 40.174472 -237.622899)
			(xy 40.123701 -237.608947) (xy 40.075656 -237.587408) (xy 40.031461 -237.558788) (xy 39.992153 -237.523757)
			(xy 39.958653 -237.483136) (xy 39.931747 -237.437877) (xy 39.912064 -237.389042) (xy 39.900067 -237.337774)
			(xy 39.896037 -237.285276) (xy 33.039304 -237.285276) (xy 33.0388 -237.311602) (xy 33.030763 -237.363638)
			(xy 33.014877 -237.413837) (xy 32.991514 -237.461022) (xy 32.961222 -237.504088) (xy 32.92471 -237.542026)
			(xy 32.882836 -237.573945) (xy 32.83658 -237.599098) (xy 32.787027 -237.616896) (xy 32.735337 -237.62692)
			(xy 32.682723 -237.628937) (xy 32.630418 -237.622899) (xy 32.579647 -237.608947) (xy 32.531602 -237.587408)
			(xy 32.487407 -237.558788) (xy 32.448099 -237.523757) (xy 32.414599 -237.483136) (xy 32.387693 -237.437877)
			(xy 32.36801 -237.389042) (xy 32.356013 -237.337774) (xy 32.351983 -237.285276) (xy 25.495504 -237.285276)
			(xy 25.495 -237.311602) (xy 25.486963 -237.363638) (xy 25.471077 -237.413837) (xy 25.447714 -237.461022)
			(xy 25.417422 -237.504088) (xy 25.38091 -237.542026) (xy 25.339036 -237.573945) (xy 25.29278 -237.599098)
			(xy 25.243227 -237.616896) (xy 25.191537 -237.62692) (xy 25.138923 -237.628937) (xy 25.086618 -237.622899)
			(xy 25.035847 -237.608947) (xy 24.987802 -237.587408) (xy 24.943607 -237.558788) (xy 24.904299 -237.523757)
			(xy 24.870799 -237.483136) (xy 24.843893 -237.437877) (xy 24.82421 -237.389042) (xy 24.812213 -237.337774)
			(xy 24.808183 -237.285276) (xy 17.95145 -237.285276) (xy 17.950946 -237.311602) (xy 17.942909 -237.363638)
			(xy 17.927023 -237.413837) (xy 17.90366 -237.461022) (xy 17.873368 -237.504088) (xy 17.836856 -237.542026)
			(xy 17.794982 -237.573945) (xy 17.748726 -237.599098) (xy 17.699173 -237.616896) (xy 17.647483 -237.62692)
			(xy 17.594869 -237.628937) (xy 17.542564 -237.622899) (xy 17.491793 -237.608947) (xy 17.443748 -237.587408)
			(xy 17.399553 -237.558788) (xy 17.360245 -237.523757) (xy 17.326745 -237.483136) (xy 17.299839 -237.437877)
			(xy 17.280156 -237.389042) (xy 17.268159 -237.337774) (xy 17.264129 -237.285276) (xy 16.086074 -237.285276)
			(xy 16.086074 -238.135414) (xy 21.364197 -238.135414) (xy 21.368227 -238.082916) (xy 21.380224 -238.031648)
			(xy 21.399907 -237.982813) (xy 21.426813 -237.937554) (xy 21.460313 -237.896933) (xy 21.499621 -237.861902)
			(xy 21.543816 -237.833282) (xy 21.591861 -237.811743) (xy 21.642632 -237.797791) (xy 21.694937 -237.791753)
			(xy 21.747551 -237.79377) (xy 21.799241 -237.803794) (xy 21.848794 -237.821592) (xy 21.89505 -237.846745)
			(xy 21.936924 -237.878664) (xy 21.973436 -237.916602) (xy 22.003728 -237.959668) (xy 22.027091 -238.006853)
			(xy 22.042977 -238.057052) (xy 22.051014 -238.109088) (xy 22.051518 -238.135414) (xy 28.908251 -238.135414)
			(xy 28.912281 -238.082916) (xy 28.924278 -238.031648) (xy 28.943961 -237.982813) (xy 28.970867 -237.937554)
			(xy 29.004367 -237.896933) (xy 29.043675 -237.861902) (xy 29.08787 -237.833282) (xy 29.135915 -237.811743)
			(xy 29.186686 -237.797791) (xy 29.238991 -237.791753) (xy 29.291605 -237.79377) (xy 29.343295 -237.803794)
			(xy 29.392848 -237.821592) (xy 29.439104 -237.846745) (xy 29.480978 -237.878664) (xy 29.51749 -237.916602)
			(xy 29.547782 -237.959668) (xy 29.571145 -238.006853) (xy 29.587031 -238.057052) (xy 29.595068 -238.109088)
			(xy 29.595572 -238.135414) (xy 36.452051 -238.135414) (xy 36.456081 -238.082916) (xy 36.468078 -238.031648)
			(xy 36.487761 -237.982813) (xy 36.514667 -237.937554) (xy 36.548167 -237.896933) (xy 36.587475 -237.861902)
			(xy 36.63167 -237.833282) (xy 36.679715 -237.811743) (xy 36.730486 -237.797791) (xy 36.782791 -237.791753)
			(xy 36.835405 -237.79377) (xy 36.887095 -237.803794) (xy 36.936648 -237.821592) (xy 36.982904 -237.846745)
			(xy 37.024778 -237.878664) (xy 37.06129 -237.916602) (xy 37.091582 -237.959668) (xy 37.114945 -238.006853)
			(xy 37.130831 -238.057052) (xy 37.138868 -238.109088) (xy 37.139372 -238.135414) (xy 43.996105 -238.135414)
			(xy 44.000135 -238.082916) (xy 44.012132 -238.031648) (xy 44.031815 -237.982813) (xy 44.058721 -237.937554)
			(xy 44.092221 -237.896933) (xy 44.131529 -237.861902) (xy 44.175724 -237.833282) (xy 44.223769 -237.811743)
			(xy 44.27454 -237.797791) (xy 44.326845 -237.791753) (xy 44.379459 -237.79377) (xy 44.431149 -237.803794)
			(xy 44.480702 -237.821592) (xy 44.526958 -237.846745) (xy 44.568832 -237.878664) (xy 44.605344 -237.916602)
			(xy 44.635636 -237.959668) (xy 44.658999 -238.006853) (xy 44.674885 -238.057052) (xy 44.682922 -238.109088)
			(xy 44.683426 -238.135414) (xy 51.540159 -238.135414) (xy 51.544189 -238.082916) (xy 51.556186 -238.031648)
			(xy 51.575869 -237.982813) (xy 51.602775 -237.937554) (xy 51.636275 -237.896933) (xy 51.675583 -237.861902)
			(xy 51.719778 -237.833282) (xy 51.767823 -237.811743) (xy 51.818594 -237.797791) (xy 51.870899 -237.791753)
			(xy 51.923513 -237.79377) (xy 51.975203 -237.803794) (xy 52.024756 -237.821592) (xy 52.071012 -237.846745)
			(xy 52.112886 -237.878664) (xy 52.149398 -237.916602) (xy 52.17969 -237.959668) (xy 52.203053 -238.006853)
			(xy 52.218939 -238.057052) (xy 52.226976 -238.109088) (xy 52.22748 -238.135414) (xy 52.226976 -238.16174)
			(xy 52.218939 -238.213776) (xy 52.203053 -238.263975) (xy 52.17969 -238.31116) (xy 52.149398 -238.354226)
			(xy 52.112886 -238.392164) (xy 52.071012 -238.424083) (xy 52.024756 -238.449236) (xy 51.975203 -238.467034)
			(xy 51.923513 -238.477058) (xy 51.870899 -238.479075) (xy 51.818594 -238.473037) (xy 51.767823 -238.459085)
			(xy 51.719778 -238.437546) (xy 51.675583 -238.408926) (xy 51.636275 -238.373895) (xy 51.602775 -238.333274)
			(xy 51.575869 -238.288015) (xy 51.556186 -238.23918) (xy 51.544189 -238.187912) (xy 51.540159 -238.135414)
			(xy 44.683426 -238.135414) (xy 44.682922 -238.16174) (xy 44.674885 -238.213776) (xy 44.658999 -238.263975)
			(xy 44.635636 -238.31116) (xy 44.605344 -238.354226) (xy 44.568832 -238.392164) (xy 44.526958 -238.424083)
			(xy 44.480702 -238.449236) (xy 44.431149 -238.467034) (xy 44.379459 -238.477058) (xy 44.326845 -238.479075)
			(xy 44.27454 -238.473037) (xy 44.223769 -238.459085) (xy 44.175724 -238.437546) (xy 44.131529 -238.408926)
			(xy 44.092221 -238.373895) (xy 44.058721 -238.333274) (xy 44.031815 -238.288015) (xy 44.012132 -238.23918)
			(xy 44.000135 -238.187912) (xy 43.996105 -238.135414) (xy 37.139372 -238.135414) (xy 37.138868 -238.16174)
			(xy 37.130831 -238.213776) (xy 37.114945 -238.263975) (xy 37.091582 -238.31116) (xy 37.06129 -238.354226)
			(xy 37.024778 -238.392164) (xy 36.982904 -238.424083) (xy 36.936648 -238.449236) (xy 36.887095 -238.467034)
			(xy 36.835405 -238.477058) (xy 36.782791 -238.479075) (xy 36.730486 -238.473037) (xy 36.679715 -238.459085)
			(xy 36.63167 -238.437546) (xy 36.587475 -238.408926) (xy 36.548167 -238.373895) (xy 36.514667 -238.333274)
			(xy 36.487761 -238.288015) (xy 36.468078 -238.23918) (xy 36.456081 -238.187912) (xy 36.452051 -238.135414)
			(xy 29.595572 -238.135414) (xy 29.595068 -238.16174) (xy 29.587031 -238.213776) (xy 29.571145 -238.263975)
			(xy 29.547782 -238.31116) (xy 29.51749 -238.354226) (xy 29.480978 -238.392164) (xy 29.439104 -238.424083)
			(xy 29.392848 -238.449236) (xy 29.343295 -238.467034) (xy 29.291605 -238.477058) (xy 29.238991 -238.479075)
			(xy 29.186686 -238.473037) (xy 29.135915 -238.459085) (xy 29.08787 -238.437546) (xy 29.043675 -238.408926)
			(xy 29.004367 -238.373895) (xy 28.970867 -238.333274) (xy 28.943961 -238.288015) (xy 28.924278 -238.23918)
			(xy 28.912281 -238.187912) (xy 28.908251 -238.135414) (xy 22.051518 -238.135414) (xy 22.051014 -238.16174)
			(xy 22.042977 -238.213776) (xy 22.027091 -238.263975) (xy 22.003728 -238.31116) (xy 21.973436 -238.354226)
			(xy 21.936924 -238.392164) (xy 21.89505 -238.424083) (xy 21.848794 -238.449236) (xy 21.799241 -238.467034)
			(xy 21.747551 -238.477058) (xy 21.694937 -238.479075) (xy 21.642632 -238.473037) (xy 21.591861 -238.459085)
			(xy 21.543816 -238.437546) (xy 21.499621 -238.408926) (xy 21.460313 -238.373895) (xy 21.426813 -238.333274)
			(xy 21.399907 -238.288015) (xy 21.380224 -238.23918) (xy 21.368227 -238.187912) (xy 21.364197 -238.135414)
			(xy 16.086074 -238.135414) (xy 16.086074 -238.985298) (xy 17.264129 -238.985298) (xy 17.268159 -238.9328)
			(xy 17.280156 -238.881532) (xy 17.299839 -238.832697) (xy 17.326745 -238.787438) (xy 17.360245 -238.746817)
			(xy 17.399553 -238.711786) (xy 17.443748 -238.683166) (xy 17.491793 -238.661627) (xy 17.542564 -238.647675)
			(xy 17.594869 -238.641637) (xy 17.647483 -238.643654) (xy 17.699173 -238.653678) (xy 17.748726 -238.671476)
			(xy 17.794982 -238.696629) (xy 17.836856 -238.728548) (xy 17.873368 -238.766486) (xy 17.90366 -238.809552)
			(xy 17.927023 -238.856737) (xy 17.942909 -238.906936) (xy 17.950946 -238.958972) (xy 17.95145 -238.985298)
			(xy 21.364197 -238.985298) (xy 21.368227 -238.9328) (xy 21.380224 -238.881532) (xy 21.399907 -238.832697)
			(xy 21.426813 -238.787438) (xy 21.460313 -238.746817) (xy 21.499621 -238.711786) (xy 21.543816 -238.683166)
			(xy 21.591861 -238.661627) (xy 21.642632 -238.647675) (xy 21.694937 -238.641637) (xy 21.747551 -238.643654)
			(xy 21.799241 -238.653678) (xy 21.848794 -238.671476) (xy 21.89505 -238.696629) (xy 21.936924 -238.728548)
			(xy 21.973436 -238.766486) (xy 22.003728 -238.809552) (xy 22.027091 -238.856737) (xy 22.042977 -238.906936)
			(xy 22.051014 -238.958972) (xy 22.051518 -238.985298) (xy 24.808183 -238.985298) (xy 24.812213 -238.9328)
			(xy 24.82421 -238.881532) (xy 24.843893 -238.832697) (xy 24.870799 -238.787438) (xy 24.904299 -238.746817)
			(xy 24.943607 -238.711786) (xy 24.987802 -238.683166) (xy 25.035847 -238.661627) (xy 25.086618 -238.647675)
			(xy 25.138923 -238.641637) (xy 25.191537 -238.643654) (xy 25.243227 -238.653678) (xy 25.29278 -238.671476)
			(xy 25.339036 -238.696629) (xy 25.38091 -238.728548) (xy 25.417422 -238.766486) (xy 25.447714 -238.809552)
			(xy 25.471077 -238.856737) (xy 25.486963 -238.906936) (xy 25.495 -238.958972) (xy 25.495504 -238.985298)
			(xy 28.908251 -238.985298) (xy 28.912281 -238.9328) (xy 28.924278 -238.881532) (xy 28.943961 -238.832697)
			(xy 28.970867 -238.787438) (xy 29.004367 -238.746817) (xy 29.043675 -238.711786) (xy 29.08787 -238.683166)
			(xy 29.135915 -238.661627) (xy 29.186686 -238.647675) (xy 29.238991 -238.641637) (xy 29.291605 -238.643654)
			(xy 29.343295 -238.653678) (xy 29.392848 -238.671476) (xy 29.439104 -238.696629) (xy 29.480978 -238.728548)
			(xy 29.51749 -238.766486) (xy 29.547782 -238.809552) (xy 29.571145 -238.856737) (xy 29.587031 -238.906936)
			(xy 29.595068 -238.958972) (xy 29.595572 -238.985298) (xy 32.351983 -238.985298) (xy 32.356013 -238.9328)
			(xy 32.36801 -238.881532) (xy 32.387693 -238.832697) (xy 32.414599 -238.787438) (xy 32.448099 -238.746817)
			(xy 32.487407 -238.711786) (xy 32.531602 -238.683166) (xy 32.579647 -238.661627) (xy 32.630418 -238.647675)
			(xy 32.682723 -238.641637) (xy 32.735337 -238.643654) (xy 32.787027 -238.653678) (xy 32.83658 -238.671476)
			(xy 32.882836 -238.696629) (xy 32.92471 -238.728548) (xy 32.961222 -238.766486) (xy 32.991514 -238.809552)
			(xy 33.014877 -238.856737) (xy 33.030763 -238.906936) (xy 33.0388 -238.958972) (xy 33.039304 -238.985298)
			(xy 36.452051 -238.985298) (xy 36.456081 -238.9328) (xy 36.468078 -238.881532) (xy 36.487761 -238.832697)
			(xy 36.514667 -238.787438) (xy 36.548167 -238.746817) (xy 36.587475 -238.711786) (xy 36.63167 -238.683166)
			(xy 36.679715 -238.661627) (xy 36.730486 -238.647675) (xy 36.782791 -238.641637) (xy 36.835405 -238.643654)
			(xy 36.887095 -238.653678) (xy 36.936648 -238.671476) (xy 36.982904 -238.696629) (xy 37.024778 -238.728548)
			(xy 37.06129 -238.766486) (xy 37.091582 -238.809552) (xy 37.114945 -238.856737) (xy 37.130831 -238.906936)
			(xy 37.138868 -238.958972) (xy 37.139372 -238.985298) (xy 39.896037 -238.985298) (xy 39.900067 -238.9328)
			(xy 39.912064 -238.881532) (xy 39.931747 -238.832697) (xy 39.958653 -238.787438) (xy 39.992153 -238.746817)
			(xy 40.031461 -238.711786) (xy 40.075656 -238.683166) (xy 40.123701 -238.661627) (xy 40.174472 -238.647675)
			(xy 40.226777 -238.641637) (xy 40.279391 -238.643654) (xy 40.331081 -238.653678) (xy 40.380634 -238.671476)
			(xy 40.42689 -238.696629) (xy 40.468764 -238.728548) (xy 40.505276 -238.766486) (xy 40.535568 -238.809552)
			(xy 40.558931 -238.856737) (xy 40.574817 -238.906936) (xy 40.582854 -238.958972) (xy 40.583358 -238.985298)
			(xy 43.996105 -238.985298) (xy 44.000135 -238.9328) (xy 44.012132 -238.881532) (xy 44.031815 -238.832697)
			(xy 44.058721 -238.787438) (xy 44.092221 -238.746817) (xy 44.131529 -238.711786) (xy 44.175724 -238.683166)
			(xy 44.223769 -238.661627) (xy 44.27454 -238.647675) (xy 44.326845 -238.641637) (xy 44.379459 -238.643654)
			(xy 44.431149 -238.653678) (xy 44.480702 -238.671476) (xy 44.526958 -238.696629) (xy 44.568832 -238.728548)
			(xy 44.605344 -238.766486) (xy 44.635636 -238.809552) (xy 44.658999 -238.856737) (xy 44.674885 -238.906936)
			(xy 44.682922 -238.958972) (xy 44.683426 -238.985298) (xy 47.440091 -238.985298) (xy 47.444121 -238.9328)
			(xy 47.456118 -238.881532) (xy 47.475801 -238.832697) (xy 47.502707 -238.787438) (xy 47.536207 -238.746817)
			(xy 47.575515 -238.711786) (xy 47.61971 -238.683166) (xy 47.667755 -238.661627) (xy 47.718526 -238.647675)
			(xy 47.770831 -238.641637) (xy 47.823445 -238.643654) (xy 47.875135 -238.653678) (xy 47.924688 -238.671476)
			(xy 47.970944 -238.696629) (xy 48.012818 -238.728548) (xy 48.04933 -238.766486) (xy 48.079622 -238.809552)
			(xy 48.102985 -238.856737) (xy 48.118871 -238.906936) (xy 48.126908 -238.958972) (xy 48.127412 -238.985298)
			(xy 51.540159 -238.985298) (xy 51.544189 -238.9328) (xy 51.556186 -238.881532) (xy 51.575869 -238.832697)
			(xy 51.602775 -238.787438) (xy 51.636275 -238.746817) (xy 51.675583 -238.711786) (xy 51.719778 -238.683166)
			(xy 51.767823 -238.661627) (xy 51.818594 -238.647675) (xy 51.870899 -238.641637) (xy 51.923513 -238.643654)
			(xy 51.975203 -238.653678) (xy 52.024756 -238.671476) (xy 52.071012 -238.696629) (xy 52.112886 -238.728548)
			(xy 52.149398 -238.766486) (xy 52.17969 -238.809552) (xy 52.203053 -238.856737) (xy 52.218939 -238.906936)
			(xy 52.226976 -238.958972) (xy 52.22748 -238.985298) (xy 52.226976 -239.011624) (xy 52.218939 -239.06366)
			(xy 52.203053 -239.113859) (xy 52.17969 -239.161044) (xy 52.149398 -239.20411) (xy 52.112886 -239.242048)
			(xy 52.071012 -239.273967) (xy 52.024756 -239.29912) (xy 51.975203 -239.316918) (xy 51.923513 -239.326942)
			(xy 51.870899 -239.328959) (xy 51.818594 -239.322921) (xy 51.767823 -239.308969) (xy 51.719778 -239.28743)
			(xy 51.675583 -239.25881) (xy 51.636275 -239.223779) (xy 51.602775 -239.183158) (xy 51.575869 -239.137899)
			(xy 51.556186 -239.089064) (xy 51.544189 -239.037796) (xy 51.540159 -238.985298) (xy 48.127412 -238.985298)
			(xy 48.126908 -239.011624) (xy 48.118871 -239.06366) (xy 48.102985 -239.113859) (xy 48.079622 -239.161044)
			(xy 48.04933 -239.20411) (xy 48.012818 -239.242048) (xy 47.970944 -239.273967) (xy 47.924688 -239.29912)
			(xy 47.875135 -239.316918) (xy 47.823445 -239.326942) (xy 47.770831 -239.328959) (xy 47.718526 -239.322921)
			(xy 47.667755 -239.308969) (xy 47.61971 -239.28743) (xy 47.575515 -239.25881) (xy 47.536207 -239.223779)
			(xy 47.502707 -239.183158) (xy 47.475801 -239.137899) (xy 47.456118 -239.089064) (xy 47.444121 -239.037796)
			(xy 47.440091 -238.985298) (xy 44.683426 -238.985298) (xy 44.682922 -239.011624) (xy 44.674885 -239.06366)
			(xy 44.658999 -239.113859) (xy 44.635636 -239.161044) (xy 44.605344 -239.20411) (xy 44.568832 -239.242048)
			(xy 44.526958 -239.273967) (xy 44.480702 -239.29912) (xy 44.431149 -239.316918) (xy 44.379459 -239.326942)
			(xy 44.326845 -239.328959) (xy 44.27454 -239.322921) (xy 44.223769 -239.308969) (xy 44.175724 -239.28743)
			(xy 44.131529 -239.25881) (xy 44.092221 -239.223779) (xy 44.058721 -239.183158) (xy 44.031815 -239.137899)
			(xy 44.012132 -239.089064) (xy 44.000135 -239.037796) (xy 43.996105 -238.985298) (xy 40.583358 -238.985298)
			(xy 40.582854 -239.011624) (xy 40.574817 -239.06366) (xy 40.558931 -239.113859) (xy 40.535568 -239.161044)
			(xy 40.505276 -239.20411) (xy 40.468764 -239.242048) (xy 40.42689 -239.273967) (xy 40.380634 -239.29912)
			(xy 40.331081 -239.316918) (xy 40.279391 -239.326942) (xy 40.226777 -239.328959) (xy 40.174472 -239.322921)
			(xy 40.123701 -239.308969) (xy 40.075656 -239.28743) (xy 40.031461 -239.25881) (xy 39.992153 -239.223779)
			(xy 39.958653 -239.183158) (xy 39.931747 -239.137899) (xy 39.912064 -239.089064) (xy 39.900067 -239.037796)
			(xy 39.896037 -238.985298) (xy 37.139372 -238.985298) (xy 37.138868 -239.011624) (xy 37.130831 -239.06366)
			(xy 37.114945 -239.113859) (xy 37.091582 -239.161044) (xy 37.06129 -239.20411) (xy 37.024778 -239.242048)
			(xy 36.982904 -239.273967) (xy 36.936648 -239.29912) (xy 36.887095 -239.316918) (xy 36.835405 -239.326942)
			(xy 36.782791 -239.328959) (xy 36.730486 -239.322921) (xy 36.679715 -239.308969) (xy 36.63167 -239.28743)
			(xy 36.587475 -239.25881) (xy 36.548167 -239.223779) (xy 36.514667 -239.183158) (xy 36.487761 -239.137899)
			(xy 36.468078 -239.089064) (xy 36.456081 -239.037796) (xy 36.452051 -238.985298) (xy 33.039304 -238.985298)
			(xy 33.0388 -239.011624) (xy 33.030763 -239.06366) (xy 33.014877 -239.113859) (xy 32.991514 -239.161044)
			(xy 32.961222 -239.20411) (xy 32.92471 -239.242048) (xy 32.882836 -239.273967) (xy 32.83658 -239.29912)
			(xy 32.787027 -239.316918) (xy 32.735337 -239.326942) (xy 32.682723 -239.328959) (xy 32.630418 -239.322921)
			(xy 32.579647 -239.308969) (xy 32.531602 -239.28743) (xy 32.487407 -239.25881) (xy 32.448099 -239.223779)
			(xy 32.414599 -239.183158) (xy 32.387693 -239.137899) (xy 32.36801 -239.089064) (xy 32.356013 -239.037796)
			(xy 32.351983 -238.985298) (xy 29.595572 -238.985298) (xy 29.595068 -239.011624) (xy 29.587031 -239.06366)
			(xy 29.571145 -239.113859) (xy 29.547782 -239.161044) (xy 29.51749 -239.20411) (xy 29.480978 -239.242048)
			(xy 29.439104 -239.273967) (xy 29.392848 -239.29912) (xy 29.343295 -239.316918) (xy 29.291605 -239.326942)
			(xy 29.238991 -239.328959) (xy 29.186686 -239.322921) (xy 29.135915 -239.308969) (xy 29.08787 -239.28743)
			(xy 29.043675 -239.25881) (xy 29.004367 -239.223779) (xy 28.970867 -239.183158) (xy 28.943961 -239.137899)
			(xy 28.924278 -239.089064) (xy 28.912281 -239.037796) (xy 28.908251 -238.985298) (xy 25.495504 -238.985298)
			(xy 25.495 -239.011624) (xy 25.486963 -239.06366) (xy 25.471077 -239.113859) (xy 25.447714 -239.161044)
			(xy 25.417422 -239.20411) (xy 25.38091 -239.242048) (xy 25.339036 -239.273967) (xy 25.29278 -239.29912)
			(xy 25.243227 -239.316918) (xy 25.191537 -239.326942) (xy 25.138923 -239.328959) (xy 25.086618 -239.322921)
			(xy 25.035847 -239.308969) (xy 24.987802 -239.28743) (xy 24.943607 -239.25881) (xy 24.904299 -239.223779)
			(xy 24.870799 -239.183158) (xy 24.843893 -239.137899) (xy 24.82421 -239.089064) (xy 24.812213 -239.037796)
			(xy 24.808183 -238.985298) (xy 22.051518 -238.985298) (xy 22.051014 -239.011624) (xy 22.042977 -239.06366)
			(xy 22.027091 -239.113859) (xy 22.003728 -239.161044) (xy 21.973436 -239.20411) (xy 21.936924 -239.242048)
			(xy 21.89505 -239.273967) (xy 21.848794 -239.29912) (xy 21.799241 -239.316918) (xy 21.747551 -239.326942)
			(xy 21.694937 -239.328959) (xy 21.642632 -239.322921) (xy 21.591861 -239.308969) (xy 21.543816 -239.28743)
			(xy 21.499621 -239.25881) (xy 21.460313 -239.223779) (xy 21.426813 -239.183158) (xy 21.399907 -239.137899)
			(xy 21.380224 -239.089064) (xy 21.368227 -239.037796) (xy 21.364197 -238.985298) (xy 17.95145 -238.985298)
			(xy 17.950946 -239.011624) (xy 17.942909 -239.06366) (xy 17.927023 -239.113859) (xy 17.90366 -239.161044)
			(xy 17.873368 -239.20411) (xy 17.836856 -239.242048) (xy 17.794982 -239.273967) (xy 17.748726 -239.29912)
			(xy 17.699173 -239.316918) (xy 17.647483 -239.326942) (xy 17.594869 -239.328959) (xy 17.542564 -239.322921)
			(xy 17.491793 -239.308969) (xy 17.443748 -239.28743) (xy 17.399553 -239.25881) (xy 17.360245 -239.223779)
			(xy 17.326745 -239.183158) (xy 17.299839 -239.137899) (xy 17.280156 -239.089064) (xy 17.268159 -239.037796)
			(xy 17.264129 -238.985298) (xy 16.086074 -238.985298) (xy 16.086074 -239.835436) (xy 17.264129 -239.835436)
			(xy 17.268159 -239.782938) (xy 17.280156 -239.73167) (xy 17.299839 -239.682835) (xy 17.326745 -239.637576)
			(xy 17.360245 -239.596955) (xy 17.399553 -239.561924) (xy 17.443748 -239.533304) (xy 17.491793 -239.511765)
			(xy 17.542564 -239.497813) (xy 17.594869 -239.491775) (xy 17.647483 -239.493792) (xy 17.699173 -239.503816)
			(xy 17.748726 -239.521614) (xy 17.794982 -239.546767) (xy 17.836856 -239.578686) (xy 17.873368 -239.616624)
			(xy 17.90366 -239.65969) (xy 17.927023 -239.706875) (xy 17.942909 -239.757074) (xy 17.950946 -239.80911)
			(xy 17.95145 -239.835436) (xy 24.808183 -239.835436) (xy 24.812213 -239.782938) (xy 24.82421 -239.73167)
			(xy 24.843893 -239.682835) (xy 24.870799 -239.637576) (xy 24.904299 -239.596955) (xy 24.943607 -239.561924)
			(xy 24.987802 -239.533304) (xy 25.035847 -239.511765) (xy 25.086618 -239.497813) (xy 25.138923 -239.491775)
			(xy 25.191537 -239.493792) (xy 25.243227 -239.503816) (xy 25.29278 -239.521614) (xy 25.339036 -239.546767)
			(xy 25.38091 -239.578686) (xy 25.417422 -239.616624) (xy 25.447714 -239.65969) (xy 25.471077 -239.706875)
			(xy 25.486963 -239.757074) (xy 25.495 -239.80911) (xy 25.495504 -239.835436) (xy 32.351983 -239.835436)
			(xy 32.356013 -239.782938) (xy 32.36801 -239.73167) (xy 32.387693 -239.682835) (xy 32.414599 -239.637576)
			(xy 32.448099 -239.596955) (xy 32.487407 -239.561924) (xy 32.531602 -239.533304) (xy 32.579647 -239.511765)
			(xy 32.630418 -239.497813) (xy 32.682723 -239.491775) (xy 32.735337 -239.493792) (xy 32.787027 -239.503816)
			(xy 32.83658 -239.521614) (xy 32.882836 -239.546767) (xy 32.92471 -239.578686) (xy 32.961222 -239.616624)
			(xy 32.991514 -239.65969) (xy 33.014877 -239.706875) (xy 33.030763 -239.757074) (xy 33.0388 -239.80911)
			(xy 33.039304 -239.835436) (xy 39.896037 -239.835436) (xy 39.900067 -239.782938) (xy 39.912064 -239.73167)
			(xy 39.931747 -239.682835) (xy 39.958653 -239.637576) (xy 39.992153 -239.596955) (xy 40.031461 -239.561924)
			(xy 40.075656 -239.533304) (xy 40.123701 -239.511765) (xy 40.174472 -239.497813) (xy 40.226777 -239.491775)
			(xy 40.279391 -239.493792) (xy 40.331081 -239.503816) (xy 40.380634 -239.521614) (xy 40.42689 -239.546767)
			(xy 40.468764 -239.578686) (xy 40.505276 -239.616624) (xy 40.535568 -239.65969) (xy 40.558931 -239.706875)
			(xy 40.574817 -239.757074) (xy 40.582854 -239.80911) (xy 40.583358 -239.835436) (xy 47.440091 -239.835436)
			(xy 47.444121 -239.782938) (xy 47.456118 -239.73167) (xy 47.475801 -239.682835) (xy 47.502707 -239.637576)
			(xy 47.536207 -239.596955) (xy 47.575515 -239.561924) (xy 47.61971 -239.533304) (xy 47.667755 -239.511765)
			(xy 47.718526 -239.497813) (xy 47.770831 -239.491775) (xy 47.823445 -239.493792) (xy 47.875135 -239.503816)
			(xy 47.924688 -239.521614) (xy 47.970944 -239.546767) (xy 48.012818 -239.578686) (xy 48.04933 -239.616624)
			(xy 48.079622 -239.65969) (xy 48.102985 -239.706875) (xy 48.118871 -239.757074) (xy 48.126908 -239.80911)
			(xy 48.127412 -239.835436) (xy 48.126908 -239.861762) (xy 48.118871 -239.913798) (xy 48.102985 -239.963997)
			(xy 48.079622 -240.011182) (xy 48.04933 -240.054248) (xy 48.012818 -240.092186) (xy 47.970944 -240.124105)
			(xy 47.924688 -240.149258) (xy 47.875135 -240.167056) (xy 47.823445 -240.17708) (xy 47.770831 -240.179097)
			(xy 47.718526 -240.173059) (xy 47.667755 -240.159107) (xy 47.61971 -240.137568) (xy 47.575515 -240.108948)
			(xy 47.536207 -240.073917) (xy 47.502707 -240.033296) (xy 47.475801 -239.988037) (xy 47.456118 -239.939202)
			(xy 47.444121 -239.887934) (xy 47.440091 -239.835436) (xy 40.583358 -239.835436) (xy 40.582854 -239.861762)
			(xy 40.574817 -239.913798) (xy 40.558931 -239.963997) (xy 40.535568 -240.011182) (xy 40.505276 -240.054248)
			(xy 40.468764 -240.092186) (xy 40.42689 -240.124105) (xy 40.380634 -240.149258) (xy 40.331081 -240.167056)
			(xy 40.279391 -240.17708) (xy 40.226777 -240.179097) (xy 40.174472 -240.173059) (xy 40.123701 -240.159107)
			(xy 40.075656 -240.137568) (xy 40.031461 -240.108948) (xy 39.992153 -240.073917) (xy 39.958653 -240.033296)
			(xy 39.931747 -239.988037) (xy 39.912064 -239.939202) (xy 39.900067 -239.887934) (xy 39.896037 -239.835436)
			(xy 33.039304 -239.835436) (xy 33.0388 -239.861762) (xy 33.030763 -239.913798) (xy 33.014877 -239.963997)
			(xy 32.991514 -240.011182) (xy 32.961222 -240.054248) (xy 32.92471 -240.092186) (xy 32.882836 -240.124105)
			(xy 32.83658 -240.149258) (xy 32.787027 -240.167056) (xy 32.735337 -240.17708) (xy 32.682723 -240.179097)
			(xy 32.630418 -240.173059) (xy 32.579647 -240.159107) (xy 32.531602 -240.137568) (xy 32.487407 -240.108948)
			(xy 32.448099 -240.073917) (xy 32.414599 -240.033296) (xy 32.387693 -239.988037) (xy 32.36801 -239.939202)
			(xy 32.356013 -239.887934) (xy 32.351983 -239.835436) (xy 25.495504 -239.835436) (xy 25.495 -239.861762)
			(xy 25.486963 -239.913798) (xy 25.471077 -239.963997) (xy 25.447714 -240.011182) (xy 25.417422 -240.054248)
			(xy 25.38091 -240.092186) (xy 25.339036 -240.124105) (xy 25.29278 -240.149258) (xy 25.243227 -240.167056)
			(xy 25.191537 -240.17708) (xy 25.138923 -240.179097) (xy 25.086618 -240.173059) (xy 25.035847 -240.159107)
			(xy 24.987802 -240.137568) (xy 24.943607 -240.108948) (xy 24.904299 -240.073917) (xy 24.870799 -240.033296)
			(xy 24.843893 -239.988037) (xy 24.82421 -239.939202) (xy 24.812213 -239.887934) (xy 24.808183 -239.835436)
			(xy 17.95145 -239.835436) (xy 17.950946 -239.861762) (xy 17.942909 -239.913798) (xy 17.927023 -239.963997)
			(xy 17.90366 -240.011182) (xy 17.873368 -240.054248) (xy 17.836856 -240.092186) (xy 17.794982 -240.124105)
			(xy 17.748726 -240.149258) (xy 17.699173 -240.167056) (xy 17.647483 -240.17708) (xy 17.594869 -240.179097)
			(xy 17.542564 -240.173059) (xy 17.491793 -240.159107) (xy 17.443748 -240.137568) (xy 17.399553 -240.108948)
			(xy 17.360245 -240.073917) (xy 17.326745 -240.033296) (xy 17.299839 -239.988037) (xy 17.280156 -239.939202)
			(xy 17.268159 -239.887934) (xy 17.264129 -239.835436) (xy 16.086074 -239.835436) (xy 16.086074 -240.68532)
			(xy 21.364197 -240.68532) (xy 21.368227 -240.632822) (xy 21.380224 -240.581554) (xy 21.399907 -240.532719)
			(xy 21.426813 -240.48746) (xy 21.460313 -240.446839) (xy 21.499621 -240.411808) (xy 21.543816 -240.383188)
			(xy 21.591861 -240.361649) (xy 21.642632 -240.347697) (xy 21.694937 -240.341659) (xy 21.747551 -240.343676)
			(xy 21.799241 -240.3537) (xy 21.848794 -240.371498) (xy 21.89505 -240.396651) (xy 21.936924 -240.42857)
			(xy 21.973436 -240.466508) (xy 22.003728 -240.509574) (xy 22.027091 -240.556759) (xy 22.042977 -240.606958)
			(xy 22.051014 -240.658994) (xy 22.051518 -240.68532) (xy 28.908251 -240.68532) (xy 28.912281 -240.632822)
			(xy 28.924278 -240.581554) (xy 28.943961 -240.532719) (xy 28.970867 -240.48746) (xy 29.004367 -240.446839)
			(xy 29.043675 -240.411808) (xy 29.08787 -240.383188) (xy 29.135915 -240.361649) (xy 29.186686 -240.347697)
			(xy 29.238991 -240.341659) (xy 29.291605 -240.343676) (xy 29.343295 -240.3537) (xy 29.392848 -240.371498)
			(xy 29.439104 -240.396651) (xy 29.480978 -240.42857) (xy 29.51749 -240.466508) (xy 29.547782 -240.509574)
			(xy 29.571145 -240.556759) (xy 29.587031 -240.606958) (xy 29.595068 -240.658994) (xy 29.595572 -240.68532)
			(xy 36.452051 -240.68532) (xy 36.456081 -240.632822) (xy 36.468078 -240.581554) (xy 36.487761 -240.532719)
			(xy 36.514667 -240.48746) (xy 36.548167 -240.446839) (xy 36.587475 -240.411808) (xy 36.63167 -240.383188)
			(xy 36.679715 -240.361649) (xy 36.730486 -240.347697) (xy 36.782791 -240.341659) (xy 36.835405 -240.343676)
			(xy 36.887095 -240.3537) (xy 36.936648 -240.371498) (xy 36.982904 -240.396651) (xy 37.024778 -240.42857)
			(xy 37.06129 -240.466508) (xy 37.091582 -240.509574) (xy 37.114945 -240.556759) (xy 37.130831 -240.606958)
			(xy 37.138868 -240.658994) (xy 37.139372 -240.68532) (xy 43.996105 -240.68532) (xy 44.000135 -240.632822)
			(xy 44.012132 -240.581554) (xy 44.031815 -240.532719) (xy 44.058721 -240.48746) (xy 44.092221 -240.446839)
			(xy 44.131529 -240.411808) (xy 44.175724 -240.383188) (xy 44.223769 -240.361649) (xy 44.27454 -240.347697)
			(xy 44.326845 -240.341659) (xy 44.379459 -240.343676) (xy 44.431149 -240.3537) (xy 44.480702 -240.371498)
			(xy 44.526958 -240.396651) (xy 44.568832 -240.42857) (xy 44.605344 -240.466508) (xy 44.635636 -240.509574)
			(xy 44.658999 -240.556759) (xy 44.674885 -240.606958) (xy 44.682922 -240.658994) (xy 44.683426 -240.68532)
			(xy 51.540159 -240.68532) (xy 51.544189 -240.632822) (xy 51.556186 -240.581554) (xy 51.575869 -240.532719)
			(xy 51.602775 -240.48746) (xy 51.636275 -240.446839) (xy 51.675583 -240.411808) (xy 51.719778 -240.383188)
			(xy 51.767823 -240.361649) (xy 51.818594 -240.347697) (xy 51.870899 -240.341659) (xy 51.923513 -240.343676)
			(xy 51.975203 -240.3537) (xy 52.024756 -240.371498) (xy 52.071012 -240.396651) (xy 52.112886 -240.42857)
			(xy 52.149398 -240.466508) (xy 52.17969 -240.509574) (xy 52.203053 -240.556759) (xy 52.218939 -240.606958)
			(xy 52.226976 -240.658994) (xy 52.22748 -240.68532) (xy 52.226976 -240.711646) (xy 52.218939 -240.763682)
			(xy 52.203053 -240.813881) (xy 52.17969 -240.861066) (xy 52.149398 -240.904132) (xy 52.112886 -240.94207)
			(xy 52.071012 -240.973989) (xy 52.024756 -240.999142) (xy 51.975203 -241.01694) (xy 51.923513 -241.026964)
			(xy 51.870899 -241.028981) (xy 51.818594 -241.022943) (xy 51.767823 -241.008991) (xy 51.719778 -240.987452)
			(xy 51.675583 -240.958832) (xy 51.636275 -240.923801) (xy 51.602775 -240.88318) (xy 51.575869 -240.837921)
			(xy 51.556186 -240.789086) (xy 51.544189 -240.737818) (xy 51.540159 -240.68532) (xy 44.683426 -240.68532)
			(xy 44.682922 -240.711646) (xy 44.674885 -240.763682) (xy 44.658999 -240.813881) (xy 44.635636 -240.861066)
			(xy 44.605344 -240.904132) (xy 44.568832 -240.94207) (xy 44.526958 -240.973989) (xy 44.480702 -240.999142)
			(xy 44.431149 -241.01694) (xy 44.379459 -241.026964) (xy 44.326845 -241.028981) (xy 44.27454 -241.022943)
			(xy 44.223769 -241.008991) (xy 44.175724 -240.987452) (xy 44.131529 -240.958832) (xy 44.092221 -240.923801)
			(xy 44.058721 -240.88318) (xy 44.031815 -240.837921) (xy 44.012132 -240.789086) (xy 44.000135 -240.737818)
			(xy 43.996105 -240.68532) (xy 37.139372 -240.68532) (xy 37.138868 -240.711646) (xy 37.130831 -240.763682)
			(xy 37.114945 -240.813881) (xy 37.091582 -240.861066) (xy 37.06129 -240.904132) (xy 37.024778 -240.94207)
			(xy 36.982904 -240.973989) (xy 36.936648 -240.999142) (xy 36.887095 -241.01694) (xy 36.835405 -241.026964)
			(xy 36.782791 -241.028981) (xy 36.730486 -241.022943) (xy 36.679715 -241.008991) (xy 36.63167 -240.987452)
			(xy 36.587475 -240.958832) (xy 36.548167 -240.923801) (xy 36.514667 -240.88318) (xy 36.487761 -240.837921)
			(xy 36.468078 -240.789086) (xy 36.456081 -240.737818) (xy 36.452051 -240.68532) (xy 29.595572 -240.68532)
			(xy 29.595068 -240.711646) (xy 29.587031 -240.763682) (xy 29.571145 -240.813881) (xy 29.547782 -240.861066)
			(xy 29.51749 -240.904132) (xy 29.480978 -240.94207) (xy 29.439104 -240.973989) (xy 29.392848 -240.999142)
			(xy 29.343295 -241.01694) (xy 29.291605 -241.026964) (xy 29.238991 -241.028981) (xy 29.186686 -241.022943)
			(xy 29.135915 -241.008991) (xy 29.08787 -240.987452) (xy 29.043675 -240.958832) (xy 29.004367 -240.923801)
			(xy 28.970867 -240.88318) (xy 28.943961 -240.837921) (xy 28.924278 -240.789086) (xy 28.912281 -240.737818)
			(xy 28.908251 -240.68532) (xy 22.051518 -240.68532) (xy 22.051014 -240.711646) (xy 22.042977 -240.763682)
			(xy 22.027091 -240.813881) (xy 22.003728 -240.861066) (xy 21.973436 -240.904132) (xy 21.936924 -240.94207)
			(xy 21.89505 -240.973989) (xy 21.848794 -240.999142) (xy 21.799241 -241.01694) (xy 21.747551 -241.026964)
			(xy 21.694937 -241.028981) (xy 21.642632 -241.022943) (xy 21.591861 -241.008991) (xy 21.543816 -240.987452)
			(xy 21.499621 -240.958832) (xy 21.460313 -240.923801) (xy 21.426813 -240.88318) (xy 21.399907 -240.837921)
			(xy 21.380224 -240.789086) (xy 21.368227 -240.737818) (xy 21.364197 -240.68532) (xy 16.086074 -240.68532)
			(xy 16.086074 -241.535204) (xy 17.264129 -241.535204) (xy 17.268159 -241.482706) (xy 17.280156 -241.431438)
			(xy 17.299839 -241.382603) (xy 17.326745 -241.337344) (xy 17.360245 -241.296723) (xy 17.399553 -241.261692)
			(xy 17.443748 -241.233072) (xy 17.491793 -241.211533) (xy 17.542564 -241.197581) (xy 17.594869 -241.191543)
			(xy 17.647483 -241.19356) (xy 17.699173 -241.203584) (xy 17.748726 -241.221382) (xy 17.794982 -241.246535)
			(xy 17.836856 -241.278454) (xy 17.873368 -241.316392) (xy 17.90366 -241.359458) (xy 17.927023 -241.406643)
			(xy 17.942909 -241.456842) (xy 17.950946 -241.508878) (xy 17.95145 -241.535204) (xy 24.808183 -241.535204)
			(xy 24.812213 -241.482706) (xy 24.82421 -241.431438) (xy 24.843893 -241.382603) (xy 24.870799 -241.337344)
			(xy 24.904299 -241.296723) (xy 24.943607 -241.261692) (xy 24.987802 -241.233072) (xy 25.035847 -241.211533)
			(xy 25.086618 -241.197581) (xy 25.138923 -241.191543) (xy 25.191537 -241.19356) (xy 25.243227 -241.203584)
			(xy 25.29278 -241.221382) (xy 25.339036 -241.246535) (xy 25.38091 -241.278454) (xy 25.417422 -241.316392)
			(xy 25.447714 -241.359458) (xy 25.471077 -241.406643) (xy 25.486963 -241.456842) (xy 25.495 -241.508878)
			(xy 25.495504 -241.535204) (xy 32.351983 -241.535204) (xy 32.356013 -241.482706) (xy 32.36801 -241.431438)
			(xy 32.387693 -241.382603) (xy 32.414599 -241.337344) (xy 32.448099 -241.296723) (xy 32.487407 -241.261692)
			(xy 32.531602 -241.233072) (xy 32.579647 -241.211533) (xy 32.630418 -241.197581) (xy 32.682723 -241.191543)
			(xy 32.735337 -241.19356) (xy 32.787027 -241.203584) (xy 32.83658 -241.221382) (xy 32.882836 -241.246535)
			(xy 32.92471 -241.278454) (xy 32.961222 -241.316392) (xy 32.991514 -241.359458) (xy 33.014877 -241.406643)
			(xy 33.030763 -241.456842) (xy 33.0388 -241.508878) (xy 33.039304 -241.535204) (xy 39.896037 -241.535204)
			(xy 39.900067 -241.482706) (xy 39.912064 -241.431438) (xy 39.931747 -241.382603) (xy 39.958653 -241.337344)
			(xy 39.992153 -241.296723) (xy 40.031461 -241.261692) (xy 40.075656 -241.233072) (xy 40.123701 -241.211533)
			(xy 40.174472 -241.197581) (xy 40.226777 -241.191543) (xy 40.279391 -241.19356) (xy 40.331081 -241.203584)
			(xy 40.380634 -241.221382) (xy 40.42689 -241.246535) (xy 40.468764 -241.278454) (xy 40.505276 -241.316392)
			(xy 40.535568 -241.359458) (xy 40.558931 -241.406643) (xy 40.574817 -241.456842) (xy 40.582854 -241.508878)
			(xy 40.583358 -241.535204) (xy 47.440091 -241.535204) (xy 47.444121 -241.482706) (xy 47.456118 -241.431438)
			(xy 47.475801 -241.382603) (xy 47.502707 -241.337344) (xy 47.536207 -241.296723) (xy 47.575515 -241.261692)
			(xy 47.61971 -241.233072) (xy 47.667755 -241.211533) (xy 47.718526 -241.197581) (xy 47.770831 -241.191543)
			(xy 47.823445 -241.19356) (xy 47.875135 -241.203584) (xy 47.924688 -241.221382) (xy 47.970944 -241.246535)
			(xy 48.012818 -241.278454) (xy 48.04933 -241.316392) (xy 48.079622 -241.359458) (xy 48.102985 -241.406643)
			(xy 48.118871 -241.456842) (xy 48.126908 -241.508878) (xy 48.127412 -241.535204) (xy 48.126908 -241.56153)
			(xy 48.118871 -241.613566) (xy 48.102985 -241.663765) (xy 48.079622 -241.71095) (xy 48.04933 -241.754016)
			(xy 48.012818 -241.791954) (xy 47.970944 -241.823873) (xy 47.924688 -241.849026) (xy 47.875135 -241.866824)
			(xy 47.823445 -241.876848) (xy 47.770831 -241.878865) (xy 47.718526 -241.872827) (xy 47.667755 -241.858875)
			(xy 47.61971 -241.837336) (xy 47.575515 -241.808716) (xy 47.536207 -241.773685) (xy 47.502707 -241.733064)
			(xy 47.475801 -241.687805) (xy 47.456118 -241.63897) (xy 47.444121 -241.587702) (xy 47.440091 -241.535204)
			(xy 40.583358 -241.535204) (xy 40.582854 -241.56153) (xy 40.574817 -241.613566) (xy 40.558931 -241.663765)
			(xy 40.535568 -241.71095) (xy 40.505276 -241.754016) (xy 40.468764 -241.791954) (xy 40.42689 -241.823873)
			(xy 40.380634 -241.849026) (xy 40.331081 -241.866824) (xy 40.279391 -241.876848) (xy 40.226777 -241.878865)
			(xy 40.174472 -241.872827) (xy 40.123701 -241.858875) (xy 40.075656 -241.837336) (xy 40.031461 -241.808716)
			(xy 39.992153 -241.773685) (xy 39.958653 -241.733064) (xy 39.931747 -241.687805) (xy 39.912064 -241.63897)
			(xy 39.900067 -241.587702) (xy 39.896037 -241.535204) (xy 33.039304 -241.535204) (xy 33.0388 -241.56153)
			(xy 33.030763 -241.613566) (xy 33.014877 -241.663765) (xy 32.991514 -241.71095) (xy 32.961222 -241.754016)
			(xy 32.92471 -241.791954) (xy 32.882836 -241.823873) (xy 32.83658 -241.849026) (xy 32.787027 -241.866824)
			(xy 32.735337 -241.876848) (xy 32.682723 -241.878865) (xy 32.630418 -241.872827) (xy 32.579647 -241.858875)
			(xy 32.531602 -241.837336) (xy 32.487407 -241.808716) (xy 32.448099 -241.773685) (xy 32.414599 -241.733064)
			(xy 32.387693 -241.687805) (xy 32.36801 -241.63897) (xy 32.356013 -241.587702) (xy 32.351983 -241.535204)
			(xy 25.495504 -241.535204) (xy 25.495 -241.56153) (xy 25.486963 -241.613566) (xy 25.471077 -241.663765)
			(xy 25.447714 -241.71095) (xy 25.417422 -241.754016) (xy 25.38091 -241.791954) (xy 25.339036 -241.823873)
			(xy 25.29278 -241.849026) (xy 25.243227 -241.866824) (xy 25.191537 -241.876848) (xy 25.138923 -241.878865)
			(xy 25.086618 -241.872827) (xy 25.035847 -241.858875) (xy 24.987802 -241.837336) (xy 24.943607 -241.808716)
			(xy 24.904299 -241.773685) (xy 24.870799 -241.733064) (xy 24.843893 -241.687805) (xy 24.82421 -241.63897)
			(xy 24.812213 -241.587702) (xy 24.808183 -241.535204) (xy 17.95145 -241.535204) (xy 17.950946 -241.56153)
			(xy 17.942909 -241.613566) (xy 17.927023 -241.663765) (xy 17.90366 -241.71095) (xy 17.873368 -241.754016)
			(xy 17.836856 -241.791954) (xy 17.794982 -241.823873) (xy 17.748726 -241.849026) (xy 17.699173 -241.866824)
			(xy 17.647483 -241.876848) (xy 17.594869 -241.878865) (xy 17.542564 -241.872827) (xy 17.491793 -241.858875)
			(xy 17.443748 -241.837336) (xy 17.399553 -241.808716) (xy 17.360245 -241.773685) (xy 17.326745 -241.733064)
			(xy 17.299839 -241.687805) (xy 17.280156 -241.63897) (xy 17.268159 -241.587702) (xy 17.264129 -241.535204)
			(xy 16.086074 -241.535204) (xy 16.086074 -242.385342) (xy 21.364197 -242.385342) (xy 21.368227 -242.332844)
			(xy 21.380224 -242.281576) (xy 21.399907 -242.232741) (xy 21.426813 -242.187482) (xy 21.460313 -242.146861)
			(xy 21.499621 -242.11183) (xy 21.543816 -242.08321) (xy 21.591861 -242.061671) (xy 21.642632 -242.047719)
			(xy 21.694937 -242.041681) (xy 21.747551 -242.043698) (xy 21.799241 -242.053722) (xy 21.848794 -242.07152)
			(xy 21.89505 -242.096673) (xy 21.936924 -242.128592) (xy 21.973436 -242.16653) (xy 22.003728 -242.209596)
			(xy 22.027091 -242.256781) (xy 22.042977 -242.30698) (xy 22.051014 -242.359016) (xy 22.051518 -242.385342)
			(xy 28.908251 -242.385342) (xy 28.912281 -242.332844) (xy 28.924278 -242.281576) (xy 28.943961 -242.232741)
			(xy 28.970867 -242.187482) (xy 29.004367 -242.146861) (xy 29.043675 -242.11183) (xy 29.08787 -242.08321)
			(xy 29.135915 -242.061671) (xy 29.186686 -242.047719) (xy 29.238991 -242.041681) (xy 29.291605 -242.043698)
			(xy 29.343295 -242.053722) (xy 29.392848 -242.07152) (xy 29.439104 -242.096673) (xy 29.480978 -242.128592)
			(xy 29.51749 -242.16653) (xy 29.547782 -242.209596) (xy 29.571145 -242.256781) (xy 29.587031 -242.30698)
			(xy 29.595068 -242.359016) (xy 29.595572 -242.385342) (xy 36.452051 -242.385342) (xy 36.456081 -242.332844)
			(xy 36.468078 -242.281576) (xy 36.487761 -242.232741) (xy 36.514667 -242.187482) (xy 36.548167 -242.146861)
			(xy 36.587475 -242.11183) (xy 36.63167 -242.08321) (xy 36.679715 -242.061671) (xy 36.730486 -242.047719)
			(xy 36.782791 -242.041681) (xy 36.835405 -242.043698) (xy 36.887095 -242.053722) (xy 36.936648 -242.07152)
			(xy 36.982904 -242.096673) (xy 37.024778 -242.128592) (xy 37.06129 -242.16653) (xy 37.091582 -242.209596)
			(xy 37.114945 -242.256781) (xy 37.130831 -242.30698) (xy 37.138868 -242.359016) (xy 37.139372 -242.385342)
			(xy 43.996105 -242.385342) (xy 44.000135 -242.332844) (xy 44.012132 -242.281576) (xy 44.031815 -242.232741)
			(xy 44.058721 -242.187482) (xy 44.092221 -242.146861) (xy 44.131529 -242.11183) (xy 44.175724 -242.08321)
			(xy 44.223769 -242.061671) (xy 44.27454 -242.047719) (xy 44.326845 -242.041681) (xy 44.379459 -242.043698)
			(xy 44.431149 -242.053722) (xy 44.480702 -242.07152) (xy 44.526958 -242.096673) (xy 44.568832 -242.128592)
			(xy 44.605344 -242.16653) (xy 44.635636 -242.209596) (xy 44.658999 -242.256781) (xy 44.674885 -242.30698)
			(xy 44.682922 -242.359016) (xy 44.683426 -242.385342) (xy 51.540159 -242.385342) (xy 51.544189 -242.332844)
			(xy 51.556186 -242.281576) (xy 51.575869 -242.232741) (xy 51.602775 -242.187482) (xy 51.636275 -242.146861)
			(xy 51.675583 -242.11183) (xy 51.719778 -242.08321) (xy 51.767823 -242.061671) (xy 51.818594 -242.047719)
			(xy 51.870899 -242.041681) (xy 51.923513 -242.043698) (xy 51.975203 -242.053722) (xy 52.024756 -242.07152)
			(xy 52.071012 -242.096673) (xy 52.112886 -242.128592) (xy 52.149398 -242.16653) (xy 52.17969 -242.209596)
			(xy 52.203053 -242.256781) (xy 52.218939 -242.30698) (xy 52.226976 -242.359016) (xy 52.22748 -242.385342)
			(xy 52.226976 -242.411668) (xy 52.218939 -242.463704) (xy 52.203053 -242.513903) (xy 52.17969 -242.561088)
			(xy 52.149398 -242.604154) (xy 52.112886 -242.642092) (xy 52.071012 -242.674011) (xy 52.024756 -242.699164)
			(xy 51.975203 -242.716962) (xy 51.923513 -242.726986) (xy 51.870899 -242.729003) (xy 51.818594 -242.722965)
			(xy 51.767823 -242.709013) (xy 51.719778 -242.687474) (xy 51.675583 -242.658854) (xy 51.636275 -242.623823)
			(xy 51.602775 -242.583202) (xy 51.575869 -242.537943) (xy 51.556186 -242.489108) (xy 51.544189 -242.43784)
			(xy 51.540159 -242.385342) (xy 44.683426 -242.385342) (xy 44.682922 -242.411668) (xy 44.674885 -242.463704)
			(xy 44.658999 -242.513903) (xy 44.635636 -242.561088) (xy 44.605344 -242.604154) (xy 44.568832 -242.642092)
			(xy 44.526958 -242.674011) (xy 44.480702 -242.699164) (xy 44.431149 -242.716962) (xy 44.379459 -242.726986)
			(xy 44.326845 -242.729003) (xy 44.27454 -242.722965) (xy 44.223769 -242.709013) (xy 44.175724 -242.687474)
			(xy 44.131529 -242.658854) (xy 44.092221 -242.623823) (xy 44.058721 -242.583202) (xy 44.031815 -242.537943)
			(xy 44.012132 -242.489108) (xy 44.000135 -242.43784) (xy 43.996105 -242.385342) (xy 37.139372 -242.385342)
			(xy 37.138868 -242.411668) (xy 37.130831 -242.463704) (xy 37.114945 -242.513903) (xy 37.091582 -242.561088)
			(xy 37.06129 -242.604154) (xy 37.024778 -242.642092) (xy 36.982904 -242.674011) (xy 36.936648 -242.699164)
			(xy 36.887095 -242.716962) (xy 36.835405 -242.726986) (xy 36.782791 -242.729003) (xy 36.730486 -242.722965)
			(xy 36.679715 -242.709013) (xy 36.63167 -242.687474) (xy 36.587475 -242.658854) (xy 36.548167 -242.623823)
			(xy 36.514667 -242.583202) (xy 36.487761 -242.537943) (xy 36.468078 -242.489108) (xy 36.456081 -242.43784)
			(xy 36.452051 -242.385342) (xy 29.595572 -242.385342) (xy 29.595068 -242.411668) (xy 29.587031 -242.463704)
			(xy 29.571145 -242.513903) (xy 29.547782 -242.561088) (xy 29.51749 -242.604154) (xy 29.480978 -242.642092)
			(xy 29.439104 -242.674011) (xy 29.392848 -242.699164) (xy 29.343295 -242.716962) (xy 29.291605 -242.726986)
			(xy 29.238991 -242.729003) (xy 29.186686 -242.722965) (xy 29.135915 -242.709013) (xy 29.08787 -242.687474)
			(xy 29.043675 -242.658854) (xy 29.004367 -242.623823) (xy 28.970867 -242.583202) (xy 28.943961 -242.537943)
			(xy 28.924278 -242.489108) (xy 28.912281 -242.43784) (xy 28.908251 -242.385342) (xy 22.051518 -242.385342)
			(xy 22.051014 -242.411668) (xy 22.042977 -242.463704) (xy 22.027091 -242.513903) (xy 22.003728 -242.561088)
			(xy 21.973436 -242.604154) (xy 21.936924 -242.642092) (xy 21.89505 -242.674011) (xy 21.848794 -242.699164)
			(xy 21.799241 -242.716962) (xy 21.747551 -242.726986) (xy 21.694937 -242.729003) (xy 21.642632 -242.722965)
			(xy 21.591861 -242.709013) (xy 21.543816 -242.687474) (xy 21.499621 -242.658854) (xy 21.460313 -242.623823)
			(xy 21.426813 -242.583202) (xy 21.399907 -242.537943) (xy 21.380224 -242.489108) (xy 21.368227 -242.43784)
			(xy 21.364197 -242.385342) (xy 16.086074 -242.385342) (xy 16.086074 -243.235226) (xy 17.264129 -243.235226)
			(xy 17.268159 -243.182728) (xy 17.280156 -243.13146) (xy 17.299839 -243.082625) (xy 17.326745 -243.037366)
			(xy 17.360245 -242.996745) (xy 17.399553 -242.961714) (xy 17.443748 -242.933094) (xy 17.491793 -242.911555)
			(xy 17.542564 -242.897603) (xy 17.594869 -242.891565) (xy 17.647483 -242.893582) (xy 17.699173 -242.903606)
			(xy 17.748726 -242.921404) (xy 17.794982 -242.946557) (xy 17.836856 -242.978476) (xy 17.873368 -243.016414)
			(xy 17.90366 -243.05948) (xy 17.927023 -243.106665) (xy 17.942909 -243.156864) (xy 17.950946 -243.2089)
			(xy 17.95145 -243.235226) (xy 24.808183 -243.235226) (xy 24.812213 -243.182728) (xy 24.82421 -243.13146)
			(xy 24.843893 -243.082625) (xy 24.870799 -243.037366) (xy 24.904299 -242.996745) (xy 24.943607 -242.961714)
			(xy 24.987802 -242.933094) (xy 25.035847 -242.911555) (xy 25.086618 -242.897603) (xy 25.138923 -242.891565)
			(xy 25.191537 -242.893582) (xy 25.243227 -242.903606) (xy 25.29278 -242.921404) (xy 25.339036 -242.946557)
			(xy 25.38091 -242.978476) (xy 25.417422 -243.016414) (xy 25.447714 -243.05948) (xy 25.471077 -243.106665)
			(xy 25.486963 -243.156864) (xy 25.495 -243.2089) (xy 25.495504 -243.235226) (xy 32.351983 -243.235226)
			(xy 32.356013 -243.182728) (xy 32.36801 -243.13146) (xy 32.387693 -243.082625) (xy 32.414599 -243.037366)
			(xy 32.448099 -242.996745) (xy 32.487407 -242.961714) (xy 32.531602 -242.933094) (xy 32.579647 -242.911555)
			(xy 32.630418 -242.897603) (xy 32.682723 -242.891565) (xy 32.735337 -242.893582) (xy 32.787027 -242.903606)
			(xy 32.83658 -242.921404) (xy 32.882836 -242.946557) (xy 32.92471 -242.978476) (xy 32.961222 -243.016414)
			(xy 32.991514 -243.05948) (xy 33.014877 -243.106665) (xy 33.030763 -243.156864) (xy 33.0388 -243.2089)
			(xy 33.039304 -243.235226) (xy 39.896037 -243.235226) (xy 39.900067 -243.182728) (xy 39.912064 -243.13146)
			(xy 39.931747 -243.082625) (xy 39.958653 -243.037366) (xy 39.992153 -242.996745) (xy 40.031461 -242.961714)
			(xy 40.075656 -242.933094) (xy 40.123701 -242.911555) (xy 40.174472 -242.897603) (xy 40.226777 -242.891565)
			(xy 40.279391 -242.893582) (xy 40.331081 -242.903606) (xy 40.380634 -242.921404) (xy 40.42689 -242.946557)
			(xy 40.468764 -242.978476) (xy 40.505276 -243.016414) (xy 40.535568 -243.05948) (xy 40.558931 -243.106665)
			(xy 40.574817 -243.156864) (xy 40.582854 -243.2089) (xy 40.583358 -243.235226) (xy 47.440091 -243.235226)
			(xy 47.444121 -243.182728) (xy 47.456118 -243.13146) (xy 47.475801 -243.082625) (xy 47.502707 -243.037366)
			(xy 47.536207 -242.996745) (xy 47.575515 -242.961714) (xy 47.61971 -242.933094) (xy 47.667755 -242.911555)
			(xy 47.718526 -242.897603) (xy 47.770831 -242.891565) (xy 47.823445 -242.893582) (xy 47.875135 -242.903606)
			(xy 47.924688 -242.921404) (xy 47.970944 -242.946557) (xy 48.012818 -242.978476) (xy 48.04933 -243.016414)
			(xy 48.079622 -243.05948) (xy 48.102985 -243.106665) (xy 48.118871 -243.156864) (xy 48.126908 -243.2089)
			(xy 48.127412 -243.235226) (xy 48.126908 -243.261552) (xy 48.118871 -243.313588) (xy 48.102985 -243.363787)
			(xy 48.079622 -243.410972) (xy 48.04933 -243.454038) (xy 48.012818 -243.491976) (xy 47.970944 -243.523895)
			(xy 47.924688 -243.549048) (xy 47.875135 -243.566846) (xy 47.823445 -243.57687) (xy 47.770831 -243.578887)
			(xy 47.718526 -243.572849) (xy 47.667755 -243.558897) (xy 47.61971 -243.537358) (xy 47.575515 -243.508738)
			(xy 47.536207 -243.473707) (xy 47.502707 -243.433086) (xy 47.475801 -243.387827) (xy 47.456118 -243.338992)
			(xy 47.444121 -243.287724) (xy 47.440091 -243.235226) (xy 40.583358 -243.235226) (xy 40.582854 -243.261552)
			(xy 40.574817 -243.313588) (xy 40.558931 -243.363787) (xy 40.535568 -243.410972) (xy 40.505276 -243.454038)
			(xy 40.468764 -243.491976) (xy 40.42689 -243.523895) (xy 40.380634 -243.549048) (xy 40.331081 -243.566846)
			(xy 40.279391 -243.57687) (xy 40.226777 -243.578887) (xy 40.174472 -243.572849) (xy 40.123701 -243.558897)
			(xy 40.075656 -243.537358) (xy 40.031461 -243.508738) (xy 39.992153 -243.473707) (xy 39.958653 -243.433086)
			(xy 39.931747 -243.387827) (xy 39.912064 -243.338992) (xy 39.900067 -243.287724) (xy 39.896037 -243.235226)
			(xy 33.039304 -243.235226) (xy 33.0388 -243.261552) (xy 33.030763 -243.313588) (xy 33.014877 -243.363787)
			(xy 32.991514 -243.410972) (xy 32.961222 -243.454038) (xy 32.92471 -243.491976) (xy 32.882836 -243.523895)
			(xy 32.83658 -243.549048) (xy 32.787027 -243.566846) (xy 32.735337 -243.57687) (xy 32.682723 -243.578887)
			(xy 32.630418 -243.572849) (xy 32.579647 -243.558897) (xy 32.531602 -243.537358) (xy 32.487407 -243.508738)
			(xy 32.448099 -243.473707) (xy 32.414599 -243.433086) (xy 32.387693 -243.387827) (xy 32.36801 -243.338992)
			(xy 32.356013 -243.287724) (xy 32.351983 -243.235226) (xy 25.495504 -243.235226) (xy 25.495 -243.261552)
			(xy 25.486963 -243.313588) (xy 25.471077 -243.363787) (xy 25.447714 -243.410972) (xy 25.417422 -243.454038)
			(xy 25.38091 -243.491976) (xy 25.339036 -243.523895) (xy 25.29278 -243.549048) (xy 25.243227 -243.566846)
			(xy 25.191537 -243.57687) (xy 25.138923 -243.578887) (xy 25.086618 -243.572849) (xy 25.035847 -243.558897)
			(xy 24.987802 -243.537358) (xy 24.943607 -243.508738) (xy 24.904299 -243.473707) (xy 24.870799 -243.433086)
			(xy 24.843893 -243.387827) (xy 24.82421 -243.338992) (xy 24.812213 -243.287724) (xy 24.808183 -243.235226)
			(xy 17.95145 -243.235226) (xy 17.950946 -243.261552) (xy 17.942909 -243.313588) (xy 17.927023 -243.363787)
			(xy 17.90366 -243.410972) (xy 17.873368 -243.454038) (xy 17.836856 -243.491976) (xy 17.794982 -243.523895)
			(xy 17.748726 -243.549048) (xy 17.699173 -243.566846) (xy 17.647483 -243.57687) (xy 17.594869 -243.578887)
			(xy 17.542564 -243.572849) (xy 17.491793 -243.558897) (xy 17.443748 -243.537358) (xy 17.399553 -243.508738)
			(xy 17.360245 -243.473707) (xy 17.326745 -243.433086) (xy 17.299839 -243.387827) (xy 17.280156 -243.338992)
			(xy 17.268159 -243.287724) (xy 17.264129 -243.235226) (xy 16.086074 -243.235226) (xy 16.086074 -244.085364)
			(xy 21.364197 -244.085364) (xy 21.368227 -244.032866) (xy 21.380224 -243.981598) (xy 21.399907 -243.932763)
			(xy 21.426813 -243.887504) (xy 21.460313 -243.846883) (xy 21.499621 -243.811852) (xy 21.543816 -243.783232)
			(xy 21.591861 -243.761693) (xy 21.642632 -243.747741) (xy 21.694937 -243.741703) (xy 21.747551 -243.74372)
			(xy 21.799241 -243.753744) (xy 21.848794 -243.771542) (xy 21.89505 -243.796695) (xy 21.936924 -243.828614)
			(xy 21.973436 -243.866552) (xy 22.003728 -243.909618) (xy 22.027091 -243.956803) (xy 22.042977 -244.007002)
			(xy 22.051014 -244.059038) (xy 22.051518 -244.085364) (xy 22.761197 -244.085364) (xy 22.765227 -244.032866)
			(xy 22.777224 -243.981598) (xy 22.796907 -243.932763) (xy 22.823813 -243.887504) (xy 22.857313 -243.846883)
			(xy 22.896621 -243.811852) (xy 22.940816 -243.783232) (xy 22.988861 -243.761693) (xy 23.039632 -243.747741)
			(xy 23.091937 -243.741703) (xy 23.144551 -243.74372) (xy 23.196241 -243.753744) (xy 23.245794 -243.771542)
			(xy 23.29205 -243.796695) (xy 23.333924 -243.828614) (xy 23.370436 -243.866552) (xy 23.400728 -243.909618)
			(xy 23.424091 -243.956803) (xy 23.439977 -244.007002) (xy 23.448014 -244.059038) (xy 23.448518 -244.085364)
			(xy 28.908251 -244.085364) (xy 28.912281 -244.032866) (xy 28.924278 -243.981598) (xy 28.943961 -243.932763)
			(xy 28.970867 -243.887504) (xy 29.004367 -243.846883) (xy 29.043675 -243.811852) (xy 29.08787 -243.783232)
			(xy 29.135915 -243.761693) (xy 29.186686 -243.747741) (xy 29.238991 -243.741703) (xy 29.291605 -243.74372)
			(xy 29.343295 -243.753744) (xy 29.392848 -243.771542) (xy 29.439104 -243.796695) (xy 29.480978 -243.828614)
			(xy 29.51749 -243.866552) (xy 29.547782 -243.909618) (xy 29.571145 -243.956803) (xy 29.587031 -244.007002)
			(xy 29.595068 -244.059038) (xy 29.595572 -244.085364) (xy 30.305251 -244.085364) (xy 30.309281 -244.032866)
			(xy 30.321278 -243.981598) (xy 30.340961 -243.932763) (xy 30.367867 -243.887504) (xy 30.401367 -243.846883)
			(xy 30.440675 -243.811852) (xy 30.48487 -243.783232) (xy 30.532915 -243.761693) (xy 30.583686 -243.747741)
			(xy 30.635991 -243.741703) (xy 30.688605 -243.74372) (xy 30.740295 -243.753744) (xy 30.789848 -243.771542)
			(xy 30.836104 -243.796695) (xy 30.877978 -243.828614) (xy 30.91449 -243.866552) (xy 30.944782 -243.909618)
			(xy 30.968145 -243.956803) (xy 30.984031 -244.007002) (xy 30.992068 -244.059038) (xy 30.992572 -244.085364)
			(xy 36.452051 -244.085364) (xy 36.456081 -244.032866) (xy 36.468078 -243.981598) (xy 36.487761 -243.932763)
			(xy 36.514667 -243.887504) (xy 36.548167 -243.846883) (xy 36.587475 -243.811852) (xy 36.63167 -243.783232)
			(xy 36.679715 -243.761693) (xy 36.730486 -243.747741) (xy 36.782791 -243.741703) (xy 36.835405 -243.74372)
			(xy 36.887095 -243.753744) (xy 36.936648 -243.771542) (xy 36.982904 -243.796695) (xy 37.024778 -243.828614)
			(xy 37.06129 -243.866552) (xy 37.091582 -243.909618) (xy 37.114945 -243.956803) (xy 37.130831 -244.007002)
			(xy 37.138868 -244.059038) (xy 37.139372 -244.085364) (xy 37.849051 -244.085364) (xy 37.853081 -244.032866)
			(xy 37.865078 -243.981598) (xy 37.884761 -243.932763) (xy 37.911667 -243.887504) (xy 37.945167 -243.846883)
			(xy 37.984475 -243.811852) (xy 38.02867 -243.783232) (xy 38.076715 -243.761693) (xy 38.127486 -243.747741)
			(xy 38.179791 -243.741703) (xy 38.232405 -243.74372) (xy 38.284095 -243.753744) (xy 38.333648 -243.771542)
			(xy 38.379904 -243.796695) (xy 38.421778 -243.828614) (xy 38.45829 -243.866552) (xy 38.488582 -243.909618)
			(xy 38.511945 -243.956803) (xy 38.527831 -244.007002) (xy 38.535868 -244.059038) (xy 38.536372 -244.085364)
			(xy 43.996105 -244.085364) (xy 44.000135 -244.032866) (xy 44.012132 -243.981598) (xy 44.031815 -243.932763)
			(xy 44.058721 -243.887504) (xy 44.092221 -243.846883) (xy 44.131529 -243.811852) (xy 44.175724 -243.783232)
			(xy 44.223769 -243.761693) (xy 44.27454 -243.747741) (xy 44.326845 -243.741703) (xy 44.379459 -243.74372)
			(xy 44.431149 -243.753744) (xy 44.480702 -243.771542) (xy 44.526958 -243.796695) (xy 44.568832 -243.828614)
			(xy 44.605344 -243.866552) (xy 44.635636 -243.909618) (xy 44.658999 -243.956803) (xy 44.674885 -244.007002)
			(xy 44.682922 -244.059038) (xy 44.683426 -244.085364) (xy 45.393105 -244.085364) (xy 45.397135 -244.032866)
			(xy 45.409132 -243.981598) (xy 45.428815 -243.932763) (xy 45.455721 -243.887504) (xy 45.489221 -243.846883)
			(xy 45.528529 -243.811852) (xy 45.572724 -243.783232) (xy 45.620769 -243.761693) (xy 45.67154 -243.747741)
			(xy 45.723845 -243.741703) (xy 45.776459 -243.74372) (xy 45.828149 -243.753744) (xy 45.877702 -243.771542)
			(xy 45.923958 -243.796695) (xy 45.965832 -243.828614) (xy 46.002344 -243.866552) (xy 46.032636 -243.909618)
			(xy 46.055999 -243.956803) (xy 46.071885 -244.007002) (xy 46.079922 -244.059038) (xy 46.080426 -244.085364)
			(xy 51.540159 -244.085364) (xy 51.544189 -244.032866) (xy 51.556186 -243.981598) (xy 51.575869 -243.932763)
			(xy 51.602775 -243.887504) (xy 51.636275 -243.846883) (xy 51.675583 -243.811852) (xy 51.719778 -243.783232)
			(xy 51.767823 -243.761693) (xy 51.818594 -243.747741) (xy 51.870899 -243.741703) (xy 51.923513 -243.74372)
			(xy 51.975203 -243.753744) (xy 52.024756 -243.771542) (xy 52.071012 -243.796695) (xy 52.112886 -243.828614)
			(xy 52.149398 -243.866552) (xy 52.17969 -243.909618) (xy 52.203053 -243.956803) (xy 52.218939 -244.007002)
			(xy 52.226976 -244.059038) (xy 52.22748 -244.085364) (xy 52.937159 -244.085364) (xy 52.941189 -244.032866)
			(xy 52.953186 -243.981598) (xy 52.972869 -243.932763) (xy 52.999775 -243.887504) (xy 53.033275 -243.846883)
			(xy 53.072583 -243.811852) (xy 53.116778 -243.783232) (xy 53.164823 -243.761693) (xy 53.215594 -243.747741)
			(xy 53.267899 -243.741703) (xy 53.320513 -243.74372) (xy 53.372203 -243.753744) (xy 53.421756 -243.771542)
			(xy 53.468012 -243.796695) (xy 53.509886 -243.828614) (xy 53.546398 -243.866552) (xy 53.57669 -243.909618)
			(xy 53.600053 -243.956803) (xy 53.615939 -244.007002) (xy 53.623976 -244.059038) (xy 53.62448 -244.085364)
			(xy 57.451247 -244.085364) (xy 57.455277 -244.032866) (xy 57.467274 -243.981598) (xy 57.486957 -243.932763)
			(xy 57.513863 -243.887504) (xy 57.547363 -243.846883) (xy 57.586671 -243.811852) (xy 57.630866 -243.783232)
			(xy 57.678911 -243.761693) (xy 57.729682 -243.747741) (xy 57.781987 -243.741703) (xy 57.834601 -243.74372)
			(xy 57.886291 -243.753744) (xy 57.935844 -243.771542) (xy 57.9821 -243.796695) (xy 58.023974 -243.828614)
			(xy 58.060486 -243.866552) (xy 58.090778 -243.909618) (xy 58.114141 -243.956803) (xy 58.130027 -244.007002)
			(xy 58.138064 -244.059038) (xy 58.138568 -244.085364) (xy 59.084213 -244.085364) (xy 59.088243 -244.032866)
			(xy 59.10024 -243.981598) (xy 59.119923 -243.932763) (xy 59.146829 -243.887504) (xy 59.180329 -243.846883)
			(xy 59.219637 -243.811852) (xy 59.263832 -243.783232) (xy 59.311877 -243.761693) (xy 59.362648 -243.747741)
			(xy 59.414953 -243.741703) (xy 59.467567 -243.74372) (xy 59.519257 -243.753744) (xy 59.56881 -243.771542)
			(xy 59.615066 -243.796695) (xy 59.65694 -243.828614) (xy 59.693452 -243.866552) (xy 59.723744 -243.909618)
			(xy 59.747107 -243.956803) (xy 59.762993 -244.007002) (xy 59.77103 -244.059038) (xy 59.771534 -244.085364)
			(xy 59.77103 -244.11169) (xy 59.762993 -244.163726) (xy 59.747107 -244.213925) (xy 59.723744 -244.26111)
			(xy 59.693452 -244.304176) (xy 59.65694 -244.342114) (xy 59.615066 -244.374033) (xy 59.56881 -244.399186)
			(xy 59.519257 -244.416984) (xy 59.467567 -244.427008) (xy 59.414953 -244.429025) (xy 59.362648 -244.422987)
			(xy 59.311877 -244.409035) (xy 59.263832 -244.387496) (xy 59.219637 -244.358876) (xy 59.180329 -244.323845)
			(xy 59.146829 -244.283224) (xy 59.119923 -244.237965) (xy 59.10024 -244.18913) (xy 59.088243 -244.137862)
			(xy 59.084213 -244.085364) (xy 58.138568 -244.085364) (xy 58.138064 -244.11169) (xy 58.130027 -244.163726)
			(xy 58.114141 -244.213925) (xy 58.090778 -244.26111) (xy 58.060486 -244.304176) (xy 58.023974 -244.342114)
			(xy 57.9821 -244.374033) (xy 57.935844 -244.399186) (xy 57.886291 -244.416984) (xy 57.834601 -244.427008)
			(xy 57.781987 -244.429025) (xy 57.729682 -244.422987) (xy 57.678911 -244.409035) (xy 57.630866 -244.387496)
			(xy 57.586671 -244.358876) (xy 57.547363 -244.323845) (xy 57.513863 -244.283224) (xy 57.486957 -244.237965)
			(xy 57.467274 -244.18913) (xy 57.455277 -244.137862) (xy 57.451247 -244.085364) (xy 53.62448 -244.085364)
			(xy 53.623976 -244.11169) (xy 53.615939 -244.163726) (xy 53.600053 -244.213925) (xy 53.57669 -244.26111)
			(xy 53.546398 -244.304176) (xy 53.509886 -244.342114) (xy 53.468012 -244.374033) (xy 53.421756 -244.399186)
			(xy 53.372203 -244.416984) (xy 53.320513 -244.427008) (xy 53.267899 -244.429025) (xy 53.215594 -244.422987)
			(xy 53.164823 -244.409035) (xy 53.116778 -244.387496) (xy 53.072583 -244.358876) (xy 53.033275 -244.323845)
			(xy 52.999775 -244.283224) (xy 52.972869 -244.237965) (xy 52.953186 -244.18913) (xy 52.941189 -244.137862)
			(xy 52.937159 -244.085364) (xy 52.22748 -244.085364) (xy 52.226976 -244.11169) (xy 52.218939 -244.163726)
			(xy 52.203053 -244.213925) (xy 52.17969 -244.26111) (xy 52.149398 -244.304176) (xy 52.112886 -244.342114)
			(xy 52.071012 -244.374033) (xy 52.024756 -244.399186) (xy 51.975203 -244.416984) (xy 51.923513 -244.427008)
			(xy 51.870899 -244.429025) (xy 51.818594 -244.422987) (xy 51.767823 -244.409035) (xy 51.719778 -244.387496)
			(xy 51.675583 -244.358876) (xy 51.636275 -244.323845) (xy 51.602775 -244.283224) (xy 51.575869 -244.237965)
			(xy 51.556186 -244.18913) (xy 51.544189 -244.137862) (xy 51.540159 -244.085364) (xy 46.080426 -244.085364)
			(xy 46.079922 -244.11169) (xy 46.071885 -244.163726) (xy 46.055999 -244.213925) (xy 46.032636 -244.26111)
			(xy 46.002344 -244.304176) (xy 45.965832 -244.342114) (xy 45.923958 -244.374033) (xy 45.877702 -244.399186)
			(xy 45.828149 -244.416984) (xy 45.776459 -244.427008) (xy 45.723845 -244.429025) (xy 45.67154 -244.422987)
			(xy 45.620769 -244.409035) (xy 45.572724 -244.387496) (xy 45.528529 -244.358876) (xy 45.489221 -244.323845)
			(xy 45.455721 -244.283224) (xy 45.428815 -244.237965) (xy 45.409132 -244.18913) (xy 45.397135 -244.137862)
			(xy 45.393105 -244.085364) (xy 44.683426 -244.085364) (xy 44.682922 -244.11169) (xy 44.674885 -244.163726)
			(xy 44.658999 -244.213925) (xy 44.635636 -244.26111) (xy 44.605344 -244.304176) (xy 44.568832 -244.342114)
			(xy 44.526958 -244.374033) (xy 44.480702 -244.399186) (xy 44.431149 -244.416984) (xy 44.379459 -244.427008)
			(xy 44.326845 -244.429025) (xy 44.27454 -244.422987) (xy 44.223769 -244.409035) (xy 44.175724 -244.387496)
			(xy 44.131529 -244.358876) (xy 44.092221 -244.323845) (xy 44.058721 -244.283224) (xy 44.031815 -244.237965)
			(xy 44.012132 -244.18913) (xy 44.000135 -244.137862) (xy 43.996105 -244.085364) (xy 38.536372 -244.085364)
			(xy 38.535868 -244.11169) (xy 38.527831 -244.163726) (xy 38.511945 -244.213925) (xy 38.488582 -244.26111)
			(xy 38.45829 -244.304176) (xy 38.421778 -244.342114) (xy 38.379904 -244.374033) (xy 38.333648 -244.399186)
			(xy 38.284095 -244.416984) (xy 38.232405 -244.427008) (xy 38.179791 -244.429025) (xy 38.127486 -244.422987)
			(xy 38.076715 -244.409035) (xy 38.02867 -244.387496) (xy 37.984475 -244.358876) (xy 37.945167 -244.323845)
			(xy 37.911667 -244.283224) (xy 37.884761 -244.237965) (xy 37.865078 -244.18913) (xy 37.853081 -244.137862)
			(xy 37.849051 -244.085364) (xy 37.139372 -244.085364) (xy 37.138868 -244.11169) (xy 37.130831 -244.163726)
			(xy 37.114945 -244.213925) (xy 37.091582 -244.26111) (xy 37.06129 -244.304176) (xy 37.024778 -244.342114)
			(xy 36.982904 -244.374033) (xy 36.936648 -244.399186) (xy 36.887095 -244.416984) (xy 36.835405 -244.427008)
			(xy 36.782791 -244.429025) (xy 36.730486 -244.422987) (xy 36.679715 -244.409035) (xy 36.63167 -244.387496)
			(xy 36.587475 -244.358876) (xy 36.548167 -244.323845) (xy 36.514667 -244.283224) (xy 36.487761 -244.237965)
			(xy 36.468078 -244.18913) (xy 36.456081 -244.137862) (xy 36.452051 -244.085364) (xy 30.992572 -244.085364)
			(xy 30.992068 -244.11169) (xy 30.984031 -244.163726) (xy 30.968145 -244.213925) (xy 30.944782 -244.26111)
			(xy 30.91449 -244.304176) (xy 30.877978 -244.342114) (xy 30.836104 -244.374033) (xy 30.789848 -244.399186)
			(xy 30.740295 -244.416984) (xy 30.688605 -244.427008) (xy 30.635991 -244.429025) (xy 30.583686 -244.422987)
			(xy 30.532915 -244.409035) (xy 30.48487 -244.387496) (xy 30.440675 -244.358876) (xy 30.401367 -244.323845)
			(xy 30.367867 -244.283224) (xy 30.340961 -244.237965) (xy 30.321278 -244.18913) (xy 30.309281 -244.137862)
			(xy 30.305251 -244.085364) (xy 29.595572 -244.085364) (xy 29.595068 -244.11169) (xy 29.587031 -244.163726)
			(xy 29.571145 -244.213925) (xy 29.547782 -244.26111) (xy 29.51749 -244.304176) (xy 29.480978 -244.342114)
			(xy 29.439104 -244.374033) (xy 29.392848 -244.399186) (xy 29.343295 -244.416984) (xy 29.291605 -244.427008)
			(xy 29.238991 -244.429025) (xy 29.186686 -244.422987) (xy 29.135915 -244.409035) (xy 29.08787 -244.387496)
			(xy 29.043675 -244.358876) (xy 29.004367 -244.323845) (xy 28.970867 -244.283224) (xy 28.943961 -244.237965)
			(xy 28.924278 -244.18913) (xy 28.912281 -244.137862) (xy 28.908251 -244.085364) (xy 23.448518 -244.085364)
			(xy 23.448014 -244.11169) (xy 23.439977 -244.163726) (xy 23.424091 -244.213925) (xy 23.400728 -244.26111)
			(xy 23.370436 -244.304176) (xy 23.333924 -244.342114) (xy 23.29205 -244.374033) (xy 23.245794 -244.399186)
			(xy 23.196241 -244.416984) (xy 23.144551 -244.427008) (xy 23.091937 -244.429025) (xy 23.039632 -244.422987)
			(xy 22.988861 -244.409035) (xy 22.940816 -244.387496) (xy 22.896621 -244.358876) (xy 22.857313 -244.323845)
			(xy 22.823813 -244.283224) (xy 22.796907 -244.237965) (xy 22.777224 -244.18913) (xy 22.765227 -244.137862)
			(xy 22.761197 -244.085364) (xy 22.051518 -244.085364) (xy 22.051014 -244.11169) (xy 22.042977 -244.163726)
			(xy 22.027091 -244.213925) (xy 22.003728 -244.26111) (xy 21.973436 -244.304176) (xy 21.936924 -244.342114)
			(xy 21.89505 -244.374033) (xy 21.848794 -244.399186) (xy 21.799241 -244.416984) (xy 21.747551 -244.427008)
			(xy 21.694937 -244.429025) (xy 21.642632 -244.422987) (xy 21.591861 -244.409035) (xy 21.543816 -244.387496)
			(xy 21.499621 -244.358876) (xy 21.460313 -244.323845) (xy 21.426813 -244.283224) (xy 21.399907 -244.237965)
			(xy 21.380224 -244.18913) (xy 21.368227 -244.137862) (xy 21.364197 -244.085364) (xy 16.086074 -244.085364)
			(xy 16.086074 -244.935248) (xy 17.264129 -244.935248) (xy 17.268159 -244.88275) (xy 17.280156 -244.831482)
			(xy 17.299839 -244.782647) (xy 17.326745 -244.737388) (xy 17.360245 -244.696767) (xy 17.399553 -244.661736)
			(xy 17.443748 -244.633116) (xy 17.491793 -244.611577) (xy 17.542564 -244.597625) (xy 17.594869 -244.591587)
			(xy 17.647483 -244.593604) (xy 17.699173 -244.603628) (xy 17.748726 -244.621426) (xy 17.794982 -244.646579)
			(xy 17.836856 -244.678498) (xy 17.873368 -244.716436) (xy 17.90366 -244.759502) (xy 17.927023 -244.806687)
			(xy 17.942909 -244.856886) (xy 17.950946 -244.908922) (xy 17.95145 -244.935248) (xy 24.808183 -244.935248)
			(xy 24.812213 -244.88275) (xy 24.82421 -244.831482) (xy 24.843893 -244.782647) (xy 24.870799 -244.737388)
			(xy 24.904299 -244.696767) (xy 24.943607 -244.661736) (xy 24.987802 -244.633116) (xy 25.035847 -244.611577)
			(xy 25.086618 -244.597625) (xy 25.138923 -244.591587) (xy 25.191537 -244.593604) (xy 25.243227 -244.603628)
			(xy 25.29278 -244.621426) (xy 25.339036 -244.646579) (xy 25.38091 -244.678498) (xy 25.417422 -244.716436)
			(xy 25.447714 -244.759502) (xy 25.471077 -244.806687) (xy 25.486963 -244.856886) (xy 25.495 -244.908922)
			(xy 25.495504 -244.935248) (xy 32.351983 -244.935248) (xy 32.356013 -244.88275) (xy 32.36801 -244.831482)
			(xy 32.387693 -244.782647) (xy 32.414599 -244.737388) (xy 32.448099 -244.696767) (xy 32.487407 -244.661736)
			(xy 32.531602 -244.633116) (xy 32.579647 -244.611577) (xy 32.630418 -244.597625) (xy 32.682723 -244.591587)
			(xy 32.735337 -244.593604) (xy 32.787027 -244.603628) (xy 32.83658 -244.621426) (xy 32.882836 -244.646579)
			(xy 32.92471 -244.678498) (xy 32.961222 -244.716436) (xy 32.991514 -244.759502) (xy 33.014877 -244.806687)
			(xy 33.030763 -244.856886) (xy 33.0388 -244.908922) (xy 33.039304 -244.935248) (xy 39.896037 -244.935248)
			(xy 39.900067 -244.88275) (xy 39.912064 -244.831482) (xy 39.931747 -244.782647) (xy 39.958653 -244.737388)
			(xy 39.992153 -244.696767) (xy 40.031461 -244.661736) (xy 40.075656 -244.633116) (xy 40.123701 -244.611577)
			(xy 40.174472 -244.597625) (xy 40.226777 -244.591587) (xy 40.279391 -244.593604) (xy 40.331081 -244.603628)
			(xy 40.380634 -244.621426) (xy 40.42689 -244.646579) (xy 40.468764 -244.678498) (xy 40.505276 -244.716436)
			(xy 40.535568 -244.759502) (xy 40.558931 -244.806687) (xy 40.574817 -244.856886) (xy 40.582854 -244.908922)
			(xy 40.583358 -244.935248) (xy 47.440091 -244.935248) (xy 47.444121 -244.88275) (xy 47.456118 -244.831482)
			(xy 47.475801 -244.782647) (xy 47.502707 -244.737388) (xy 47.536207 -244.696767) (xy 47.575515 -244.661736)
			(xy 47.61971 -244.633116) (xy 47.667755 -244.611577) (xy 47.718526 -244.597625) (xy 47.770831 -244.591587)
			(xy 47.823445 -244.593604) (xy 47.875135 -244.603628) (xy 47.924688 -244.621426) (xy 47.970944 -244.646579)
			(xy 48.012818 -244.678498) (xy 48.04933 -244.716436) (xy 48.079622 -244.759502) (xy 48.102985 -244.806687)
			(xy 48.118871 -244.856886) (xy 48.126908 -244.908922) (xy 48.127412 -244.935248) (xy 48.126908 -244.961574)
			(xy 48.118871 -245.01361) (xy 48.102985 -245.063809) (xy 48.079622 -245.110994) (xy 48.04933 -245.15406)
			(xy 48.012818 -245.191998) (xy 47.970944 -245.223917) (xy 47.924688 -245.24907) (xy 47.875135 -245.266868)
			(xy 47.823445 -245.276892) (xy 47.770831 -245.278909) (xy 47.718526 -245.272871) (xy 47.667755 -245.258919)
			(xy 47.61971 -245.23738) (xy 47.575515 -245.20876) (xy 47.536207 -245.173729) (xy 47.502707 -245.133108)
			(xy 47.475801 -245.087849) (xy 47.456118 -245.039014) (xy 47.444121 -244.987746) (xy 47.440091 -244.935248)
			(xy 40.583358 -244.935248) (xy 40.582854 -244.961574) (xy 40.574817 -245.01361) (xy 40.558931 -245.063809)
			(xy 40.535568 -245.110994) (xy 40.505276 -245.15406) (xy 40.468764 -245.191998) (xy 40.42689 -245.223917)
			(xy 40.380634 -245.24907) (xy 40.331081 -245.266868) (xy 40.279391 -245.276892) (xy 40.226777 -245.278909)
			(xy 40.174472 -245.272871) (xy 40.123701 -245.258919) (xy 40.075656 -245.23738) (xy 40.031461 -245.20876)
			(xy 39.992153 -245.173729) (xy 39.958653 -245.133108) (xy 39.931747 -245.087849) (xy 39.912064 -245.039014)
			(xy 39.900067 -244.987746) (xy 39.896037 -244.935248) (xy 33.039304 -244.935248) (xy 33.0388 -244.961574)
			(xy 33.030763 -245.01361) (xy 33.014877 -245.063809) (xy 32.991514 -245.110994) (xy 32.961222 -245.15406)
			(xy 32.92471 -245.191998) (xy 32.882836 -245.223917) (xy 32.83658 -245.24907) (xy 32.787027 -245.266868)
			(xy 32.735337 -245.276892) (xy 32.682723 -245.278909) (xy 32.630418 -245.272871) (xy 32.579647 -245.258919)
			(xy 32.531602 -245.23738) (xy 32.487407 -245.20876) (xy 32.448099 -245.173729) (xy 32.414599 -245.133108)
			(xy 32.387693 -245.087849) (xy 32.36801 -245.039014) (xy 32.356013 -244.987746) (xy 32.351983 -244.935248)
			(xy 25.495504 -244.935248) (xy 25.495 -244.961574) (xy 25.486963 -245.01361) (xy 25.471077 -245.063809)
			(xy 25.447714 -245.110994) (xy 25.417422 -245.15406) (xy 25.38091 -245.191998) (xy 25.339036 -245.223917)
			(xy 25.29278 -245.24907) (xy 25.243227 -245.266868) (xy 25.191537 -245.276892) (xy 25.138923 -245.278909)
			(xy 25.086618 -245.272871) (xy 25.035847 -245.258919) (xy 24.987802 -245.23738) (xy 24.943607 -245.20876)
			(xy 24.904299 -245.173729) (xy 24.870799 -245.133108) (xy 24.843893 -245.087849) (xy 24.82421 -245.039014)
			(xy 24.812213 -244.987746) (xy 24.808183 -244.935248) (xy 17.95145 -244.935248) (xy 17.950946 -244.961574)
			(xy 17.942909 -245.01361) (xy 17.927023 -245.063809) (xy 17.90366 -245.110994) (xy 17.873368 -245.15406)
			(xy 17.836856 -245.191998) (xy 17.794982 -245.223917) (xy 17.748726 -245.24907) (xy 17.699173 -245.266868)
			(xy 17.647483 -245.276892) (xy 17.594869 -245.278909) (xy 17.542564 -245.272871) (xy 17.491793 -245.258919)
			(xy 17.443748 -245.23738) (xy 17.399553 -245.20876) (xy 17.360245 -245.173729) (xy 17.326745 -245.133108)
			(xy 17.299839 -245.087849) (xy 17.280156 -245.039014) (xy 17.268159 -244.987746) (xy 17.264129 -244.935248)
			(xy 16.086074 -244.935248) (xy 16.086074 -245.785386) (xy 21.364197 -245.785386) (xy 21.368227 -245.732888)
			(xy 21.380224 -245.68162) (xy 21.399907 -245.632785) (xy 21.426813 -245.587526) (xy 21.460313 -245.546905)
			(xy 21.499621 -245.511874) (xy 21.543816 -245.483254) (xy 21.591861 -245.461715) (xy 21.642632 -245.447763)
			(xy 21.694937 -245.441725) (xy 21.747551 -245.443742) (xy 21.799241 -245.453766) (xy 21.848794 -245.471564)
			(xy 21.89505 -245.496717) (xy 21.936924 -245.528636) (xy 21.973436 -245.566574) (xy 22.003728 -245.60964)
			(xy 22.027091 -245.656825) (xy 22.042977 -245.707024) (xy 22.051014 -245.75906) (xy 22.051518 -245.785386)
			(xy 28.908251 -245.785386) (xy 28.912281 -245.732888) (xy 28.924278 -245.68162) (xy 28.943961 -245.632785)
			(xy 28.970867 -245.587526) (xy 29.004367 -245.546905) (xy 29.043675 -245.511874) (xy 29.08787 -245.483254)
			(xy 29.135915 -245.461715) (xy 29.186686 -245.447763) (xy 29.238991 -245.441725) (xy 29.291605 -245.443742)
			(xy 29.343295 -245.453766) (xy 29.392848 -245.471564) (xy 29.439104 -245.496717) (xy 29.480978 -245.528636)
			(xy 29.51749 -245.566574) (xy 29.547782 -245.60964) (xy 29.571145 -245.656825) (xy 29.587031 -245.707024)
			(xy 29.595068 -245.75906) (xy 29.595572 -245.785386) (xy 36.452051 -245.785386) (xy 36.456081 -245.732888)
			(xy 36.468078 -245.68162) (xy 36.487761 -245.632785) (xy 36.514667 -245.587526) (xy 36.548167 -245.546905)
			(xy 36.587475 -245.511874) (xy 36.63167 -245.483254) (xy 36.679715 -245.461715) (xy 36.730486 -245.447763)
			(xy 36.782791 -245.441725) (xy 36.835405 -245.443742) (xy 36.887095 -245.453766) (xy 36.936648 -245.471564)
			(xy 36.982904 -245.496717) (xy 37.024778 -245.528636) (xy 37.06129 -245.566574) (xy 37.091582 -245.60964)
			(xy 37.114945 -245.656825) (xy 37.130831 -245.707024) (xy 37.138868 -245.75906) (xy 37.139372 -245.785386)
			(xy 43.996105 -245.785386) (xy 44.000135 -245.732888) (xy 44.012132 -245.68162) (xy 44.031815 -245.632785)
			(xy 44.058721 -245.587526) (xy 44.092221 -245.546905) (xy 44.131529 -245.511874) (xy 44.175724 -245.483254)
			(xy 44.223769 -245.461715) (xy 44.27454 -245.447763) (xy 44.326845 -245.441725) (xy 44.379459 -245.443742)
			(xy 44.431149 -245.453766) (xy 44.480702 -245.471564) (xy 44.526958 -245.496717) (xy 44.568832 -245.528636)
			(xy 44.605344 -245.566574) (xy 44.635636 -245.60964) (xy 44.658999 -245.656825) (xy 44.674885 -245.707024)
			(xy 44.682922 -245.75906) (xy 44.683426 -245.785386) (xy 51.540159 -245.785386) (xy 51.544189 -245.732888)
			(xy 51.556186 -245.68162) (xy 51.575869 -245.632785) (xy 51.602775 -245.587526) (xy 51.636275 -245.546905)
			(xy 51.675583 -245.511874) (xy 51.719778 -245.483254) (xy 51.767823 -245.461715) (xy 51.818594 -245.447763)
			(xy 51.870899 -245.441725) (xy 51.923513 -245.443742) (xy 51.975203 -245.453766) (xy 52.024756 -245.471564)
			(xy 52.071012 -245.496717) (xy 52.112886 -245.528636) (xy 52.149398 -245.566574) (xy 52.17969 -245.60964)
			(xy 52.203053 -245.656825) (xy 52.218939 -245.707024) (xy 52.226976 -245.75906) (xy 52.22748 -245.785386)
			(xy 52.226976 -245.811712) (xy 52.218939 -245.863748) (xy 52.203053 -245.913947) (xy 52.17969 -245.961132)
			(xy 52.149398 -246.004198) (xy 52.112886 -246.042136) (xy 52.071012 -246.074055) (xy 52.024756 -246.099208)
			(xy 51.975203 -246.117006) (xy 51.923513 -246.12703) (xy 51.870899 -246.129047) (xy 51.818594 -246.123009)
			(xy 51.767823 -246.109057) (xy 51.719778 -246.087518) (xy 51.675583 -246.058898) (xy 51.636275 -246.023867)
			(xy 51.602775 -245.983246) (xy 51.575869 -245.937987) (xy 51.556186 -245.889152) (xy 51.544189 -245.837884)
			(xy 51.540159 -245.785386) (xy 44.683426 -245.785386) (xy 44.682922 -245.811712) (xy 44.674885 -245.863748)
			(xy 44.658999 -245.913947) (xy 44.635636 -245.961132) (xy 44.605344 -246.004198) (xy 44.568832 -246.042136)
			(xy 44.526958 -246.074055) (xy 44.480702 -246.099208) (xy 44.431149 -246.117006) (xy 44.379459 -246.12703)
			(xy 44.326845 -246.129047) (xy 44.27454 -246.123009) (xy 44.223769 -246.109057) (xy 44.175724 -246.087518)
			(xy 44.131529 -246.058898) (xy 44.092221 -246.023867) (xy 44.058721 -245.983246) (xy 44.031815 -245.937987)
			(xy 44.012132 -245.889152) (xy 44.000135 -245.837884) (xy 43.996105 -245.785386) (xy 37.139372 -245.785386)
			(xy 37.138868 -245.811712) (xy 37.130831 -245.863748) (xy 37.114945 -245.913947) (xy 37.091582 -245.961132)
			(xy 37.06129 -246.004198) (xy 37.024778 -246.042136) (xy 36.982904 -246.074055) (xy 36.936648 -246.099208)
			(xy 36.887095 -246.117006) (xy 36.835405 -246.12703) (xy 36.782791 -246.129047) (xy 36.730486 -246.123009)
			(xy 36.679715 -246.109057) (xy 36.63167 -246.087518) (xy 36.587475 -246.058898) (xy 36.548167 -246.023867)
			(xy 36.514667 -245.983246) (xy 36.487761 -245.937987) (xy 36.468078 -245.889152) (xy 36.456081 -245.837884)
			(xy 36.452051 -245.785386) (xy 29.595572 -245.785386) (xy 29.595068 -245.811712) (xy 29.587031 -245.863748)
			(xy 29.571145 -245.913947) (xy 29.547782 -245.961132) (xy 29.51749 -246.004198) (xy 29.480978 -246.042136)
			(xy 29.439104 -246.074055) (xy 29.392848 -246.099208) (xy 29.343295 -246.117006) (xy 29.291605 -246.12703)
			(xy 29.238991 -246.129047) (xy 29.186686 -246.123009) (xy 29.135915 -246.109057) (xy 29.08787 -246.087518)
			(xy 29.043675 -246.058898) (xy 29.004367 -246.023867) (xy 28.970867 -245.983246) (xy 28.943961 -245.937987)
			(xy 28.924278 -245.889152) (xy 28.912281 -245.837884) (xy 28.908251 -245.785386) (xy 22.051518 -245.785386)
			(xy 22.051014 -245.811712) (xy 22.042977 -245.863748) (xy 22.027091 -245.913947) (xy 22.003728 -245.961132)
			(xy 21.973436 -246.004198) (xy 21.936924 -246.042136) (xy 21.89505 -246.074055) (xy 21.848794 -246.099208)
			(xy 21.799241 -246.117006) (xy 21.747551 -246.12703) (xy 21.694937 -246.129047) (xy 21.642632 -246.123009)
			(xy 21.591861 -246.109057) (xy 21.543816 -246.087518) (xy 21.499621 -246.058898) (xy 21.460313 -246.023867)
			(xy 21.426813 -245.983246) (xy 21.399907 -245.937987) (xy 21.380224 -245.889152) (xy 21.368227 -245.837884)
			(xy 21.364197 -245.785386) (xy 16.086074 -245.785386) (xy 16.086074 -246.63527) (xy 17.264129 -246.63527)
			(xy 17.268159 -246.582772) (xy 17.280156 -246.531504) (xy 17.299839 -246.482669) (xy 17.326745 -246.43741)
			(xy 17.360245 -246.396789) (xy 17.399553 -246.361758) (xy 17.443748 -246.333138) (xy 17.491793 -246.311599)
			(xy 17.542564 -246.297647) (xy 17.594869 -246.291609) (xy 17.647483 -246.293626) (xy 17.699173 -246.30365)
			(xy 17.748726 -246.321448) (xy 17.794982 -246.346601) (xy 17.836856 -246.37852) (xy 17.873368 -246.416458)
			(xy 17.90366 -246.459524) (xy 17.927023 -246.506709) (xy 17.942909 -246.556908) (xy 17.950946 -246.608944)
			(xy 17.95145 -246.63527) (xy 24.808183 -246.63527) (xy 24.812213 -246.582772) (xy 24.82421 -246.531504)
			(xy 24.843893 -246.482669) (xy 24.870799 -246.43741) (xy 24.904299 -246.396789) (xy 24.943607 -246.361758)
			(xy 24.987802 -246.333138) (xy 25.035847 -246.311599) (xy 25.086618 -246.297647) (xy 25.138923 -246.291609)
			(xy 25.191537 -246.293626) (xy 25.243227 -246.30365) (xy 25.29278 -246.321448) (xy 25.339036 -246.346601)
			(xy 25.38091 -246.37852) (xy 25.417422 -246.416458) (xy 25.447714 -246.459524) (xy 25.471077 -246.506709)
			(xy 25.486963 -246.556908) (xy 25.495 -246.608944) (xy 25.495504 -246.63527) (xy 32.351983 -246.63527)
			(xy 32.356013 -246.582772) (xy 32.36801 -246.531504) (xy 32.387693 -246.482669) (xy 32.414599 -246.43741)
			(xy 32.448099 -246.396789) (xy 32.487407 -246.361758) (xy 32.531602 -246.333138) (xy 32.579647 -246.311599)
			(xy 32.630418 -246.297647) (xy 32.682723 -246.291609) (xy 32.735337 -246.293626) (xy 32.787027 -246.30365)
			(xy 32.83658 -246.321448) (xy 32.882836 -246.346601) (xy 32.92471 -246.37852) (xy 32.961222 -246.416458)
			(xy 32.991514 -246.459524) (xy 33.014877 -246.506709) (xy 33.030763 -246.556908) (xy 33.0388 -246.608944)
			(xy 33.039304 -246.63527) (xy 39.896037 -246.63527) (xy 39.900067 -246.582772) (xy 39.912064 -246.531504)
			(xy 39.931747 -246.482669) (xy 39.958653 -246.43741) (xy 39.992153 -246.396789) (xy 40.031461 -246.361758)
			(xy 40.075656 -246.333138) (xy 40.123701 -246.311599) (xy 40.174472 -246.297647) (xy 40.226777 -246.291609)
			(xy 40.279391 -246.293626) (xy 40.331081 -246.30365) (xy 40.380634 -246.321448) (xy 40.42689 -246.346601)
			(xy 40.468764 -246.37852) (xy 40.505276 -246.416458) (xy 40.535568 -246.459524) (xy 40.558931 -246.506709)
			(xy 40.574817 -246.556908) (xy 40.582854 -246.608944) (xy 40.583358 -246.63527) (xy 47.440091 -246.63527)
			(xy 47.444121 -246.582772) (xy 47.456118 -246.531504) (xy 47.475801 -246.482669) (xy 47.502707 -246.43741)
			(xy 47.536207 -246.396789) (xy 47.575515 -246.361758) (xy 47.61971 -246.333138) (xy 47.667755 -246.311599)
			(xy 47.718526 -246.297647) (xy 47.770831 -246.291609) (xy 47.823445 -246.293626) (xy 47.875135 -246.30365)
			(xy 47.924688 -246.321448) (xy 47.970944 -246.346601) (xy 48.012818 -246.37852) (xy 48.04933 -246.416458)
			(xy 48.079622 -246.459524) (xy 48.102985 -246.506709) (xy 48.118871 -246.556908) (xy 48.126908 -246.608944)
			(xy 48.127412 -246.63527) (xy 48.126908 -246.661596) (xy 48.118871 -246.713632) (xy 48.102985 -246.763831)
			(xy 48.079622 -246.811016) (xy 48.04933 -246.854082) (xy 48.012818 -246.89202) (xy 47.970944 -246.923939)
			(xy 47.924688 -246.949092) (xy 47.875135 -246.96689) (xy 47.823445 -246.976914) (xy 47.770831 -246.978931)
			(xy 47.718526 -246.972893) (xy 47.667755 -246.958941) (xy 47.61971 -246.937402) (xy 47.575515 -246.908782)
			(xy 47.536207 -246.873751) (xy 47.502707 -246.83313) (xy 47.475801 -246.787871) (xy 47.456118 -246.739036)
			(xy 47.444121 -246.687768) (xy 47.440091 -246.63527) (xy 40.583358 -246.63527) (xy 40.582854 -246.661596)
			(xy 40.574817 -246.713632) (xy 40.558931 -246.763831) (xy 40.535568 -246.811016) (xy 40.505276 -246.854082)
			(xy 40.468764 -246.89202) (xy 40.42689 -246.923939) (xy 40.380634 -246.949092) (xy 40.331081 -246.96689)
			(xy 40.279391 -246.976914) (xy 40.226777 -246.978931) (xy 40.174472 -246.972893) (xy 40.123701 -246.958941)
			(xy 40.075656 -246.937402) (xy 40.031461 -246.908782) (xy 39.992153 -246.873751) (xy 39.958653 -246.83313)
			(xy 39.931747 -246.787871) (xy 39.912064 -246.739036) (xy 39.900067 -246.687768) (xy 39.896037 -246.63527)
			(xy 33.039304 -246.63527) (xy 33.0388 -246.661596) (xy 33.030763 -246.713632) (xy 33.014877 -246.763831)
			(xy 32.991514 -246.811016) (xy 32.961222 -246.854082) (xy 32.92471 -246.89202) (xy 32.882836 -246.923939)
			(xy 32.83658 -246.949092) (xy 32.787027 -246.96689) (xy 32.735337 -246.976914) (xy 32.682723 -246.978931)
			(xy 32.630418 -246.972893) (xy 32.579647 -246.958941) (xy 32.531602 -246.937402) (xy 32.487407 -246.908782)
			(xy 32.448099 -246.873751) (xy 32.414599 -246.83313) (xy 32.387693 -246.787871) (xy 32.36801 -246.739036)
			(xy 32.356013 -246.687768) (xy 32.351983 -246.63527) (xy 25.495504 -246.63527) (xy 25.495 -246.661596)
			(xy 25.486963 -246.713632) (xy 25.471077 -246.763831) (xy 25.447714 -246.811016) (xy 25.417422 -246.854082)
			(xy 25.38091 -246.89202) (xy 25.339036 -246.923939) (xy 25.29278 -246.949092) (xy 25.243227 -246.96689)
			(xy 25.191537 -246.976914) (xy 25.138923 -246.978931) (xy 25.086618 -246.972893) (xy 25.035847 -246.958941)
			(xy 24.987802 -246.937402) (xy 24.943607 -246.908782) (xy 24.904299 -246.873751) (xy 24.870799 -246.83313)
			(xy 24.843893 -246.787871) (xy 24.82421 -246.739036) (xy 24.812213 -246.687768) (xy 24.808183 -246.63527)
			(xy 17.95145 -246.63527) (xy 17.950946 -246.661596) (xy 17.942909 -246.713632) (xy 17.927023 -246.763831)
			(xy 17.90366 -246.811016) (xy 17.873368 -246.854082) (xy 17.836856 -246.89202) (xy 17.794982 -246.923939)
			(xy 17.748726 -246.949092) (xy 17.699173 -246.96689) (xy 17.647483 -246.976914) (xy 17.594869 -246.978931)
			(xy 17.542564 -246.972893) (xy 17.491793 -246.958941) (xy 17.443748 -246.937402) (xy 17.399553 -246.908782)
			(xy 17.360245 -246.873751) (xy 17.326745 -246.83313) (xy 17.299839 -246.787871) (xy 17.280156 -246.739036)
			(xy 17.268159 -246.687768) (xy 17.264129 -246.63527) (xy 16.086074 -246.63527) (xy 16.086074 -247.485408)
			(xy 21.364197 -247.485408) (xy 21.368227 -247.43291) (xy 21.380224 -247.381642) (xy 21.399907 -247.332807)
			(xy 21.426813 -247.287548) (xy 21.460313 -247.246927) (xy 21.499621 -247.211896) (xy 21.543816 -247.183276)
			(xy 21.591861 -247.161737) (xy 21.642632 -247.147785) (xy 21.694937 -247.141747) (xy 21.747551 -247.143764)
			(xy 21.799241 -247.153788) (xy 21.848794 -247.171586) (xy 21.89505 -247.196739) (xy 21.936924 -247.228658)
			(xy 21.973436 -247.266596) (xy 22.003728 -247.309662) (xy 22.027091 -247.356847) (xy 22.042977 -247.407046)
			(xy 22.051014 -247.459082) (xy 22.051518 -247.485408) (xy 28.908251 -247.485408) (xy 28.912281 -247.43291)
			(xy 28.924278 -247.381642) (xy 28.943961 -247.332807) (xy 28.970867 -247.287548) (xy 29.004367 -247.246927)
			(xy 29.043675 -247.211896) (xy 29.08787 -247.183276) (xy 29.135915 -247.161737) (xy 29.186686 -247.147785)
			(xy 29.238991 -247.141747) (xy 29.291605 -247.143764) (xy 29.343295 -247.153788) (xy 29.392848 -247.171586)
			(xy 29.439104 -247.196739) (xy 29.480978 -247.228658) (xy 29.51749 -247.266596) (xy 29.547782 -247.309662)
			(xy 29.571145 -247.356847) (xy 29.587031 -247.407046) (xy 29.595068 -247.459082) (xy 29.595572 -247.485408)
			(xy 36.452051 -247.485408) (xy 36.456081 -247.43291) (xy 36.468078 -247.381642) (xy 36.487761 -247.332807)
			(xy 36.514667 -247.287548) (xy 36.548167 -247.246927) (xy 36.587475 -247.211896) (xy 36.63167 -247.183276)
			(xy 36.679715 -247.161737) (xy 36.730486 -247.147785) (xy 36.782791 -247.141747) (xy 36.835405 -247.143764)
			(xy 36.887095 -247.153788) (xy 36.936648 -247.171586) (xy 36.982904 -247.196739) (xy 37.024778 -247.228658)
			(xy 37.06129 -247.266596) (xy 37.091582 -247.309662) (xy 37.114945 -247.356847) (xy 37.130831 -247.407046)
			(xy 37.138868 -247.459082) (xy 37.139372 -247.485408) (xy 43.996105 -247.485408) (xy 44.000135 -247.43291)
			(xy 44.012132 -247.381642) (xy 44.031815 -247.332807) (xy 44.058721 -247.287548) (xy 44.092221 -247.246927)
			(xy 44.131529 -247.211896) (xy 44.175724 -247.183276) (xy 44.223769 -247.161737) (xy 44.27454 -247.147785)
			(xy 44.326845 -247.141747) (xy 44.379459 -247.143764) (xy 44.431149 -247.153788) (xy 44.480702 -247.171586)
			(xy 44.526958 -247.196739) (xy 44.568832 -247.228658) (xy 44.605344 -247.266596) (xy 44.635636 -247.309662)
			(xy 44.658999 -247.356847) (xy 44.674885 -247.407046) (xy 44.682922 -247.459082) (xy 44.683426 -247.485408)
			(xy 51.540159 -247.485408) (xy 51.544189 -247.43291) (xy 51.556186 -247.381642) (xy 51.575869 -247.332807)
			(xy 51.602775 -247.287548) (xy 51.636275 -247.246927) (xy 51.675583 -247.211896) (xy 51.719778 -247.183276)
			(xy 51.767823 -247.161737) (xy 51.818594 -247.147785) (xy 51.870899 -247.141747) (xy 51.923513 -247.143764)
			(xy 51.975203 -247.153788) (xy 52.024756 -247.171586) (xy 52.071012 -247.196739) (xy 52.112886 -247.228658)
			(xy 52.149398 -247.266596) (xy 52.17969 -247.309662) (xy 52.203053 -247.356847) (xy 52.218939 -247.407046)
			(xy 52.226976 -247.459082) (xy 52.22748 -247.485408) (xy 52.226976 -247.511734) (xy 52.218939 -247.56377)
			(xy 52.203053 -247.613969) (xy 52.17969 -247.661154) (xy 52.149398 -247.70422) (xy 52.112886 -247.742158)
			(xy 52.071012 -247.774077) (xy 52.024756 -247.79923) (xy 51.975203 -247.817028) (xy 51.923513 -247.827052)
			(xy 51.870899 -247.829069) (xy 51.818594 -247.823031) (xy 51.767823 -247.809079) (xy 51.719778 -247.78754)
			(xy 51.675583 -247.75892) (xy 51.636275 -247.723889) (xy 51.602775 -247.683268) (xy 51.575869 -247.638009)
			(xy 51.556186 -247.589174) (xy 51.544189 -247.537906) (xy 51.540159 -247.485408) (xy 44.683426 -247.485408)
			(xy 44.682922 -247.511734) (xy 44.674885 -247.56377) (xy 44.658999 -247.613969) (xy 44.635636 -247.661154)
			(xy 44.605344 -247.70422) (xy 44.568832 -247.742158) (xy 44.526958 -247.774077) (xy 44.480702 -247.79923)
			(xy 44.431149 -247.817028) (xy 44.379459 -247.827052) (xy 44.326845 -247.829069) (xy 44.27454 -247.823031)
			(xy 44.223769 -247.809079) (xy 44.175724 -247.78754) (xy 44.131529 -247.75892) (xy 44.092221 -247.723889)
			(xy 44.058721 -247.683268) (xy 44.031815 -247.638009) (xy 44.012132 -247.589174) (xy 44.000135 -247.537906)
			(xy 43.996105 -247.485408) (xy 37.139372 -247.485408) (xy 37.138868 -247.511734) (xy 37.130831 -247.56377)
			(xy 37.114945 -247.613969) (xy 37.091582 -247.661154) (xy 37.06129 -247.70422) (xy 37.024778 -247.742158)
			(xy 36.982904 -247.774077) (xy 36.936648 -247.79923) (xy 36.887095 -247.817028) (xy 36.835405 -247.827052)
			(xy 36.782791 -247.829069) (xy 36.730486 -247.823031) (xy 36.679715 -247.809079) (xy 36.63167 -247.78754)
			(xy 36.587475 -247.75892) (xy 36.548167 -247.723889) (xy 36.514667 -247.683268) (xy 36.487761 -247.638009)
			(xy 36.468078 -247.589174) (xy 36.456081 -247.537906) (xy 36.452051 -247.485408) (xy 29.595572 -247.485408)
			(xy 29.595068 -247.511734) (xy 29.587031 -247.56377) (xy 29.571145 -247.613969) (xy 29.547782 -247.661154)
			(xy 29.51749 -247.70422) (xy 29.480978 -247.742158) (xy 29.439104 -247.774077) (xy 29.392848 -247.79923)
			(xy 29.343295 -247.817028) (xy 29.291605 -247.827052) (xy 29.238991 -247.829069) (xy 29.186686 -247.823031)
			(xy 29.135915 -247.809079) (xy 29.08787 -247.78754) (xy 29.043675 -247.75892) (xy 29.004367 -247.723889)
			(xy 28.970867 -247.683268) (xy 28.943961 -247.638009) (xy 28.924278 -247.589174) (xy 28.912281 -247.537906)
			(xy 28.908251 -247.485408) (xy 22.051518 -247.485408) (xy 22.051014 -247.511734) (xy 22.042977 -247.56377)
			(xy 22.027091 -247.613969) (xy 22.003728 -247.661154) (xy 21.973436 -247.70422) (xy 21.936924 -247.742158)
			(xy 21.89505 -247.774077) (xy 21.848794 -247.79923) (xy 21.799241 -247.817028) (xy 21.747551 -247.827052)
			(xy 21.694937 -247.829069) (xy 21.642632 -247.823031) (xy 21.591861 -247.809079) (xy 21.543816 -247.78754)
			(xy 21.499621 -247.75892) (xy 21.460313 -247.723889) (xy 21.426813 -247.683268) (xy 21.399907 -247.638009)
			(xy 21.380224 -247.589174) (xy 21.368227 -247.537906) (xy 21.364197 -247.485408) (xy 16.086074 -247.485408)
			(xy 16.086074 -248.335292) (xy 17.264129 -248.335292) (xy 17.268159 -248.282794) (xy 17.280156 -248.231526)
			(xy 17.299839 -248.182691) (xy 17.326745 -248.137432) (xy 17.360245 -248.096811) (xy 17.399553 -248.06178)
			(xy 17.443748 -248.03316) (xy 17.491793 -248.011621) (xy 17.542564 -247.997669) (xy 17.594869 -247.991631)
			(xy 17.647483 -247.993648) (xy 17.699173 -248.003672) (xy 17.748726 -248.02147) (xy 17.794982 -248.046623)
			(xy 17.836856 -248.078542) (xy 17.873368 -248.11648) (xy 17.90366 -248.159546) (xy 17.927023 -248.206731)
			(xy 17.942909 -248.25693) (xy 17.950946 -248.308966) (xy 17.95145 -248.335292) (xy 24.808183 -248.335292)
			(xy 24.812213 -248.282794) (xy 24.82421 -248.231526) (xy 24.843893 -248.182691) (xy 24.870799 -248.137432)
			(xy 24.904299 -248.096811) (xy 24.943607 -248.06178) (xy 24.987802 -248.03316) (xy 25.035847 -248.011621)
			(xy 25.086618 -247.997669) (xy 25.138923 -247.991631) (xy 25.191537 -247.993648) (xy 25.243227 -248.003672)
			(xy 25.29278 -248.02147) (xy 25.339036 -248.046623) (xy 25.38091 -248.078542) (xy 25.417422 -248.11648)
			(xy 25.447714 -248.159546) (xy 25.471077 -248.206731) (xy 25.486963 -248.25693) (xy 25.495 -248.308966)
			(xy 25.495504 -248.335292) (xy 32.351983 -248.335292) (xy 32.356013 -248.282794) (xy 32.36801 -248.231526)
			(xy 32.387693 -248.182691) (xy 32.414599 -248.137432) (xy 32.448099 -248.096811) (xy 32.487407 -248.06178)
			(xy 32.531602 -248.03316) (xy 32.579647 -248.011621) (xy 32.630418 -247.997669) (xy 32.682723 -247.991631)
			(xy 32.735337 -247.993648) (xy 32.787027 -248.003672) (xy 32.83658 -248.02147) (xy 32.882836 -248.046623)
			(xy 32.92471 -248.078542) (xy 32.961222 -248.11648) (xy 32.991514 -248.159546) (xy 33.014877 -248.206731)
			(xy 33.030763 -248.25693) (xy 33.0388 -248.308966) (xy 33.039304 -248.335292) (xy 39.896037 -248.335292)
			(xy 39.900067 -248.282794) (xy 39.912064 -248.231526) (xy 39.931747 -248.182691) (xy 39.958653 -248.137432)
			(xy 39.992153 -248.096811) (xy 40.031461 -248.06178) (xy 40.075656 -248.03316) (xy 40.123701 -248.011621)
			(xy 40.174472 -247.997669) (xy 40.226777 -247.991631) (xy 40.279391 -247.993648) (xy 40.331081 -248.003672)
			(xy 40.380634 -248.02147) (xy 40.42689 -248.046623) (xy 40.468764 -248.078542) (xy 40.505276 -248.11648)
			(xy 40.535568 -248.159546) (xy 40.558931 -248.206731) (xy 40.574817 -248.25693) (xy 40.582854 -248.308966)
			(xy 40.583358 -248.335292) (xy 47.440091 -248.335292) (xy 47.444121 -248.282794) (xy 47.456118 -248.231526)
			(xy 47.475801 -248.182691) (xy 47.502707 -248.137432) (xy 47.536207 -248.096811) (xy 47.575515 -248.06178)
			(xy 47.61971 -248.03316) (xy 47.667755 -248.011621) (xy 47.718526 -247.997669) (xy 47.770831 -247.991631)
			(xy 47.823445 -247.993648) (xy 47.875135 -248.003672) (xy 47.924688 -248.02147) (xy 47.970944 -248.046623)
			(xy 48.012818 -248.078542) (xy 48.04933 -248.11648) (xy 48.079622 -248.159546) (xy 48.102985 -248.206731)
			(xy 48.118871 -248.25693) (xy 48.126908 -248.308966) (xy 48.127412 -248.335292) (xy 48.126908 -248.361618)
			(xy 48.118871 -248.413654) (xy 48.102985 -248.463853) (xy 48.079622 -248.511038) (xy 48.04933 -248.554104)
			(xy 48.012818 -248.592042) (xy 47.970944 -248.623961) (xy 47.924688 -248.649114) (xy 47.875135 -248.666912)
			(xy 47.823445 -248.676936) (xy 47.770831 -248.678953) (xy 47.718526 -248.672915) (xy 47.667755 -248.658963)
			(xy 47.61971 -248.637424) (xy 47.575515 -248.608804) (xy 47.536207 -248.573773) (xy 47.502707 -248.533152)
			(xy 47.475801 -248.487893) (xy 47.456118 -248.439058) (xy 47.444121 -248.38779) (xy 47.440091 -248.335292)
			(xy 40.583358 -248.335292) (xy 40.582854 -248.361618) (xy 40.574817 -248.413654) (xy 40.558931 -248.463853)
			(xy 40.535568 -248.511038) (xy 40.505276 -248.554104) (xy 40.468764 -248.592042) (xy 40.42689 -248.623961)
			(xy 40.380634 -248.649114) (xy 40.331081 -248.666912) (xy 40.279391 -248.676936) (xy 40.226777 -248.678953)
			(xy 40.174472 -248.672915) (xy 40.123701 -248.658963) (xy 40.075656 -248.637424) (xy 40.031461 -248.608804)
			(xy 39.992153 -248.573773) (xy 39.958653 -248.533152) (xy 39.931747 -248.487893) (xy 39.912064 -248.439058)
			(xy 39.900067 -248.38779) (xy 39.896037 -248.335292) (xy 33.039304 -248.335292) (xy 33.0388 -248.361618)
			(xy 33.030763 -248.413654) (xy 33.014877 -248.463853) (xy 32.991514 -248.511038) (xy 32.961222 -248.554104)
			(xy 32.92471 -248.592042) (xy 32.882836 -248.623961) (xy 32.83658 -248.649114) (xy 32.787027 -248.666912)
			(xy 32.735337 -248.676936) (xy 32.682723 -248.678953) (xy 32.630418 -248.672915) (xy 32.579647 -248.658963)
			(xy 32.531602 -248.637424) (xy 32.487407 -248.608804) (xy 32.448099 -248.573773) (xy 32.414599 -248.533152)
			(xy 32.387693 -248.487893) (xy 32.36801 -248.439058) (xy 32.356013 -248.38779) (xy 32.351983 -248.335292)
			(xy 25.495504 -248.335292) (xy 25.495 -248.361618) (xy 25.486963 -248.413654) (xy 25.471077 -248.463853)
			(xy 25.447714 -248.511038) (xy 25.417422 -248.554104) (xy 25.38091 -248.592042) (xy 25.339036 -248.623961)
			(xy 25.29278 -248.649114) (xy 25.243227 -248.666912) (xy 25.191537 -248.676936) (xy 25.138923 -248.678953)
			(xy 25.086618 -248.672915) (xy 25.035847 -248.658963) (xy 24.987802 -248.637424) (xy 24.943607 -248.608804)
			(xy 24.904299 -248.573773) (xy 24.870799 -248.533152) (xy 24.843893 -248.487893) (xy 24.82421 -248.439058)
			(xy 24.812213 -248.38779) (xy 24.808183 -248.335292) (xy 17.95145 -248.335292) (xy 17.950946 -248.361618)
			(xy 17.942909 -248.413654) (xy 17.927023 -248.463853) (xy 17.90366 -248.511038) (xy 17.873368 -248.554104)
			(xy 17.836856 -248.592042) (xy 17.794982 -248.623961) (xy 17.748726 -248.649114) (xy 17.699173 -248.666912)
			(xy 17.647483 -248.676936) (xy 17.594869 -248.678953) (xy 17.542564 -248.672915) (xy 17.491793 -248.658963)
			(xy 17.443748 -248.637424) (xy 17.399553 -248.608804) (xy 17.360245 -248.573773) (xy 17.326745 -248.533152)
			(xy 17.299839 -248.487893) (xy 17.280156 -248.439058) (xy 17.268159 -248.38779) (xy 17.264129 -248.335292)
			(xy 16.086074 -248.335292) (xy 16.086074 -249.18543) (xy 21.364197 -249.18543) (xy 21.368227 -249.132932)
			(xy 21.380224 -249.081664) (xy 21.399907 -249.032829) (xy 21.426813 -248.98757) (xy 21.460313 -248.946949)
			(xy 21.499621 -248.911918) (xy 21.543816 -248.883298) (xy 21.591861 -248.861759) (xy 21.642632 -248.847807)
			(xy 21.694937 -248.841769) (xy 21.747551 -248.843786) (xy 21.799241 -248.85381) (xy 21.848794 -248.871608)
			(xy 21.89505 -248.896761) (xy 21.936924 -248.92868) (xy 21.973436 -248.966618) (xy 22.003728 -249.009684)
			(xy 22.027091 -249.056869) (xy 22.042977 -249.107068) (xy 22.051014 -249.159104) (xy 22.051518 -249.18543)
			(xy 28.908251 -249.18543) (xy 28.912281 -249.132932) (xy 28.924278 -249.081664) (xy 28.943961 -249.032829)
			(xy 28.970867 -248.98757) (xy 29.004367 -248.946949) (xy 29.043675 -248.911918) (xy 29.08787 -248.883298)
			(xy 29.135915 -248.861759) (xy 29.186686 -248.847807) (xy 29.238991 -248.841769) (xy 29.291605 -248.843786)
			(xy 29.343295 -248.85381) (xy 29.392848 -248.871608) (xy 29.439104 -248.896761) (xy 29.480978 -248.92868)
			(xy 29.51749 -248.966618) (xy 29.547782 -249.009684) (xy 29.571145 -249.056869) (xy 29.587031 -249.107068)
			(xy 29.595068 -249.159104) (xy 29.595572 -249.18543) (xy 36.452051 -249.18543) (xy 36.456081 -249.132932)
			(xy 36.468078 -249.081664) (xy 36.487761 -249.032829) (xy 36.514667 -248.98757) (xy 36.548167 -248.946949)
			(xy 36.587475 -248.911918) (xy 36.63167 -248.883298) (xy 36.679715 -248.861759) (xy 36.730486 -248.847807)
			(xy 36.782791 -248.841769) (xy 36.835405 -248.843786) (xy 36.887095 -248.85381) (xy 36.936648 -248.871608)
			(xy 36.982904 -248.896761) (xy 37.024778 -248.92868) (xy 37.06129 -248.966618) (xy 37.091582 -249.009684)
			(xy 37.114945 -249.056869) (xy 37.130831 -249.107068) (xy 37.138868 -249.159104) (xy 37.139372 -249.18543)
			(xy 43.996105 -249.18543) (xy 44.000135 -249.132932) (xy 44.012132 -249.081664) (xy 44.031815 -249.032829)
			(xy 44.058721 -248.98757) (xy 44.092221 -248.946949) (xy 44.131529 -248.911918) (xy 44.175724 -248.883298)
			(xy 44.223769 -248.861759) (xy 44.27454 -248.847807) (xy 44.326845 -248.841769) (xy 44.379459 -248.843786)
			(xy 44.431149 -248.85381) (xy 44.480702 -248.871608) (xy 44.526958 -248.896761) (xy 44.568832 -248.92868)
			(xy 44.605344 -248.966618) (xy 44.635636 -249.009684) (xy 44.658999 -249.056869) (xy 44.674885 -249.107068)
			(xy 44.682922 -249.159104) (xy 44.683426 -249.18543) (xy 51.540159 -249.18543) (xy 51.544189 -249.132932)
			(xy 51.556186 -249.081664) (xy 51.575869 -249.032829) (xy 51.602775 -248.98757) (xy 51.636275 -248.946949)
			(xy 51.675583 -248.911918) (xy 51.719778 -248.883298) (xy 51.767823 -248.861759) (xy 51.818594 -248.847807)
			(xy 51.870899 -248.841769) (xy 51.923513 -248.843786) (xy 51.975203 -248.85381) (xy 52.024756 -248.871608)
			(xy 52.071012 -248.896761) (xy 52.112886 -248.92868) (xy 52.149398 -248.966618) (xy 52.17969 -249.009684)
			(xy 52.203053 -249.056869) (xy 52.218939 -249.107068) (xy 52.226976 -249.159104) (xy 52.22748 -249.18543)
			(xy 52.226976 -249.211756) (xy 52.218939 -249.263792) (xy 52.203053 -249.313991) (xy 52.17969 -249.361176)
			(xy 52.149398 -249.404242) (xy 52.112886 -249.44218) (xy 52.071012 -249.474099) (xy 52.024756 -249.499252)
			(xy 51.975203 -249.51705) (xy 51.923513 -249.527074) (xy 51.870899 -249.529091) (xy 51.818594 -249.523053)
			(xy 51.767823 -249.509101) (xy 51.719778 -249.487562) (xy 51.675583 -249.458942) (xy 51.636275 -249.423911)
			(xy 51.602775 -249.38329) (xy 51.575869 -249.338031) (xy 51.556186 -249.289196) (xy 51.544189 -249.237928)
			(xy 51.540159 -249.18543) (xy 44.683426 -249.18543) (xy 44.682922 -249.211756) (xy 44.674885 -249.263792)
			(xy 44.658999 -249.313991) (xy 44.635636 -249.361176) (xy 44.605344 -249.404242) (xy 44.568832 -249.44218)
			(xy 44.526958 -249.474099) (xy 44.480702 -249.499252) (xy 44.431149 -249.51705) (xy 44.379459 -249.527074)
			(xy 44.326845 -249.529091) (xy 44.27454 -249.523053) (xy 44.223769 -249.509101) (xy 44.175724 -249.487562)
			(xy 44.131529 -249.458942) (xy 44.092221 -249.423911) (xy 44.058721 -249.38329) (xy 44.031815 -249.338031)
			(xy 44.012132 -249.289196) (xy 44.000135 -249.237928) (xy 43.996105 -249.18543) (xy 37.139372 -249.18543)
			(xy 37.138868 -249.211756) (xy 37.130831 -249.263792) (xy 37.114945 -249.313991) (xy 37.091582 -249.361176)
			(xy 37.06129 -249.404242) (xy 37.024778 -249.44218) (xy 36.982904 -249.474099) (xy 36.936648 -249.499252)
			(xy 36.887095 -249.51705) (xy 36.835405 -249.527074) (xy 36.782791 -249.529091) (xy 36.730486 -249.523053)
			(xy 36.679715 -249.509101) (xy 36.63167 -249.487562) (xy 36.587475 -249.458942) (xy 36.548167 -249.423911)
			(xy 36.514667 -249.38329) (xy 36.487761 -249.338031) (xy 36.468078 -249.289196) (xy 36.456081 -249.237928)
			(xy 36.452051 -249.18543) (xy 29.595572 -249.18543) (xy 29.595068 -249.211756) (xy 29.587031 -249.263792)
			(xy 29.571145 -249.313991) (xy 29.547782 -249.361176) (xy 29.51749 -249.404242) (xy 29.480978 -249.44218)
			(xy 29.439104 -249.474099) (xy 29.392848 -249.499252) (xy 29.343295 -249.51705) (xy 29.291605 -249.527074)
			(xy 29.238991 -249.529091) (xy 29.186686 -249.523053) (xy 29.135915 -249.509101) (xy 29.08787 -249.487562)
			(xy 29.043675 -249.458942) (xy 29.004367 -249.423911) (xy 28.970867 -249.38329) (xy 28.943961 -249.338031)
			(xy 28.924278 -249.289196) (xy 28.912281 -249.237928) (xy 28.908251 -249.18543) (xy 22.051518 -249.18543)
			(xy 22.051014 -249.211756) (xy 22.042977 -249.263792) (xy 22.027091 -249.313991) (xy 22.003728 -249.361176)
			(xy 21.973436 -249.404242) (xy 21.936924 -249.44218) (xy 21.89505 -249.474099) (xy 21.848794 -249.499252)
			(xy 21.799241 -249.51705) (xy 21.747551 -249.527074) (xy 21.694937 -249.529091) (xy 21.642632 -249.523053)
			(xy 21.591861 -249.509101) (xy 21.543816 -249.487562) (xy 21.499621 -249.458942) (xy 21.460313 -249.423911)
			(xy 21.426813 -249.38329) (xy 21.399907 -249.338031) (xy 21.380224 -249.289196) (xy 21.368227 -249.237928)
			(xy 21.364197 -249.18543) (xy 16.086074 -249.18543) (xy 16.086074 -250.035314) (xy 17.264129 -250.035314)
			(xy 17.268159 -249.982816) (xy 17.280156 -249.931548) (xy 17.299839 -249.882713) (xy 17.326745 -249.837454)
			(xy 17.360245 -249.796833) (xy 17.399553 -249.761802) (xy 17.443748 -249.733182) (xy 17.491793 -249.711643)
			(xy 17.542564 -249.697691) (xy 17.594869 -249.691653) (xy 17.647483 -249.69367) (xy 17.699173 -249.703694)
			(xy 17.748726 -249.721492) (xy 17.794982 -249.746645) (xy 17.836856 -249.778564) (xy 17.873368 -249.816502)
			(xy 17.90366 -249.859568) (xy 17.927023 -249.906753) (xy 17.942909 -249.956952) (xy 17.950946 -250.008988)
			(xy 17.95145 -250.035314) (xy 24.808183 -250.035314) (xy 24.812213 -249.982816) (xy 24.82421 -249.931548)
			(xy 24.843893 -249.882713) (xy 24.870799 -249.837454) (xy 24.904299 -249.796833) (xy 24.943607 -249.761802)
			(xy 24.987802 -249.733182) (xy 25.035847 -249.711643) (xy 25.086618 -249.697691) (xy 25.138923 -249.691653)
			(xy 25.191537 -249.69367) (xy 25.243227 -249.703694) (xy 25.29278 -249.721492) (xy 25.339036 -249.746645)
			(xy 25.38091 -249.778564) (xy 25.417422 -249.816502) (xy 25.447714 -249.859568) (xy 25.471077 -249.906753)
			(xy 25.486963 -249.956952) (xy 25.495 -250.008988) (xy 25.495504 -250.035314) (xy 32.351983 -250.035314)
			(xy 32.356013 -249.982816) (xy 32.36801 -249.931548) (xy 32.387693 -249.882713) (xy 32.414599 -249.837454)
			(xy 32.448099 -249.796833) (xy 32.487407 -249.761802) (xy 32.531602 -249.733182) (xy 32.579647 -249.711643)
			(xy 32.630418 -249.697691) (xy 32.682723 -249.691653) (xy 32.735337 -249.69367) (xy 32.787027 -249.703694)
			(xy 32.83658 -249.721492) (xy 32.882836 -249.746645) (xy 32.92471 -249.778564) (xy 32.961222 -249.816502)
			(xy 32.991514 -249.859568) (xy 33.014877 -249.906753) (xy 33.030763 -249.956952) (xy 33.0388 -250.008988)
			(xy 33.039304 -250.035314) (xy 39.896037 -250.035314) (xy 39.900067 -249.982816) (xy 39.912064 -249.931548)
			(xy 39.931747 -249.882713) (xy 39.958653 -249.837454) (xy 39.992153 -249.796833) (xy 40.031461 -249.761802)
			(xy 40.075656 -249.733182) (xy 40.123701 -249.711643) (xy 40.174472 -249.697691) (xy 40.226777 -249.691653)
			(xy 40.279391 -249.69367) (xy 40.331081 -249.703694) (xy 40.380634 -249.721492) (xy 40.42689 -249.746645)
			(xy 40.468764 -249.778564) (xy 40.505276 -249.816502) (xy 40.535568 -249.859568) (xy 40.558931 -249.906753)
			(xy 40.574817 -249.956952) (xy 40.582854 -250.008988) (xy 40.583358 -250.035314) (xy 47.440091 -250.035314)
			(xy 47.444121 -249.982816) (xy 47.456118 -249.931548) (xy 47.475801 -249.882713) (xy 47.502707 -249.837454)
			(xy 47.536207 -249.796833) (xy 47.575515 -249.761802) (xy 47.61971 -249.733182) (xy 47.667755 -249.711643)
			(xy 47.718526 -249.697691) (xy 47.770831 -249.691653) (xy 47.823445 -249.69367) (xy 47.875135 -249.703694)
			(xy 47.924688 -249.721492) (xy 47.970944 -249.746645) (xy 48.012818 -249.778564) (xy 48.04933 -249.816502)
			(xy 48.079622 -249.859568) (xy 48.102985 -249.906753) (xy 48.118871 -249.956952) (xy 48.126908 -250.008988)
			(xy 48.127412 -250.035314) (xy 48.126908 -250.06164) (xy 48.118871 -250.113676) (xy 48.102985 -250.163875)
			(xy 48.079622 -250.21106) (xy 48.04933 -250.254126) (xy 48.012818 -250.292064) (xy 47.970944 -250.323983)
			(xy 47.924688 -250.349136) (xy 47.875135 -250.366934) (xy 47.823445 -250.376958) (xy 47.770831 -250.378975)
			(xy 47.718526 -250.372937) (xy 47.667755 -250.358985) (xy 47.61971 -250.337446) (xy 47.575515 -250.308826)
			(xy 47.536207 -250.273795) (xy 47.502707 -250.233174) (xy 47.475801 -250.187915) (xy 47.456118 -250.13908)
			(xy 47.444121 -250.087812) (xy 47.440091 -250.035314) (xy 40.583358 -250.035314) (xy 40.582854 -250.06164)
			(xy 40.574817 -250.113676) (xy 40.558931 -250.163875) (xy 40.535568 -250.21106) (xy 40.505276 -250.254126)
			(xy 40.468764 -250.292064) (xy 40.42689 -250.323983) (xy 40.380634 -250.349136) (xy 40.331081 -250.366934)
			(xy 40.279391 -250.376958) (xy 40.226777 -250.378975) (xy 40.174472 -250.372937) (xy 40.123701 -250.358985)
			(xy 40.075656 -250.337446) (xy 40.031461 -250.308826) (xy 39.992153 -250.273795) (xy 39.958653 -250.233174)
			(xy 39.931747 -250.187915) (xy 39.912064 -250.13908) (xy 39.900067 -250.087812) (xy 39.896037 -250.035314)
			(xy 33.039304 -250.035314) (xy 33.0388 -250.06164) (xy 33.030763 -250.113676) (xy 33.014877 -250.163875)
			(xy 32.991514 -250.21106) (xy 32.961222 -250.254126) (xy 32.92471 -250.292064) (xy 32.882836 -250.323983)
			(xy 32.83658 -250.349136) (xy 32.787027 -250.366934) (xy 32.735337 -250.376958) (xy 32.682723 -250.378975)
			(xy 32.630418 -250.372937) (xy 32.579647 -250.358985) (xy 32.531602 -250.337446) (xy 32.487407 -250.308826)
			(xy 32.448099 -250.273795) (xy 32.414599 -250.233174) (xy 32.387693 -250.187915) (xy 32.36801 -250.13908)
			(xy 32.356013 -250.087812) (xy 32.351983 -250.035314) (xy 25.495504 -250.035314) (xy 25.495 -250.06164)
			(xy 25.486963 -250.113676) (xy 25.471077 -250.163875) (xy 25.447714 -250.21106) (xy 25.417422 -250.254126)
			(xy 25.38091 -250.292064) (xy 25.339036 -250.323983) (xy 25.29278 -250.349136) (xy 25.243227 -250.366934)
			(xy 25.191537 -250.376958) (xy 25.138923 -250.378975) (xy 25.086618 -250.372937) (xy 25.035847 -250.358985)
			(xy 24.987802 -250.337446) (xy 24.943607 -250.308826) (xy 24.904299 -250.273795) (xy 24.870799 -250.233174)
			(xy 24.843893 -250.187915) (xy 24.82421 -250.13908) (xy 24.812213 -250.087812) (xy 24.808183 -250.035314)
			(xy 17.95145 -250.035314) (xy 17.950946 -250.06164) (xy 17.942909 -250.113676) (xy 17.927023 -250.163875)
			(xy 17.90366 -250.21106) (xy 17.873368 -250.254126) (xy 17.836856 -250.292064) (xy 17.794982 -250.323983)
			(xy 17.748726 -250.349136) (xy 17.699173 -250.366934) (xy 17.647483 -250.376958) (xy 17.594869 -250.378975)
			(xy 17.542564 -250.372937) (xy 17.491793 -250.358985) (xy 17.443748 -250.337446) (xy 17.399553 -250.308826)
			(xy 17.360245 -250.273795) (xy 17.326745 -250.233174) (xy 17.299839 -250.187915) (xy 17.280156 -250.13908)
			(xy 17.268159 -250.087812) (xy 17.264129 -250.035314) (xy 16.086074 -250.035314) (xy 16.086074 -250.885198)
			(xy 21.364197 -250.885198) (xy 21.368227 -250.8327) (xy 21.380224 -250.781432) (xy 21.399907 -250.732597)
			(xy 21.426813 -250.687338) (xy 21.460313 -250.646717) (xy 21.499621 -250.611686) (xy 21.543816 -250.583066)
			(xy 21.591861 -250.561527) (xy 21.642632 -250.547575) (xy 21.694937 -250.541537) (xy 21.747551 -250.543554)
			(xy 21.799241 -250.553578) (xy 21.848794 -250.571376) (xy 21.89505 -250.596529) (xy 21.936924 -250.628448)
			(xy 21.973436 -250.666386) (xy 22.003728 -250.709452) (xy 22.027091 -250.756637) (xy 22.042977 -250.806836)
			(xy 22.051014 -250.858872) (xy 22.051518 -250.885198) (xy 28.908251 -250.885198) (xy 28.912281 -250.8327)
			(xy 28.924278 -250.781432) (xy 28.943961 -250.732597) (xy 28.970867 -250.687338) (xy 29.004367 -250.646717)
			(xy 29.043675 -250.611686) (xy 29.08787 -250.583066) (xy 29.135915 -250.561527) (xy 29.186686 -250.547575)
			(xy 29.238991 -250.541537) (xy 29.291605 -250.543554) (xy 29.343295 -250.553578) (xy 29.392848 -250.571376)
			(xy 29.439104 -250.596529) (xy 29.480978 -250.628448) (xy 29.51749 -250.666386) (xy 29.547782 -250.709452)
			(xy 29.571145 -250.756637) (xy 29.587031 -250.806836) (xy 29.595068 -250.858872) (xy 29.595572 -250.885198)
			(xy 36.452051 -250.885198) (xy 36.456081 -250.8327) (xy 36.468078 -250.781432) (xy 36.487761 -250.732597)
			(xy 36.514667 -250.687338) (xy 36.548167 -250.646717) (xy 36.587475 -250.611686) (xy 36.63167 -250.583066)
			(xy 36.679715 -250.561527) (xy 36.730486 -250.547575) (xy 36.782791 -250.541537) (xy 36.835405 -250.543554)
			(xy 36.887095 -250.553578) (xy 36.936648 -250.571376) (xy 36.982904 -250.596529) (xy 37.024778 -250.628448)
			(xy 37.06129 -250.666386) (xy 37.091582 -250.709452) (xy 37.114945 -250.756637) (xy 37.130831 -250.806836)
			(xy 37.138868 -250.858872) (xy 37.139372 -250.885198) (xy 43.996105 -250.885198) (xy 44.000135 -250.8327)
			(xy 44.012132 -250.781432) (xy 44.031815 -250.732597) (xy 44.058721 -250.687338) (xy 44.092221 -250.646717)
			(xy 44.131529 -250.611686) (xy 44.175724 -250.583066) (xy 44.223769 -250.561527) (xy 44.27454 -250.547575)
			(xy 44.326845 -250.541537) (xy 44.379459 -250.543554) (xy 44.431149 -250.553578) (xy 44.480702 -250.571376)
			(xy 44.526958 -250.596529) (xy 44.568832 -250.628448) (xy 44.605344 -250.666386) (xy 44.635636 -250.709452)
			(xy 44.658999 -250.756637) (xy 44.674885 -250.806836) (xy 44.682922 -250.858872) (xy 44.683426 -250.885198)
			(xy 51.540159 -250.885198) (xy 51.544189 -250.8327) (xy 51.556186 -250.781432) (xy 51.575869 -250.732597)
			(xy 51.602775 -250.687338) (xy 51.636275 -250.646717) (xy 51.675583 -250.611686) (xy 51.719778 -250.583066)
			(xy 51.767823 -250.561527) (xy 51.818594 -250.547575) (xy 51.870899 -250.541537) (xy 51.923513 -250.543554)
			(xy 51.975203 -250.553578) (xy 52.024756 -250.571376) (xy 52.071012 -250.596529) (xy 52.112886 -250.628448)
			(xy 52.149398 -250.666386) (xy 52.17969 -250.709452) (xy 52.203053 -250.756637) (xy 52.218939 -250.806836)
			(xy 52.226976 -250.858872) (xy 52.22748 -250.885198) (xy 52.226976 -250.911524) (xy 52.218939 -250.96356)
			(xy 52.203053 -251.013759) (xy 52.17969 -251.060944) (xy 52.149398 -251.10401) (xy 52.112886 -251.141948)
			(xy 52.071012 -251.173867) (xy 52.024756 -251.19902) (xy 51.975203 -251.216818) (xy 51.923513 -251.226842)
			(xy 51.870899 -251.228859) (xy 51.818594 -251.222821) (xy 51.767823 -251.208869) (xy 51.719778 -251.18733)
			(xy 51.675583 -251.15871) (xy 51.636275 -251.123679) (xy 51.602775 -251.083058) (xy 51.575869 -251.037799)
			(xy 51.556186 -250.988964) (xy 51.544189 -250.937696) (xy 51.540159 -250.885198) (xy 44.683426 -250.885198)
			(xy 44.682922 -250.911524) (xy 44.674885 -250.96356) (xy 44.658999 -251.013759) (xy 44.635636 -251.060944)
			(xy 44.605344 -251.10401) (xy 44.568832 -251.141948) (xy 44.526958 -251.173867) (xy 44.480702 -251.19902)
			(xy 44.431149 -251.216818) (xy 44.379459 -251.226842) (xy 44.326845 -251.228859) (xy 44.27454 -251.222821)
			(xy 44.223769 -251.208869) (xy 44.175724 -251.18733) (xy 44.131529 -251.15871) (xy 44.092221 -251.123679)
			(xy 44.058721 -251.083058) (xy 44.031815 -251.037799) (xy 44.012132 -250.988964) (xy 44.000135 -250.937696)
			(xy 43.996105 -250.885198) (xy 37.139372 -250.885198) (xy 37.138868 -250.911524) (xy 37.130831 -250.96356)
			(xy 37.114945 -251.013759) (xy 37.091582 -251.060944) (xy 37.06129 -251.10401) (xy 37.024778 -251.141948)
			(xy 36.982904 -251.173867) (xy 36.936648 -251.19902) (xy 36.887095 -251.216818) (xy 36.835405 -251.226842)
			(xy 36.782791 -251.228859) (xy 36.730486 -251.222821) (xy 36.679715 -251.208869) (xy 36.63167 -251.18733)
			(xy 36.587475 -251.15871) (xy 36.548167 -251.123679) (xy 36.514667 -251.083058) (xy 36.487761 -251.037799)
			(xy 36.468078 -250.988964) (xy 36.456081 -250.937696) (xy 36.452051 -250.885198) (xy 29.595572 -250.885198)
			(xy 29.595068 -250.911524) (xy 29.587031 -250.96356) (xy 29.571145 -251.013759) (xy 29.547782 -251.060944)
			(xy 29.51749 -251.10401) (xy 29.480978 -251.141948) (xy 29.439104 -251.173867) (xy 29.392848 -251.19902)
			(xy 29.343295 -251.216818) (xy 29.291605 -251.226842) (xy 29.238991 -251.228859) (xy 29.186686 -251.222821)
			(xy 29.135915 -251.208869) (xy 29.08787 -251.18733) (xy 29.043675 -251.15871) (xy 29.004367 -251.123679)
			(xy 28.970867 -251.083058) (xy 28.943961 -251.037799) (xy 28.924278 -250.988964) (xy 28.912281 -250.937696)
			(xy 28.908251 -250.885198) (xy 22.051518 -250.885198) (xy 22.051014 -250.911524) (xy 22.042977 -250.96356)
			(xy 22.027091 -251.013759) (xy 22.003728 -251.060944) (xy 21.973436 -251.10401) (xy 21.936924 -251.141948)
			(xy 21.89505 -251.173867) (xy 21.848794 -251.19902) (xy 21.799241 -251.216818) (xy 21.747551 -251.226842)
			(xy 21.694937 -251.228859) (xy 21.642632 -251.222821) (xy 21.591861 -251.208869) (xy 21.543816 -251.18733)
			(xy 21.499621 -251.15871) (xy 21.460313 -251.123679) (xy 21.426813 -251.083058) (xy 21.399907 -251.037799)
			(xy 21.380224 -250.988964) (xy 21.368227 -250.937696) (xy 21.364197 -250.885198) (xy 16.086074 -250.885198)
			(xy 16.086074 -251.735336) (xy 17.264129 -251.735336) (xy 17.268159 -251.682838) (xy 17.280156 -251.63157)
			(xy 17.299839 -251.582735) (xy 17.326745 -251.537476) (xy 17.360245 -251.496855) (xy 17.399553 -251.461824)
			(xy 17.443748 -251.433204) (xy 17.491793 -251.411665) (xy 17.542564 -251.397713) (xy 17.594869 -251.391675)
			(xy 17.647483 -251.393692) (xy 17.699173 -251.403716) (xy 17.748726 -251.421514) (xy 17.794982 -251.446667)
			(xy 17.836856 -251.478586) (xy 17.873368 -251.516524) (xy 17.90366 -251.55959) (xy 17.927023 -251.606775)
			(xy 17.942909 -251.656974) (xy 17.950946 -251.70901) (xy 17.95145 -251.735336) (xy 24.808183 -251.735336)
			(xy 24.812213 -251.682838) (xy 24.82421 -251.63157) (xy 24.843893 -251.582735) (xy 24.870799 -251.537476)
			(xy 24.904299 -251.496855) (xy 24.943607 -251.461824) (xy 24.987802 -251.433204) (xy 25.035847 -251.411665)
			(xy 25.086618 -251.397713) (xy 25.138923 -251.391675) (xy 25.191537 -251.393692) (xy 25.243227 -251.403716)
			(xy 25.29278 -251.421514) (xy 25.339036 -251.446667) (xy 25.38091 -251.478586) (xy 25.417422 -251.516524)
			(xy 25.447714 -251.55959) (xy 25.471077 -251.606775) (xy 25.486963 -251.656974) (xy 25.495 -251.70901)
			(xy 25.495504 -251.735336) (xy 32.351983 -251.735336) (xy 32.356013 -251.682838) (xy 32.36801 -251.63157)
			(xy 32.387693 -251.582735) (xy 32.414599 -251.537476) (xy 32.448099 -251.496855) (xy 32.487407 -251.461824)
			(xy 32.531602 -251.433204) (xy 32.579647 -251.411665) (xy 32.630418 -251.397713) (xy 32.682723 -251.391675)
			(xy 32.735337 -251.393692) (xy 32.787027 -251.403716) (xy 32.83658 -251.421514) (xy 32.882836 -251.446667)
			(xy 32.92471 -251.478586) (xy 32.961222 -251.516524) (xy 32.991514 -251.55959) (xy 33.014877 -251.606775)
			(xy 33.030763 -251.656974) (xy 33.0388 -251.70901) (xy 33.039304 -251.735336) (xy 39.896037 -251.735336)
			(xy 39.900067 -251.682838) (xy 39.912064 -251.63157) (xy 39.931747 -251.582735) (xy 39.958653 -251.537476)
			(xy 39.992153 -251.496855) (xy 40.031461 -251.461824) (xy 40.075656 -251.433204) (xy 40.123701 -251.411665)
			(xy 40.174472 -251.397713) (xy 40.226777 -251.391675) (xy 40.279391 -251.393692) (xy 40.331081 -251.403716)
			(xy 40.380634 -251.421514) (xy 40.42689 -251.446667) (xy 40.468764 -251.478586) (xy 40.505276 -251.516524)
			(xy 40.535568 -251.55959) (xy 40.558931 -251.606775) (xy 40.574817 -251.656974) (xy 40.582854 -251.70901)
			(xy 40.583358 -251.735336) (xy 47.440091 -251.735336) (xy 47.444121 -251.682838) (xy 47.456118 -251.63157)
			(xy 47.475801 -251.582735) (xy 47.502707 -251.537476) (xy 47.536207 -251.496855) (xy 47.575515 -251.461824)
			(xy 47.61971 -251.433204) (xy 47.667755 -251.411665) (xy 47.718526 -251.397713) (xy 47.770831 -251.391675)
			(xy 47.823445 -251.393692) (xy 47.875135 -251.403716) (xy 47.924688 -251.421514) (xy 47.970944 -251.446667)
			(xy 48.012818 -251.478586) (xy 48.04933 -251.516524) (xy 48.079622 -251.55959) (xy 48.102985 -251.606775)
			(xy 48.118871 -251.656974) (xy 48.126908 -251.70901) (xy 48.127412 -251.735336) (xy 48.126908 -251.761662)
			(xy 48.118871 -251.813698) (xy 48.102985 -251.863897) (xy 48.079622 -251.911082) (xy 48.04933 -251.954148)
			(xy 48.012818 -251.992086) (xy 47.970944 -252.024005) (xy 47.924688 -252.049158) (xy 47.875135 -252.066956)
			(xy 47.823445 -252.07698) (xy 47.770831 -252.078997) (xy 47.718526 -252.072959) (xy 47.667755 -252.059007)
			(xy 47.61971 -252.037468) (xy 47.575515 -252.008848) (xy 47.536207 -251.973817) (xy 47.502707 -251.933196)
			(xy 47.475801 -251.887937) (xy 47.456118 -251.839102) (xy 47.444121 -251.787834) (xy 47.440091 -251.735336)
			(xy 40.583358 -251.735336) (xy 40.582854 -251.761662) (xy 40.574817 -251.813698) (xy 40.558931 -251.863897)
			(xy 40.535568 -251.911082) (xy 40.505276 -251.954148) (xy 40.468764 -251.992086) (xy 40.42689 -252.024005)
			(xy 40.380634 -252.049158) (xy 40.331081 -252.066956) (xy 40.279391 -252.07698) (xy 40.226777 -252.078997)
			(xy 40.174472 -252.072959) (xy 40.123701 -252.059007) (xy 40.075656 -252.037468) (xy 40.031461 -252.008848)
			(xy 39.992153 -251.973817) (xy 39.958653 -251.933196) (xy 39.931747 -251.887937) (xy 39.912064 -251.839102)
			(xy 39.900067 -251.787834) (xy 39.896037 -251.735336) (xy 33.039304 -251.735336) (xy 33.0388 -251.761662)
			(xy 33.030763 -251.813698) (xy 33.014877 -251.863897) (xy 32.991514 -251.911082) (xy 32.961222 -251.954148)
			(xy 32.92471 -251.992086) (xy 32.882836 -252.024005) (xy 32.83658 -252.049158) (xy 32.787027 -252.066956)
			(xy 32.735337 -252.07698) (xy 32.682723 -252.078997) (xy 32.630418 -252.072959) (xy 32.579647 -252.059007)
			(xy 32.531602 -252.037468) (xy 32.487407 -252.008848) (xy 32.448099 -251.973817) (xy 32.414599 -251.933196)
			(xy 32.387693 -251.887937) (xy 32.36801 -251.839102) (xy 32.356013 -251.787834) (xy 32.351983 -251.735336)
			(xy 25.495504 -251.735336) (xy 25.495 -251.761662) (xy 25.486963 -251.813698) (xy 25.471077 -251.863897)
			(xy 25.447714 -251.911082) (xy 25.417422 -251.954148) (xy 25.38091 -251.992086) (xy 25.339036 -252.024005)
			(xy 25.29278 -252.049158) (xy 25.243227 -252.066956) (xy 25.191537 -252.07698) (xy 25.138923 -252.078997)
			(xy 25.086618 -252.072959) (xy 25.035847 -252.059007) (xy 24.987802 -252.037468) (xy 24.943607 -252.008848)
			(xy 24.904299 -251.973817) (xy 24.870799 -251.933196) (xy 24.843893 -251.887937) (xy 24.82421 -251.839102)
			(xy 24.812213 -251.787834) (xy 24.808183 -251.735336) (xy 17.95145 -251.735336) (xy 17.950946 -251.761662)
			(xy 17.942909 -251.813698) (xy 17.927023 -251.863897) (xy 17.90366 -251.911082) (xy 17.873368 -251.954148)
			(xy 17.836856 -251.992086) (xy 17.794982 -252.024005) (xy 17.748726 -252.049158) (xy 17.699173 -252.066956)
			(xy 17.647483 -252.07698) (xy 17.594869 -252.078997) (xy 17.542564 -252.072959) (xy 17.491793 -252.059007)
			(xy 17.443748 -252.037468) (xy 17.399553 -252.008848) (xy 17.360245 -251.973817) (xy 17.326745 -251.933196)
			(xy 17.299839 -251.887937) (xy 17.280156 -251.839102) (xy 17.268159 -251.787834) (xy 17.264129 -251.735336)
			(xy 16.086074 -251.735336) (xy 16.086074 -252.58522) (xy 21.364197 -252.58522) (xy 21.368227 -252.532722)
			(xy 21.380224 -252.481454) (xy 21.399907 -252.432619) (xy 21.426813 -252.38736) (xy 21.460313 -252.346739)
			(xy 21.499621 -252.311708) (xy 21.543816 -252.283088) (xy 21.591861 -252.261549) (xy 21.642632 -252.247597)
			(xy 21.694937 -252.241559) (xy 21.747551 -252.243576) (xy 21.799241 -252.2536) (xy 21.848794 -252.271398)
			(xy 21.89505 -252.296551) (xy 21.936924 -252.32847) (xy 21.973436 -252.366408) (xy 22.003728 -252.409474)
			(xy 22.027091 -252.456659) (xy 22.042977 -252.506858) (xy 22.051014 -252.558894) (xy 22.051518 -252.58522)
			(xy 28.908251 -252.58522) (xy 28.912281 -252.532722) (xy 28.924278 -252.481454) (xy 28.943961 -252.432619)
			(xy 28.970867 -252.38736) (xy 29.004367 -252.346739) (xy 29.043675 -252.311708) (xy 29.08787 -252.283088)
			(xy 29.135915 -252.261549) (xy 29.186686 -252.247597) (xy 29.238991 -252.241559) (xy 29.291605 -252.243576)
			(xy 29.343295 -252.2536) (xy 29.392848 -252.271398) (xy 29.439104 -252.296551) (xy 29.480978 -252.32847)
			(xy 29.51749 -252.366408) (xy 29.547782 -252.409474) (xy 29.571145 -252.456659) (xy 29.587031 -252.506858)
			(xy 29.595068 -252.558894) (xy 29.595572 -252.58522) (xy 36.452051 -252.58522) (xy 36.456081 -252.532722)
			(xy 36.468078 -252.481454) (xy 36.487761 -252.432619) (xy 36.514667 -252.38736) (xy 36.548167 -252.346739)
			(xy 36.587475 -252.311708) (xy 36.63167 -252.283088) (xy 36.679715 -252.261549) (xy 36.730486 -252.247597)
			(xy 36.782791 -252.241559) (xy 36.835405 -252.243576) (xy 36.887095 -252.2536) (xy 36.936648 -252.271398)
			(xy 36.982904 -252.296551) (xy 37.024778 -252.32847) (xy 37.06129 -252.366408) (xy 37.091582 -252.409474)
			(xy 37.114945 -252.456659) (xy 37.130831 -252.506858) (xy 37.138868 -252.558894) (xy 37.139372 -252.58522)
			(xy 43.996105 -252.58522) (xy 44.000135 -252.532722) (xy 44.012132 -252.481454) (xy 44.031815 -252.432619)
			(xy 44.058721 -252.38736) (xy 44.092221 -252.346739) (xy 44.131529 -252.311708) (xy 44.175724 -252.283088)
			(xy 44.223769 -252.261549) (xy 44.27454 -252.247597) (xy 44.326845 -252.241559) (xy 44.379459 -252.243576)
			(xy 44.431149 -252.2536) (xy 44.480702 -252.271398) (xy 44.526958 -252.296551) (xy 44.568832 -252.32847)
			(xy 44.605344 -252.366408) (xy 44.635636 -252.409474) (xy 44.658999 -252.456659) (xy 44.674885 -252.506858)
			(xy 44.682922 -252.558894) (xy 44.683426 -252.58522) (xy 51.540159 -252.58522) (xy 51.544189 -252.532722)
			(xy 51.556186 -252.481454) (xy 51.575869 -252.432619) (xy 51.602775 -252.38736) (xy 51.636275 -252.346739)
			(xy 51.675583 -252.311708) (xy 51.719778 -252.283088) (xy 51.767823 -252.261549) (xy 51.818594 -252.247597)
			(xy 51.870899 -252.241559) (xy 51.923513 -252.243576) (xy 51.975203 -252.2536) (xy 52.024756 -252.271398)
			(xy 52.071012 -252.296551) (xy 52.112886 -252.32847) (xy 52.149398 -252.366408) (xy 52.17969 -252.409474)
			(xy 52.203053 -252.456659) (xy 52.218939 -252.506858) (xy 52.226976 -252.558894) (xy 52.22748 -252.58522)
			(xy 52.226976 -252.611546) (xy 52.218939 -252.663582) (xy 52.203053 -252.713781) (xy 52.17969 -252.760966)
			(xy 52.149398 -252.804032) (xy 52.112886 -252.84197) (xy 52.071012 -252.873889) (xy 52.024756 -252.899042)
			(xy 51.975203 -252.91684) (xy 51.923513 -252.926864) (xy 51.870899 -252.928881) (xy 51.818594 -252.922843)
			(xy 51.767823 -252.908891) (xy 51.719778 -252.887352) (xy 51.675583 -252.858732) (xy 51.636275 -252.823701)
			(xy 51.602775 -252.78308) (xy 51.575869 -252.737821) (xy 51.556186 -252.688986) (xy 51.544189 -252.637718)
			(xy 51.540159 -252.58522) (xy 44.683426 -252.58522) (xy 44.682922 -252.611546) (xy 44.674885 -252.663582)
			(xy 44.658999 -252.713781) (xy 44.635636 -252.760966) (xy 44.605344 -252.804032) (xy 44.568832 -252.84197)
			(xy 44.526958 -252.873889) (xy 44.480702 -252.899042) (xy 44.431149 -252.91684) (xy 44.379459 -252.926864)
			(xy 44.326845 -252.928881) (xy 44.27454 -252.922843) (xy 44.223769 -252.908891) (xy 44.175724 -252.887352)
			(xy 44.131529 -252.858732) (xy 44.092221 -252.823701) (xy 44.058721 -252.78308) (xy 44.031815 -252.737821)
			(xy 44.012132 -252.688986) (xy 44.000135 -252.637718) (xy 43.996105 -252.58522) (xy 37.139372 -252.58522)
			(xy 37.138868 -252.611546) (xy 37.130831 -252.663582) (xy 37.114945 -252.713781) (xy 37.091582 -252.760966)
			(xy 37.06129 -252.804032) (xy 37.024778 -252.84197) (xy 36.982904 -252.873889) (xy 36.936648 -252.899042)
			(xy 36.887095 -252.91684) (xy 36.835405 -252.926864) (xy 36.782791 -252.928881) (xy 36.730486 -252.922843)
			(xy 36.679715 -252.908891) (xy 36.63167 -252.887352) (xy 36.587475 -252.858732) (xy 36.548167 -252.823701)
			(xy 36.514667 -252.78308) (xy 36.487761 -252.737821) (xy 36.468078 -252.688986) (xy 36.456081 -252.637718)
			(xy 36.452051 -252.58522) (xy 29.595572 -252.58522) (xy 29.595068 -252.611546) (xy 29.587031 -252.663582)
			(xy 29.571145 -252.713781) (xy 29.547782 -252.760966) (xy 29.51749 -252.804032) (xy 29.480978 -252.84197)
			(xy 29.439104 -252.873889) (xy 29.392848 -252.899042) (xy 29.343295 -252.91684) (xy 29.291605 -252.926864)
			(xy 29.238991 -252.928881) (xy 29.186686 -252.922843) (xy 29.135915 -252.908891) (xy 29.08787 -252.887352)
			(xy 29.043675 -252.858732) (xy 29.004367 -252.823701) (xy 28.970867 -252.78308) (xy 28.943961 -252.737821)
			(xy 28.924278 -252.688986) (xy 28.912281 -252.637718) (xy 28.908251 -252.58522) (xy 22.051518 -252.58522)
			(xy 22.051014 -252.611546) (xy 22.042977 -252.663582) (xy 22.027091 -252.713781) (xy 22.003728 -252.760966)
			(xy 21.973436 -252.804032) (xy 21.936924 -252.84197) (xy 21.89505 -252.873889) (xy 21.848794 -252.899042)
			(xy 21.799241 -252.91684) (xy 21.747551 -252.926864) (xy 21.694937 -252.928881) (xy 21.642632 -252.922843)
			(xy 21.591861 -252.908891) (xy 21.543816 -252.887352) (xy 21.499621 -252.858732) (xy 21.460313 -252.823701)
			(xy 21.426813 -252.78308) (xy 21.399907 -252.737821) (xy 21.380224 -252.688986) (xy 21.368227 -252.637718)
			(xy 21.364197 -252.58522) (xy 16.086074 -252.58522) (xy 16.086074 -253.435358) (xy 17.264129 -253.435358)
			(xy 17.268159 -253.38286) (xy 17.280156 -253.331592) (xy 17.299839 -253.282757) (xy 17.326745 -253.237498)
			(xy 17.360245 -253.196877) (xy 17.399553 -253.161846) (xy 17.443748 -253.133226) (xy 17.491793 -253.111687)
			(xy 17.542564 -253.097735) (xy 17.594869 -253.091697) (xy 17.647483 -253.093714) (xy 17.699173 -253.103738)
			(xy 17.748726 -253.121536) (xy 17.794982 -253.146689) (xy 17.836856 -253.178608) (xy 17.873368 -253.216546)
			(xy 17.90366 -253.259612) (xy 17.927023 -253.306797) (xy 17.942909 -253.356996) (xy 17.950946 -253.409032)
			(xy 17.95145 -253.435358) (xy 24.808183 -253.435358) (xy 24.812213 -253.38286) (xy 24.82421 -253.331592)
			(xy 24.843893 -253.282757) (xy 24.870799 -253.237498) (xy 24.904299 -253.196877) (xy 24.943607 -253.161846)
			(xy 24.987802 -253.133226) (xy 25.035847 -253.111687) (xy 25.086618 -253.097735) (xy 25.138923 -253.091697)
			(xy 25.191537 -253.093714) (xy 25.243227 -253.103738) (xy 25.29278 -253.121536) (xy 25.339036 -253.146689)
			(xy 25.38091 -253.178608) (xy 25.417422 -253.216546) (xy 25.447714 -253.259612) (xy 25.471077 -253.306797)
			(xy 25.486963 -253.356996) (xy 25.495 -253.409032) (xy 25.495504 -253.435358) (xy 32.351983 -253.435358)
			(xy 32.356013 -253.38286) (xy 32.36801 -253.331592) (xy 32.387693 -253.282757) (xy 32.414599 -253.237498)
			(xy 32.448099 -253.196877) (xy 32.487407 -253.161846) (xy 32.531602 -253.133226) (xy 32.579647 -253.111687)
			(xy 32.630418 -253.097735) (xy 32.682723 -253.091697) (xy 32.735337 -253.093714) (xy 32.787027 -253.103738)
			(xy 32.83658 -253.121536) (xy 32.882836 -253.146689) (xy 32.92471 -253.178608) (xy 32.961222 -253.216546)
			(xy 32.991514 -253.259612) (xy 33.014877 -253.306797) (xy 33.030763 -253.356996) (xy 33.0388 -253.409032)
			(xy 33.039304 -253.435358) (xy 39.896037 -253.435358) (xy 39.900067 -253.38286) (xy 39.912064 -253.331592)
			(xy 39.931747 -253.282757) (xy 39.958653 -253.237498) (xy 39.992153 -253.196877) (xy 40.031461 -253.161846)
			(xy 40.075656 -253.133226) (xy 40.123701 -253.111687) (xy 40.174472 -253.097735) (xy 40.226777 -253.091697)
			(xy 40.279391 -253.093714) (xy 40.331081 -253.103738) (xy 40.380634 -253.121536) (xy 40.42689 -253.146689)
			(xy 40.468764 -253.178608) (xy 40.505276 -253.216546) (xy 40.535568 -253.259612) (xy 40.558931 -253.306797)
			(xy 40.574817 -253.356996) (xy 40.582854 -253.409032) (xy 40.583358 -253.435358) (xy 47.440091 -253.435358)
			(xy 47.444121 -253.38286) (xy 47.456118 -253.331592) (xy 47.475801 -253.282757) (xy 47.502707 -253.237498)
			(xy 47.536207 -253.196877) (xy 47.575515 -253.161846) (xy 47.61971 -253.133226) (xy 47.667755 -253.111687)
			(xy 47.718526 -253.097735) (xy 47.770831 -253.091697) (xy 47.823445 -253.093714) (xy 47.875135 -253.103738)
			(xy 47.924688 -253.121536) (xy 47.970944 -253.146689) (xy 48.012818 -253.178608) (xy 48.04933 -253.216546)
			(xy 48.079622 -253.259612) (xy 48.102985 -253.306797) (xy 48.118871 -253.356996) (xy 48.126908 -253.409032)
			(xy 48.127412 -253.435358) (xy 48.126908 -253.461684) (xy 48.118871 -253.51372) (xy 48.102985 -253.563919)
			(xy 48.079622 -253.611104) (xy 48.04933 -253.65417) (xy 48.012818 -253.692108) (xy 47.970944 -253.724027)
			(xy 47.924688 -253.74918) (xy 47.875135 -253.766978) (xy 47.823445 -253.777002) (xy 47.770831 -253.779019)
			(xy 47.718526 -253.772981) (xy 47.667755 -253.759029) (xy 47.61971 -253.73749) (xy 47.575515 -253.70887)
			(xy 47.536207 -253.673839) (xy 47.502707 -253.633218) (xy 47.475801 -253.587959) (xy 47.456118 -253.539124)
			(xy 47.444121 -253.487856) (xy 47.440091 -253.435358) (xy 40.583358 -253.435358) (xy 40.582854 -253.461684)
			(xy 40.574817 -253.51372) (xy 40.558931 -253.563919) (xy 40.535568 -253.611104) (xy 40.505276 -253.65417)
			(xy 40.468764 -253.692108) (xy 40.42689 -253.724027) (xy 40.380634 -253.74918) (xy 40.331081 -253.766978)
			(xy 40.279391 -253.777002) (xy 40.226777 -253.779019) (xy 40.174472 -253.772981) (xy 40.123701 -253.759029)
			(xy 40.075656 -253.73749) (xy 40.031461 -253.70887) (xy 39.992153 -253.673839) (xy 39.958653 -253.633218)
			(xy 39.931747 -253.587959) (xy 39.912064 -253.539124) (xy 39.900067 -253.487856) (xy 39.896037 -253.435358)
			(xy 33.039304 -253.435358) (xy 33.0388 -253.461684) (xy 33.030763 -253.51372) (xy 33.014877 -253.563919)
			(xy 32.991514 -253.611104) (xy 32.961222 -253.65417) (xy 32.92471 -253.692108) (xy 32.882836 -253.724027)
			(xy 32.83658 -253.74918) (xy 32.787027 -253.766978) (xy 32.735337 -253.777002) (xy 32.682723 -253.779019)
			(xy 32.630418 -253.772981) (xy 32.579647 -253.759029) (xy 32.531602 -253.73749) (xy 32.487407 -253.70887)
			(xy 32.448099 -253.673839) (xy 32.414599 -253.633218) (xy 32.387693 -253.587959) (xy 32.36801 -253.539124)
			(xy 32.356013 -253.487856) (xy 32.351983 -253.435358) (xy 25.495504 -253.435358) (xy 25.495 -253.461684)
			(xy 25.486963 -253.51372) (xy 25.471077 -253.563919) (xy 25.447714 -253.611104) (xy 25.417422 -253.65417)
			(xy 25.38091 -253.692108) (xy 25.339036 -253.724027) (xy 25.29278 -253.74918) (xy 25.243227 -253.766978)
			(xy 25.191537 -253.777002) (xy 25.138923 -253.779019) (xy 25.086618 -253.772981) (xy 25.035847 -253.759029)
			(xy 24.987802 -253.73749) (xy 24.943607 -253.70887) (xy 24.904299 -253.673839) (xy 24.870799 -253.633218)
			(xy 24.843893 -253.587959) (xy 24.82421 -253.539124) (xy 24.812213 -253.487856) (xy 24.808183 -253.435358)
			(xy 17.95145 -253.435358) (xy 17.950946 -253.461684) (xy 17.942909 -253.51372) (xy 17.927023 -253.563919)
			(xy 17.90366 -253.611104) (xy 17.873368 -253.65417) (xy 17.836856 -253.692108) (xy 17.794982 -253.724027)
			(xy 17.748726 -253.74918) (xy 17.699173 -253.766978) (xy 17.647483 -253.777002) (xy 17.594869 -253.779019)
			(xy 17.542564 -253.772981) (xy 17.491793 -253.759029) (xy 17.443748 -253.73749) (xy 17.399553 -253.70887)
			(xy 17.360245 -253.673839) (xy 17.326745 -253.633218) (xy 17.299839 -253.587959) (xy 17.280156 -253.539124)
			(xy 17.268159 -253.487856) (xy 17.264129 -253.435358) (xy 16.086074 -253.435358) (xy 16.086074 -254.285242)
			(xy 17.264129 -254.285242) (xy 17.268159 -254.232744) (xy 17.280156 -254.181476) (xy 17.299839 -254.132641)
			(xy 17.326745 -254.087382) (xy 17.360245 -254.046761) (xy 17.399553 -254.01173) (xy 17.443748 -253.98311)
			(xy 17.491793 -253.961571) (xy 17.542564 -253.947619) (xy 17.594869 -253.941581) (xy 17.647483 -253.943598)
			(xy 17.699173 -253.953622) (xy 17.748726 -253.97142) (xy 17.794982 -253.996573) (xy 17.836856 -254.028492)
			(xy 17.873368 -254.06643) (xy 17.90366 -254.109496) (xy 17.927023 -254.156681) (xy 17.942909 -254.20688)
			(xy 17.950946 -254.258916) (xy 17.95145 -254.285242) (xy 21.364197 -254.285242) (xy 21.368227 -254.232744)
			(xy 21.380224 -254.181476) (xy 21.399907 -254.132641) (xy 21.426813 -254.087382) (xy 21.460313 -254.046761)
			(xy 21.499621 -254.01173) (xy 21.543816 -253.98311) (xy 21.591861 -253.961571) (xy 21.642632 -253.947619)
			(xy 21.694937 -253.941581) (xy 21.747551 -253.943598) (xy 21.799241 -253.953622) (xy 21.848794 -253.97142)
			(xy 21.89505 -253.996573) (xy 21.936924 -254.028492) (xy 21.973436 -254.06643) (xy 22.003728 -254.109496)
			(xy 22.027091 -254.156681) (xy 22.042977 -254.20688) (xy 22.051014 -254.258916) (xy 22.051518 -254.285242)
			(xy 24.808183 -254.285242) (xy 24.812213 -254.232744) (xy 24.82421 -254.181476) (xy 24.843893 -254.132641)
			(xy 24.870799 -254.087382) (xy 24.904299 -254.046761) (xy 24.943607 -254.01173) (xy 24.987802 -253.98311)
			(xy 25.035847 -253.961571) (xy 25.086618 -253.947619) (xy 25.138923 -253.941581) (xy 25.191537 -253.943598)
			(xy 25.243227 -253.953622) (xy 25.29278 -253.97142) (xy 25.339036 -253.996573) (xy 25.38091 -254.028492)
			(xy 25.417422 -254.06643) (xy 25.447714 -254.109496) (xy 25.471077 -254.156681) (xy 25.486963 -254.20688)
			(xy 25.495 -254.258916) (xy 25.495504 -254.285242) (xy 28.908251 -254.285242) (xy 28.912281 -254.232744)
			(xy 28.924278 -254.181476) (xy 28.943961 -254.132641) (xy 28.970867 -254.087382) (xy 29.004367 -254.046761)
			(xy 29.043675 -254.01173) (xy 29.08787 -253.98311) (xy 29.135915 -253.961571) (xy 29.186686 -253.947619)
			(xy 29.238991 -253.941581) (xy 29.291605 -253.943598) (xy 29.343295 -253.953622) (xy 29.392848 -253.97142)
			(xy 29.439104 -253.996573) (xy 29.480978 -254.028492) (xy 29.51749 -254.06643) (xy 29.547782 -254.109496)
			(xy 29.571145 -254.156681) (xy 29.587031 -254.20688) (xy 29.595068 -254.258916) (xy 29.595572 -254.285242)
			(xy 32.351983 -254.285242) (xy 32.356013 -254.232744) (xy 32.36801 -254.181476) (xy 32.387693 -254.132641)
			(xy 32.414599 -254.087382) (xy 32.448099 -254.046761) (xy 32.487407 -254.01173) (xy 32.531602 -253.98311)
			(xy 32.579647 -253.961571) (xy 32.630418 -253.947619) (xy 32.682723 -253.941581) (xy 32.735337 -253.943598)
			(xy 32.787027 -253.953622) (xy 32.83658 -253.97142) (xy 32.882836 -253.996573) (xy 32.92471 -254.028492)
			(xy 32.961222 -254.06643) (xy 32.991514 -254.109496) (xy 33.014877 -254.156681) (xy 33.030763 -254.20688)
			(xy 33.0388 -254.258916) (xy 33.039304 -254.285242) (xy 36.452051 -254.285242) (xy 36.456081 -254.232744)
			(xy 36.468078 -254.181476) (xy 36.487761 -254.132641) (xy 36.514667 -254.087382) (xy 36.548167 -254.046761)
			(xy 36.587475 -254.01173) (xy 36.63167 -253.98311) (xy 36.679715 -253.961571) (xy 36.730486 -253.947619)
			(xy 36.782791 -253.941581) (xy 36.835405 -253.943598) (xy 36.887095 -253.953622) (xy 36.936648 -253.97142)
			(xy 36.982904 -253.996573) (xy 37.024778 -254.028492) (xy 37.06129 -254.06643) (xy 37.091582 -254.109496)
			(xy 37.114945 -254.156681) (xy 37.130831 -254.20688) (xy 37.138868 -254.258916) (xy 37.139372 -254.285242)
			(xy 39.896037 -254.285242) (xy 39.900067 -254.232744) (xy 39.912064 -254.181476) (xy 39.931747 -254.132641)
			(xy 39.958653 -254.087382) (xy 39.992153 -254.046761) (xy 40.031461 -254.01173) (xy 40.075656 -253.98311)
			(xy 40.123701 -253.961571) (xy 40.174472 -253.947619) (xy 40.226777 -253.941581) (xy 40.279391 -253.943598)
			(xy 40.331081 -253.953622) (xy 40.380634 -253.97142) (xy 40.42689 -253.996573) (xy 40.468764 -254.028492)
			(xy 40.505276 -254.06643) (xy 40.535568 -254.109496) (xy 40.558931 -254.156681) (xy 40.574817 -254.20688)
			(xy 40.582854 -254.258916) (xy 40.583358 -254.285242) (xy 43.996105 -254.285242) (xy 44.000135 -254.232744)
			(xy 44.012132 -254.181476) (xy 44.031815 -254.132641) (xy 44.058721 -254.087382) (xy 44.092221 -254.046761)
			(xy 44.131529 -254.01173) (xy 44.175724 -253.98311) (xy 44.223769 -253.961571) (xy 44.27454 -253.947619)
			(xy 44.326845 -253.941581) (xy 44.379459 -253.943598) (xy 44.431149 -253.953622) (xy 44.480702 -253.97142)
			(xy 44.526958 -253.996573) (xy 44.568832 -254.028492) (xy 44.605344 -254.06643) (xy 44.635636 -254.109496)
			(xy 44.658999 -254.156681) (xy 44.674885 -254.20688) (xy 44.682922 -254.258916) (xy 44.683426 -254.285242)
			(xy 47.440091 -254.285242) (xy 47.444121 -254.232744) (xy 47.456118 -254.181476) (xy 47.475801 -254.132641)
			(xy 47.502707 -254.087382) (xy 47.536207 -254.046761) (xy 47.575515 -254.01173) (xy 47.61971 -253.98311)
			(xy 47.667755 -253.961571) (xy 47.718526 -253.947619) (xy 47.770831 -253.941581) (xy 47.823445 -253.943598)
			(xy 47.875135 -253.953622) (xy 47.924688 -253.97142) (xy 47.970944 -253.996573) (xy 48.012818 -254.028492)
			(xy 48.04933 -254.06643) (xy 48.079622 -254.109496) (xy 48.102985 -254.156681) (xy 48.118871 -254.20688)
			(xy 48.126908 -254.258916) (xy 48.127412 -254.285242) (xy 51.540159 -254.285242) (xy 51.544189 -254.232744)
			(xy 51.556186 -254.181476) (xy 51.575869 -254.132641) (xy 51.602775 -254.087382) (xy 51.636275 -254.046761)
			(xy 51.675583 -254.01173) (xy 51.719778 -253.98311) (xy 51.767823 -253.961571) (xy 51.818594 -253.947619)
			(xy 51.870899 -253.941581) (xy 51.923513 -253.943598) (xy 51.975203 -253.953622) (xy 52.024756 -253.97142)
			(xy 52.071012 -253.996573) (xy 52.112886 -254.028492) (xy 52.149398 -254.06643) (xy 52.17969 -254.109496)
			(xy 52.203053 -254.156681) (xy 52.218939 -254.20688) (xy 52.226976 -254.258916) (xy 52.22748 -254.285242)
			(xy 52.226976 -254.311568) (xy 52.218939 -254.363604) (xy 52.203053 -254.413803) (xy 52.17969 -254.460988)
			(xy 52.149398 -254.504054) (xy 52.112886 -254.541992) (xy 52.071012 -254.573911) (xy 52.024756 -254.599064)
			(xy 51.975203 -254.616862) (xy 51.923513 -254.626886) (xy 51.870899 -254.628903) (xy 51.818594 -254.622865)
			(xy 51.767823 -254.608913) (xy 51.719778 -254.587374) (xy 51.675583 -254.558754) (xy 51.636275 -254.523723)
			(xy 51.602775 -254.483102) (xy 51.575869 -254.437843) (xy 51.556186 -254.389008) (xy 51.544189 -254.33774)
			(xy 51.540159 -254.285242) (xy 48.127412 -254.285242) (xy 48.126908 -254.311568) (xy 48.118871 -254.363604)
			(xy 48.102985 -254.413803) (xy 48.079622 -254.460988) (xy 48.04933 -254.504054) (xy 48.012818 -254.541992)
			(xy 47.970944 -254.573911) (xy 47.924688 -254.599064) (xy 47.875135 -254.616862) (xy 47.823445 -254.626886)
			(xy 47.770831 -254.628903) (xy 47.718526 -254.622865) (xy 47.667755 -254.608913) (xy 47.61971 -254.587374)
			(xy 47.575515 -254.558754) (xy 47.536207 -254.523723) (xy 47.502707 -254.483102) (xy 47.475801 -254.437843)
			(xy 47.456118 -254.389008) (xy 47.444121 -254.33774) (xy 47.440091 -254.285242) (xy 44.683426 -254.285242)
			(xy 44.682922 -254.311568) (xy 44.674885 -254.363604) (xy 44.658999 -254.413803) (xy 44.635636 -254.460988)
			(xy 44.605344 -254.504054) (xy 44.568832 -254.541992) (xy 44.526958 -254.573911) (xy 44.480702 -254.599064)
			(xy 44.431149 -254.616862) (xy 44.379459 -254.626886) (xy 44.326845 -254.628903) (xy 44.27454 -254.622865)
			(xy 44.223769 -254.608913) (xy 44.175724 -254.587374) (xy 44.131529 -254.558754) (xy 44.092221 -254.523723)
			(xy 44.058721 -254.483102) (xy 44.031815 -254.437843) (xy 44.012132 -254.389008) (xy 44.000135 -254.33774)
			(xy 43.996105 -254.285242) (xy 40.583358 -254.285242) (xy 40.582854 -254.311568) (xy 40.574817 -254.363604)
			(xy 40.558931 -254.413803) (xy 40.535568 -254.460988) (xy 40.505276 -254.504054) (xy 40.468764 -254.541992)
			(xy 40.42689 -254.573911) (xy 40.380634 -254.599064) (xy 40.331081 -254.616862) (xy 40.279391 -254.626886)
			(xy 40.226777 -254.628903) (xy 40.174472 -254.622865) (xy 40.123701 -254.608913) (xy 40.075656 -254.587374)
			(xy 40.031461 -254.558754) (xy 39.992153 -254.523723) (xy 39.958653 -254.483102) (xy 39.931747 -254.437843)
			(xy 39.912064 -254.389008) (xy 39.900067 -254.33774) (xy 39.896037 -254.285242) (xy 37.139372 -254.285242)
			(xy 37.138868 -254.311568) (xy 37.130831 -254.363604) (xy 37.114945 -254.413803) (xy 37.091582 -254.460988)
			(xy 37.06129 -254.504054) (xy 37.024778 -254.541992) (xy 36.982904 -254.573911) (xy 36.936648 -254.599064)
			(xy 36.887095 -254.616862) (xy 36.835405 -254.626886) (xy 36.782791 -254.628903) (xy 36.730486 -254.622865)
			(xy 36.679715 -254.608913) (xy 36.63167 -254.587374) (xy 36.587475 -254.558754) (xy 36.548167 -254.523723)
			(xy 36.514667 -254.483102) (xy 36.487761 -254.437843) (xy 36.468078 -254.389008) (xy 36.456081 -254.33774)
			(xy 36.452051 -254.285242) (xy 33.039304 -254.285242) (xy 33.0388 -254.311568) (xy 33.030763 -254.363604)
			(xy 33.014877 -254.413803) (xy 32.991514 -254.460988) (xy 32.961222 -254.504054) (xy 32.92471 -254.541992)
			(xy 32.882836 -254.573911) (xy 32.83658 -254.599064) (xy 32.787027 -254.616862) (xy 32.735337 -254.626886)
			(xy 32.682723 -254.628903) (xy 32.630418 -254.622865) (xy 32.579647 -254.608913) (xy 32.531602 -254.587374)
			(xy 32.487407 -254.558754) (xy 32.448099 -254.523723) (xy 32.414599 -254.483102) (xy 32.387693 -254.437843)
			(xy 32.36801 -254.389008) (xy 32.356013 -254.33774) (xy 32.351983 -254.285242) (xy 29.595572 -254.285242)
			(xy 29.595068 -254.311568) (xy 29.587031 -254.363604) (xy 29.571145 -254.413803) (xy 29.547782 -254.460988)
			(xy 29.51749 -254.504054) (xy 29.480978 -254.541992) (xy 29.439104 -254.573911) (xy 29.392848 -254.599064)
			(xy 29.343295 -254.616862) (xy 29.291605 -254.626886) (xy 29.238991 -254.628903) (xy 29.186686 -254.622865)
			(xy 29.135915 -254.608913) (xy 29.08787 -254.587374) (xy 29.043675 -254.558754) (xy 29.004367 -254.523723)
			(xy 28.970867 -254.483102) (xy 28.943961 -254.437843) (xy 28.924278 -254.389008) (xy 28.912281 -254.33774)
			(xy 28.908251 -254.285242) (xy 25.495504 -254.285242) (xy 25.495 -254.311568) (xy 25.486963 -254.363604)
			(xy 25.471077 -254.413803) (xy 25.447714 -254.460988) (xy 25.417422 -254.504054) (xy 25.38091 -254.541992)
			(xy 25.339036 -254.573911) (xy 25.29278 -254.599064) (xy 25.243227 -254.616862) (xy 25.191537 -254.626886)
			(xy 25.138923 -254.628903) (xy 25.086618 -254.622865) (xy 25.035847 -254.608913) (xy 24.987802 -254.587374)
			(xy 24.943607 -254.558754) (xy 24.904299 -254.523723) (xy 24.870799 -254.483102) (xy 24.843893 -254.437843)
			(xy 24.82421 -254.389008) (xy 24.812213 -254.33774) (xy 24.808183 -254.285242) (xy 22.051518 -254.285242)
			(xy 22.051014 -254.311568) (xy 22.042977 -254.363604) (xy 22.027091 -254.413803) (xy 22.003728 -254.460988)
			(xy 21.973436 -254.504054) (xy 21.936924 -254.541992) (xy 21.89505 -254.573911) (xy 21.848794 -254.599064)
			(xy 21.799241 -254.616862) (xy 21.747551 -254.626886) (xy 21.694937 -254.628903) (xy 21.642632 -254.622865)
			(xy 21.591861 -254.608913) (xy 21.543816 -254.587374) (xy 21.499621 -254.558754) (xy 21.460313 -254.523723)
			(xy 21.426813 -254.483102) (xy 21.399907 -254.437843) (xy 21.380224 -254.389008) (xy 21.368227 -254.33774)
			(xy 21.364197 -254.285242) (xy 17.95145 -254.285242) (xy 17.950946 -254.311568) (xy 17.942909 -254.363604)
			(xy 17.927023 -254.413803) (xy 17.90366 -254.460988) (xy 17.873368 -254.504054) (xy 17.836856 -254.541992)
			(xy 17.794982 -254.573911) (xy 17.748726 -254.599064) (xy 17.699173 -254.616862) (xy 17.647483 -254.626886)
			(xy 17.594869 -254.628903) (xy 17.542564 -254.622865) (xy 17.491793 -254.608913) (xy 17.443748 -254.587374)
			(xy 17.399553 -254.558754) (xy 17.360245 -254.523723) (xy 17.326745 -254.483102) (xy 17.299839 -254.437843)
			(xy 17.280156 -254.389008) (xy 17.268159 -254.33774) (xy 17.264129 -254.285242) (xy 16.086074 -254.285242)
			(xy 16.086074 -261.08533) (xy 21.364197 -261.08533) (xy 21.368227 -261.032832) (xy 21.380224 -260.981564)
			(xy 21.399907 -260.932729) (xy 21.426813 -260.88747) (xy 21.460313 -260.846849) (xy 21.499621 -260.811818)
			(xy 21.543816 -260.783198) (xy 21.591861 -260.761659) (xy 21.642632 -260.747707) (xy 21.694937 -260.741669)
			(xy 21.747551 -260.743686) (xy 21.799241 -260.75371) (xy 21.848794 -260.771508) (xy 21.89505 -260.796661)
			(xy 21.936924 -260.82858) (xy 21.973436 -260.866518) (xy 22.003728 -260.909584) (xy 22.027091 -260.956769)
			(xy 22.042977 -261.006968) (xy 22.051014 -261.059004) (xy 22.051518 -261.08533) (xy 28.908251 -261.08533)
			(xy 28.912281 -261.032832) (xy 28.924278 -260.981564) (xy 28.943961 -260.932729) (xy 28.970867 -260.88747)
			(xy 29.004367 -260.846849) (xy 29.043675 -260.811818) (xy 29.08787 -260.783198) (xy 29.135915 -260.761659)
			(xy 29.186686 -260.747707) (xy 29.238991 -260.741669) (xy 29.291605 -260.743686) (xy 29.343295 -260.75371)
			(xy 29.392848 -260.771508) (xy 29.439104 -260.796661) (xy 29.480978 -260.82858) (xy 29.51749 -260.866518)
			(xy 29.547782 -260.909584) (xy 29.571145 -260.956769) (xy 29.587031 -261.006968) (xy 29.595068 -261.059004)
			(xy 29.595572 -261.08533) (xy 36.452051 -261.08533) (xy 36.456081 -261.032832) (xy 36.468078 -260.981564)
			(xy 36.487761 -260.932729) (xy 36.514667 -260.88747) (xy 36.548167 -260.846849) (xy 36.587475 -260.811818)
			(xy 36.63167 -260.783198) (xy 36.679715 -260.761659) (xy 36.730486 -260.747707) (xy 36.782791 -260.741669)
			(xy 36.835405 -260.743686) (xy 36.887095 -260.75371) (xy 36.936648 -260.771508) (xy 36.982904 -260.796661)
			(xy 37.024778 -260.82858) (xy 37.06129 -260.866518) (xy 37.091582 -260.909584) (xy 37.114945 -260.956769)
			(xy 37.130831 -261.006968) (xy 37.138868 -261.059004) (xy 37.139372 -261.08533) (xy 43.996105 -261.08533)
			(xy 44.000135 -261.032832) (xy 44.012132 -260.981564) (xy 44.031815 -260.932729) (xy 44.058721 -260.88747)
			(xy 44.092221 -260.846849) (xy 44.131529 -260.811818) (xy 44.175724 -260.783198) (xy 44.223769 -260.761659)
			(xy 44.27454 -260.747707) (xy 44.326845 -260.741669) (xy 44.379459 -260.743686) (xy 44.431149 -260.75371)
			(xy 44.480702 -260.771508) (xy 44.526958 -260.796661) (xy 44.568832 -260.82858) (xy 44.605344 -260.866518)
			(xy 44.635636 -260.909584) (xy 44.658999 -260.956769) (xy 44.674885 -261.006968) (xy 44.682922 -261.059004)
			(xy 44.683426 -261.08533) (xy 51.540159 -261.08533) (xy 51.544189 -261.032832) (xy 51.556186 -260.981564)
			(xy 51.575869 -260.932729) (xy 51.602775 -260.88747) (xy 51.636275 -260.846849) (xy 51.675583 -260.811818)
			(xy 51.719778 -260.783198) (xy 51.767823 -260.761659) (xy 51.818594 -260.747707) (xy 51.870899 -260.741669)
			(xy 51.923513 -260.743686) (xy 51.975203 -260.75371) (xy 52.024756 -260.771508) (xy 52.071012 -260.796661)
			(xy 52.112886 -260.82858) (xy 52.149398 -260.866518) (xy 52.17969 -260.909584) (xy 52.203053 -260.956769)
			(xy 52.218939 -261.006968) (xy 52.226976 -261.059004) (xy 52.22748 -261.08533) (xy 52.226976 -261.111656)
			(xy 52.218939 -261.163692) (xy 52.203053 -261.213891) (xy 52.17969 -261.261076) (xy 52.149398 -261.304142)
			(xy 52.112886 -261.34208) (xy 52.071012 -261.373999) (xy 52.024756 -261.399152) (xy 51.975203 -261.41695)
			(xy 51.923513 -261.426974) (xy 51.870899 -261.428991) (xy 51.818594 -261.422953) (xy 51.767823 -261.409001)
			(xy 51.719778 -261.387462) (xy 51.675583 -261.358842) (xy 51.636275 -261.323811) (xy 51.602775 -261.28319)
			(xy 51.575869 -261.237931) (xy 51.556186 -261.189096) (xy 51.544189 -261.137828) (xy 51.540159 -261.08533)
			(xy 44.683426 -261.08533) (xy 44.682922 -261.111656) (xy 44.674885 -261.163692) (xy 44.658999 -261.213891)
			(xy 44.635636 -261.261076) (xy 44.605344 -261.304142) (xy 44.568832 -261.34208) (xy 44.526958 -261.373999)
			(xy 44.480702 -261.399152) (xy 44.431149 -261.41695) (xy 44.379459 -261.426974) (xy 44.326845 -261.428991)
			(xy 44.27454 -261.422953) (xy 44.223769 -261.409001) (xy 44.175724 -261.387462) (xy 44.131529 -261.358842)
			(xy 44.092221 -261.323811) (xy 44.058721 -261.28319) (xy 44.031815 -261.237931) (xy 44.012132 -261.189096)
			(xy 44.000135 -261.137828) (xy 43.996105 -261.08533) (xy 37.139372 -261.08533) (xy 37.138868 -261.111656)
			(xy 37.130831 -261.163692) (xy 37.114945 -261.213891) (xy 37.091582 -261.261076) (xy 37.06129 -261.304142)
			(xy 37.024778 -261.34208) (xy 36.982904 -261.373999) (xy 36.936648 -261.399152) (xy 36.887095 -261.41695)
			(xy 36.835405 -261.426974) (xy 36.782791 -261.428991) (xy 36.730486 -261.422953) (xy 36.679715 -261.409001)
			(xy 36.63167 -261.387462) (xy 36.587475 -261.358842) (xy 36.548167 -261.323811) (xy 36.514667 -261.28319)
			(xy 36.487761 -261.237931) (xy 36.468078 -261.189096) (xy 36.456081 -261.137828) (xy 36.452051 -261.08533)
			(xy 29.595572 -261.08533) (xy 29.595068 -261.111656) (xy 29.587031 -261.163692) (xy 29.571145 -261.213891)
			(xy 29.547782 -261.261076) (xy 29.51749 -261.304142) (xy 29.480978 -261.34208) (xy 29.439104 -261.373999)
			(xy 29.392848 -261.399152) (xy 29.343295 -261.41695) (xy 29.291605 -261.426974) (xy 29.238991 -261.428991)
			(xy 29.186686 -261.422953) (xy 29.135915 -261.409001) (xy 29.08787 -261.387462) (xy 29.043675 -261.358842)
			(xy 29.004367 -261.323811) (xy 28.970867 -261.28319) (xy 28.943961 -261.237931) (xy 28.924278 -261.189096)
			(xy 28.912281 -261.137828) (xy 28.908251 -261.08533) (xy 22.051518 -261.08533) (xy 22.051014 -261.111656)
			(xy 22.042977 -261.163692) (xy 22.027091 -261.213891) (xy 22.003728 -261.261076) (xy 21.973436 -261.304142)
			(xy 21.936924 -261.34208) (xy 21.89505 -261.373999) (xy 21.848794 -261.399152) (xy 21.799241 -261.41695)
			(xy 21.747551 -261.426974) (xy 21.694937 -261.428991) (xy 21.642632 -261.422953) (xy 21.591861 -261.409001)
			(xy 21.543816 -261.387462) (xy 21.499621 -261.358842) (xy 21.460313 -261.323811) (xy 21.426813 -261.28319)
			(xy 21.399907 -261.237931) (xy 21.380224 -261.189096) (xy 21.368227 -261.137828) (xy 21.364197 -261.08533)
			(xy 16.086074 -261.08533) (xy 16.086074 -261.935214) (xy 17.264129 -261.935214) (xy 17.268159 -261.882716)
			(xy 17.280156 -261.831448) (xy 17.299839 -261.782613) (xy 17.326745 -261.737354) (xy 17.360245 -261.696733)
			(xy 17.399553 -261.661702) (xy 17.443748 -261.633082) (xy 17.491793 -261.611543) (xy 17.542564 -261.597591)
			(xy 17.594869 -261.591553) (xy 17.647483 -261.59357) (xy 17.699173 -261.603594) (xy 17.748726 -261.621392)
			(xy 17.794982 -261.646545) (xy 17.836856 -261.678464) (xy 17.873368 -261.716402) (xy 17.90366 -261.759468)
			(xy 17.927023 -261.806653) (xy 17.942909 -261.856852) (xy 17.950946 -261.908888) (xy 17.95145 -261.935214)
			(xy 24.808183 -261.935214) (xy 24.812213 -261.882716) (xy 24.82421 -261.831448) (xy 24.843893 -261.782613)
			(xy 24.870799 -261.737354) (xy 24.904299 -261.696733) (xy 24.943607 -261.661702) (xy 24.987802 -261.633082)
			(xy 25.035847 -261.611543) (xy 25.086618 -261.597591) (xy 25.138923 -261.591553) (xy 25.191537 -261.59357)
			(xy 25.243227 -261.603594) (xy 25.29278 -261.621392) (xy 25.339036 -261.646545) (xy 25.38091 -261.678464)
			(xy 25.417422 -261.716402) (xy 25.447714 -261.759468) (xy 25.471077 -261.806653) (xy 25.486963 -261.856852)
			(xy 25.495 -261.908888) (xy 25.495504 -261.935214) (xy 32.351983 -261.935214) (xy 32.356013 -261.882716)
			(xy 32.36801 -261.831448) (xy 32.387693 -261.782613) (xy 32.414599 -261.737354) (xy 32.448099 -261.696733)
			(xy 32.487407 -261.661702) (xy 32.531602 -261.633082) (xy 32.579647 -261.611543) (xy 32.630418 -261.597591)
			(xy 32.682723 -261.591553) (xy 32.735337 -261.59357) (xy 32.787027 -261.603594) (xy 32.83658 -261.621392)
			(xy 32.882836 -261.646545) (xy 32.92471 -261.678464) (xy 32.961222 -261.716402) (xy 32.991514 -261.759468)
			(xy 33.014877 -261.806653) (xy 33.030763 -261.856852) (xy 33.0388 -261.908888) (xy 33.039304 -261.935214)
			(xy 39.896037 -261.935214) (xy 39.900067 -261.882716) (xy 39.912064 -261.831448) (xy 39.931747 -261.782613)
			(xy 39.958653 -261.737354) (xy 39.992153 -261.696733) (xy 40.031461 -261.661702) (xy 40.075656 -261.633082)
			(xy 40.123701 -261.611543) (xy 40.174472 -261.597591) (xy 40.226777 -261.591553) (xy 40.279391 -261.59357)
			(xy 40.331081 -261.603594) (xy 40.380634 -261.621392) (xy 40.42689 -261.646545) (xy 40.468764 -261.678464)
			(xy 40.505276 -261.716402) (xy 40.535568 -261.759468) (xy 40.558931 -261.806653) (xy 40.574817 -261.856852)
			(xy 40.582854 -261.908888) (xy 40.583358 -261.935214) (xy 47.440091 -261.935214) (xy 47.444121 -261.882716)
			(xy 47.456118 -261.831448) (xy 47.475801 -261.782613) (xy 47.502707 -261.737354) (xy 47.536207 -261.696733)
			(xy 47.575515 -261.661702) (xy 47.61971 -261.633082) (xy 47.667755 -261.611543) (xy 47.718526 -261.597591)
			(xy 47.770831 -261.591553) (xy 47.823445 -261.59357) (xy 47.875135 -261.603594) (xy 47.924688 -261.621392)
			(xy 47.970944 -261.646545) (xy 48.012818 -261.678464) (xy 48.04933 -261.716402) (xy 48.079622 -261.759468)
			(xy 48.102985 -261.806653) (xy 48.118871 -261.856852) (xy 48.126908 -261.908888) (xy 48.127412 -261.935214)
			(xy 48.126908 -261.96154) (xy 48.118871 -262.013576) (xy 48.102985 -262.063775) (xy 48.079622 -262.11096)
			(xy 48.04933 -262.154026) (xy 48.012818 -262.191964) (xy 47.970944 -262.223883) (xy 47.924688 -262.249036)
			(xy 47.875135 -262.266834) (xy 47.823445 -262.276858) (xy 47.770831 -262.278875) (xy 47.718526 -262.272837)
			(xy 47.667755 -262.258885) (xy 47.61971 -262.237346) (xy 47.575515 -262.208726) (xy 47.536207 -262.173695)
			(xy 47.502707 -262.133074) (xy 47.475801 -262.087815) (xy 47.456118 -262.03898) (xy 47.444121 -261.987712)
			(xy 47.440091 -261.935214) (xy 40.583358 -261.935214) (xy 40.582854 -261.96154) (xy 40.574817 -262.013576)
			(xy 40.558931 -262.063775) (xy 40.535568 -262.11096) (xy 40.505276 -262.154026) (xy 40.468764 -262.191964)
			(xy 40.42689 -262.223883) (xy 40.380634 -262.249036) (xy 40.331081 -262.266834) (xy 40.279391 -262.276858)
			(xy 40.226777 -262.278875) (xy 40.174472 -262.272837) (xy 40.123701 -262.258885) (xy 40.075656 -262.237346)
			(xy 40.031461 -262.208726) (xy 39.992153 -262.173695) (xy 39.958653 -262.133074) (xy 39.931747 -262.087815)
			(xy 39.912064 -262.03898) (xy 39.900067 -261.987712) (xy 39.896037 -261.935214) (xy 33.039304 -261.935214)
			(xy 33.0388 -261.96154) (xy 33.030763 -262.013576) (xy 33.014877 -262.063775) (xy 32.991514 -262.11096)
			(xy 32.961222 -262.154026) (xy 32.92471 -262.191964) (xy 32.882836 -262.223883) (xy 32.83658 -262.249036)
			(xy 32.787027 -262.266834) (xy 32.735337 -262.276858) (xy 32.682723 -262.278875) (xy 32.630418 -262.272837)
			(xy 32.579647 -262.258885) (xy 32.531602 -262.237346) (xy 32.487407 -262.208726) (xy 32.448099 -262.173695)
			(xy 32.414599 -262.133074) (xy 32.387693 -262.087815) (xy 32.36801 -262.03898) (xy 32.356013 -261.987712)
			(xy 32.351983 -261.935214) (xy 25.495504 -261.935214) (xy 25.495 -261.96154) (xy 25.486963 -262.013576)
			(xy 25.471077 -262.063775) (xy 25.447714 -262.11096) (xy 25.417422 -262.154026) (xy 25.38091 -262.191964)
			(xy 25.339036 -262.223883) (xy 25.29278 -262.249036) (xy 25.243227 -262.266834) (xy 25.191537 -262.276858)
			(xy 25.138923 -262.278875) (xy 25.086618 -262.272837) (xy 25.035847 -262.258885) (xy 24.987802 -262.237346)
			(xy 24.943607 -262.208726) (xy 24.904299 -262.173695) (xy 24.870799 -262.133074) (xy 24.843893 -262.087815)
			(xy 24.82421 -262.03898) (xy 24.812213 -261.987712) (xy 24.808183 -261.935214) (xy 17.95145 -261.935214)
			(xy 17.950946 -261.96154) (xy 17.942909 -262.013576) (xy 17.927023 -262.063775) (xy 17.90366 -262.11096)
			(xy 17.873368 -262.154026) (xy 17.836856 -262.191964) (xy 17.794982 -262.223883) (xy 17.748726 -262.249036)
			(xy 17.699173 -262.266834) (xy 17.647483 -262.276858) (xy 17.594869 -262.278875) (xy 17.542564 -262.272837)
			(xy 17.491793 -262.258885) (xy 17.443748 -262.237346) (xy 17.399553 -262.208726) (xy 17.360245 -262.173695)
			(xy 17.326745 -262.133074) (xy 17.299839 -262.087815) (xy 17.280156 -262.03898) (xy 17.268159 -261.987712)
			(xy 17.264129 -261.935214) (xy 16.086074 -261.935214) (xy 16.086074 -262.785352) (xy 21.364197 -262.785352)
			(xy 21.368227 -262.732854) (xy 21.380224 -262.681586) (xy 21.399907 -262.632751) (xy 21.426813 -262.587492)
			(xy 21.460313 -262.546871) (xy 21.499621 -262.51184) (xy 21.543816 -262.48322) (xy 21.591861 -262.461681)
			(xy 21.642632 -262.447729) (xy 21.694937 -262.441691) (xy 21.747551 -262.443708) (xy 21.799241 -262.453732)
			(xy 21.848794 -262.47153) (xy 21.89505 -262.496683) (xy 21.936924 -262.528602) (xy 21.973436 -262.56654)
			(xy 22.003728 -262.609606) (xy 22.027091 -262.656791) (xy 22.042977 -262.70699) (xy 22.051014 -262.759026)
			(xy 22.051518 -262.785352) (xy 28.908251 -262.785352) (xy 28.912281 -262.732854) (xy 28.924278 -262.681586)
			(xy 28.943961 -262.632751) (xy 28.970867 -262.587492) (xy 29.004367 -262.546871) (xy 29.043675 -262.51184)
			(xy 29.08787 -262.48322) (xy 29.135915 -262.461681) (xy 29.186686 -262.447729) (xy 29.238991 -262.441691)
			(xy 29.291605 -262.443708) (xy 29.343295 -262.453732) (xy 29.392848 -262.47153) (xy 29.439104 -262.496683)
			(xy 29.480978 -262.528602) (xy 29.51749 -262.56654) (xy 29.547782 -262.609606) (xy 29.571145 -262.656791)
			(xy 29.587031 -262.70699) (xy 29.595068 -262.759026) (xy 29.595572 -262.785352) (xy 36.452051 -262.785352)
			(xy 36.456081 -262.732854) (xy 36.468078 -262.681586) (xy 36.487761 -262.632751) (xy 36.514667 -262.587492)
			(xy 36.548167 -262.546871) (xy 36.587475 -262.51184) (xy 36.63167 -262.48322) (xy 36.679715 -262.461681)
			(xy 36.730486 -262.447729) (xy 36.782791 -262.441691) (xy 36.835405 -262.443708) (xy 36.887095 -262.453732)
			(xy 36.936648 -262.47153) (xy 36.982904 -262.496683) (xy 37.024778 -262.528602) (xy 37.06129 -262.56654)
			(xy 37.091582 -262.609606) (xy 37.114945 -262.656791) (xy 37.130831 -262.70699) (xy 37.138868 -262.759026)
			(xy 37.139372 -262.785352) (xy 43.996105 -262.785352) (xy 44.000135 -262.732854) (xy 44.012132 -262.681586)
			(xy 44.031815 -262.632751) (xy 44.058721 -262.587492) (xy 44.092221 -262.546871) (xy 44.131529 -262.51184)
			(xy 44.175724 -262.48322) (xy 44.223769 -262.461681) (xy 44.27454 -262.447729) (xy 44.326845 -262.441691)
			(xy 44.379459 -262.443708) (xy 44.431149 -262.453732) (xy 44.480702 -262.47153) (xy 44.526958 -262.496683)
			(xy 44.568832 -262.528602) (xy 44.605344 -262.56654) (xy 44.635636 -262.609606) (xy 44.658999 -262.656791)
			(xy 44.674885 -262.70699) (xy 44.682922 -262.759026) (xy 44.683426 -262.785352) (xy 51.540159 -262.785352)
			(xy 51.544189 -262.732854) (xy 51.556186 -262.681586) (xy 51.575869 -262.632751) (xy 51.602775 -262.587492)
			(xy 51.636275 -262.546871) (xy 51.675583 -262.51184) (xy 51.719778 -262.48322) (xy 51.767823 -262.461681)
			(xy 51.818594 -262.447729) (xy 51.870899 -262.441691) (xy 51.923513 -262.443708) (xy 51.975203 -262.453732)
			(xy 52.024756 -262.47153) (xy 52.071012 -262.496683) (xy 52.112886 -262.528602) (xy 52.149398 -262.56654)
			(xy 52.17969 -262.609606) (xy 52.203053 -262.656791) (xy 52.218939 -262.70699) (xy 52.226976 -262.759026)
			(xy 52.22748 -262.785352) (xy 52.226976 -262.811678) (xy 52.218939 -262.863714) (xy 52.203053 -262.913913)
			(xy 52.17969 -262.961098) (xy 52.149398 -263.004164) (xy 52.112886 -263.042102) (xy 52.071012 -263.074021)
			(xy 52.024756 -263.099174) (xy 51.975203 -263.116972) (xy 51.923513 -263.126996) (xy 51.870899 -263.129013)
			(xy 51.818594 -263.122975) (xy 51.767823 -263.109023) (xy 51.719778 -263.087484) (xy 51.675583 -263.058864)
			(xy 51.636275 -263.023833) (xy 51.602775 -262.983212) (xy 51.575869 -262.937953) (xy 51.556186 -262.889118)
			(xy 51.544189 -262.83785) (xy 51.540159 -262.785352) (xy 44.683426 -262.785352) (xy 44.682922 -262.811678)
			(xy 44.674885 -262.863714) (xy 44.658999 -262.913913) (xy 44.635636 -262.961098) (xy 44.605344 -263.004164)
			(xy 44.568832 -263.042102) (xy 44.526958 -263.074021) (xy 44.480702 -263.099174) (xy 44.431149 -263.116972)
			(xy 44.379459 -263.126996) (xy 44.326845 -263.129013) (xy 44.27454 -263.122975) (xy 44.223769 -263.109023)
			(xy 44.175724 -263.087484) (xy 44.131529 -263.058864) (xy 44.092221 -263.023833) (xy 44.058721 -262.983212)
			(xy 44.031815 -262.937953) (xy 44.012132 -262.889118) (xy 44.000135 -262.83785) (xy 43.996105 -262.785352)
			(xy 37.139372 -262.785352) (xy 37.138868 -262.811678) (xy 37.130831 -262.863714) (xy 37.114945 -262.913913)
			(xy 37.091582 -262.961098) (xy 37.06129 -263.004164) (xy 37.024778 -263.042102) (xy 36.982904 -263.074021)
			(xy 36.936648 -263.099174) (xy 36.887095 -263.116972) (xy 36.835405 -263.126996) (xy 36.782791 -263.129013)
			(xy 36.730486 -263.122975) (xy 36.679715 -263.109023) (xy 36.63167 -263.087484) (xy 36.587475 -263.058864)
			(xy 36.548167 -263.023833) (xy 36.514667 -262.983212) (xy 36.487761 -262.937953) (xy 36.468078 -262.889118)
			(xy 36.456081 -262.83785) (xy 36.452051 -262.785352) (xy 29.595572 -262.785352) (xy 29.595068 -262.811678)
			(xy 29.587031 -262.863714) (xy 29.571145 -262.913913) (xy 29.547782 -262.961098) (xy 29.51749 -263.004164)
			(xy 29.480978 -263.042102) (xy 29.439104 -263.074021) (xy 29.392848 -263.099174) (xy 29.343295 -263.116972)
			(xy 29.291605 -263.126996) (xy 29.238991 -263.129013) (xy 29.186686 -263.122975) (xy 29.135915 -263.109023)
			(xy 29.08787 -263.087484) (xy 29.043675 -263.058864) (xy 29.004367 -263.023833) (xy 28.970867 -262.983212)
			(xy 28.943961 -262.937953) (xy 28.924278 -262.889118) (xy 28.912281 -262.83785) (xy 28.908251 -262.785352)
			(xy 22.051518 -262.785352) (xy 22.051014 -262.811678) (xy 22.042977 -262.863714) (xy 22.027091 -262.913913)
			(xy 22.003728 -262.961098) (xy 21.973436 -263.004164) (xy 21.936924 -263.042102) (xy 21.89505 -263.074021)
			(xy 21.848794 -263.099174) (xy 21.799241 -263.116972) (xy 21.747551 -263.126996) (xy 21.694937 -263.129013)
			(xy 21.642632 -263.122975) (xy 21.591861 -263.109023) (xy 21.543816 -263.087484) (xy 21.499621 -263.058864)
			(xy 21.460313 -263.023833) (xy 21.426813 -262.983212) (xy 21.399907 -262.937953) (xy 21.380224 -262.889118)
			(xy 21.368227 -262.83785) (xy 21.364197 -262.785352) (xy 16.086074 -262.785352) (xy 16.086074 -263.635236)
			(xy 17.264129 -263.635236) (xy 17.268159 -263.582738) (xy 17.280156 -263.53147) (xy 17.299839 -263.482635)
			(xy 17.326745 -263.437376) (xy 17.360245 -263.396755) (xy 17.399553 -263.361724) (xy 17.443748 -263.333104)
			(xy 17.491793 -263.311565) (xy 17.542564 -263.297613) (xy 17.594869 -263.291575) (xy 17.647483 -263.293592)
			(xy 17.699173 -263.303616) (xy 17.748726 -263.321414) (xy 17.794982 -263.346567) (xy 17.836856 -263.378486)
			(xy 17.873368 -263.416424) (xy 17.90366 -263.45949) (xy 17.927023 -263.506675) (xy 17.942909 -263.556874)
			(xy 17.950946 -263.60891) (xy 17.95145 -263.635236) (xy 24.808183 -263.635236) (xy 24.812213 -263.582738)
			(xy 24.82421 -263.53147) (xy 24.843893 -263.482635) (xy 24.870799 -263.437376) (xy 24.904299 -263.396755)
			(xy 24.943607 -263.361724) (xy 24.987802 -263.333104) (xy 25.035847 -263.311565) (xy 25.086618 -263.297613)
			(xy 25.138923 -263.291575) (xy 25.191537 -263.293592) (xy 25.243227 -263.303616) (xy 25.29278 -263.321414)
			(xy 25.339036 -263.346567) (xy 25.38091 -263.378486) (xy 25.417422 -263.416424) (xy 25.447714 -263.45949)
			(xy 25.471077 -263.506675) (xy 25.486963 -263.556874) (xy 25.495 -263.60891) (xy 25.495504 -263.635236)
			(xy 32.351983 -263.635236) (xy 32.356013 -263.582738) (xy 32.36801 -263.53147) (xy 32.387693 -263.482635)
			(xy 32.414599 -263.437376) (xy 32.448099 -263.396755) (xy 32.487407 -263.361724) (xy 32.531602 -263.333104)
			(xy 32.579647 -263.311565) (xy 32.630418 -263.297613) (xy 32.682723 -263.291575) (xy 32.735337 -263.293592)
			(xy 32.787027 -263.303616) (xy 32.83658 -263.321414) (xy 32.882836 -263.346567) (xy 32.92471 -263.378486)
			(xy 32.961222 -263.416424) (xy 32.991514 -263.45949) (xy 33.014877 -263.506675) (xy 33.030763 -263.556874)
			(xy 33.0388 -263.60891) (xy 33.039304 -263.635236) (xy 39.896037 -263.635236) (xy 39.900067 -263.582738)
			(xy 39.912064 -263.53147) (xy 39.931747 -263.482635) (xy 39.958653 -263.437376) (xy 39.992153 -263.396755)
			(xy 40.031461 -263.361724) (xy 40.075656 -263.333104) (xy 40.123701 -263.311565) (xy 40.174472 -263.297613)
			(xy 40.226777 -263.291575) (xy 40.279391 -263.293592) (xy 40.331081 -263.303616) (xy 40.380634 -263.321414)
			(xy 40.42689 -263.346567) (xy 40.468764 -263.378486) (xy 40.505276 -263.416424) (xy 40.535568 -263.45949)
			(xy 40.558931 -263.506675) (xy 40.574817 -263.556874) (xy 40.582854 -263.60891) (xy 40.583358 -263.635236)
			(xy 47.440091 -263.635236) (xy 47.444121 -263.582738) (xy 47.456118 -263.53147) (xy 47.475801 -263.482635)
			(xy 47.502707 -263.437376) (xy 47.536207 -263.396755) (xy 47.575515 -263.361724) (xy 47.61971 -263.333104)
			(xy 47.667755 -263.311565) (xy 47.718526 -263.297613) (xy 47.770831 -263.291575) (xy 47.823445 -263.293592)
			(xy 47.875135 -263.303616) (xy 47.924688 -263.321414) (xy 47.970944 -263.346567) (xy 48.012818 -263.378486)
			(xy 48.04933 -263.416424) (xy 48.079622 -263.45949) (xy 48.102985 -263.506675) (xy 48.118871 -263.556874)
			(xy 48.126908 -263.60891) (xy 48.127412 -263.635236) (xy 48.126908 -263.661562) (xy 48.118871 -263.713598)
			(xy 48.102985 -263.763797) (xy 48.079622 -263.810982) (xy 48.04933 -263.854048) (xy 48.012818 -263.891986)
			(xy 47.970944 -263.923905) (xy 47.924688 -263.949058) (xy 47.875135 -263.966856) (xy 47.823445 -263.97688)
			(xy 47.770831 -263.978897) (xy 47.718526 -263.972859) (xy 47.667755 -263.958907) (xy 47.61971 -263.937368)
			(xy 47.575515 -263.908748) (xy 47.536207 -263.873717) (xy 47.502707 -263.833096) (xy 47.475801 -263.787837)
			(xy 47.456118 -263.739002) (xy 47.444121 -263.687734) (xy 47.440091 -263.635236) (xy 40.583358 -263.635236)
			(xy 40.582854 -263.661562) (xy 40.574817 -263.713598) (xy 40.558931 -263.763797) (xy 40.535568 -263.810982)
			(xy 40.505276 -263.854048) (xy 40.468764 -263.891986) (xy 40.42689 -263.923905) (xy 40.380634 -263.949058)
			(xy 40.331081 -263.966856) (xy 40.279391 -263.97688) (xy 40.226777 -263.978897) (xy 40.174472 -263.972859)
			(xy 40.123701 -263.958907) (xy 40.075656 -263.937368) (xy 40.031461 -263.908748) (xy 39.992153 -263.873717)
			(xy 39.958653 -263.833096) (xy 39.931747 -263.787837) (xy 39.912064 -263.739002) (xy 39.900067 -263.687734)
			(xy 39.896037 -263.635236) (xy 33.039304 -263.635236) (xy 33.0388 -263.661562) (xy 33.030763 -263.713598)
			(xy 33.014877 -263.763797) (xy 32.991514 -263.810982) (xy 32.961222 -263.854048) (xy 32.92471 -263.891986)
			(xy 32.882836 -263.923905) (xy 32.83658 -263.949058) (xy 32.787027 -263.966856) (xy 32.735337 -263.97688)
			(xy 32.682723 -263.978897) (xy 32.630418 -263.972859) (xy 32.579647 -263.958907) (xy 32.531602 -263.937368)
			(xy 32.487407 -263.908748) (xy 32.448099 -263.873717) (xy 32.414599 -263.833096) (xy 32.387693 -263.787837)
			(xy 32.36801 -263.739002) (xy 32.356013 -263.687734) (xy 32.351983 -263.635236) (xy 25.495504 -263.635236)
			(xy 25.495 -263.661562) (xy 25.486963 -263.713598) (xy 25.471077 -263.763797) (xy 25.447714 -263.810982)
			(xy 25.417422 -263.854048) (xy 25.38091 -263.891986) (xy 25.339036 -263.923905) (xy 25.29278 -263.949058)
			(xy 25.243227 -263.966856) (xy 25.191537 -263.97688) (xy 25.138923 -263.978897) (xy 25.086618 -263.972859)
			(xy 25.035847 -263.958907) (xy 24.987802 -263.937368) (xy 24.943607 -263.908748) (xy 24.904299 -263.873717)
			(xy 24.870799 -263.833096) (xy 24.843893 -263.787837) (xy 24.82421 -263.739002) (xy 24.812213 -263.687734)
			(xy 24.808183 -263.635236) (xy 17.95145 -263.635236) (xy 17.950946 -263.661562) (xy 17.942909 -263.713598)
			(xy 17.927023 -263.763797) (xy 17.90366 -263.810982) (xy 17.873368 -263.854048) (xy 17.836856 -263.891986)
			(xy 17.794982 -263.923905) (xy 17.748726 -263.949058) (xy 17.699173 -263.966856) (xy 17.647483 -263.97688)
			(xy 17.594869 -263.978897) (xy 17.542564 -263.972859) (xy 17.491793 -263.958907) (xy 17.443748 -263.937368)
			(xy 17.399553 -263.908748) (xy 17.360245 -263.873717) (xy 17.326745 -263.833096) (xy 17.299839 -263.787837)
			(xy 17.280156 -263.739002) (xy 17.268159 -263.687734) (xy 17.264129 -263.635236) (xy 16.086074 -263.635236)
			(xy 16.086074 -264.485374) (xy 21.364197 -264.485374) (xy 21.368227 -264.432876) (xy 21.380224 -264.381608)
			(xy 21.399907 -264.332773) (xy 21.426813 -264.287514) (xy 21.460313 -264.246893) (xy 21.499621 -264.211862)
			(xy 21.543816 -264.183242) (xy 21.591861 -264.161703) (xy 21.642632 -264.147751) (xy 21.694937 -264.141713)
			(xy 21.747551 -264.14373) (xy 21.799241 -264.153754) (xy 21.848794 -264.171552) (xy 21.89505 -264.196705)
			(xy 21.936924 -264.228624) (xy 21.973436 -264.266562) (xy 22.003728 -264.309628) (xy 22.027091 -264.356813)
			(xy 22.042977 -264.407012) (xy 22.051014 -264.459048) (xy 22.051518 -264.485374) (xy 28.908251 -264.485374)
			(xy 28.912281 -264.432876) (xy 28.924278 -264.381608) (xy 28.943961 -264.332773) (xy 28.970867 -264.287514)
			(xy 29.004367 -264.246893) (xy 29.043675 -264.211862) (xy 29.08787 -264.183242) (xy 29.135915 -264.161703)
			(xy 29.186686 -264.147751) (xy 29.238991 -264.141713) (xy 29.291605 -264.14373) (xy 29.343295 -264.153754)
			(xy 29.392848 -264.171552) (xy 29.439104 -264.196705) (xy 29.480978 -264.228624) (xy 29.51749 -264.266562)
			(xy 29.547782 -264.309628) (xy 29.571145 -264.356813) (xy 29.587031 -264.407012) (xy 29.595068 -264.459048)
			(xy 29.595572 -264.485374) (xy 36.452051 -264.485374) (xy 36.456081 -264.432876) (xy 36.468078 -264.381608)
			(xy 36.487761 -264.332773) (xy 36.514667 -264.287514) (xy 36.548167 -264.246893) (xy 36.587475 -264.211862)
			(xy 36.63167 -264.183242) (xy 36.679715 -264.161703) (xy 36.730486 -264.147751) (xy 36.782791 -264.141713)
			(xy 36.835405 -264.14373) (xy 36.887095 -264.153754) (xy 36.936648 -264.171552) (xy 36.982904 -264.196705)
			(xy 37.024778 -264.228624) (xy 37.06129 -264.266562) (xy 37.091582 -264.309628) (xy 37.114945 -264.356813)
			(xy 37.130831 -264.407012) (xy 37.138868 -264.459048) (xy 37.139372 -264.485374) (xy 43.996105 -264.485374)
			(xy 44.000135 -264.432876) (xy 44.012132 -264.381608) (xy 44.031815 -264.332773) (xy 44.058721 -264.287514)
			(xy 44.092221 -264.246893) (xy 44.131529 -264.211862) (xy 44.175724 -264.183242) (xy 44.223769 -264.161703)
			(xy 44.27454 -264.147751) (xy 44.326845 -264.141713) (xy 44.379459 -264.14373) (xy 44.431149 -264.153754)
			(xy 44.480702 -264.171552) (xy 44.526958 -264.196705) (xy 44.568832 -264.228624) (xy 44.605344 -264.266562)
			(xy 44.635636 -264.309628) (xy 44.658999 -264.356813) (xy 44.674885 -264.407012) (xy 44.682922 -264.459048)
			(xy 44.683426 -264.485374) (xy 51.540159 -264.485374) (xy 51.544189 -264.432876) (xy 51.556186 -264.381608)
			(xy 51.575869 -264.332773) (xy 51.602775 -264.287514) (xy 51.636275 -264.246893) (xy 51.675583 -264.211862)
			(xy 51.719778 -264.183242) (xy 51.767823 -264.161703) (xy 51.818594 -264.147751) (xy 51.870899 -264.141713)
			(xy 51.923513 -264.14373) (xy 51.975203 -264.153754) (xy 52.024756 -264.171552) (xy 52.071012 -264.196705)
			(xy 52.112886 -264.228624) (xy 52.149398 -264.266562) (xy 52.17969 -264.309628) (xy 52.203053 -264.356813)
			(xy 52.218939 -264.407012) (xy 52.226976 -264.459048) (xy 52.22748 -264.485374) (xy 52.226976 -264.5117)
			(xy 52.218939 -264.563736) (xy 52.203053 -264.613935) (xy 52.17969 -264.66112) (xy 52.149398 -264.704186)
			(xy 52.112886 -264.742124) (xy 52.071012 -264.774043) (xy 52.024756 -264.799196) (xy 51.975203 -264.816994)
			(xy 51.923513 -264.827018) (xy 51.870899 -264.829035) (xy 51.818594 -264.822997) (xy 51.767823 -264.809045)
			(xy 51.719778 -264.787506) (xy 51.675583 -264.758886) (xy 51.636275 -264.723855) (xy 51.602775 -264.683234)
			(xy 51.575869 -264.637975) (xy 51.556186 -264.58914) (xy 51.544189 -264.537872) (xy 51.540159 -264.485374)
			(xy 44.683426 -264.485374) (xy 44.682922 -264.5117) (xy 44.674885 -264.563736) (xy 44.658999 -264.613935)
			(xy 44.635636 -264.66112) (xy 44.605344 -264.704186) (xy 44.568832 -264.742124) (xy 44.526958 -264.774043)
			(xy 44.480702 -264.799196) (xy 44.431149 -264.816994) (xy 44.379459 -264.827018) (xy 44.326845 -264.829035)
			(xy 44.27454 -264.822997) (xy 44.223769 -264.809045) (xy 44.175724 -264.787506) (xy 44.131529 -264.758886)
			(xy 44.092221 -264.723855) (xy 44.058721 -264.683234) (xy 44.031815 -264.637975) (xy 44.012132 -264.58914)
			(xy 44.000135 -264.537872) (xy 43.996105 -264.485374) (xy 37.139372 -264.485374) (xy 37.138868 -264.5117)
			(xy 37.130831 -264.563736) (xy 37.114945 -264.613935) (xy 37.091582 -264.66112) (xy 37.06129 -264.704186)
			(xy 37.024778 -264.742124) (xy 36.982904 -264.774043) (xy 36.936648 -264.799196) (xy 36.887095 -264.816994)
			(xy 36.835405 -264.827018) (xy 36.782791 -264.829035) (xy 36.730486 -264.822997) (xy 36.679715 -264.809045)
			(xy 36.63167 -264.787506) (xy 36.587475 -264.758886) (xy 36.548167 -264.723855) (xy 36.514667 -264.683234)
			(xy 36.487761 -264.637975) (xy 36.468078 -264.58914) (xy 36.456081 -264.537872) (xy 36.452051 -264.485374)
			(xy 29.595572 -264.485374) (xy 29.595068 -264.5117) (xy 29.587031 -264.563736) (xy 29.571145 -264.613935)
			(xy 29.547782 -264.66112) (xy 29.51749 -264.704186) (xy 29.480978 -264.742124) (xy 29.439104 -264.774043)
			(xy 29.392848 -264.799196) (xy 29.343295 -264.816994) (xy 29.291605 -264.827018) (xy 29.238991 -264.829035)
			(xy 29.186686 -264.822997) (xy 29.135915 -264.809045) (xy 29.08787 -264.787506) (xy 29.043675 -264.758886)
			(xy 29.004367 -264.723855) (xy 28.970867 -264.683234) (xy 28.943961 -264.637975) (xy 28.924278 -264.58914)
			(xy 28.912281 -264.537872) (xy 28.908251 -264.485374) (xy 22.051518 -264.485374) (xy 22.051014 -264.5117)
			(xy 22.042977 -264.563736) (xy 22.027091 -264.613935) (xy 22.003728 -264.66112) (xy 21.973436 -264.704186)
			(xy 21.936924 -264.742124) (xy 21.89505 -264.774043) (xy 21.848794 -264.799196) (xy 21.799241 -264.816994)
			(xy 21.747551 -264.827018) (xy 21.694937 -264.829035) (xy 21.642632 -264.822997) (xy 21.591861 -264.809045)
			(xy 21.543816 -264.787506) (xy 21.499621 -264.758886) (xy 21.460313 -264.723855) (xy 21.426813 -264.683234)
			(xy 21.399907 -264.637975) (xy 21.380224 -264.58914) (xy 21.368227 -264.537872) (xy 21.364197 -264.485374)
			(xy 16.086074 -264.485374) (xy 16.086074 -265.335258) (xy 17.264129 -265.335258) (xy 17.268159 -265.28276)
			(xy 17.280156 -265.231492) (xy 17.299839 -265.182657) (xy 17.326745 -265.137398) (xy 17.360245 -265.096777)
			(xy 17.399553 -265.061746) (xy 17.443748 -265.033126) (xy 17.491793 -265.011587) (xy 17.542564 -264.997635)
			(xy 17.594869 -264.991597) (xy 17.647483 -264.993614) (xy 17.699173 -265.003638) (xy 17.748726 -265.021436)
			(xy 17.794982 -265.046589) (xy 17.836856 -265.078508) (xy 17.873368 -265.116446) (xy 17.90366 -265.159512)
			(xy 17.927023 -265.206697) (xy 17.942909 -265.256896) (xy 17.950946 -265.308932) (xy 17.95145 -265.335258)
			(xy 24.808183 -265.335258) (xy 24.812213 -265.28276) (xy 24.82421 -265.231492) (xy 24.843893 -265.182657)
			(xy 24.870799 -265.137398) (xy 24.904299 -265.096777) (xy 24.943607 -265.061746) (xy 24.987802 -265.033126)
			(xy 25.035847 -265.011587) (xy 25.086618 -264.997635) (xy 25.138923 -264.991597) (xy 25.191537 -264.993614)
			(xy 25.243227 -265.003638) (xy 25.29278 -265.021436) (xy 25.339036 -265.046589) (xy 25.38091 -265.078508)
			(xy 25.417422 -265.116446) (xy 25.447714 -265.159512) (xy 25.471077 -265.206697) (xy 25.486963 -265.256896)
			(xy 25.495 -265.308932) (xy 25.495504 -265.335258) (xy 32.351983 -265.335258) (xy 32.356013 -265.28276)
			(xy 32.36801 -265.231492) (xy 32.387693 -265.182657) (xy 32.414599 -265.137398) (xy 32.448099 -265.096777)
			(xy 32.487407 -265.061746) (xy 32.531602 -265.033126) (xy 32.579647 -265.011587) (xy 32.630418 -264.997635)
			(xy 32.682723 -264.991597) (xy 32.735337 -264.993614) (xy 32.787027 -265.003638) (xy 32.83658 -265.021436)
			(xy 32.882836 -265.046589) (xy 32.92471 -265.078508) (xy 32.961222 -265.116446) (xy 32.991514 -265.159512)
			(xy 33.014877 -265.206697) (xy 33.030763 -265.256896) (xy 33.0388 -265.308932) (xy 33.039304 -265.335258)
			(xy 39.896037 -265.335258) (xy 39.900067 -265.28276) (xy 39.912064 -265.231492) (xy 39.931747 -265.182657)
			(xy 39.958653 -265.137398) (xy 39.992153 -265.096777) (xy 40.031461 -265.061746) (xy 40.075656 -265.033126)
			(xy 40.123701 -265.011587) (xy 40.174472 -264.997635) (xy 40.226777 -264.991597) (xy 40.279391 -264.993614)
			(xy 40.331081 -265.003638) (xy 40.380634 -265.021436) (xy 40.42689 -265.046589) (xy 40.468764 -265.078508)
			(xy 40.505276 -265.116446) (xy 40.535568 -265.159512) (xy 40.558931 -265.206697) (xy 40.574817 -265.256896)
			(xy 40.582854 -265.308932) (xy 40.583358 -265.335258) (xy 47.440091 -265.335258) (xy 47.444121 -265.28276)
			(xy 47.456118 -265.231492) (xy 47.475801 -265.182657) (xy 47.502707 -265.137398) (xy 47.536207 -265.096777)
			(xy 47.575515 -265.061746) (xy 47.61971 -265.033126) (xy 47.667755 -265.011587) (xy 47.718526 -264.997635)
			(xy 47.770831 -264.991597) (xy 47.823445 -264.993614) (xy 47.875135 -265.003638) (xy 47.924688 -265.021436)
			(xy 47.970944 -265.046589) (xy 48.012818 -265.078508) (xy 48.04933 -265.116446) (xy 48.079622 -265.159512)
			(xy 48.102985 -265.206697) (xy 48.118871 -265.256896) (xy 48.126908 -265.308932) (xy 48.127412 -265.335258)
			(xy 48.126908 -265.361584) (xy 48.118871 -265.41362) (xy 48.102985 -265.463819) (xy 48.079622 -265.511004)
			(xy 48.04933 -265.55407) (xy 48.012818 -265.592008) (xy 47.970944 -265.623927) (xy 47.924688 -265.64908)
			(xy 47.875135 -265.666878) (xy 47.823445 -265.676902) (xy 47.770831 -265.678919) (xy 47.718526 -265.672881)
			(xy 47.667755 -265.658929) (xy 47.61971 -265.63739) (xy 47.575515 -265.60877) (xy 47.536207 -265.573739)
			(xy 47.502707 -265.533118) (xy 47.475801 -265.487859) (xy 47.456118 -265.439024) (xy 47.444121 -265.387756)
			(xy 47.440091 -265.335258) (xy 40.583358 -265.335258) (xy 40.582854 -265.361584) (xy 40.574817 -265.41362)
			(xy 40.558931 -265.463819) (xy 40.535568 -265.511004) (xy 40.505276 -265.55407) (xy 40.468764 -265.592008)
			(xy 40.42689 -265.623927) (xy 40.380634 -265.64908) (xy 40.331081 -265.666878) (xy 40.279391 -265.676902)
			(xy 40.226777 -265.678919) (xy 40.174472 -265.672881) (xy 40.123701 -265.658929) (xy 40.075656 -265.63739)
			(xy 40.031461 -265.60877) (xy 39.992153 -265.573739) (xy 39.958653 -265.533118) (xy 39.931747 -265.487859)
			(xy 39.912064 -265.439024) (xy 39.900067 -265.387756) (xy 39.896037 -265.335258) (xy 33.039304 -265.335258)
			(xy 33.0388 -265.361584) (xy 33.030763 -265.41362) (xy 33.014877 -265.463819) (xy 32.991514 -265.511004)
			(xy 32.961222 -265.55407) (xy 32.92471 -265.592008) (xy 32.882836 -265.623927) (xy 32.83658 -265.64908)
			(xy 32.787027 -265.666878) (xy 32.735337 -265.676902) (xy 32.682723 -265.678919) (xy 32.630418 -265.672881)
			(xy 32.579647 -265.658929) (xy 32.531602 -265.63739) (xy 32.487407 -265.60877) (xy 32.448099 -265.573739)
			(xy 32.414599 -265.533118) (xy 32.387693 -265.487859) (xy 32.36801 -265.439024) (xy 32.356013 -265.387756)
			(xy 32.351983 -265.335258) (xy 25.495504 -265.335258) (xy 25.495 -265.361584) (xy 25.486963 -265.41362)
			(xy 25.471077 -265.463819) (xy 25.447714 -265.511004) (xy 25.417422 -265.55407) (xy 25.38091 -265.592008)
			(xy 25.339036 -265.623927) (xy 25.29278 -265.64908) (xy 25.243227 -265.666878) (xy 25.191537 -265.676902)
			(xy 25.138923 -265.678919) (xy 25.086618 -265.672881) (xy 25.035847 -265.658929) (xy 24.987802 -265.63739)
			(xy 24.943607 -265.60877) (xy 24.904299 -265.573739) (xy 24.870799 -265.533118) (xy 24.843893 -265.487859)
			(xy 24.82421 -265.439024) (xy 24.812213 -265.387756) (xy 24.808183 -265.335258) (xy 17.95145 -265.335258)
			(xy 17.950946 -265.361584) (xy 17.942909 -265.41362) (xy 17.927023 -265.463819) (xy 17.90366 -265.511004)
			(xy 17.873368 -265.55407) (xy 17.836856 -265.592008) (xy 17.794982 -265.623927) (xy 17.748726 -265.64908)
			(xy 17.699173 -265.666878) (xy 17.647483 -265.676902) (xy 17.594869 -265.678919) (xy 17.542564 -265.672881)
			(xy 17.491793 -265.658929) (xy 17.443748 -265.63739) (xy 17.399553 -265.60877) (xy 17.360245 -265.573739)
			(xy 17.326745 -265.533118) (xy 17.299839 -265.487859) (xy 17.280156 -265.439024) (xy 17.268159 -265.387756)
			(xy 17.264129 -265.335258) (xy 16.086074 -265.335258) (xy 16.086074 -266.185396) (xy 21.364197 -266.185396)
			(xy 21.368227 -266.132898) (xy 21.380224 -266.08163) (xy 21.399907 -266.032795) (xy 21.426813 -265.987536)
			(xy 21.460313 -265.946915) (xy 21.499621 -265.911884) (xy 21.543816 -265.883264) (xy 21.591861 -265.861725)
			(xy 21.642632 -265.847773) (xy 21.694937 -265.841735) (xy 21.747551 -265.843752) (xy 21.799241 -265.853776)
			(xy 21.848794 -265.871574) (xy 21.89505 -265.896727) (xy 21.936924 -265.928646) (xy 21.973436 -265.966584)
			(xy 22.003728 -266.00965) (xy 22.027091 -266.056835) (xy 22.042977 -266.107034) (xy 22.051014 -266.15907)
			(xy 22.051518 -266.185396) (xy 28.908251 -266.185396) (xy 28.912281 -266.132898) (xy 28.924278 -266.08163)
			(xy 28.943961 -266.032795) (xy 28.970867 -265.987536) (xy 29.004367 -265.946915) (xy 29.043675 -265.911884)
			(xy 29.08787 -265.883264) (xy 29.135915 -265.861725) (xy 29.186686 -265.847773) (xy 29.238991 -265.841735)
			(xy 29.291605 -265.843752) (xy 29.343295 -265.853776) (xy 29.392848 -265.871574) (xy 29.439104 -265.896727)
			(xy 29.480978 -265.928646) (xy 29.51749 -265.966584) (xy 29.547782 -266.00965) (xy 29.571145 -266.056835)
			(xy 29.587031 -266.107034) (xy 29.595068 -266.15907) (xy 29.595572 -266.185396) (xy 36.452051 -266.185396)
			(xy 36.456081 -266.132898) (xy 36.468078 -266.08163) (xy 36.487761 -266.032795) (xy 36.514667 -265.987536)
			(xy 36.548167 -265.946915) (xy 36.587475 -265.911884) (xy 36.63167 -265.883264) (xy 36.679715 -265.861725)
			(xy 36.730486 -265.847773) (xy 36.782791 -265.841735) (xy 36.835405 -265.843752) (xy 36.887095 -265.853776)
			(xy 36.936648 -265.871574) (xy 36.982904 -265.896727) (xy 37.024778 -265.928646) (xy 37.06129 -265.966584)
			(xy 37.091582 -266.00965) (xy 37.114945 -266.056835) (xy 37.130831 -266.107034) (xy 37.138868 -266.15907)
			(xy 37.139372 -266.185396) (xy 43.996105 -266.185396) (xy 44.000135 -266.132898) (xy 44.012132 -266.08163)
			(xy 44.031815 -266.032795) (xy 44.058721 -265.987536) (xy 44.092221 -265.946915) (xy 44.131529 -265.911884)
			(xy 44.175724 -265.883264) (xy 44.223769 -265.861725) (xy 44.27454 -265.847773) (xy 44.326845 -265.841735)
			(xy 44.379459 -265.843752) (xy 44.431149 -265.853776) (xy 44.480702 -265.871574) (xy 44.526958 -265.896727)
			(xy 44.568832 -265.928646) (xy 44.605344 -265.966584) (xy 44.635636 -266.00965) (xy 44.658999 -266.056835)
			(xy 44.674885 -266.107034) (xy 44.682922 -266.15907) (xy 44.683426 -266.185396) (xy 51.540159 -266.185396)
			(xy 51.544189 -266.132898) (xy 51.556186 -266.08163) (xy 51.575869 -266.032795) (xy 51.602775 -265.987536)
			(xy 51.636275 -265.946915) (xy 51.675583 -265.911884) (xy 51.719778 -265.883264) (xy 51.767823 -265.861725)
			(xy 51.818594 -265.847773) (xy 51.870899 -265.841735) (xy 51.923513 -265.843752) (xy 51.975203 -265.853776)
			(xy 52.024756 -265.871574) (xy 52.071012 -265.896727) (xy 52.112886 -265.928646) (xy 52.149398 -265.966584)
			(xy 52.17969 -266.00965) (xy 52.203053 -266.056835) (xy 52.218939 -266.107034) (xy 52.226976 -266.15907)
			(xy 52.22748 -266.185396) (xy 52.226976 -266.211722) (xy 52.218939 -266.263758) (xy 52.203053 -266.313957)
			(xy 52.17969 -266.361142) (xy 52.149398 -266.404208) (xy 52.112886 -266.442146) (xy 52.071012 -266.474065)
			(xy 52.024756 -266.499218) (xy 51.975203 -266.517016) (xy 51.923513 -266.52704) (xy 51.870899 -266.529057)
			(xy 51.818594 -266.523019) (xy 51.767823 -266.509067) (xy 51.719778 -266.487528) (xy 51.675583 -266.458908)
			(xy 51.636275 -266.423877) (xy 51.602775 -266.383256) (xy 51.575869 -266.337997) (xy 51.556186 -266.289162)
			(xy 51.544189 -266.237894) (xy 51.540159 -266.185396) (xy 44.683426 -266.185396) (xy 44.682922 -266.211722)
			(xy 44.674885 -266.263758) (xy 44.658999 -266.313957) (xy 44.635636 -266.361142) (xy 44.605344 -266.404208)
			(xy 44.568832 -266.442146) (xy 44.526958 -266.474065) (xy 44.480702 -266.499218) (xy 44.431149 -266.517016)
			(xy 44.379459 -266.52704) (xy 44.326845 -266.529057) (xy 44.27454 -266.523019) (xy 44.223769 -266.509067)
			(xy 44.175724 -266.487528) (xy 44.131529 -266.458908) (xy 44.092221 -266.423877) (xy 44.058721 -266.383256)
			(xy 44.031815 -266.337997) (xy 44.012132 -266.289162) (xy 44.000135 -266.237894) (xy 43.996105 -266.185396)
			(xy 37.139372 -266.185396) (xy 37.138868 -266.211722) (xy 37.130831 -266.263758) (xy 37.114945 -266.313957)
			(xy 37.091582 -266.361142) (xy 37.06129 -266.404208) (xy 37.024778 -266.442146) (xy 36.982904 -266.474065)
			(xy 36.936648 -266.499218) (xy 36.887095 -266.517016) (xy 36.835405 -266.52704) (xy 36.782791 -266.529057)
			(xy 36.730486 -266.523019) (xy 36.679715 -266.509067) (xy 36.63167 -266.487528) (xy 36.587475 -266.458908)
			(xy 36.548167 -266.423877) (xy 36.514667 -266.383256) (xy 36.487761 -266.337997) (xy 36.468078 -266.289162)
			(xy 36.456081 -266.237894) (xy 36.452051 -266.185396) (xy 29.595572 -266.185396) (xy 29.595068 -266.211722)
			(xy 29.587031 -266.263758) (xy 29.571145 -266.313957) (xy 29.547782 -266.361142) (xy 29.51749 -266.404208)
			(xy 29.480978 -266.442146) (xy 29.439104 -266.474065) (xy 29.392848 -266.499218) (xy 29.343295 -266.517016)
			(xy 29.291605 -266.52704) (xy 29.238991 -266.529057) (xy 29.186686 -266.523019) (xy 29.135915 -266.509067)
			(xy 29.08787 -266.487528) (xy 29.043675 -266.458908) (xy 29.004367 -266.423877) (xy 28.970867 -266.383256)
			(xy 28.943961 -266.337997) (xy 28.924278 -266.289162) (xy 28.912281 -266.237894) (xy 28.908251 -266.185396)
			(xy 22.051518 -266.185396) (xy 22.051014 -266.211722) (xy 22.042977 -266.263758) (xy 22.027091 -266.313957)
			(xy 22.003728 -266.361142) (xy 21.973436 -266.404208) (xy 21.936924 -266.442146) (xy 21.89505 -266.474065)
			(xy 21.848794 -266.499218) (xy 21.799241 -266.517016) (xy 21.747551 -266.52704) (xy 21.694937 -266.529057)
			(xy 21.642632 -266.523019) (xy 21.591861 -266.509067) (xy 21.543816 -266.487528) (xy 21.499621 -266.458908)
			(xy 21.460313 -266.423877) (xy 21.426813 -266.383256) (xy 21.399907 -266.337997) (xy 21.380224 -266.289162)
			(xy 21.368227 -266.237894) (xy 21.364197 -266.185396) (xy 16.086074 -266.185396) (xy 16.086074 -267.03528)
			(xy 17.264129 -267.03528) (xy 17.268159 -266.982782) (xy 17.280156 -266.931514) (xy 17.299839 -266.882679)
			(xy 17.326745 -266.83742) (xy 17.360245 -266.796799) (xy 17.399553 -266.761768) (xy 17.443748 -266.733148)
			(xy 17.491793 -266.711609) (xy 17.542564 -266.697657) (xy 17.594869 -266.691619) (xy 17.647483 -266.693636)
			(xy 17.699173 -266.70366) (xy 17.748726 -266.721458) (xy 17.794982 -266.746611) (xy 17.836856 -266.77853)
			(xy 17.873368 -266.816468) (xy 17.90366 -266.859534) (xy 17.927023 -266.906719) (xy 17.942909 -266.956918)
			(xy 17.950946 -267.008954) (xy 17.95145 -267.03528) (xy 24.808183 -267.03528) (xy 24.812213 -266.982782)
			(xy 24.82421 -266.931514) (xy 24.843893 -266.882679) (xy 24.870799 -266.83742) (xy 24.904299 -266.796799)
			(xy 24.943607 -266.761768) (xy 24.987802 -266.733148) (xy 25.035847 -266.711609) (xy 25.086618 -266.697657)
			(xy 25.138923 -266.691619) (xy 25.191537 -266.693636) (xy 25.243227 -266.70366) (xy 25.29278 -266.721458)
			(xy 25.339036 -266.746611) (xy 25.38091 -266.77853) (xy 25.417422 -266.816468) (xy 25.447714 -266.859534)
			(xy 25.471077 -266.906719) (xy 25.486963 -266.956918) (xy 25.495 -267.008954) (xy 25.495504 -267.03528)
			(xy 32.351983 -267.03528) (xy 32.356013 -266.982782) (xy 32.36801 -266.931514) (xy 32.387693 -266.882679)
			(xy 32.414599 -266.83742) (xy 32.448099 -266.796799) (xy 32.487407 -266.761768) (xy 32.531602 -266.733148)
			(xy 32.579647 -266.711609) (xy 32.630418 -266.697657) (xy 32.682723 -266.691619) (xy 32.735337 -266.693636)
			(xy 32.787027 -266.70366) (xy 32.83658 -266.721458) (xy 32.882836 -266.746611) (xy 32.92471 -266.77853)
			(xy 32.961222 -266.816468) (xy 32.991514 -266.859534) (xy 33.014877 -266.906719) (xy 33.030763 -266.956918)
			(xy 33.0388 -267.008954) (xy 33.039304 -267.03528) (xy 39.896037 -267.03528) (xy 39.900067 -266.982782)
			(xy 39.912064 -266.931514) (xy 39.931747 -266.882679) (xy 39.958653 -266.83742) (xy 39.992153 -266.796799)
			(xy 40.031461 -266.761768) (xy 40.075656 -266.733148) (xy 40.123701 -266.711609) (xy 40.174472 -266.697657)
			(xy 40.226777 -266.691619) (xy 40.279391 -266.693636) (xy 40.331081 -266.70366) (xy 40.380634 -266.721458)
			(xy 40.42689 -266.746611) (xy 40.468764 -266.77853) (xy 40.505276 -266.816468) (xy 40.535568 -266.859534)
			(xy 40.558931 -266.906719) (xy 40.574817 -266.956918) (xy 40.582854 -267.008954) (xy 40.583358 -267.03528)
			(xy 47.440091 -267.03528) (xy 47.444121 -266.982782) (xy 47.456118 -266.931514) (xy 47.475801 -266.882679)
			(xy 47.502707 -266.83742) (xy 47.536207 -266.796799) (xy 47.575515 -266.761768) (xy 47.61971 -266.733148)
			(xy 47.667755 -266.711609) (xy 47.718526 -266.697657) (xy 47.770831 -266.691619) (xy 47.823445 -266.693636)
			(xy 47.875135 -266.70366) (xy 47.924688 -266.721458) (xy 47.970944 -266.746611) (xy 48.012818 -266.77853)
			(xy 48.04933 -266.816468) (xy 48.079622 -266.859534) (xy 48.102985 -266.906719) (xy 48.118871 -266.956918)
			(xy 48.126908 -267.008954) (xy 48.127412 -267.03528) (xy 48.126908 -267.061606) (xy 48.118871 -267.113642)
			(xy 48.102985 -267.163841) (xy 48.079622 -267.211026) (xy 48.04933 -267.254092) (xy 48.012818 -267.29203)
			(xy 47.970944 -267.323949) (xy 47.924688 -267.349102) (xy 47.875135 -267.3669) (xy 47.823445 -267.376924)
			(xy 47.770831 -267.378941) (xy 47.718526 -267.372903) (xy 47.667755 -267.358951) (xy 47.61971 -267.337412)
			(xy 47.575515 -267.308792) (xy 47.536207 -267.273761) (xy 47.502707 -267.23314) (xy 47.475801 -267.187881)
			(xy 47.456118 -267.139046) (xy 47.444121 -267.087778) (xy 47.440091 -267.03528) (xy 40.583358 -267.03528)
			(xy 40.582854 -267.061606) (xy 40.574817 -267.113642) (xy 40.558931 -267.163841) (xy 40.535568 -267.211026)
			(xy 40.505276 -267.254092) (xy 40.468764 -267.29203) (xy 40.42689 -267.323949) (xy 40.380634 -267.349102)
			(xy 40.331081 -267.3669) (xy 40.279391 -267.376924) (xy 40.226777 -267.378941) (xy 40.174472 -267.372903)
			(xy 40.123701 -267.358951) (xy 40.075656 -267.337412) (xy 40.031461 -267.308792) (xy 39.992153 -267.273761)
			(xy 39.958653 -267.23314) (xy 39.931747 -267.187881) (xy 39.912064 -267.139046) (xy 39.900067 -267.087778)
			(xy 39.896037 -267.03528) (xy 33.039304 -267.03528) (xy 33.0388 -267.061606) (xy 33.030763 -267.113642)
			(xy 33.014877 -267.163841) (xy 32.991514 -267.211026) (xy 32.961222 -267.254092) (xy 32.92471 -267.29203)
			(xy 32.882836 -267.323949) (xy 32.83658 -267.349102) (xy 32.787027 -267.3669) (xy 32.735337 -267.376924)
			(xy 32.682723 -267.378941) (xy 32.630418 -267.372903) (xy 32.579647 -267.358951) (xy 32.531602 -267.337412)
			(xy 32.487407 -267.308792) (xy 32.448099 -267.273761) (xy 32.414599 -267.23314) (xy 32.387693 -267.187881)
			(xy 32.36801 -267.139046) (xy 32.356013 -267.087778) (xy 32.351983 -267.03528) (xy 25.495504 -267.03528)
			(xy 25.495 -267.061606) (xy 25.486963 -267.113642) (xy 25.471077 -267.163841) (xy 25.447714 -267.211026)
			(xy 25.417422 -267.254092) (xy 25.38091 -267.29203) (xy 25.339036 -267.323949) (xy 25.29278 -267.349102)
			(xy 25.243227 -267.3669) (xy 25.191537 -267.376924) (xy 25.138923 -267.378941) (xy 25.086618 -267.372903)
			(xy 25.035847 -267.358951) (xy 24.987802 -267.337412) (xy 24.943607 -267.308792) (xy 24.904299 -267.273761)
			(xy 24.870799 -267.23314) (xy 24.843893 -267.187881) (xy 24.82421 -267.139046) (xy 24.812213 -267.087778)
			(xy 24.808183 -267.03528) (xy 17.95145 -267.03528) (xy 17.950946 -267.061606) (xy 17.942909 -267.113642)
			(xy 17.927023 -267.163841) (xy 17.90366 -267.211026) (xy 17.873368 -267.254092) (xy 17.836856 -267.29203)
			(xy 17.794982 -267.323949) (xy 17.748726 -267.349102) (xy 17.699173 -267.3669) (xy 17.647483 -267.376924)
			(xy 17.594869 -267.378941) (xy 17.542564 -267.372903) (xy 17.491793 -267.358951) (xy 17.443748 -267.337412)
			(xy 17.399553 -267.308792) (xy 17.360245 -267.273761) (xy 17.326745 -267.23314) (xy 17.299839 -267.187881)
			(xy 17.280156 -267.139046) (xy 17.268159 -267.087778) (xy 17.264129 -267.03528) (xy 16.086074 -267.03528)
			(xy 16.086074 -267.885418) (xy 21.364197 -267.885418) (xy 21.368227 -267.83292) (xy 21.380224 -267.781652)
			(xy 21.399907 -267.732817) (xy 21.426813 -267.687558) (xy 21.460313 -267.646937) (xy 21.499621 -267.611906)
			(xy 21.543816 -267.583286) (xy 21.591861 -267.561747) (xy 21.642632 -267.547795) (xy 21.694937 -267.541757)
			(xy 21.747551 -267.543774) (xy 21.799241 -267.553798) (xy 21.848794 -267.571596) (xy 21.89505 -267.596749)
			(xy 21.936924 -267.628668) (xy 21.973436 -267.666606) (xy 22.003728 -267.709672) (xy 22.027091 -267.756857)
			(xy 22.042977 -267.807056) (xy 22.051014 -267.859092) (xy 22.051518 -267.885418) (xy 28.908251 -267.885418)
			(xy 28.912281 -267.83292) (xy 28.924278 -267.781652) (xy 28.943961 -267.732817) (xy 28.970867 -267.687558)
			(xy 29.004367 -267.646937) (xy 29.043675 -267.611906) (xy 29.08787 -267.583286) (xy 29.135915 -267.561747)
			(xy 29.186686 -267.547795) (xy 29.238991 -267.541757) (xy 29.291605 -267.543774) (xy 29.343295 -267.553798)
			(xy 29.392848 -267.571596) (xy 29.439104 -267.596749) (xy 29.480978 -267.628668) (xy 29.51749 -267.666606)
			(xy 29.547782 -267.709672) (xy 29.571145 -267.756857) (xy 29.587031 -267.807056) (xy 29.595068 -267.859092)
			(xy 29.595572 -267.885418) (xy 36.452051 -267.885418) (xy 36.456081 -267.83292) (xy 36.468078 -267.781652)
			(xy 36.487761 -267.732817) (xy 36.514667 -267.687558) (xy 36.548167 -267.646937) (xy 36.587475 -267.611906)
			(xy 36.63167 -267.583286) (xy 36.679715 -267.561747) (xy 36.730486 -267.547795) (xy 36.782791 -267.541757)
			(xy 36.835405 -267.543774) (xy 36.887095 -267.553798) (xy 36.936648 -267.571596) (xy 36.982904 -267.596749)
			(xy 37.024778 -267.628668) (xy 37.06129 -267.666606) (xy 37.091582 -267.709672) (xy 37.114945 -267.756857)
			(xy 37.130831 -267.807056) (xy 37.138868 -267.859092) (xy 37.139372 -267.885418) (xy 43.996105 -267.885418)
			(xy 44.000135 -267.83292) (xy 44.012132 -267.781652) (xy 44.031815 -267.732817) (xy 44.058721 -267.687558)
			(xy 44.092221 -267.646937) (xy 44.131529 -267.611906) (xy 44.175724 -267.583286) (xy 44.223769 -267.561747)
			(xy 44.27454 -267.547795) (xy 44.326845 -267.541757) (xy 44.379459 -267.543774) (xy 44.431149 -267.553798)
			(xy 44.480702 -267.571596) (xy 44.526958 -267.596749) (xy 44.568832 -267.628668) (xy 44.605344 -267.666606)
			(xy 44.635636 -267.709672) (xy 44.658999 -267.756857) (xy 44.674885 -267.807056) (xy 44.682922 -267.859092)
			(xy 44.683426 -267.885418) (xy 51.540159 -267.885418) (xy 51.544189 -267.83292) (xy 51.556186 -267.781652)
			(xy 51.575869 -267.732817) (xy 51.602775 -267.687558) (xy 51.636275 -267.646937) (xy 51.675583 -267.611906)
			(xy 51.719778 -267.583286) (xy 51.767823 -267.561747) (xy 51.818594 -267.547795) (xy 51.870899 -267.541757)
			(xy 51.923513 -267.543774) (xy 51.975203 -267.553798) (xy 52.024756 -267.571596) (xy 52.071012 -267.596749)
			(xy 52.112886 -267.628668) (xy 52.149398 -267.666606) (xy 52.17969 -267.709672) (xy 52.203053 -267.756857)
			(xy 52.218939 -267.807056) (xy 52.226976 -267.859092) (xy 52.22748 -267.885418) (xy 52.226976 -267.911744)
			(xy 52.218939 -267.96378) (xy 52.203053 -268.013979) (xy 52.17969 -268.061164) (xy 52.149398 -268.10423)
			(xy 52.112886 -268.142168) (xy 52.071012 -268.174087) (xy 52.024756 -268.19924) (xy 51.975203 -268.217038)
			(xy 51.923513 -268.227062) (xy 51.870899 -268.229079) (xy 51.818594 -268.223041) (xy 51.767823 -268.209089)
			(xy 51.719778 -268.18755) (xy 51.675583 -268.15893) (xy 51.636275 -268.123899) (xy 51.602775 -268.083278)
			(xy 51.575869 -268.038019) (xy 51.556186 -267.989184) (xy 51.544189 -267.937916) (xy 51.540159 -267.885418)
			(xy 44.683426 -267.885418) (xy 44.682922 -267.911744) (xy 44.674885 -267.96378) (xy 44.658999 -268.013979)
			(xy 44.635636 -268.061164) (xy 44.605344 -268.10423) (xy 44.568832 -268.142168) (xy 44.526958 -268.174087)
			(xy 44.480702 -268.19924) (xy 44.431149 -268.217038) (xy 44.379459 -268.227062) (xy 44.326845 -268.229079)
			(xy 44.27454 -268.223041) (xy 44.223769 -268.209089) (xy 44.175724 -268.18755) (xy 44.131529 -268.15893)
			(xy 44.092221 -268.123899) (xy 44.058721 -268.083278) (xy 44.031815 -268.038019) (xy 44.012132 -267.989184)
			(xy 44.000135 -267.937916) (xy 43.996105 -267.885418) (xy 37.139372 -267.885418) (xy 37.138868 -267.911744)
			(xy 37.130831 -267.96378) (xy 37.114945 -268.013979) (xy 37.091582 -268.061164) (xy 37.06129 -268.10423)
			(xy 37.024778 -268.142168) (xy 36.982904 -268.174087) (xy 36.936648 -268.19924) (xy 36.887095 -268.217038)
			(xy 36.835405 -268.227062) (xy 36.782791 -268.229079) (xy 36.730486 -268.223041) (xy 36.679715 -268.209089)
			(xy 36.63167 -268.18755) (xy 36.587475 -268.15893) (xy 36.548167 -268.123899) (xy 36.514667 -268.083278)
			(xy 36.487761 -268.038019) (xy 36.468078 -267.989184) (xy 36.456081 -267.937916) (xy 36.452051 -267.885418)
			(xy 29.595572 -267.885418) (xy 29.595068 -267.911744) (xy 29.587031 -267.96378) (xy 29.571145 -268.013979)
			(xy 29.547782 -268.061164) (xy 29.51749 -268.10423) (xy 29.480978 -268.142168) (xy 29.439104 -268.174087)
			(xy 29.392848 -268.19924) (xy 29.343295 -268.217038) (xy 29.291605 -268.227062) (xy 29.238991 -268.229079)
			(xy 29.186686 -268.223041) (xy 29.135915 -268.209089) (xy 29.08787 -268.18755) (xy 29.043675 -268.15893)
			(xy 29.004367 -268.123899) (xy 28.970867 -268.083278) (xy 28.943961 -268.038019) (xy 28.924278 -267.989184)
			(xy 28.912281 -267.937916) (xy 28.908251 -267.885418) (xy 22.051518 -267.885418) (xy 22.051014 -267.911744)
			(xy 22.042977 -267.96378) (xy 22.027091 -268.013979) (xy 22.003728 -268.061164) (xy 21.973436 -268.10423)
			(xy 21.936924 -268.142168) (xy 21.89505 -268.174087) (xy 21.848794 -268.19924) (xy 21.799241 -268.217038)
			(xy 21.747551 -268.227062) (xy 21.694937 -268.229079) (xy 21.642632 -268.223041) (xy 21.591861 -268.209089)
			(xy 21.543816 -268.18755) (xy 21.499621 -268.15893) (xy 21.460313 -268.123899) (xy 21.426813 -268.083278)
			(xy 21.399907 -268.038019) (xy 21.380224 -267.989184) (xy 21.368227 -267.937916) (xy 21.364197 -267.885418)
			(xy 16.086074 -267.885418) (xy 16.086074 -268.735302) (xy 17.264129 -268.735302) (xy 17.268159 -268.682804)
			(xy 17.280156 -268.631536) (xy 17.299839 -268.582701) (xy 17.326745 -268.537442) (xy 17.360245 -268.496821)
			(xy 17.399553 -268.46179) (xy 17.443748 -268.43317) (xy 17.491793 -268.411631) (xy 17.542564 -268.397679)
			(xy 17.594869 -268.391641) (xy 17.647483 -268.393658) (xy 17.699173 -268.403682) (xy 17.748726 -268.42148)
			(xy 17.794982 -268.446633) (xy 17.836856 -268.478552) (xy 17.873368 -268.51649) (xy 17.90366 -268.559556)
			(xy 17.927023 -268.606741) (xy 17.942909 -268.65694) (xy 17.950946 -268.708976) (xy 17.95145 -268.735302)
			(xy 24.808183 -268.735302) (xy 24.812213 -268.682804) (xy 24.82421 -268.631536) (xy 24.843893 -268.582701)
			(xy 24.870799 -268.537442) (xy 24.904299 -268.496821) (xy 24.943607 -268.46179) (xy 24.987802 -268.43317)
			(xy 25.035847 -268.411631) (xy 25.086618 -268.397679) (xy 25.138923 -268.391641) (xy 25.191537 -268.393658)
			(xy 25.243227 -268.403682) (xy 25.29278 -268.42148) (xy 25.339036 -268.446633) (xy 25.38091 -268.478552)
			(xy 25.417422 -268.51649) (xy 25.447714 -268.559556) (xy 25.471077 -268.606741) (xy 25.486963 -268.65694)
			(xy 25.495 -268.708976) (xy 25.495504 -268.735302) (xy 32.351983 -268.735302) (xy 32.356013 -268.682804)
			(xy 32.36801 -268.631536) (xy 32.387693 -268.582701) (xy 32.414599 -268.537442) (xy 32.448099 -268.496821)
			(xy 32.487407 -268.46179) (xy 32.531602 -268.43317) (xy 32.579647 -268.411631) (xy 32.630418 -268.397679)
			(xy 32.682723 -268.391641) (xy 32.735337 -268.393658) (xy 32.787027 -268.403682) (xy 32.83658 -268.42148)
			(xy 32.882836 -268.446633) (xy 32.92471 -268.478552) (xy 32.961222 -268.51649) (xy 32.991514 -268.559556)
			(xy 33.014877 -268.606741) (xy 33.030763 -268.65694) (xy 33.0388 -268.708976) (xy 33.039304 -268.735302)
			(xy 39.896037 -268.735302) (xy 39.900067 -268.682804) (xy 39.912064 -268.631536) (xy 39.931747 -268.582701)
			(xy 39.958653 -268.537442) (xy 39.992153 -268.496821) (xy 40.031461 -268.46179) (xy 40.075656 -268.43317)
			(xy 40.123701 -268.411631) (xy 40.174472 -268.397679) (xy 40.226777 -268.391641) (xy 40.279391 -268.393658)
			(xy 40.331081 -268.403682) (xy 40.380634 -268.42148) (xy 40.42689 -268.446633) (xy 40.468764 -268.478552)
			(xy 40.505276 -268.51649) (xy 40.535568 -268.559556) (xy 40.558931 -268.606741) (xy 40.574817 -268.65694)
			(xy 40.582854 -268.708976) (xy 40.583358 -268.735302) (xy 47.440091 -268.735302) (xy 47.444121 -268.682804)
			(xy 47.456118 -268.631536) (xy 47.475801 -268.582701) (xy 47.502707 -268.537442) (xy 47.536207 -268.496821)
			(xy 47.575515 -268.46179) (xy 47.61971 -268.43317) (xy 47.667755 -268.411631) (xy 47.718526 -268.397679)
			(xy 47.770831 -268.391641) (xy 47.823445 -268.393658) (xy 47.875135 -268.403682) (xy 47.924688 -268.42148)
			(xy 47.970944 -268.446633) (xy 48.012818 -268.478552) (xy 48.04933 -268.51649) (xy 48.079622 -268.559556)
			(xy 48.102985 -268.606741) (xy 48.118871 -268.65694) (xy 48.126908 -268.708976) (xy 48.127412 -268.735302)
			(xy 48.126908 -268.761628) (xy 48.118871 -268.813664) (xy 48.102985 -268.863863) (xy 48.079622 -268.911048)
			(xy 48.04933 -268.954114) (xy 48.012818 -268.992052) (xy 47.970944 -269.023971) (xy 47.924688 -269.049124)
			(xy 47.875135 -269.066922) (xy 47.823445 -269.076946) (xy 47.770831 -269.078963) (xy 47.718526 -269.072925)
			(xy 47.667755 -269.058973) (xy 47.61971 -269.037434) (xy 47.575515 -269.008814) (xy 47.536207 -268.973783)
			(xy 47.502707 -268.933162) (xy 47.475801 -268.887903) (xy 47.456118 -268.839068) (xy 47.444121 -268.7878)
			(xy 47.440091 -268.735302) (xy 40.583358 -268.735302) (xy 40.582854 -268.761628) (xy 40.574817 -268.813664)
			(xy 40.558931 -268.863863) (xy 40.535568 -268.911048) (xy 40.505276 -268.954114) (xy 40.468764 -268.992052)
			(xy 40.42689 -269.023971) (xy 40.380634 -269.049124) (xy 40.331081 -269.066922) (xy 40.279391 -269.076946)
			(xy 40.226777 -269.078963) (xy 40.174472 -269.072925) (xy 40.123701 -269.058973) (xy 40.075656 -269.037434)
			(xy 40.031461 -269.008814) (xy 39.992153 -268.973783) (xy 39.958653 -268.933162) (xy 39.931747 -268.887903)
			(xy 39.912064 -268.839068) (xy 39.900067 -268.7878) (xy 39.896037 -268.735302) (xy 33.039304 -268.735302)
			(xy 33.0388 -268.761628) (xy 33.030763 -268.813664) (xy 33.014877 -268.863863) (xy 32.991514 -268.911048)
			(xy 32.961222 -268.954114) (xy 32.92471 -268.992052) (xy 32.882836 -269.023971) (xy 32.83658 -269.049124)
			(xy 32.787027 -269.066922) (xy 32.735337 -269.076946) (xy 32.682723 -269.078963) (xy 32.630418 -269.072925)
			(xy 32.579647 -269.058973) (xy 32.531602 -269.037434) (xy 32.487407 -269.008814) (xy 32.448099 -268.973783)
			(xy 32.414599 -268.933162) (xy 32.387693 -268.887903) (xy 32.36801 -268.839068) (xy 32.356013 -268.7878)
			(xy 32.351983 -268.735302) (xy 25.495504 -268.735302) (xy 25.495 -268.761628) (xy 25.486963 -268.813664)
			(xy 25.471077 -268.863863) (xy 25.447714 -268.911048) (xy 25.417422 -268.954114) (xy 25.38091 -268.992052)
			(xy 25.339036 -269.023971) (xy 25.29278 -269.049124) (xy 25.243227 -269.066922) (xy 25.191537 -269.076946)
			(xy 25.138923 -269.078963) (xy 25.086618 -269.072925) (xy 25.035847 -269.058973) (xy 24.987802 -269.037434)
			(xy 24.943607 -269.008814) (xy 24.904299 -268.973783) (xy 24.870799 -268.933162) (xy 24.843893 -268.887903)
			(xy 24.82421 -268.839068) (xy 24.812213 -268.7878) (xy 24.808183 -268.735302) (xy 17.95145 -268.735302)
			(xy 17.950946 -268.761628) (xy 17.942909 -268.813664) (xy 17.927023 -268.863863) (xy 17.90366 -268.911048)
			(xy 17.873368 -268.954114) (xy 17.836856 -268.992052) (xy 17.794982 -269.023971) (xy 17.748726 -269.049124)
			(xy 17.699173 -269.066922) (xy 17.647483 -269.076946) (xy 17.594869 -269.078963) (xy 17.542564 -269.072925)
			(xy 17.491793 -269.058973) (xy 17.443748 -269.037434) (xy 17.399553 -269.008814) (xy 17.360245 -268.973783)
			(xy 17.326745 -268.933162) (xy 17.299839 -268.887903) (xy 17.280156 -268.839068) (xy 17.268159 -268.7878)
			(xy 17.264129 -268.735302) (xy 16.086074 -268.735302) (xy 16.086074 -269.58544) (xy 21.364197 -269.58544)
			(xy 21.368227 -269.532942) (xy 21.380224 -269.481674) (xy 21.399907 -269.432839) (xy 21.426813 -269.38758)
			(xy 21.460313 -269.346959) (xy 21.499621 -269.311928) (xy 21.543816 -269.283308) (xy 21.591861 -269.261769)
			(xy 21.642632 -269.247817) (xy 21.694937 -269.241779) (xy 21.747551 -269.243796) (xy 21.799241 -269.25382)
			(xy 21.848794 -269.271618) (xy 21.89505 -269.296771) (xy 21.936924 -269.32869) (xy 21.973436 -269.366628)
			(xy 22.003728 -269.409694) (xy 22.027091 -269.456879) (xy 22.042977 -269.507078) (xy 22.051014 -269.559114)
			(xy 22.051518 -269.58544) (xy 28.908251 -269.58544) (xy 28.912281 -269.532942) (xy 28.924278 -269.481674)
			(xy 28.943961 -269.432839) (xy 28.970867 -269.38758) (xy 29.004367 -269.346959) (xy 29.043675 -269.311928)
			(xy 29.08787 -269.283308) (xy 29.135915 -269.261769) (xy 29.186686 -269.247817) (xy 29.238991 -269.241779)
			(xy 29.291605 -269.243796) (xy 29.343295 -269.25382) (xy 29.392848 -269.271618) (xy 29.439104 -269.296771)
			(xy 29.480978 -269.32869) (xy 29.51749 -269.366628) (xy 29.547782 -269.409694) (xy 29.571145 -269.456879)
			(xy 29.587031 -269.507078) (xy 29.595068 -269.559114) (xy 29.595572 -269.58544) (xy 36.452051 -269.58544)
			(xy 36.456081 -269.532942) (xy 36.468078 -269.481674) (xy 36.487761 -269.432839) (xy 36.514667 -269.38758)
			(xy 36.548167 -269.346959) (xy 36.587475 -269.311928) (xy 36.63167 -269.283308) (xy 36.679715 -269.261769)
			(xy 36.730486 -269.247817) (xy 36.782791 -269.241779) (xy 36.835405 -269.243796) (xy 36.887095 -269.25382)
			(xy 36.936648 -269.271618) (xy 36.982904 -269.296771) (xy 37.024778 -269.32869) (xy 37.06129 -269.366628)
			(xy 37.091582 -269.409694) (xy 37.114945 -269.456879) (xy 37.130831 -269.507078) (xy 37.138868 -269.559114)
			(xy 37.139372 -269.58544) (xy 43.996105 -269.58544) (xy 44.000135 -269.532942) (xy 44.012132 -269.481674)
			(xy 44.031815 -269.432839) (xy 44.058721 -269.38758) (xy 44.092221 -269.346959) (xy 44.131529 -269.311928)
			(xy 44.175724 -269.283308) (xy 44.223769 -269.261769) (xy 44.27454 -269.247817) (xy 44.326845 -269.241779)
			(xy 44.379459 -269.243796) (xy 44.431149 -269.25382) (xy 44.480702 -269.271618) (xy 44.526958 -269.296771)
			(xy 44.568832 -269.32869) (xy 44.605344 -269.366628) (xy 44.635636 -269.409694) (xy 44.658999 -269.456879)
			(xy 44.674885 -269.507078) (xy 44.682922 -269.559114) (xy 44.683426 -269.58544) (xy 51.540159 -269.58544)
			(xy 51.544189 -269.532942) (xy 51.556186 -269.481674) (xy 51.575869 -269.432839) (xy 51.602775 -269.38758)
			(xy 51.636275 -269.346959) (xy 51.675583 -269.311928) (xy 51.719778 -269.283308) (xy 51.767823 -269.261769)
			(xy 51.818594 -269.247817) (xy 51.870899 -269.241779) (xy 51.923513 -269.243796) (xy 51.975203 -269.25382)
			(xy 52.024756 -269.271618) (xy 52.071012 -269.296771) (xy 52.112886 -269.32869) (xy 52.149398 -269.366628)
			(xy 52.17969 -269.409694) (xy 52.203053 -269.456879) (xy 52.218939 -269.507078) (xy 52.226976 -269.559114)
			(xy 52.22748 -269.58544) (xy 52.226976 -269.611766) (xy 52.218939 -269.663802) (xy 52.203053 -269.714001)
			(xy 52.17969 -269.761186) (xy 52.149398 -269.804252) (xy 52.112886 -269.84219) (xy 52.071012 -269.874109)
			(xy 52.024756 -269.899262) (xy 51.975203 -269.91706) (xy 51.923513 -269.927084) (xy 51.870899 -269.929101)
			(xy 51.818594 -269.923063) (xy 51.767823 -269.909111) (xy 51.719778 -269.887572) (xy 51.675583 -269.858952)
			(xy 51.636275 -269.823921) (xy 51.602775 -269.7833) (xy 51.575869 -269.738041) (xy 51.556186 -269.689206)
			(xy 51.544189 -269.637938) (xy 51.540159 -269.58544) (xy 44.683426 -269.58544) (xy 44.682922 -269.611766)
			(xy 44.674885 -269.663802) (xy 44.658999 -269.714001) (xy 44.635636 -269.761186) (xy 44.605344 -269.804252)
			(xy 44.568832 -269.84219) (xy 44.526958 -269.874109) (xy 44.480702 -269.899262) (xy 44.431149 -269.91706)
			(xy 44.379459 -269.927084) (xy 44.326845 -269.929101) (xy 44.27454 -269.923063) (xy 44.223769 -269.909111)
			(xy 44.175724 -269.887572) (xy 44.131529 -269.858952) (xy 44.092221 -269.823921) (xy 44.058721 -269.7833)
			(xy 44.031815 -269.738041) (xy 44.012132 -269.689206) (xy 44.000135 -269.637938) (xy 43.996105 -269.58544)
			(xy 37.139372 -269.58544) (xy 37.138868 -269.611766) (xy 37.130831 -269.663802) (xy 37.114945 -269.714001)
			(xy 37.091582 -269.761186) (xy 37.06129 -269.804252) (xy 37.024778 -269.84219) (xy 36.982904 -269.874109)
			(xy 36.936648 -269.899262) (xy 36.887095 -269.91706) (xy 36.835405 -269.927084) (xy 36.782791 -269.929101)
			(xy 36.730486 -269.923063) (xy 36.679715 -269.909111) (xy 36.63167 -269.887572) (xy 36.587475 -269.858952)
			(xy 36.548167 -269.823921) (xy 36.514667 -269.7833) (xy 36.487761 -269.738041) (xy 36.468078 -269.689206)
			(xy 36.456081 -269.637938) (xy 36.452051 -269.58544) (xy 29.595572 -269.58544) (xy 29.595068 -269.611766)
			(xy 29.587031 -269.663802) (xy 29.571145 -269.714001) (xy 29.547782 -269.761186) (xy 29.51749 -269.804252)
			(xy 29.480978 -269.84219) (xy 29.439104 -269.874109) (xy 29.392848 -269.899262) (xy 29.343295 -269.91706)
			(xy 29.291605 -269.927084) (xy 29.238991 -269.929101) (xy 29.186686 -269.923063) (xy 29.135915 -269.909111)
			(xy 29.08787 -269.887572) (xy 29.043675 -269.858952) (xy 29.004367 -269.823921) (xy 28.970867 -269.7833)
			(xy 28.943961 -269.738041) (xy 28.924278 -269.689206) (xy 28.912281 -269.637938) (xy 28.908251 -269.58544)
			(xy 22.051518 -269.58544) (xy 22.051014 -269.611766) (xy 22.042977 -269.663802) (xy 22.027091 -269.714001)
			(xy 22.003728 -269.761186) (xy 21.973436 -269.804252) (xy 21.936924 -269.84219) (xy 21.89505 -269.874109)
			(xy 21.848794 -269.899262) (xy 21.799241 -269.91706) (xy 21.747551 -269.927084) (xy 21.694937 -269.929101)
			(xy 21.642632 -269.923063) (xy 21.591861 -269.909111) (xy 21.543816 -269.887572) (xy 21.499621 -269.858952)
			(xy 21.460313 -269.823921) (xy 21.426813 -269.7833) (xy 21.399907 -269.738041) (xy 21.380224 -269.689206)
			(xy 21.368227 -269.637938) (xy 21.364197 -269.58544) (xy 16.086074 -269.58544) (xy 16.086074 -270.435324)
			(xy 17.238741 -270.435324) (xy 17.242676 -270.381553) (xy 17.254399 -270.328929) (xy 17.273659 -270.278572)
			(xy 17.300045 -270.231555) (xy 17.332997 -270.188882) (xy 17.37181 -270.151461) (xy 17.415658 -270.120091)
			(xy 17.463606 -270.095439) (xy 17.514633 -270.078031) (xy 17.567651 -270.068238) (xy 17.62153 -270.066269)
			(xy 17.675121 -270.072166) (xy 17.727282 -270.085802) (xy 17.776902 -270.106889) (xy 17.822923 -270.134975)
			(xy 17.864365 -270.169463) (xy 17.900343 -270.209617) (xy 17.930091 -270.254581) (xy 17.952976 -270.303398)
			(xy 17.968508 -270.355027) (xy 17.976358 -270.408367) (xy 17.97685 -270.435324) (xy 21.364197 -270.435324)
			(xy 21.368227 -270.382826) (xy 21.380224 -270.331558) (xy 21.399907 -270.282723) (xy 21.426813 -270.237464)
			(xy 21.460313 -270.196843) (xy 21.499621 -270.161812) (xy 21.543816 -270.133192) (xy 21.591861 -270.111653)
			(xy 21.642632 -270.097701) (xy 21.694937 -270.091663) (xy 21.747551 -270.09368) (xy 21.799241 -270.103704)
			(xy 21.848794 -270.121502) (xy 21.89505 -270.146655) (xy 21.936924 -270.178574) (xy 21.973436 -270.216512)
			(xy 22.003728 -270.259578) (xy 22.027091 -270.306763) (xy 22.042977 -270.356962) (xy 22.051014 -270.408998)
			(xy 22.051518 -270.435324) (xy 24.782795 -270.435324) (xy 24.78673 -270.381553) (xy 24.798453 -270.328929)
			(xy 24.817713 -270.278572) (xy 24.844099 -270.231555) (xy 24.877051 -270.188882) (xy 24.915864 -270.151461)
			(xy 24.959712 -270.120091) (xy 25.00766 -270.095439) (xy 25.058687 -270.078031) (xy 25.111705 -270.068238)
			(xy 25.165584 -270.066269) (xy 25.219175 -270.072166) (xy 25.271336 -270.085802) (xy 25.320956 -270.106889)
			(xy 25.366977 -270.134975) (xy 25.408419 -270.169463) (xy 25.444397 -270.209617) (xy 25.474145 -270.254581)
			(xy 25.49703 -270.303398) (xy 25.512562 -270.355027) (xy 25.520412 -270.408367) (xy 25.520904 -270.435324)
			(xy 28.908251 -270.435324) (xy 28.912281 -270.382826) (xy 28.924278 -270.331558) (xy 28.943961 -270.282723)
			(xy 28.970867 -270.237464) (xy 29.004367 -270.196843) (xy 29.043675 -270.161812) (xy 29.08787 -270.133192)
			(xy 29.135915 -270.111653) (xy 29.186686 -270.097701) (xy 29.238991 -270.091663) (xy 29.291605 -270.09368)
			(xy 29.343295 -270.103704) (xy 29.392848 -270.121502) (xy 29.439104 -270.146655) (xy 29.480978 -270.178574)
			(xy 29.51749 -270.216512) (xy 29.547782 -270.259578) (xy 29.571145 -270.306763) (xy 29.587031 -270.356962)
			(xy 29.595068 -270.408998) (xy 29.595572 -270.435324) (xy 32.326595 -270.435324) (xy 32.33053 -270.381553)
			(xy 32.342253 -270.328929) (xy 32.361513 -270.278572) (xy 32.387899 -270.231555) (xy 32.420851 -270.188882)
			(xy 32.459664 -270.151461) (xy 32.503512 -270.120091) (xy 32.55146 -270.095439) (xy 32.602487 -270.078031)
			(xy 32.655505 -270.068238) (xy 32.709384 -270.066269) (xy 32.762975 -270.072166) (xy 32.815136 -270.085802)
			(xy 32.864756 -270.106889) (xy 32.910777 -270.134975) (xy 32.952219 -270.169463) (xy 32.988197 -270.209617)
			(xy 33.017945 -270.254581) (xy 33.04083 -270.303398) (xy 33.056362 -270.355027) (xy 33.064212 -270.408367)
			(xy 33.064704 -270.435324) (xy 36.452051 -270.435324) (xy 36.456081 -270.382826) (xy 36.468078 -270.331558)
			(xy 36.487761 -270.282723) (xy 36.514667 -270.237464) (xy 36.548167 -270.196843) (xy 36.587475 -270.161812)
			(xy 36.63167 -270.133192) (xy 36.679715 -270.111653) (xy 36.730486 -270.097701) (xy 36.782791 -270.091663)
			(xy 36.835405 -270.09368) (xy 36.887095 -270.103704) (xy 36.936648 -270.121502) (xy 36.982904 -270.146655)
			(xy 37.024778 -270.178574) (xy 37.06129 -270.216512) (xy 37.091582 -270.259578) (xy 37.114945 -270.306763)
			(xy 37.130831 -270.356962) (xy 37.138868 -270.408998) (xy 37.139372 -270.435324) (xy 39.870649 -270.435324)
			(xy 39.874584 -270.381553) (xy 39.886307 -270.328929) (xy 39.905567 -270.278572) (xy 39.931953 -270.231555)
			(xy 39.964905 -270.188882) (xy 40.003718 -270.151461) (xy 40.047566 -270.120091) (xy 40.095514 -270.095439)
			(xy 40.146541 -270.078031) (xy 40.199559 -270.068238) (xy 40.253438 -270.066269) (xy 40.307029 -270.072166)
			(xy 40.35919 -270.085802) (xy 40.40881 -270.106889) (xy 40.454831 -270.134975) (xy 40.496273 -270.169463)
			(xy 40.532251 -270.209617) (xy 40.561999 -270.254581) (xy 40.584884 -270.303398) (xy 40.600416 -270.355027)
			(xy 40.608266 -270.408367) (xy 40.608758 -270.435324) (xy 43.996105 -270.435324) (xy 44.000135 -270.382826)
			(xy 44.012132 -270.331558) (xy 44.031815 -270.282723) (xy 44.058721 -270.237464) (xy 44.092221 -270.196843)
			(xy 44.131529 -270.161812) (xy 44.175724 -270.133192) (xy 44.223769 -270.111653) (xy 44.27454 -270.097701)
			(xy 44.326845 -270.091663) (xy 44.379459 -270.09368) (xy 44.431149 -270.103704) (xy 44.480702 -270.121502)
			(xy 44.526958 -270.146655) (xy 44.568832 -270.178574) (xy 44.605344 -270.216512) (xy 44.635636 -270.259578)
			(xy 44.658999 -270.306763) (xy 44.674885 -270.356962) (xy 44.682922 -270.408998) (xy 44.683426 -270.435324)
			(xy 47.414703 -270.435324) (xy 47.418638 -270.381553) (xy 47.430361 -270.328929) (xy 47.449621 -270.278572)
			(xy 47.476007 -270.231555) (xy 47.508959 -270.188882) (xy 47.547772 -270.151461) (xy 47.59162 -270.120091)
			(xy 47.639568 -270.095439) (xy 47.690595 -270.078031) (xy 47.743613 -270.068238) (xy 47.797492 -270.066269)
			(xy 47.851083 -270.072166) (xy 47.903244 -270.085802) (xy 47.952864 -270.106889) (xy 47.998885 -270.134975)
			(xy 48.040327 -270.169463) (xy 48.076305 -270.209617) (xy 48.106053 -270.254581) (xy 48.128938 -270.303398)
			(xy 48.14447 -270.355027) (xy 48.15232 -270.408367) (xy 48.152812 -270.435324) (xy 51.540159 -270.435324)
			(xy 51.544189 -270.382826) (xy 51.556186 -270.331558) (xy 51.575869 -270.282723) (xy 51.602775 -270.237464)
			(xy 51.636275 -270.196843) (xy 51.675583 -270.161812) (xy 51.719778 -270.133192) (xy 51.767823 -270.111653)
			(xy 51.818594 -270.097701) (xy 51.870899 -270.091663) (xy 51.923513 -270.09368) (xy 51.975203 -270.103704)
			(xy 52.024756 -270.121502) (xy 52.071012 -270.146655) (xy 52.112886 -270.178574) (xy 52.149398 -270.216512)
			(xy 52.17969 -270.259578) (xy 52.203053 -270.306763) (xy 52.218939 -270.356962) (xy 52.226976 -270.408998)
			(xy 52.22748 -270.435324) (xy 52.226976 -270.46165) (xy 52.218939 -270.513686) (xy 52.203053 -270.563885)
			(xy 52.17969 -270.61107) (xy 52.149398 -270.654136) (xy 52.112886 -270.692074) (xy 52.071012 -270.723993)
			(xy 52.024756 -270.749146) (xy 51.975203 -270.766944) (xy 51.923513 -270.776968) (xy 51.870899 -270.778985)
			(xy 51.818594 -270.772947) (xy 51.767823 -270.758995) (xy 51.719778 -270.737456) (xy 51.675583 -270.708836)
			(xy 51.636275 -270.673805) (xy 51.602775 -270.633184) (xy 51.575869 -270.587925) (xy 51.556186 -270.53909)
			(xy 51.544189 -270.487822) (xy 51.540159 -270.435324) (xy 48.152812 -270.435324) (xy 48.15232 -270.462281)
			(xy 48.14447 -270.515621) (xy 48.128938 -270.56725) (xy 48.106053 -270.616067) (xy 48.076305 -270.661031)
			(xy 48.040327 -270.701185) (xy 47.998885 -270.735673) (xy 47.952864 -270.763759) (xy 47.903244 -270.784846)
			(xy 47.851083 -270.798482) (xy 47.797492 -270.804379) (xy 47.743613 -270.80241) (xy 47.690595 -270.792617)
			(xy 47.639568 -270.775209) (xy 47.59162 -270.750557) (xy 47.547772 -270.719187) (xy 47.508959 -270.681766)
			(xy 47.476007 -270.639093) (xy 47.449621 -270.592076) (xy 47.430361 -270.541719) (xy 47.418638 -270.489095)
			(xy 47.414703 -270.435324) (xy 44.683426 -270.435324) (xy 44.682922 -270.46165) (xy 44.674885 -270.513686)
			(xy 44.658999 -270.563885) (xy 44.635636 -270.61107) (xy 44.605344 -270.654136) (xy 44.568832 -270.692074)
			(xy 44.526958 -270.723993) (xy 44.480702 -270.749146) (xy 44.431149 -270.766944) (xy 44.379459 -270.776968)
			(xy 44.326845 -270.778985) (xy 44.27454 -270.772947) (xy 44.223769 -270.758995) (xy 44.175724 -270.737456)
			(xy 44.131529 -270.708836) (xy 44.092221 -270.673805) (xy 44.058721 -270.633184) (xy 44.031815 -270.587925)
			(xy 44.012132 -270.53909) (xy 44.000135 -270.487822) (xy 43.996105 -270.435324) (xy 40.608758 -270.435324)
			(xy 40.608266 -270.462281) (xy 40.600416 -270.515621) (xy 40.584884 -270.56725) (xy 40.561999 -270.616067)
			(xy 40.532251 -270.661031) (xy 40.496273 -270.701185) (xy 40.454831 -270.735673) (xy 40.40881 -270.763759)
			(xy 40.35919 -270.784846) (xy 40.307029 -270.798482) (xy 40.253438 -270.804379) (xy 40.199559 -270.80241)
			(xy 40.146541 -270.792617) (xy 40.095514 -270.775209) (xy 40.047566 -270.750557) (xy 40.003718 -270.719187)
			(xy 39.964905 -270.681766) (xy 39.931953 -270.639093) (xy 39.905567 -270.592076) (xy 39.886307 -270.541719)
			(xy 39.874584 -270.489095) (xy 39.870649 -270.435324) (xy 37.139372 -270.435324) (xy 37.138868 -270.46165)
			(xy 37.130831 -270.513686) (xy 37.114945 -270.563885) (xy 37.091582 -270.61107) (xy 37.06129 -270.654136)
			(xy 37.024778 -270.692074) (xy 36.982904 -270.723993) (xy 36.936648 -270.749146) (xy 36.887095 -270.766944)
			(xy 36.835405 -270.776968) (xy 36.782791 -270.778985) (xy 36.730486 -270.772947) (xy 36.679715 -270.758995)
			(xy 36.63167 -270.737456) (xy 36.587475 -270.708836) (xy 36.548167 -270.673805) (xy 36.514667 -270.633184)
			(xy 36.487761 -270.587925) (xy 36.468078 -270.53909) (xy 36.456081 -270.487822) (xy 36.452051 -270.435324)
			(xy 33.064704 -270.435324) (xy 33.064212 -270.462281) (xy 33.056362 -270.515621) (xy 33.04083 -270.56725)
			(xy 33.017945 -270.616067) (xy 32.988197 -270.661031) (xy 32.952219 -270.701185) (xy 32.910777 -270.735673)
			(xy 32.864756 -270.763759) (xy 32.815136 -270.784846) (xy 32.762975 -270.798482) (xy 32.709384 -270.804379)
			(xy 32.655505 -270.80241) (xy 32.602487 -270.792617) (xy 32.55146 -270.775209) (xy 32.503512 -270.750557)
			(xy 32.459664 -270.719187) (xy 32.420851 -270.681766) (xy 32.387899 -270.639093) (xy 32.361513 -270.592076)
			(xy 32.342253 -270.541719) (xy 32.33053 -270.489095) (xy 32.326595 -270.435324) (xy 29.595572 -270.435324)
			(xy 29.595068 -270.46165) (xy 29.587031 -270.513686) (xy 29.571145 -270.563885) (xy 29.547782 -270.61107)
			(xy 29.51749 -270.654136) (xy 29.480978 -270.692074) (xy 29.439104 -270.723993) (xy 29.392848 -270.749146)
			(xy 29.343295 -270.766944) (xy 29.291605 -270.776968) (xy 29.238991 -270.778985) (xy 29.186686 -270.772947)
			(xy 29.135915 -270.758995) (xy 29.08787 -270.737456) (xy 29.043675 -270.708836) (xy 29.004367 -270.673805)
			(xy 28.970867 -270.633184) (xy 28.943961 -270.587925) (xy 28.924278 -270.53909) (xy 28.912281 -270.487822)
			(xy 28.908251 -270.435324) (xy 25.520904 -270.435324) (xy 25.520412 -270.462281) (xy 25.512562 -270.515621)
			(xy 25.49703 -270.56725) (xy 25.474145 -270.616067) (xy 25.444397 -270.661031) (xy 25.408419 -270.701185)
			(xy 25.366977 -270.735673) (xy 25.320956 -270.763759) (xy 25.271336 -270.784846) (xy 25.219175 -270.798482)
			(xy 25.165584 -270.804379) (xy 25.111705 -270.80241) (xy 25.058687 -270.792617) (xy 25.00766 -270.775209)
			(xy 24.959712 -270.750557) (xy 24.915864 -270.719187) (xy 24.877051 -270.681766) (xy 24.844099 -270.639093)
			(xy 24.817713 -270.592076) (xy 24.798453 -270.541719) (xy 24.78673 -270.489095) (xy 24.782795 -270.435324)
			(xy 22.051518 -270.435324) (xy 22.051014 -270.46165) (xy 22.042977 -270.513686) (xy 22.027091 -270.563885)
			(xy 22.003728 -270.61107) (xy 21.973436 -270.654136) (xy 21.936924 -270.692074) (xy 21.89505 -270.723993)
			(xy 21.848794 -270.749146) (xy 21.799241 -270.766944) (xy 21.747551 -270.776968) (xy 21.694937 -270.778985)
			(xy 21.642632 -270.772947) (xy 21.591861 -270.758995) (xy 21.543816 -270.737456) (xy 21.499621 -270.708836)
			(xy 21.460313 -270.673805) (xy 21.426813 -270.633184) (xy 21.399907 -270.587925) (xy 21.380224 -270.53909)
			(xy 21.368227 -270.487822) (xy 21.364197 -270.435324) (xy 17.97685 -270.435324) (xy 17.976358 -270.462281)
			(xy 17.968508 -270.515621) (xy 17.952976 -270.56725) (xy 17.930091 -270.616067) (xy 17.900343 -270.661031)
			(xy 17.864365 -270.701185) (xy 17.822923 -270.735673) (xy 17.776902 -270.763759) (xy 17.727282 -270.784846)
			(xy 17.675121 -270.798482) (xy 17.62153 -270.804379) (xy 17.567651 -270.80241) (xy 17.514633 -270.792617)
			(xy 17.463606 -270.775209) (xy 17.415658 -270.750557) (xy 17.37181 -270.719187) (xy 17.332997 -270.681766)
			(xy 17.300045 -270.639093) (xy 17.273659 -270.592076) (xy 17.254399 -270.541719) (xy 17.242676 -270.489095)
			(xy 17.238741 -270.435324) (xy 16.086074 -270.435324) (xy 16.086074 -271.285208) (xy 17.238741 -271.285208)
			(xy 17.242676 -271.231437) (xy 17.254399 -271.178813) (xy 17.273659 -271.128456) (xy 17.300045 -271.081439)
			(xy 17.332997 -271.038766) (xy 17.37181 -271.001345) (xy 17.415658 -270.969975) (xy 17.463606 -270.945323)
			(xy 17.514633 -270.927915) (xy 17.567651 -270.918122) (xy 17.62153 -270.916153) (xy 17.675121 -270.92205)
			(xy 17.727282 -270.935686) (xy 17.776902 -270.956773) (xy 17.822923 -270.984859) (xy 17.864365 -271.019347)
			(xy 17.900343 -271.059501) (xy 17.930091 -271.104465) (xy 17.952976 -271.153282) (xy 17.968508 -271.204911)
			(xy 17.976358 -271.258251) (xy 17.97685 -271.285208) (xy 24.782795 -271.285208) (xy 24.78673 -271.231437)
			(xy 24.798453 -271.178813) (xy 24.817713 -271.128456) (xy 24.844099 -271.081439) (xy 24.877051 -271.038766)
			(xy 24.915864 -271.001345) (xy 24.959712 -270.969975) (xy 25.00766 -270.945323) (xy 25.058687 -270.927915)
			(xy 25.111705 -270.918122) (xy 25.165584 -270.916153) (xy 25.219175 -270.92205) (xy 25.271336 -270.935686)
			(xy 25.320956 -270.956773) (xy 25.366977 -270.984859) (xy 25.408419 -271.019347) (xy 25.444397 -271.059501)
			(xy 25.474145 -271.104465) (xy 25.49703 -271.153282) (xy 25.512562 -271.204911) (xy 25.520412 -271.258251)
			(xy 25.520904 -271.285208) (xy 32.326595 -271.285208) (xy 32.33053 -271.231437) (xy 32.342253 -271.178813)
			(xy 32.361513 -271.128456) (xy 32.387899 -271.081439) (xy 32.420851 -271.038766) (xy 32.459664 -271.001345)
			(xy 32.503512 -270.969975) (xy 32.55146 -270.945323) (xy 32.602487 -270.927915) (xy 32.655505 -270.918122)
			(xy 32.709384 -270.916153) (xy 32.762975 -270.92205) (xy 32.815136 -270.935686) (xy 32.864756 -270.956773)
			(xy 32.910777 -270.984859) (xy 32.952219 -271.019347) (xy 32.988197 -271.059501) (xy 33.017945 -271.104465)
			(xy 33.04083 -271.153282) (xy 33.056362 -271.204911) (xy 33.064212 -271.258251) (xy 33.064704 -271.285208)
			(xy 39.870649 -271.285208) (xy 39.874584 -271.231437) (xy 39.886307 -271.178813) (xy 39.905567 -271.128456)
			(xy 39.931953 -271.081439) (xy 39.964905 -271.038766) (xy 40.003718 -271.001345) (xy 40.047566 -270.969975)
			(xy 40.095514 -270.945323) (xy 40.146541 -270.927915) (xy 40.199559 -270.918122) (xy 40.253438 -270.916153)
			(xy 40.307029 -270.92205) (xy 40.35919 -270.935686) (xy 40.40881 -270.956773) (xy 40.454831 -270.984859)
			(xy 40.496273 -271.019347) (xy 40.532251 -271.059501) (xy 40.561999 -271.104465) (xy 40.584884 -271.153282)
			(xy 40.600416 -271.204911) (xy 40.608266 -271.258251) (xy 40.608758 -271.285208) (xy 47.414703 -271.285208)
			(xy 47.418638 -271.231437) (xy 47.430361 -271.178813) (xy 47.449621 -271.128456) (xy 47.476007 -271.081439)
			(xy 47.508959 -271.038766) (xy 47.547772 -271.001345) (xy 47.59162 -270.969975) (xy 47.639568 -270.945323)
			(xy 47.690595 -270.927915) (xy 47.743613 -270.918122) (xy 47.797492 -270.916153) (xy 47.851083 -270.92205)
			(xy 47.903244 -270.935686) (xy 47.952864 -270.956773) (xy 47.998885 -270.984859) (xy 48.040327 -271.019347)
			(xy 48.076305 -271.059501) (xy 48.106053 -271.104465) (xy 48.128938 -271.153282) (xy 48.14447 -271.204911)
			(xy 48.15232 -271.258251) (xy 48.152812 -271.285208) (xy 48.15232 -271.312165) (xy 48.14447 -271.365505)
			(xy 48.128938 -271.417134) (xy 48.106053 -271.465951) (xy 48.076305 -271.510915) (xy 48.040327 -271.551069)
			(xy 47.998885 -271.585557) (xy 47.952864 -271.613643) (xy 47.903244 -271.63473) (xy 47.851083 -271.648366)
			(xy 47.797492 -271.654263) (xy 47.743613 -271.652294) (xy 47.690595 -271.642501) (xy 47.639568 -271.625093)
			(xy 47.59162 -271.600441) (xy 47.547772 -271.569071) (xy 47.508959 -271.53165) (xy 47.476007 -271.488977)
			(xy 47.449621 -271.44196) (xy 47.430361 -271.391603) (xy 47.418638 -271.338979) (xy 47.414703 -271.285208)
			(xy 40.608758 -271.285208) (xy 40.608266 -271.312165) (xy 40.600416 -271.365505) (xy 40.584884 -271.417134)
			(xy 40.561999 -271.465951) (xy 40.532251 -271.510915) (xy 40.496273 -271.551069) (xy 40.454831 -271.585557)
			(xy 40.40881 -271.613643) (xy 40.35919 -271.63473) (xy 40.307029 -271.648366) (xy 40.253438 -271.654263)
			(xy 40.199559 -271.652294) (xy 40.146541 -271.642501) (xy 40.095514 -271.625093) (xy 40.047566 -271.600441)
			(xy 40.003718 -271.569071) (xy 39.964905 -271.53165) (xy 39.931953 -271.488977) (xy 39.905567 -271.44196)
			(xy 39.886307 -271.391603) (xy 39.874584 -271.338979) (xy 39.870649 -271.285208) (xy 33.064704 -271.285208)
			(xy 33.064212 -271.312165) (xy 33.056362 -271.365505) (xy 33.04083 -271.417134) (xy 33.017945 -271.465951)
			(xy 32.988197 -271.510915) (xy 32.952219 -271.551069) (xy 32.910777 -271.585557) (xy 32.864756 -271.613643)
			(xy 32.815136 -271.63473) (xy 32.762975 -271.648366) (xy 32.709384 -271.654263) (xy 32.655505 -271.652294)
			(xy 32.602487 -271.642501) (xy 32.55146 -271.625093) (xy 32.503512 -271.600441) (xy 32.459664 -271.569071)
			(xy 32.420851 -271.53165) (xy 32.387899 -271.488977) (xy 32.361513 -271.44196) (xy 32.342253 -271.391603)
			(xy 32.33053 -271.338979) (xy 32.326595 -271.285208) (xy 25.520904 -271.285208) (xy 25.520412 -271.312165)
			(xy 25.512562 -271.365505) (xy 25.49703 -271.417134) (xy 25.474145 -271.465951) (xy 25.444397 -271.510915)
			(xy 25.408419 -271.551069) (xy 25.366977 -271.585557) (xy 25.320956 -271.613643) (xy 25.271336 -271.63473)
			(xy 25.219175 -271.648366) (xy 25.165584 -271.654263) (xy 25.111705 -271.652294) (xy 25.058687 -271.642501)
			(xy 25.00766 -271.625093) (xy 24.959712 -271.600441) (xy 24.915864 -271.569071) (xy 24.877051 -271.53165)
			(xy 24.844099 -271.488977) (xy 24.817713 -271.44196) (xy 24.798453 -271.391603) (xy 24.78673 -271.338979)
			(xy 24.782795 -271.285208) (xy 17.97685 -271.285208) (xy 17.976358 -271.312165) (xy 17.968508 -271.365505)
			(xy 17.952976 -271.417134) (xy 17.930091 -271.465951) (xy 17.900343 -271.510915) (xy 17.864365 -271.551069)
			(xy 17.822923 -271.585557) (xy 17.776902 -271.613643) (xy 17.727282 -271.63473) (xy 17.675121 -271.648366)
			(xy 17.62153 -271.654263) (xy 17.567651 -271.652294) (xy 17.514633 -271.642501) (xy 17.463606 -271.625093)
			(xy 17.415658 -271.600441) (xy 17.37181 -271.569071) (xy 17.332997 -271.53165) (xy 17.300045 -271.488977)
			(xy 17.273659 -271.44196) (xy 17.254399 -271.391603) (xy 17.242676 -271.338979) (xy 17.238741 -271.285208)
			(xy 16.086074 -271.285208) (xy 16.086074 -272.135346) (xy 21.364197 -272.135346) (xy 21.368227 -272.082848)
			(xy 21.380224 -272.03158) (xy 21.399907 -271.982745) (xy 21.426813 -271.937486) (xy 21.460313 -271.896865)
			(xy 21.499621 -271.861834) (xy 21.543816 -271.833214) (xy 21.591861 -271.811675) (xy 21.642632 -271.797723)
			(xy 21.694937 -271.791685) (xy 21.747551 -271.793702) (xy 21.799241 -271.803726) (xy 21.848794 -271.821524)
			(xy 21.89505 -271.846677) (xy 21.936924 -271.878596) (xy 21.973436 -271.916534) (xy 22.003728 -271.9596)
			(xy 22.027091 -272.006785) (xy 22.042977 -272.056984) (xy 22.051014 -272.10902) (xy 22.051518 -272.135346)
			(xy 28.908251 -272.135346) (xy 28.912281 -272.082848) (xy 28.924278 -272.03158) (xy 28.943961 -271.982745)
			(xy 28.970867 -271.937486) (xy 29.004367 -271.896865) (xy 29.043675 -271.861834) (xy 29.08787 -271.833214)
			(xy 29.135915 -271.811675) (xy 29.186686 -271.797723) (xy 29.238991 -271.791685) (xy 29.291605 -271.793702)
			(xy 29.343295 -271.803726) (xy 29.392848 -271.821524) (xy 29.439104 -271.846677) (xy 29.480978 -271.878596)
			(xy 29.51749 -271.916534) (xy 29.547782 -271.9596) (xy 29.571145 -272.006785) (xy 29.587031 -272.056984)
			(xy 29.595068 -272.10902) (xy 29.595572 -272.135346) (xy 36.452051 -272.135346) (xy 36.456081 -272.082848)
			(xy 36.468078 -272.03158) (xy 36.487761 -271.982745) (xy 36.514667 -271.937486) (xy 36.548167 -271.896865)
			(xy 36.587475 -271.861834) (xy 36.63167 -271.833214) (xy 36.679715 -271.811675) (xy 36.730486 -271.797723)
			(xy 36.782791 -271.791685) (xy 36.835405 -271.793702) (xy 36.887095 -271.803726) (xy 36.936648 -271.821524)
			(xy 36.982904 -271.846677) (xy 37.024778 -271.878596) (xy 37.06129 -271.916534) (xy 37.091582 -271.9596)
			(xy 37.114945 -272.006785) (xy 37.130831 -272.056984) (xy 37.138868 -272.10902) (xy 37.139372 -272.135346)
			(xy 43.996105 -272.135346) (xy 44.000135 -272.082848) (xy 44.012132 -272.03158) (xy 44.031815 -271.982745)
			(xy 44.058721 -271.937486) (xy 44.092221 -271.896865) (xy 44.131529 -271.861834) (xy 44.175724 -271.833214)
			(xy 44.223769 -271.811675) (xy 44.27454 -271.797723) (xy 44.326845 -271.791685) (xy 44.379459 -271.793702)
			(xy 44.431149 -271.803726) (xy 44.480702 -271.821524) (xy 44.526958 -271.846677) (xy 44.568832 -271.878596)
			(xy 44.605344 -271.916534) (xy 44.635636 -271.9596) (xy 44.658999 -272.006785) (xy 44.674885 -272.056984)
			(xy 44.682922 -272.10902) (xy 44.683426 -272.135346) (xy 51.540159 -272.135346) (xy 51.544189 -272.082848)
			(xy 51.556186 -272.03158) (xy 51.575869 -271.982745) (xy 51.602775 -271.937486) (xy 51.636275 -271.896865)
			(xy 51.675583 -271.861834) (xy 51.719778 -271.833214) (xy 51.767823 -271.811675) (xy 51.818594 -271.797723)
			(xy 51.870899 -271.791685) (xy 51.923513 -271.793702) (xy 51.975203 -271.803726) (xy 52.024756 -271.821524)
			(xy 52.071012 -271.846677) (xy 52.112886 -271.878596) (xy 52.149398 -271.916534) (xy 52.17969 -271.9596)
			(xy 52.203053 -272.006785) (xy 52.218939 -272.056984) (xy 52.226976 -272.10902) (xy 52.22748 -272.135346)
			(xy 52.226976 -272.161672) (xy 52.218939 -272.213708) (xy 52.203053 -272.263907) (xy 52.17969 -272.311092)
			(xy 52.149398 -272.354158) (xy 52.112886 -272.392096) (xy 52.071012 -272.424015) (xy 52.024756 -272.449168)
			(xy 51.975203 -272.466966) (xy 51.923513 -272.47699) (xy 51.870899 -272.479007) (xy 51.818594 -272.472969)
			(xy 51.767823 -272.459017) (xy 51.719778 -272.437478) (xy 51.675583 -272.408858) (xy 51.636275 -272.373827)
			(xy 51.602775 -272.333206) (xy 51.575869 -272.287947) (xy 51.556186 -272.239112) (xy 51.544189 -272.187844)
			(xy 51.540159 -272.135346) (xy 44.683426 -272.135346) (xy 44.682922 -272.161672) (xy 44.674885 -272.213708)
			(xy 44.658999 -272.263907) (xy 44.635636 -272.311092) (xy 44.605344 -272.354158) (xy 44.568832 -272.392096)
			(xy 44.526958 -272.424015) (xy 44.480702 -272.449168) (xy 44.431149 -272.466966) (xy 44.379459 -272.47699)
			(xy 44.326845 -272.479007) (xy 44.27454 -272.472969) (xy 44.223769 -272.459017) (xy 44.175724 -272.437478)
			(xy 44.131529 -272.408858) (xy 44.092221 -272.373827) (xy 44.058721 -272.333206) (xy 44.031815 -272.287947)
			(xy 44.012132 -272.239112) (xy 44.000135 -272.187844) (xy 43.996105 -272.135346) (xy 37.139372 -272.135346)
			(xy 37.138868 -272.161672) (xy 37.130831 -272.213708) (xy 37.114945 -272.263907) (xy 37.091582 -272.311092)
			(xy 37.06129 -272.354158) (xy 37.024778 -272.392096) (xy 36.982904 -272.424015) (xy 36.936648 -272.449168)
			(xy 36.887095 -272.466966) (xy 36.835405 -272.47699) (xy 36.782791 -272.479007) (xy 36.730486 -272.472969)
			(xy 36.679715 -272.459017) (xy 36.63167 -272.437478) (xy 36.587475 -272.408858) (xy 36.548167 -272.373827)
			(xy 36.514667 -272.333206) (xy 36.487761 -272.287947) (xy 36.468078 -272.239112) (xy 36.456081 -272.187844)
			(xy 36.452051 -272.135346) (xy 29.595572 -272.135346) (xy 29.595068 -272.161672) (xy 29.587031 -272.213708)
			(xy 29.571145 -272.263907) (xy 29.547782 -272.311092) (xy 29.51749 -272.354158) (xy 29.480978 -272.392096)
			(xy 29.439104 -272.424015) (xy 29.392848 -272.449168) (xy 29.343295 -272.466966) (xy 29.291605 -272.47699)
			(xy 29.238991 -272.479007) (xy 29.186686 -272.472969) (xy 29.135915 -272.459017) (xy 29.08787 -272.437478)
			(xy 29.043675 -272.408858) (xy 29.004367 -272.373827) (xy 28.970867 -272.333206) (xy 28.943961 -272.287947)
			(xy 28.924278 -272.239112) (xy 28.912281 -272.187844) (xy 28.908251 -272.135346) (xy 22.051518 -272.135346)
			(xy 22.051014 -272.161672) (xy 22.042977 -272.213708) (xy 22.027091 -272.263907) (xy 22.003728 -272.311092)
			(xy 21.973436 -272.354158) (xy 21.936924 -272.392096) (xy 21.89505 -272.424015) (xy 21.848794 -272.449168)
			(xy 21.799241 -272.466966) (xy 21.747551 -272.47699) (xy 21.694937 -272.479007) (xy 21.642632 -272.472969)
			(xy 21.591861 -272.459017) (xy 21.543816 -272.437478) (xy 21.499621 -272.408858) (xy 21.460313 -272.373827)
			(xy 21.426813 -272.333206) (xy 21.399907 -272.287947) (xy 21.380224 -272.239112) (xy 21.368227 -272.187844)
			(xy 21.364197 -272.135346) (xy 16.086074 -272.135346) (xy 16.086074 -272.98523) (xy 17.264129 -272.98523)
			(xy 17.268159 -272.932732) (xy 17.280156 -272.881464) (xy 17.299839 -272.832629) (xy 17.326745 -272.78737)
			(xy 17.360245 -272.746749) (xy 17.399553 -272.711718) (xy 17.443748 -272.683098) (xy 17.491793 -272.661559)
			(xy 17.542564 -272.647607) (xy 17.594869 -272.641569) (xy 17.647483 -272.643586) (xy 17.699173 -272.65361)
			(xy 17.748726 -272.671408) (xy 17.794982 -272.696561) (xy 17.836856 -272.72848) (xy 17.873368 -272.766418)
			(xy 17.90366 -272.809484) (xy 17.927023 -272.856669) (xy 17.942909 -272.906868) (xy 17.950946 -272.958904)
			(xy 17.95145 -272.98523) (xy 24.808183 -272.98523) (xy 24.812213 -272.932732) (xy 24.82421 -272.881464)
			(xy 24.843893 -272.832629) (xy 24.870799 -272.78737) (xy 24.904299 -272.746749) (xy 24.943607 -272.711718)
			(xy 24.987802 -272.683098) (xy 25.035847 -272.661559) (xy 25.086618 -272.647607) (xy 25.138923 -272.641569)
			(xy 25.191537 -272.643586) (xy 25.243227 -272.65361) (xy 25.29278 -272.671408) (xy 25.339036 -272.696561)
			(xy 25.38091 -272.72848) (xy 25.417422 -272.766418) (xy 25.447714 -272.809484) (xy 25.471077 -272.856669)
			(xy 25.486963 -272.906868) (xy 25.495 -272.958904) (xy 25.495504 -272.98523) (xy 32.351983 -272.98523)
			(xy 32.356013 -272.932732) (xy 32.36801 -272.881464) (xy 32.387693 -272.832629) (xy 32.414599 -272.78737)
			(xy 32.448099 -272.746749) (xy 32.487407 -272.711718) (xy 32.531602 -272.683098) (xy 32.579647 -272.661559)
			(xy 32.630418 -272.647607) (xy 32.682723 -272.641569) (xy 32.735337 -272.643586) (xy 32.787027 -272.65361)
			(xy 32.83658 -272.671408) (xy 32.882836 -272.696561) (xy 32.92471 -272.72848) (xy 32.961222 -272.766418)
			(xy 32.991514 -272.809484) (xy 33.014877 -272.856669) (xy 33.030763 -272.906868) (xy 33.0388 -272.958904)
			(xy 33.039304 -272.98523) (xy 39.896037 -272.98523) (xy 39.900067 -272.932732) (xy 39.912064 -272.881464)
			(xy 39.931747 -272.832629) (xy 39.958653 -272.78737) (xy 39.992153 -272.746749) (xy 40.031461 -272.711718)
			(xy 40.075656 -272.683098) (xy 40.123701 -272.661559) (xy 40.174472 -272.647607) (xy 40.226777 -272.641569)
			(xy 40.279391 -272.643586) (xy 40.331081 -272.65361) (xy 40.380634 -272.671408) (xy 40.42689 -272.696561)
			(xy 40.468764 -272.72848) (xy 40.505276 -272.766418) (xy 40.535568 -272.809484) (xy 40.558931 -272.856669)
			(xy 40.574817 -272.906868) (xy 40.582854 -272.958904) (xy 40.583358 -272.98523) (xy 47.440091 -272.98523)
			(xy 47.444121 -272.932732) (xy 47.456118 -272.881464) (xy 47.475801 -272.832629) (xy 47.502707 -272.78737)
			(xy 47.536207 -272.746749) (xy 47.575515 -272.711718) (xy 47.61971 -272.683098) (xy 47.667755 -272.661559)
			(xy 47.718526 -272.647607) (xy 47.770831 -272.641569) (xy 47.823445 -272.643586) (xy 47.875135 -272.65361)
			(xy 47.924688 -272.671408) (xy 47.970944 -272.696561) (xy 48.012818 -272.72848) (xy 48.04933 -272.766418)
			(xy 48.079622 -272.809484) (xy 48.102985 -272.856669) (xy 48.118871 -272.906868) (xy 48.126908 -272.958904)
			(xy 48.127412 -272.98523) (xy 48.126908 -273.011556) (xy 48.118871 -273.063592) (xy 48.102985 -273.113791)
			(xy 48.079622 -273.160976) (xy 48.04933 -273.204042) (xy 48.012818 -273.24198) (xy 47.970944 -273.273899)
			(xy 47.924688 -273.299052) (xy 47.875135 -273.31685) (xy 47.823445 -273.326874) (xy 47.770831 -273.328891)
			(xy 47.718526 -273.322853) (xy 47.667755 -273.308901) (xy 47.61971 -273.287362) (xy 47.575515 -273.258742)
			(xy 47.536207 -273.223711) (xy 47.502707 -273.18309) (xy 47.475801 -273.137831) (xy 47.456118 -273.088996)
			(xy 47.444121 -273.037728) (xy 47.440091 -272.98523) (xy 40.583358 -272.98523) (xy 40.582854 -273.011556)
			(xy 40.574817 -273.063592) (xy 40.558931 -273.113791) (xy 40.535568 -273.160976) (xy 40.505276 -273.204042)
			(xy 40.468764 -273.24198) (xy 40.42689 -273.273899) (xy 40.380634 -273.299052) (xy 40.331081 -273.31685)
			(xy 40.279391 -273.326874) (xy 40.226777 -273.328891) (xy 40.174472 -273.322853) (xy 40.123701 -273.308901)
			(xy 40.075656 -273.287362) (xy 40.031461 -273.258742) (xy 39.992153 -273.223711) (xy 39.958653 -273.18309)
			(xy 39.931747 -273.137831) (xy 39.912064 -273.088996) (xy 39.900067 -273.037728) (xy 39.896037 -272.98523)
			(xy 33.039304 -272.98523) (xy 33.0388 -273.011556) (xy 33.030763 -273.063592) (xy 33.014877 -273.113791)
			(xy 32.991514 -273.160976) (xy 32.961222 -273.204042) (xy 32.92471 -273.24198) (xy 32.882836 -273.273899)
			(xy 32.83658 -273.299052) (xy 32.787027 -273.31685) (xy 32.735337 -273.326874) (xy 32.682723 -273.328891)
			(xy 32.630418 -273.322853) (xy 32.579647 -273.308901) (xy 32.531602 -273.287362) (xy 32.487407 -273.258742)
			(xy 32.448099 -273.223711) (xy 32.414599 -273.18309) (xy 32.387693 -273.137831) (xy 32.36801 -273.088996)
			(xy 32.356013 -273.037728) (xy 32.351983 -272.98523) (xy 25.495504 -272.98523) (xy 25.495 -273.011556)
			(xy 25.486963 -273.063592) (xy 25.471077 -273.113791) (xy 25.447714 -273.160976) (xy 25.417422 -273.204042)
			(xy 25.38091 -273.24198) (xy 25.339036 -273.273899) (xy 25.29278 -273.299052) (xy 25.243227 -273.31685)
			(xy 25.191537 -273.326874) (xy 25.138923 -273.328891) (xy 25.086618 -273.322853) (xy 25.035847 -273.308901)
			(xy 24.987802 -273.287362) (xy 24.943607 -273.258742) (xy 24.904299 -273.223711) (xy 24.870799 -273.18309)
			(xy 24.843893 -273.137831) (xy 24.82421 -273.088996) (xy 24.812213 -273.037728) (xy 24.808183 -272.98523)
			(xy 17.95145 -272.98523) (xy 17.950946 -273.011556) (xy 17.942909 -273.063592) (xy 17.927023 -273.113791)
			(xy 17.90366 -273.160976) (xy 17.873368 -273.204042) (xy 17.836856 -273.24198) (xy 17.794982 -273.273899)
			(xy 17.748726 -273.299052) (xy 17.699173 -273.31685) (xy 17.647483 -273.326874) (xy 17.594869 -273.328891)
			(xy 17.542564 -273.322853) (xy 17.491793 -273.308901) (xy 17.443748 -273.287362) (xy 17.399553 -273.258742)
			(xy 17.360245 -273.223711) (xy 17.326745 -273.18309) (xy 17.299839 -273.137831) (xy 17.280156 -273.088996)
			(xy 17.268159 -273.037728) (xy 17.264129 -272.98523) (xy 16.086074 -272.98523) (xy 16.086074 -273.835368)
			(xy 21.364197 -273.835368) (xy 21.368227 -273.78287) (xy 21.380224 -273.731602) (xy 21.399907 -273.682767)
			(xy 21.426813 -273.637508) (xy 21.460313 -273.596887) (xy 21.499621 -273.561856) (xy 21.543816 -273.533236)
			(xy 21.591861 -273.511697) (xy 21.642632 -273.497745) (xy 21.694937 -273.491707) (xy 21.747551 -273.493724)
			(xy 21.799241 -273.503748) (xy 21.848794 -273.521546) (xy 21.89505 -273.546699) (xy 21.936924 -273.578618)
			(xy 21.973436 -273.616556) (xy 22.003728 -273.659622) (xy 22.027091 -273.706807) (xy 22.042977 -273.757006)
			(xy 22.051014 -273.809042) (xy 22.051518 -273.835368) (xy 28.908251 -273.835368) (xy 28.912281 -273.78287)
			(xy 28.924278 -273.731602) (xy 28.943961 -273.682767) (xy 28.970867 -273.637508) (xy 29.004367 -273.596887)
			(xy 29.043675 -273.561856) (xy 29.08787 -273.533236) (xy 29.135915 -273.511697) (xy 29.186686 -273.497745)
			(xy 29.238991 -273.491707) (xy 29.291605 -273.493724) (xy 29.343295 -273.503748) (xy 29.392848 -273.521546)
			(xy 29.439104 -273.546699) (xy 29.480978 -273.578618) (xy 29.51749 -273.616556) (xy 29.547782 -273.659622)
			(xy 29.571145 -273.706807) (xy 29.587031 -273.757006) (xy 29.595068 -273.809042) (xy 29.595572 -273.835368)
			(xy 36.452051 -273.835368) (xy 36.456081 -273.78287) (xy 36.468078 -273.731602) (xy 36.487761 -273.682767)
			(xy 36.514667 -273.637508) (xy 36.548167 -273.596887) (xy 36.587475 -273.561856) (xy 36.63167 -273.533236)
			(xy 36.679715 -273.511697) (xy 36.730486 -273.497745) (xy 36.782791 -273.491707) (xy 36.835405 -273.493724)
			(xy 36.887095 -273.503748) (xy 36.936648 -273.521546) (xy 36.982904 -273.546699) (xy 37.024778 -273.578618)
			(xy 37.06129 -273.616556) (xy 37.091582 -273.659622) (xy 37.114945 -273.706807) (xy 37.130831 -273.757006)
			(xy 37.138868 -273.809042) (xy 37.139372 -273.835368) (xy 43.996105 -273.835368) (xy 44.000135 -273.78287)
			(xy 44.012132 -273.731602) (xy 44.031815 -273.682767) (xy 44.058721 -273.637508) (xy 44.092221 -273.596887)
			(xy 44.131529 -273.561856) (xy 44.175724 -273.533236) (xy 44.223769 -273.511697) (xy 44.27454 -273.497745)
			(xy 44.326845 -273.491707) (xy 44.379459 -273.493724) (xy 44.431149 -273.503748) (xy 44.480702 -273.521546)
			(xy 44.526958 -273.546699) (xy 44.568832 -273.578618) (xy 44.605344 -273.616556) (xy 44.635636 -273.659622)
			(xy 44.658999 -273.706807) (xy 44.674885 -273.757006) (xy 44.682922 -273.809042) (xy 44.683426 -273.835368)
			(xy 51.540159 -273.835368) (xy 51.544189 -273.78287) (xy 51.556186 -273.731602) (xy 51.575869 -273.682767)
			(xy 51.602775 -273.637508) (xy 51.636275 -273.596887) (xy 51.675583 -273.561856) (xy 51.719778 -273.533236)
			(xy 51.767823 -273.511697) (xy 51.818594 -273.497745) (xy 51.870899 -273.491707) (xy 51.923513 -273.493724)
			(xy 51.975203 -273.503748) (xy 52.024756 -273.521546) (xy 52.071012 -273.546699) (xy 52.112886 -273.578618)
			(xy 52.149398 -273.616556) (xy 52.17969 -273.659622) (xy 52.203053 -273.706807) (xy 52.218939 -273.757006)
			(xy 52.226976 -273.809042) (xy 52.22748 -273.835368) (xy 52.226976 -273.861694) (xy 52.218939 -273.91373)
			(xy 52.203053 -273.963929) (xy 52.17969 -274.011114) (xy 52.149398 -274.05418) (xy 52.112886 -274.092118)
			(xy 52.071012 -274.124037) (xy 52.024756 -274.14919) (xy 51.975203 -274.166988) (xy 51.923513 -274.177012)
			(xy 51.870899 -274.179029) (xy 51.818594 -274.172991) (xy 51.767823 -274.159039) (xy 51.719778 -274.1375)
			(xy 51.675583 -274.10888) (xy 51.636275 -274.073849) (xy 51.602775 -274.033228) (xy 51.575869 -273.987969)
			(xy 51.556186 -273.939134) (xy 51.544189 -273.887866) (xy 51.540159 -273.835368) (xy 44.683426 -273.835368)
			(xy 44.682922 -273.861694) (xy 44.674885 -273.91373) (xy 44.658999 -273.963929) (xy 44.635636 -274.011114)
			(xy 44.605344 -274.05418) (xy 44.568832 -274.092118) (xy 44.526958 -274.124037) (xy 44.480702 -274.14919)
			(xy 44.431149 -274.166988) (xy 44.379459 -274.177012) (xy 44.326845 -274.179029) (xy 44.27454 -274.172991)
			(xy 44.223769 -274.159039) (xy 44.175724 -274.1375) (xy 44.131529 -274.10888) (xy 44.092221 -274.073849)
			(xy 44.058721 -274.033228) (xy 44.031815 -273.987969) (xy 44.012132 -273.939134) (xy 44.000135 -273.887866)
			(xy 43.996105 -273.835368) (xy 37.139372 -273.835368) (xy 37.138868 -273.861694) (xy 37.130831 -273.91373)
			(xy 37.114945 -273.963929) (xy 37.091582 -274.011114) (xy 37.06129 -274.05418) (xy 37.024778 -274.092118)
			(xy 36.982904 -274.124037) (xy 36.936648 -274.14919) (xy 36.887095 -274.166988) (xy 36.835405 -274.177012)
			(xy 36.782791 -274.179029) (xy 36.730486 -274.172991) (xy 36.679715 -274.159039) (xy 36.63167 -274.1375)
			(xy 36.587475 -274.10888) (xy 36.548167 -274.073849) (xy 36.514667 -274.033228) (xy 36.487761 -273.987969)
			(xy 36.468078 -273.939134) (xy 36.456081 -273.887866) (xy 36.452051 -273.835368) (xy 29.595572 -273.835368)
			(xy 29.595068 -273.861694) (xy 29.587031 -273.91373) (xy 29.571145 -273.963929) (xy 29.547782 -274.011114)
			(xy 29.51749 -274.05418) (xy 29.480978 -274.092118) (xy 29.439104 -274.124037) (xy 29.392848 -274.14919)
			(xy 29.343295 -274.166988) (xy 29.291605 -274.177012) (xy 29.238991 -274.179029) (xy 29.186686 -274.172991)
			(xy 29.135915 -274.159039) (xy 29.08787 -274.1375) (xy 29.043675 -274.10888) (xy 29.004367 -274.073849)
			(xy 28.970867 -274.033228) (xy 28.943961 -273.987969) (xy 28.924278 -273.939134) (xy 28.912281 -273.887866)
			(xy 28.908251 -273.835368) (xy 22.051518 -273.835368) (xy 22.051014 -273.861694) (xy 22.042977 -273.91373)
			(xy 22.027091 -273.963929) (xy 22.003728 -274.011114) (xy 21.973436 -274.05418) (xy 21.936924 -274.092118)
			(xy 21.89505 -274.124037) (xy 21.848794 -274.14919) (xy 21.799241 -274.166988) (xy 21.747551 -274.177012)
			(xy 21.694937 -274.179029) (xy 21.642632 -274.172991) (xy 21.591861 -274.159039) (xy 21.543816 -274.1375)
			(xy 21.499621 -274.10888) (xy 21.460313 -274.073849) (xy 21.426813 -274.033228) (xy 21.399907 -273.987969)
			(xy 21.380224 -273.939134) (xy 21.368227 -273.887866) (xy 21.364197 -273.835368) (xy 16.086074 -273.835368)
			(xy 16.086074 -274.685252) (xy 17.264129 -274.685252) (xy 17.268159 -274.632754) (xy 17.280156 -274.581486)
			(xy 17.299839 -274.532651) (xy 17.326745 -274.487392) (xy 17.360245 -274.446771) (xy 17.399553 -274.41174)
			(xy 17.443748 -274.38312) (xy 17.491793 -274.361581) (xy 17.542564 -274.347629) (xy 17.594869 -274.341591)
			(xy 17.647483 -274.343608) (xy 17.699173 -274.353632) (xy 17.748726 -274.37143) (xy 17.794982 -274.396583)
			(xy 17.836856 -274.428502) (xy 17.873368 -274.46644) (xy 17.90366 -274.509506) (xy 17.927023 -274.556691)
			(xy 17.942909 -274.60689) (xy 17.950946 -274.658926) (xy 17.95145 -274.685252) (xy 24.808183 -274.685252)
			(xy 24.812213 -274.632754) (xy 24.82421 -274.581486) (xy 24.843893 -274.532651) (xy 24.870799 -274.487392)
			(xy 24.904299 -274.446771) (xy 24.943607 -274.41174) (xy 24.987802 -274.38312) (xy 25.035847 -274.361581)
			(xy 25.086618 -274.347629) (xy 25.138923 -274.341591) (xy 25.191537 -274.343608) (xy 25.243227 -274.353632)
			(xy 25.29278 -274.37143) (xy 25.339036 -274.396583) (xy 25.38091 -274.428502) (xy 25.417422 -274.46644)
			(xy 25.447714 -274.509506) (xy 25.471077 -274.556691) (xy 25.486963 -274.60689) (xy 25.495 -274.658926)
			(xy 25.495504 -274.685252) (xy 32.351983 -274.685252) (xy 32.356013 -274.632754) (xy 32.36801 -274.581486)
			(xy 32.387693 -274.532651) (xy 32.414599 -274.487392) (xy 32.448099 -274.446771) (xy 32.487407 -274.41174)
			(xy 32.531602 -274.38312) (xy 32.579647 -274.361581) (xy 32.630418 -274.347629) (xy 32.682723 -274.341591)
			(xy 32.735337 -274.343608) (xy 32.787027 -274.353632) (xy 32.83658 -274.37143) (xy 32.882836 -274.396583)
			(xy 32.92471 -274.428502) (xy 32.961222 -274.46644) (xy 32.991514 -274.509506) (xy 33.014877 -274.556691)
			(xy 33.030763 -274.60689) (xy 33.0388 -274.658926) (xy 33.039304 -274.685252) (xy 39.896037 -274.685252)
			(xy 39.900067 -274.632754) (xy 39.912064 -274.581486) (xy 39.931747 -274.532651) (xy 39.958653 -274.487392)
			(xy 39.992153 -274.446771) (xy 40.031461 -274.41174) (xy 40.075656 -274.38312) (xy 40.123701 -274.361581)
			(xy 40.174472 -274.347629) (xy 40.226777 -274.341591) (xy 40.279391 -274.343608) (xy 40.331081 -274.353632)
			(xy 40.380634 -274.37143) (xy 40.42689 -274.396583) (xy 40.468764 -274.428502) (xy 40.505276 -274.46644)
			(xy 40.535568 -274.509506) (xy 40.558931 -274.556691) (xy 40.574817 -274.60689) (xy 40.582854 -274.658926)
			(xy 40.583358 -274.685252) (xy 47.440091 -274.685252) (xy 47.444121 -274.632754) (xy 47.456118 -274.581486)
			(xy 47.475801 -274.532651) (xy 47.502707 -274.487392) (xy 47.536207 -274.446771) (xy 47.575515 -274.41174)
			(xy 47.61971 -274.38312) (xy 47.667755 -274.361581) (xy 47.718526 -274.347629) (xy 47.770831 -274.341591)
			(xy 47.823445 -274.343608) (xy 47.875135 -274.353632) (xy 47.924688 -274.37143) (xy 47.970944 -274.396583)
			(xy 48.012818 -274.428502) (xy 48.04933 -274.46644) (xy 48.079622 -274.509506) (xy 48.102985 -274.556691)
			(xy 48.118871 -274.60689) (xy 48.126908 -274.658926) (xy 48.127412 -274.685252) (xy 48.126908 -274.711578)
			(xy 48.118871 -274.763614) (xy 48.102985 -274.813813) (xy 48.079622 -274.860998) (xy 48.04933 -274.904064)
			(xy 48.012818 -274.942002) (xy 47.970944 -274.973921) (xy 47.924688 -274.999074) (xy 47.875135 -275.016872)
			(xy 47.823445 -275.026896) (xy 47.770831 -275.028913) (xy 47.718526 -275.022875) (xy 47.667755 -275.008923)
			(xy 47.61971 -274.987384) (xy 47.575515 -274.958764) (xy 47.536207 -274.923733) (xy 47.502707 -274.883112)
			(xy 47.475801 -274.837853) (xy 47.456118 -274.789018) (xy 47.444121 -274.73775) (xy 47.440091 -274.685252)
			(xy 40.583358 -274.685252) (xy 40.582854 -274.711578) (xy 40.574817 -274.763614) (xy 40.558931 -274.813813)
			(xy 40.535568 -274.860998) (xy 40.505276 -274.904064) (xy 40.468764 -274.942002) (xy 40.42689 -274.973921)
			(xy 40.380634 -274.999074) (xy 40.331081 -275.016872) (xy 40.279391 -275.026896) (xy 40.226777 -275.028913)
			(xy 40.174472 -275.022875) (xy 40.123701 -275.008923) (xy 40.075656 -274.987384) (xy 40.031461 -274.958764)
			(xy 39.992153 -274.923733) (xy 39.958653 -274.883112) (xy 39.931747 -274.837853) (xy 39.912064 -274.789018)
			(xy 39.900067 -274.73775) (xy 39.896037 -274.685252) (xy 33.039304 -274.685252) (xy 33.0388 -274.711578)
			(xy 33.030763 -274.763614) (xy 33.014877 -274.813813) (xy 32.991514 -274.860998) (xy 32.961222 -274.904064)
			(xy 32.92471 -274.942002) (xy 32.882836 -274.973921) (xy 32.83658 -274.999074) (xy 32.787027 -275.016872)
			(xy 32.735337 -275.026896) (xy 32.682723 -275.028913) (xy 32.630418 -275.022875) (xy 32.579647 -275.008923)
			(xy 32.531602 -274.987384) (xy 32.487407 -274.958764) (xy 32.448099 -274.923733) (xy 32.414599 -274.883112)
			(xy 32.387693 -274.837853) (xy 32.36801 -274.789018) (xy 32.356013 -274.73775) (xy 32.351983 -274.685252)
			(xy 25.495504 -274.685252) (xy 25.495 -274.711578) (xy 25.486963 -274.763614) (xy 25.471077 -274.813813)
			(xy 25.447714 -274.860998) (xy 25.417422 -274.904064) (xy 25.38091 -274.942002) (xy 25.339036 -274.973921)
			(xy 25.29278 -274.999074) (xy 25.243227 -275.016872) (xy 25.191537 -275.026896) (xy 25.138923 -275.028913)
			(xy 25.086618 -275.022875) (xy 25.035847 -275.008923) (xy 24.987802 -274.987384) (xy 24.943607 -274.958764)
			(xy 24.904299 -274.923733) (xy 24.870799 -274.883112) (xy 24.843893 -274.837853) (xy 24.82421 -274.789018)
			(xy 24.812213 -274.73775) (xy 24.808183 -274.685252) (xy 17.95145 -274.685252) (xy 17.950946 -274.711578)
			(xy 17.942909 -274.763614) (xy 17.927023 -274.813813) (xy 17.90366 -274.860998) (xy 17.873368 -274.904064)
			(xy 17.836856 -274.942002) (xy 17.794982 -274.973921) (xy 17.748726 -274.999074) (xy 17.699173 -275.016872)
			(xy 17.647483 -275.026896) (xy 17.594869 -275.028913) (xy 17.542564 -275.022875) (xy 17.491793 -275.008923)
			(xy 17.443748 -274.987384) (xy 17.399553 -274.958764) (xy 17.360245 -274.923733) (xy 17.326745 -274.883112)
			(xy 17.299839 -274.837853) (xy 17.280156 -274.789018) (xy 17.268159 -274.73775) (xy 17.264129 -274.685252)
			(xy 16.086074 -274.685252) (xy 16.086074 -275.53539) (xy 21.364197 -275.53539) (xy 21.368227 -275.482892)
			(xy 21.380224 -275.431624) (xy 21.399907 -275.382789) (xy 21.426813 -275.33753) (xy 21.460313 -275.296909)
			(xy 21.499621 -275.261878) (xy 21.543816 -275.233258) (xy 21.591861 -275.211719) (xy 21.642632 -275.197767)
			(xy 21.694937 -275.191729) (xy 21.747551 -275.193746) (xy 21.799241 -275.20377) (xy 21.848794 -275.221568)
			(xy 21.89505 -275.246721) (xy 21.936924 -275.27864) (xy 21.973436 -275.316578) (xy 22.003728 -275.359644)
			(xy 22.027091 -275.406829) (xy 22.042977 -275.457028) (xy 22.051014 -275.509064) (xy 22.051518 -275.53539)
			(xy 28.908251 -275.53539) (xy 28.912281 -275.482892) (xy 28.924278 -275.431624) (xy 28.943961 -275.382789)
			(xy 28.970867 -275.33753) (xy 29.004367 -275.296909) (xy 29.043675 -275.261878) (xy 29.08787 -275.233258)
			(xy 29.135915 -275.211719) (xy 29.186686 -275.197767) (xy 29.238991 -275.191729) (xy 29.291605 -275.193746)
			(xy 29.343295 -275.20377) (xy 29.392848 -275.221568) (xy 29.439104 -275.246721) (xy 29.480978 -275.27864)
			(xy 29.51749 -275.316578) (xy 29.547782 -275.359644) (xy 29.571145 -275.406829) (xy 29.587031 -275.457028)
			(xy 29.595068 -275.509064) (xy 29.595572 -275.53539) (xy 36.452051 -275.53539) (xy 36.456081 -275.482892)
			(xy 36.468078 -275.431624) (xy 36.487761 -275.382789) (xy 36.514667 -275.33753) (xy 36.548167 -275.296909)
			(xy 36.587475 -275.261878) (xy 36.63167 -275.233258) (xy 36.679715 -275.211719) (xy 36.730486 -275.197767)
			(xy 36.782791 -275.191729) (xy 36.835405 -275.193746) (xy 36.887095 -275.20377) (xy 36.936648 -275.221568)
			(xy 36.982904 -275.246721) (xy 37.024778 -275.27864) (xy 37.06129 -275.316578) (xy 37.091582 -275.359644)
			(xy 37.114945 -275.406829) (xy 37.130831 -275.457028) (xy 37.138868 -275.509064) (xy 37.139372 -275.53539)
			(xy 43.996105 -275.53539) (xy 44.000135 -275.482892) (xy 44.012132 -275.431624) (xy 44.031815 -275.382789)
			(xy 44.058721 -275.33753) (xy 44.092221 -275.296909) (xy 44.131529 -275.261878) (xy 44.175724 -275.233258)
			(xy 44.223769 -275.211719) (xy 44.27454 -275.197767) (xy 44.326845 -275.191729) (xy 44.379459 -275.193746)
			(xy 44.431149 -275.20377) (xy 44.480702 -275.221568) (xy 44.526958 -275.246721) (xy 44.568832 -275.27864)
			(xy 44.605344 -275.316578) (xy 44.635636 -275.359644) (xy 44.658999 -275.406829) (xy 44.674885 -275.457028)
			(xy 44.682922 -275.509064) (xy 44.683426 -275.53539) (xy 51.540159 -275.53539) (xy 51.544189 -275.482892)
			(xy 51.556186 -275.431624) (xy 51.575869 -275.382789) (xy 51.602775 -275.33753) (xy 51.636275 -275.296909)
			(xy 51.675583 -275.261878) (xy 51.719778 -275.233258) (xy 51.767823 -275.211719) (xy 51.818594 -275.197767)
			(xy 51.870899 -275.191729) (xy 51.923513 -275.193746) (xy 51.975203 -275.20377) (xy 52.024756 -275.221568)
			(xy 52.071012 -275.246721) (xy 52.112886 -275.27864) (xy 52.149398 -275.316578) (xy 52.17969 -275.359644)
			(xy 52.203053 -275.406829) (xy 52.218939 -275.457028) (xy 52.226976 -275.509064) (xy 52.22748 -275.53539)
			(xy 52.226976 -275.561716) (xy 52.218939 -275.613752) (xy 52.203053 -275.663951) (xy 52.17969 -275.711136)
			(xy 52.149398 -275.754202) (xy 52.112886 -275.79214) (xy 52.071012 -275.824059) (xy 52.024756 -275.849212)
			(xy 51.975203 -275.86701) (xy 51.923513 -275.877034) (xy 51.870899 -275.879051) (xy 51.818594 -275.873013)
			(xy 51.767823 -275.859061) (xy 51.719778 -275.837522) (xy 51.675583 -275.808902) (xy 51.636275 -275.773871)
			(xy 51.602775 -275.73325) (xy 51.575869 -275.687991) (xy 51.556186 -275.639156) (xy 51.544189 -275.587888)
			(xy 51.540159 -275.53539) (xy 44.683426 -275.53539) (xy 44.682922 -275.561716) (xy 44.674885 -275.613752)
			(xy 44.658999 -275.663951) (xy 44.635636 -275.711136) (xy 44.605344 -275.754202) (xy 44.568832 -275.79214)
			(xy 44.526958 -275.824059) (xy 44.480702 -275.849212) (xy 44.431149 -275.86701) (xy 44.379459 -275.877034)
			(xy 44.326845 -275.879051) (xy 44.27454 -275.873013) (xy 44.223769 -275.859061) (xy 44.175724 -275.837522)
			(xy 44.131529 -275.808902) (xy 44.092221 -275.773871) (xy 44.058721 -275.73325) (xy 44.031815 -275.687991)
			(xy 44.012132 -275.639156) (xy 44.000135 -275.587888) (xy 43.996105 -275.53539) (xy 37.139372 -275.53539)
			(xy 37.138868 -275.561716) (xy 37.130831 -275.613752) (xy 37.114945 -275.663951) (xy 37.091582 -275.711136)
			(xy 37.06129 -275.754202) (xy 37.024778 -275.79214) (xy 36.982904 -275.824059) (xy 36.936648 -275.849212)
			(xy 36.887095 -275.86701) (xy 36.835405 -275.877034) (xy 36.782791 -275.879051) (xy 36.730486 -275.873013)
			(xy 36.679715 -275.859061) (xy 36.63167 -275.837522) (xy 36.587475 -275.808902) (xy 36.548167 -275.773871)
			(xy 36.514667 -275.73325) (xy 36.487761 -275.687991) (xy 36.468078 -275.639156) (xy 36.456081 -275.587888)
			(xy 36.452051 -275.53539) (xy 29.595572 -275.53539) (xy 29.595068 -275.561716) (xy 29.587031 -275.613752)
			(xy 29.571145 -275.663951) (xy 29.547782 -275.711136) (xy 29.51749 -275.754202) (xy 29.480978 -275.79214)
			(xy 29.439104 -275.824059) (xy 29.392848 -275.849212) (xy 29.343295 -275.86701) (xy 29.291605 -275.877034)
			(xy 29.238991 -275.879051) (xy 29.186686 -275.873013) (xy 29.135915 -275.859061) (xy 29.08787 -275.837522)
			(xy 29.043675 -275.808902) (xy 29.004367 -275.773871) (xy 28.970867 -275.73325) (xy 28.943961 -275.687991)
			(xy 28.924278 -275.639156) (xy 28.912281 -275.587888) (xy 28.908251 -275.53539) (xy 22.051518 -275.53539)
			(xy 22.051014 -275.561716) (xy 22.042977 -275.613752) (xy 22.027091 -275.663951) (xy 22.003728 -275.711136)
			(xy 21.973436 -275.754202) (xy 21.936924 -275.79214) (xy 21.89505 -275.824059) (xy 21.848794 -275.849212)
			(xy 21.799241 -275.86701) (xy 21.747551 -275.877034) (xy 21.694937 -275.879051) (xy 21.642632 -275.873013)
			(xy 21.591861 -275.859061) (xy 21.543816 -275.837522) (xy 21.499621 -275.808902) (xy 21.460313 -275.773871)
			(xy 21.426813 -275.73325) (xy 21.399907 -275.687991) (xy 21.380224 -275.639156) (xy 21.368227 -275.587888)
			(xy 21.364197 -275.53539) (xy 16.086074 -275.53539) (xy 16.086074 -276.385274) (xy 17.264129 -276.385274)
			(xy 17.268159 -276.332776) (xy 17.280156 -276.281508) (xy 17.299839 -276.232673) (xy 17.326745 -276.187414)
			(xy 17.360245 -276.146793) (xy 17.399553 -276.111762) (xy 17.443748 -276.083142) (xy 17.491793 -276.061603)
			(xy 17.542564 -276.047651) (xy 17.594869 -276.041613) (xy 17.647483 -276.04363) (xy 17.699173 -276.053654)
			(xy 17.748726 -276.071452) (xy 17.794982 -276.096605) (xy 17.836856 -276.128524) (xy 17.873368 -276.166462)
			(xy 17.90366 -276.209528) (xy 17.927023 -276.256713) (xy 17.942909 -276.306912) (xy 17.950946 -276.358948)
			(xy 17.95145 -276.385274) (xy 21.364197 -276.385274) (xy 21.368227 -276.332776) (xy 21.380224 -276.281508)
			(xy 21.399907 -276.232673) (xy 21.426813 -276.187414) (xy 21.460313 -276.146793) (xy 21.499621 -276.111762)
			(xy 21.543816 -276.083142) (xy 21.591861 -276.061603) (xy 21.642632 -276.047651) (xy 21.694937 -276.041613)
			(xy 21.747551 -276.04363) (xy 21.799241 -276.053654) (xy 21.848794 -276.071452) (xy 21.89505 -276.096605)
			(xy 21.936924 -276.128524) (xy 21.973436 -276.166462) (xy 22.003728 -276.209528) (xy 22.027091 -276.256713)
			(xy 22.042977 -276.306912) (xy 22.051014 -276.358948) (xy 22.051518 -276.385274) (xy 24.808183 -276.385274)
			(xy 24.812213 -276.332776) (xy 24.82421 -276.281508) (xy 24.843893 -276.232673) (xy 24.870799 -276.187414)
			(xy 24.904299 -276.146793) (xy 24.943607 -276.111762) (xy 24.987802 -276.083142) (xy 25.035847 -276.061603)
			(xy 25.086618 -276.047651) (xy 25.138923 -276.041613) (xy 25.191537 -276.04363) (xy 25.243227 -276.053654)
			(xy 25.29278 -276.071452) (xy 25.339036 -276.096605) (xy 25.38091 -276.128524) (xy 25.417422 -276.166462)
			(xy 25.447714 -276.209528) (xy 25.471077 -276.256713) (xy 25.486963 -276.306912) (xy 25.495 -276.358948)
			(xy 25.495504 -276.385274) (xy 28.908251 -276.385274) (xy 28.912281 -276.332776) (xy 28.924278 -276.281508)
			(xy 28.943961 -276.232673) (xy 28.970867 -276.187414) (xy 29.004367 -276.146793) (xy 29.043675 -276.111762)
			(xy 29.08787 -276.083142) (xy 29.135915 -276.061603) (xy 29.186686 -276.047651) (xy 29.238991 -276.041613)
			(xy 29.291605 -276.04363) (xy 29.343295 -276.053654) (xy 29.392848 -276.071452) (xy 29.439104 -276.096605)
			(xy 29.480978 -276.128524) (xy 29.51749 -276.166462) (xy 29.547782 -276.209528) (xy 29.571145 -276.256713)
			(xy 29.587031 -276.306912) (xy 29.595068 -276.358948) (xy 29.595572 -276.385274) (xy 32.351983 -276.385274)
			(xy 32.356013 -276.332776) (xy 32.36801 -276.281508) (xy 32.387693 -276.232673) (xy 32.414599 -276.187414)
			(xy 32.448099 -276.146793) (xy 32.487407 -276.111762) (xy 32.531602 -276.083142) (xy 32.579647 -276.061603)
			(xy 32.630418 -276.047651) (xy 32.682723 -276.041613) (xy 32.735337 -276.04363) (xy 32.787027 -276.053654)
			(xy 32.83658 -276.071452) (xy 32.882836 -276.096605) (xy 32.92471 -276.128524) (xy 32.961222 -276.166462)
			(xy 32.991514 -276.209528) (xy 33.014877 -276.256713) (xy 33.030763 -276.306912) (xy 33.0388 -276.358948)
			(xy 33.039304 -276.385274) (xy 36.452051 -276.385274) (xy 36.456081 -276.332776) (xy 36.468078 -276.281508)
			(xy 36.487761 -276.232673) (xy 36.514667 -276.187414) (xy 36.548167 -276.146793) (xy 36.587475 -276.111762)
			(xy 36.63167 -276.083142) (xy 36.679715 -276.061603) (xy 36.730486 -276.047651) (xy 36.782791 -276.041613)
			(xy 36.835405 -276.04363) (xy 36.887095 -276.053654) (xy 36.936648 -276.071452) (xy 36.982904 -276.096605)
			(xy 37.024778 -276.128524) (xy 37.06129 -276.166462) (xy 37.091582 -276.209528) (xy 37.114945 -276.256713)
			(xy 37.130831 -276.306912) (xy 37.138868 -276.358948) (xy 37.139372 -276.385274) (xy 39.896037 -276.385274)
			(xy 39.900067 -276.332776) (xy 39.912064 -276.281508) (xy 39.931747 -276.232673) (xy 39.958653 -276.187414)
			(xy 39.992153 -276.146793) (xy 40.031461 -276.111762) (xy 40.075656 -276.083142) (xy 40.123701 -276.061603)
			(xy 40.174472 -276.047651) (xy 40.226777 -276.041613) (xy 40.279391 -276.04363) (xy 40.331081 -276.053654)
			(xy 40.380634 -276.071452) (xy 40.42689 -276.096605) (xy 40.468764 -276.128524) (xy 40.505276 -276.166462)
			(xy 40.535568 -276.209528) (xy 40.558931 -276.256713) (xy 40.574817 -276.306912) (xy 40.582854 -276.358948)
			(xy 40.583358 -276.385274) (xy 43.996105 -276.385274) (xy 44.000135 -276.332776) (xy 44.012132 -276.281508)
			(xy 44.031815 -276.232673) (xy 44.058721 -276.187414) (xy 44.092221 -276.146793) (xy 44.131529 -276.111762)
			(xy 44.175724 -276.083142) (xy 44.223769 -276.061603) (xy 44.27454 -276.047651) (xy 44.326845 -276.041613)
			(xy 44.379459 -276.04363) (xy 44.431149 -276.053654) (xy 44.480702 -276.071452) (xy 44.526958 -276.096605)
			(xy 44.568832 -276.128524) (xy 44.605344 -276.166462) (xy 44.635636 -276.209528) (xy 44.658999 -276.256713)
			(xy 44.674885 -276.306912) (xy 44.682922 -276.358948) (xy 44.683426 -276.385274) (xy 47.440091 -276.385274)
			(xy 47.444121 -276.332776) (xy 47.456118 -276.281508) (xy 47.475801 -276.232673) (xy 47.502707 -276.187414)
			(xy 47.536207 -276.146793) (xy 47.575515 -276.111762) (xy 47.61971 -276.083142) (xy 47.667755 -276.061603)
			(xy 47.718526 -276.047651) (xy 47.770831 -276.041613) (xy 47.823445 -276.04363) (xy 47.875135 -276.053654)
			(xy 47.924688 -276.071452) (xy 47.970944 -276.096605) (xy 48.012818 -276.128524) (xy 48.04933 -276.166462)
			(xy 48.079622 -276.209528) (xy 48.102985 -276.256713) (xy 48.118871 -276.306912) (xy 48.126908 -276.358948)
			(xy 48.127412 -276.385274) (xy 51.540159 -276.385274) (xy 51.544189 -276.332776) (xy 51.556186 -276.281508)
			(xy 51.575869 -276.232673) (xy 51.602775 -276.187414) (xy 51.636275 -276.146793) (xy 51.675583 -276.111762)
			(xy 51.719778 -276.083142) (xy 51.767823 -276.061603) (xy 51.818594 -276.047651) (xy 51.870899 -276.041613)
			(xy 51.923513 -276.04363) (xy 51.975203 -276.053654) (xy 52.024756 -276.071452) (xy 52.071012 -276.096605)
			(xy 52.112886 -276.128524) (xy 52.149398 -276.166462) (xy 52.17969 -276.209528) (xy 52.203053 -276.256713)
			(xy 52.218939 -276.306912) (xy 52.226976 -276.358948) (xy 52.22748 -276.385274) (xy 52.226976 -276.4116)
			(xy 52.218939 -276.463636) (xy 52.203053 -276.513835) (xy 52.17969 -276.56102) (xy 52.149398 -276.604086)
			(xy 52.112886 -276.642024) (xy 52.071012 -276.673943) (xy 52.024756 -276.699096) (xy 51.975203 -276.716894)
			(xy 51.923513 -276.726918) (xy 51.870899 -276.728935) (xy 51.818594 -276.722897) (xy 51.767823 -276.708945)
			(xy 51.719778 -276.687406) (xy 51.675583 -276.658786) (xy 51.636275 -276.623755) (xy 51.602775 -276.583134)
			(xy 51.575869 -276.537875) (xy 51.556186 -276.48904) (xy 51.544189 -276.437772) (xy 51.540159 -276.385274)
			(xy 48.127412 -276.385274) (xy 48.126908 -276.4116) (xy 48.118871 -276.463636) (xy 48.102985 -276.513835)
			(xy 48.079622 -276.56102) (xy 48.04933 -276.604086) (xy 48.012818 -276.642024) (xy 47.970944 -276.673943)
			(xy 47.924688 -276.699096) (xy 47.875135 -276.716894) (xy 47.823445 -276.726918) (xy 47.770831 -276.728935)
			(xy 47.718526 -276.722897) (xy 47.667755 -276.708945) (xy 47.61971 -276.687406) (xy 47.575515 -276.658786)
			(xy 47.536207 -276.623755) (xy 47.502707 -276.583134) (xy 47.475801 -276.537875) (xy 47.456118 -276.48904)
			(xy 47.444121 -276.437772) (xy 47.440091 -276.385274) (xy 44.683426 -276.385274) (xy 44.682922 -276.4116)
			(xy 44.674885 -276.463636) (xy 44.658999 -276.513835) (xy 44.635636 -276.56102) (xy 44.605344 -276.604086)
			(xy 44.568832 -276.642024) (xy 44.526958 -276.673943) (xy 44.480702 -276.699096) (xy 44.431149 -276.716894)
			(xy 44.379459 -276.726918) (xy 44.326845 -276.728935) (xy 44.27454 -276.722897) (xy 44.223769 -276.708945)
			(xy 44.175724 -276.687406) (xy 44.131529 -276.658786) (xy 44.092221 -276.623755) (xy 44.058721 -276.583134)
			(xy 44.031815 -276.537875) (xy 44.012132 -276.48904) (xy 44.000135 -276.437772) (xy 43.996105 -276.385274)
			(xy 40.583358 -276.385274) (xy 40.582854 -276.4116) (xy 40.574817 -276.463636) (xy 40.558931 -276.513835)
			(xy 40.535568 -276.56102) (xy 40.505276 -276.604086) (xy 40.468764 -276.642024) (xy 40.42689 -276.673943)
			(xy 40.380634 -276.699096) (xy 40.331081 -276.716894) (xy 40.279391 -276.726918) (xy 40.226777 -276.728935)
			(xy 40.174472 -276.722897) (xy 40.123701 -276.708945) (xy 40.075656 -276.687406) (xy 40.031461 -276.658786)
			(xy 39.992153 -276.623755) (xy 39.958653 -276.583134) (xy 39.931747 -276.537875) (xy 39.912064 -276.48904)
			(xy 39.900067 -276.437772) (xy 39.896037 -276.385274) (xy 37.139372 -276.385274) (xy 37.138868 -276.4116)
			(xy 37.130831 -276.463636) (xy 37.114945 -276.513835) (xy 37.091582 -276.56102) (xy 37.06129 -276.604086)
			(xy 37.024778 -276.642024) (xy 36.982904 -276.673943) (xy 36.936648 -276.699096) (xy 36.887095 -276.716894)
			(xy 36.835405 -276.726918) (xy 36.782791 -276.728935) (xy 36.730486 -276.722897) (xy 36.679715 -276.708945)
			(xy 36.63167 -276.687406) (xy 36.587475 -276.658786) (xy 36.548167 -276.623755) (xy 36.514667 -276.583134)
			(xy 36.487761 -276.537875) (xy 36.468078 -276.48904) (xy 36.456081 -276.437772) (xy 36.452051 -276.385274)
			(xy 33.039304 -276.385274) (xy 33.0388 -276.4116) (xy 33.030763 -276.463636) (xy 33.014877 -276.513835)
			(xy 32.991514 -276.56102) (xy 32.961222 -276.604086) (xy 32.92471 -276.642024) (xy 32.882836 -276.673943)
			(xy 32.83658 -276.699096) (xy 32.787027 -276.716894) (xy 32.735337 -276.726918) (xy 32.682723 -276.728935)
			(xy 32.630418 -276.722897) (xy 32.579647 -276.708945) (xy 32.531602 -276.687406) (xy 32.487407 -276.658786)
			(xy 32.448099 -276.623755) (xy 32.414599 -276.583134) (xy 32.387693 -276.537875) (xy 32.36801 -276.48904)
			(xy 32.356013 -276.437772) (xy 32.351983 -276.385274) (xy 29.595572 -276.385274) (xy 29.595068 -276.4116)
			(xy 29.587031 -276.463636) (xy 29.571145 -276.513835) (xy 29.547782 -276.56102) (xy 29.51749 -276.604086)
			(xy 29.480978 -276.642024) (xy 29.439104 -276.673943) (xy 29.392848 -276.699096) (xy 29.343295 -276.716894)
			(xy 29.291605 -276.726918) (xy 29.238991 -276.728935) (xy 29.186686 -276.722897) (xy 29.135915 -276.708945)
			(xy 29.08787 -276.687406) (xy 29.043675 -276.658786) (xy 29.004367 -276.623755) (xy 28.970867 -276.583134)
			(xy 28.943961 -276.537875) (xy 28.924278 -276.48904) (xy 28.912281 -276.437772) (xy 28.908251 -276.385274)
			(xy 25.495504 -276.385274) (xy 25.495 -276.4116) (xy 25.486963 -276.463636) (xy 25.471077 -276.513835)
			(xy 25.447714 -276.56102) (xy 25.417422 -276.604086) (xy 25.38091 -276.642024) (xy 25.339036 -276.673943)
			(xy 25.29278 -276.699096) (xy 25.243227 -276.716894) (xy 25.191537 -276.726918) (xy 25.138923 -276.728935)
			(xy 25.086618 -276.722897) (xy 25.035847 -276.708945) (xy 24.987802 -276.687406) (xy 24.943607 -276.658786)
			(xy 24.904299 -276.623755) (xy 24.870799 -276.583134) (xy 24.843893 -276.537875) (xy 24.82421 -276.48904)
			(xy 24.812213 -276.437772) (xy 24.808183 -276.385274) (xy 22.051518 -276.385274) (xy 22.051014 -276.4116)
			(xy 22.042977 -276.463636) (xy 22.027091 -276.513835) (xy 22.003728 -276.56102) (xy 21.973436 -276.604086)
			(xy 21.936924 -276.642024) (xy 21.89505 -276.673943) (xy 21.848794 -276.699096) (xy 21.799241 -276.716894)
			(xy 21.747551 -276.726918) (xy 21.694937 -276.728935) (xy 21.642632 -276.722897) (xy 21.591861 -276.708945)
			(xy 21.543816 -276.687406) (xy 21.499621 -276.658786) (xy 21.460313 -276.623755) (xy 21.426813 -276.583134)
			(xy 21.399907 -276.537875) (xy 21.380224 -276.48904) (xy 21.368227 -276.437772) (xy 21.364197 -276.385274)
			(xy 17.95145 -276.385274) (xy 17.950946 -276.4116) (xy 17.942909 -276.463636) (xy 17.927023 -276.513835)
			(xy 17.90366 -276.56102) (xy 17.873368 -276.604086) (xy 17.836856 -276.642024) (xy 17.794982 -276.673943)
			(xy 17.748726 -276.699096) (xy 17.699173 -276.716894) (xy 17.647483 -276.726918) (xy 17.594869 -276.728935)
			(xy 17.542564 -276.722897) (xy 17.491793 -276.708945) (xy 17.443748 -276.687406) (xy 17.399553 -276.658786)
			(xy 17.360245 -276.623755) (xy 17.326745 -276.583134) (xy 17.299839 -276.537875) (xy 17.280156 -276.48904)
			(xy 17.268159 -276.437772) (xy 17.264129 -276.385274) (xy 16.086074 -276.385274) (xy 16.086074 -277.235412)
			(xy 17.264129 -277.235412) (xy 17.268159 -277.182914) (xy 17.280156 -277.131646) (xy 17.299839 -277.082811)
			(xy 17.326745 -277.037552) (xy 17.360245 -276.996931) (xy 17.399553 -276.9619) (xy 17.443748 -276.93328)
			(xy 17.491793 -276.911741) (xy 17.542564 -276.897789) (xy 17.594869 -276.891751) (xy 17.647483 -276.893768)
			(xy 17.699173 -276.903792) (xy 17.748726 -276.92159) (xy 17.794982 -276.946743) (xy 17.836856 -276.978662)
			(xy 17.873368 -277.0166) (xy 17.90366 -277.059666) (xy 17.927023 -277.106851) (xy 17.942909 -277.15705)
			(xy 17.950946 -277.209086) (xy 17.95145 -277.235412) (xy 24.808183 -277.235412) (xy 24.812213 -277.182914)
			(xy 24.82421 -277.131646) (xy 24.843893 -277.082811) (xy 24.870799 -277.037552) (xy 24.904299 -276.996931)
			(xy 24.943607 -276.9619) (xy 24.987802 -276.93328) (xy 25.035847 -276.911741) (xy 25.086618 -276.897789)
			(xy 25.138923 -276.891751) (xy 25.191537 -276.893768) (xy 25.243227 -276.903792) (xy 25.29278 -276.92159)
			(xy 25.339036 -276.946743) (xy 25.38091 -276.978662) (xy 25.417422 -277.0166) (xy 25.447714 -277.059666)
			(xy 25.471077 -277.106851) (xy 25.486963 -277.15705) (xy 25.495 -277.209086) (xy 25.495504 -277.235412)
			(xy 32.351983 -277.235412) (xy 32.356013 -277.182914) (xy 32.36801 -277.131646) (xy 32.387693 -277.082811)
			(xy 32.414599 -277.037552) (xy 32.448099 -276.996931) (xy 32.487407 -276.9619) (xy 32.531602 -276.93328)
			(xy 32.579647 -276.911741) (xy 32.630418 -276.897789) (xy 32.682723 -276.891751) (xy 32.735337 -276.893768)
			(xy 32.787027 -276.903792) (xy 32.83658 -276.92159) (xy 32.882836 -276.946743) (xy 32.92471 -276.978662)
			(xy 32.961222 -277.0166) (xy 32.991514 -277.059666) (xy 33.014877 -277.106851) (xy 33.030763 -277.15705)
			(xy 33.0388 -277.209086) (xy 33.039304 -277.235412) (xy 39.896037 -277.235412) (xy 39.900067 -277.182914)
			(xy 39.912064 -277.131646) (xy 39.931747 -277.082811) (xy 39.958653 -277.037552) (xy 39.992153 -276.996931)
			(xy 40.031461 -276.9619) (xy 40.075656 -276.93328) (xy 40.123701 -276.911741) (xy 40.174472 -276.897789)
			(xy 40.226777 -276.891751) (xy 40.279391 -276.893768) (xy 40.331081 -276.903792) (xy 40.380634 -276.92159)
			(xy 40.42689 -276.946743) (xy 40.468764 -276.978662) (xy 40.505276 -277.0166) (xy 40.535568 -277.059666)
			(xy 40.558931 -277.106851) (xy 40.574817 -277.15705) (xy 40.582854 -277.209086) (xy 40.583358 -277.235412)
			(xy 47.440091 -277.235412) (xy 47.444121 -277.182914) (xy 47.456118 -277.131646) (xy 47.475801 -277.082811)
			(xy 47.502707 -277.037552) (xy 47.536207 -276.996931) (xy 47.575515 -276.9619) (xy 47.61971 -276.93328)
			(xy 47.667755 -276.911741) (xy 47.718526 -276.897789) (xy 47.770831 -276.891751) (xy 47.823445 -276.893768)
			(xy 47.875135 -276.903792) (xy 47.924688 -276.92159) (xy 47.970944 -276.946743) (xy 48.012818 -276.978662)
			(xy 48.04933 -277.0166) (xy 48.079622 -277.059666) (xy 48.102985 -277.106851) (xy 48.118871 -277.15705)
			(xy 48.126908 -277.209086) (xy 48.127412 -277.235412) (xy 48.126908 -277.261738) (xy 48.118871 -277.313774)
			(xy 48.102985 -277.363973) (xy 48.079622 -277.411158) (xy 48.04933 -277.454224) (xy 48.012818 -277.492162)
			(xy 47.970944 -277.524081) (xy 47.924688 -277.549234) (xy 47.875135 -277.567032) (xy 47.823445 -277.577056)
			(xy 47.770831 -277.579073) (xy 47.718526 -277.573035) (xy 47.667755 -277.559083) (xy 47.61971 -277.537544)
			(xy 47.575515 -277.508924) (xy 47.536207 -277.473893) (xy 47.502707 -277.433272) (xy 47.475801 -277.388013)
			(xy 47.456118 -277.339178) (xy 47.444121 -277.28791) (xy 47.440091 -277.235412) (xy 40.583358 -277.235412)
			(xy 40.582854 -277.261738) (xy 40.574817 -277.313774) (xy 40.558931 -277.363973) (xy 40.535568 -277.411158)
			(xy 40.505276 -277.454224) (xy 40.468764 -277.492162) (xy 40.42689 -277.524081) (xy 40.380634 -277.549234)
			(xy 40.331081 -277.567032) (xy 40.279391 -277.577056) (xy 40.226777 -277.579073) (xy 40.174472 -277.573035)
			(xy 40.123701 -277.559083) (xy 40.075656 -277.537544) (xy 40.031461 -277.508924) (xy 39.992153 -277.473893)
			(xy 39.958653 -277.433272) (xy 39.931747 -277.388013) (xy 39.912064 -277.339178) (xy 39.900067 -277.28791)
			(xy 39.896037 -277.235412) (xy 33.039304 -277.235412) (xy 33.0388 -277.261738) (xy 33.030763 -277.313774)
			(xy 33.014877 -277.363973) (xy 32.991514 -277.411158) (xy 32.961222 -277.454224) (xy 32.92471 -277.492162)
			(xy 32.882836 -277.524081) (xy 32.83658 -277.549234) (xy 32.787027 -277.567032) (xy 32.735337 -277.577056)
			(xy 32.682723 -277.579073) (xy 32.630418 -277.573035) (xy 32.579647 -277.559083) (xy 32.531602 -277.537544)
			(xy 32.487407 -277.508924) (xy 32.448099 -277.473893) (xy 32.414599 -277.433272) (xy 32.387693 -277.388013)
			(xy 32.36801 -277.339178) (xy 32.356013 -277.28791) (xy 32.351983 -277.235412) (xy 25.495504 -277.235412)
			(xy 25.495 -277.261738) (xy 25.486963 -277.313774) (xy 25.471077 -277.363973) (xy 25.447714 -277.411158)
			(xy 25.417422 -277.454224) (xy 25.38091 -277.492162) (xy 25.339036 -277.524081) (xy 25.29278 -277.549234)
			(xy 25.243227 -277.567032) (xy 25.191537 -277.577056) (xy 25.138923 -277.579073) (xy 25.086618 -277.573035)
			(xy 25.035847 -277.559083) (xy 24.987802 -277.537544) (xy 24.943607 -277.508924) (xy 24.904299 -277.473893)
			(xy 24.870799 -277.433272) (xy 24.843893 -277.388013) (xy 24.82421 -277.339178) (xy 24.812213 -277.28791)
			(xy 24.808183 -277.235412) (xy 17.95145 -277.235412) (xy 17.950946 -277.261738) (xy 17.942909 -277.313774)
			(xy 17.927023 -277.363973) (xy 17.90366 -277.411158) (xy 17.873368 -277.454224) (xy 17.836856 -277.492162)
			(xy 17.794982 -277.524081) (xy 17.748726 -277.549234) (xy 17.699173 -277.567032) (xy 17.647483 -277.577056)
			(xy 17.594869 -277.579073) (xy 17.542564 -277.573035) (xy 17.491793 -277.559083) (xy 17.443748 -277.537544)
			(xy 17.399553 -277.508924) (xy 17.360245 -277.473893) (xy 17.326745 -277.433272) (xy 17.299839 -277.388013)
			(xy 17.280156 -277.339178) (xy 17.268159 -277.28791) (xy 17.264129 -277.235412) (xy 16.086074 -277.235412)
			(xy 16.086074 -278.085296) (xy 21.364197 -278.085296) (xy 21.368227 -278.032798) (xy 21.380224 -277.98153)
			(xy 21.399907 -277.932695) (xy 21.426813 -277.887436) (xy 21.460313 -277.846815) (xy 21.499621 -277.811784)
			(xy 21.543816 -277.783164) (xy 21.591861 -277.761625) (xy 21.642632 -277.747673) (xy 21.694937 -277.741635)
			(xy 21.747551 -277.743652) (xy 21.799241 -277.753676) (xy 21.848794 -277.771474) (xy 21.89505 -277.796627)
			(xy 21.936924 -277.828546) (xy 21.973436 -277.866484) (xy 22.003728 -277.90955) (xy 22.027091 -277.956735)
			(xy 22.042977 -278.006934) (xy 22.051014 -278.05897) (xy 22.051518 -278.085296) (xy 28.908251 -278.085296)
			(xy 28.912281 -278.032798) (xy 28.924278 -277.98153) (xy 28.943961 -277.932695) (xy 28.970867 -277.887436)
			(xy 29.004367 -277.846815) (xy 29.043675 -277.811784) (xy 29.08787 -277.783164) (xy 29.135915 -277.761625)
			(xy 29.186686 -277.747673) (xy 29.238991 -277.741635) (xy 29.291605 -277.743652) (xy 29.343295 -277.753676)
			(xy 29.392848 -277.771474) (xy 29.439104 -277.796627) (xy 29.480978 -277.828546) (xy 29.51749 -277.866484)
			(xy 29.547782 -277.90955) (xy 29.571145 -277.956735) (xy 29.587031 -278.006934) (xy 29.595068 -278.05897)
			(xy 29.595572 -278.085296) (xy 36.452051 -278.085296) (xy 36.456081 -278.032798) (xy 36.468078 -277.98153)
			(xy 36.487761 -277.932695) (xy 36.514667 -277.887436) (xy 36.548167 -277.846815) (xy 36.587475 -277.811784)
			(xy 36.63167 -277.783164) (xy 36.679715 -277.761625) (xy 36.730486 -277.747673) (xy 36.782791 -277.741635)
			(xy 36.835405 -277.743652) (xy 36.887095 -277.753676) (xy 36.936648 -277.771474) (xy 36.982904 -277.796627)
			(xy 37.024778 -277.828546) (xy 37.06129 -277.866484) (xy 37.091582 -277.90955) (xy 37.114945 -277.956735)
			(xy 37.130831 -278.006934) (xy 37.138868 -278.05897) (xy 37.139372 -278.085296) (xy 43.996105 -278.085296)
			(xy 44.000135 -278.032798) (xy 44.012132 -277.98153) (xy 44.031815 -277.932695) (xy 44.058721 -277.887436)
			(xy 44.092221 -277.846815) (xy 44.131529 -277.811784) (xy 44.175724 -277.783164) (xy 44.223769 -277.761625)
			(xy 44.27454 -277.747673) (xy 44.326845 -277.741635) (xy 44.379459 -277.743652) (xy 44.431149 -277.753676)
			(xy 44.480702 -277.771474) (xy 44.526958 -277.796627) (xy 44.568832 -277.828546) (xy 44.605344 -277.866484)
			(xy 44.635636 -277.90955) (xy 44.658999 -277.956735) (xy 44.674885 -278.006934) (xy 44.682922 -278.05897)
			(xy 44.683426 -278.085296) (xy 51.540159 -278.085296) (xy 51.544189 -278.032798) (xy 51.556186 -277.98153)
			(xy 51.575869 -277.932695) (xy 51.602775 -277.887436) (xy 51.636275 -277.846815) (xy 51.675583 -277.811784)
			(xy 51.719778 -277.783164) (xy 51.767823 -277.761625) (xy 51.818594 -277.747673) (xy 51.870899 -277.741635)
			(xy 51.923513 -277.743652) (xy 51.975203 -277.753676) (xy 52.024756 -277.771474) (xy 52.071012 -277.796627)
			(xy 52.112886 -277.828546) (xy 52.149398 -277.866484) (xy 52.17969 -277.90955) (xy 52.203053 -277.956735)
			(xy 52.218939 -278.006934) (xy 52.226976 -278.05897) (xy 52.22748 -278.085296) (xy 52.226976 -278.111622)
			(xy 52.218939 -278.163658) (xy 52.203053 -278.213857) (xy 52.17969 -278.261042) (xy 52.149398 -278.304108)
			(xy 52.112886 -278.342046) (xy 52.071012 -278.373965) (xy 52.024756 -278.399118) (xy 51.975203 -278.416916)
			(xy 51.923513 -278.42694) (xy 51.870899 -278.428957) (xy 51.818594 -278.422919) (xy 51.767823 -278.408967)
			(xy 51.719778 -278.387428) (xy 51.675583 -278.358808) (xy 51.636275 -278.323777) (xy 51.602775 -278.283156)
			(xy 51.575869 -278.237897) (xy 51.556186 -278.189062) (xy 51.544189 -278.137794) (xy 51.540159 -278.085296)
			(xy 44.683426 -278.085296) (xy 44.682922 -278.111622) (xy 44.674885 -278.163658) (xy 44.658999 -278.213857)
			(xy 44.635636 -278.261042) (xy 44.605344 -278.304108) (xy 44.568832 -278.342046) (xy 44.526958 -278.373965)
			(xy 44.480702 -278.399118) (xy 44.431149 -278.416916) (xy 44.379459 -278.42694) (xy 44.326845 -278.428957)
			(xy 44.27454 -278.422919) (xy 44.223769 -278.408967) (xy 44.175724 -278.387428) (xy 44.131529 -278.358808)
			(xy 44.092221 -278.323777) (xy 44.058721 -278.283156) (xy 44.031815 -278.237897) (xy 44.012132 -278.189062)
			(xy 44.000135 -278.137794) (xy 43.996105 -278.085296) (xy 37.139372 -278.085296) (xy 37.138868 -278.111622)
			(xy 37.130831 -278.163658) (xy 37.114945 -278.213857) (xy 37.091582 -278.261042) (xy 37.06129 -278.304108)
			(xy 37.024778 -278.342046) (xy 36.982904 -278.373965) (xy 36.936648 -278.399118) (xy 36.887095 -278.416916)
			(xy 36.835405 -278.42694) (xy 36.782791 -278.428957) (xy 36.730486 -278.422919) (xy 36.679715 -278.408967)
			(xy 36.63167 -278.387428) (xy 36.587475 -278.358808) (xy 36.548167 -278.323777) (xy 36.514667 -278.283156)
			(xy 36.487761 -278.237897) (xy 36.468078 -278.189062) (xy 36.456081 -278.137794) (xy 36.452051 -278.085296)
			(xy 29.595572 -278.085296) (xy 29.595068 -278.111622) (xy 29.587031 -278.163658) (xy 29.571145 -278.213857)
			(xy 29.547782 -278.261042) (xy 29.51749 -278.304108) (xy 29.480978 -278.342046) (xy 29.439104 -278.373965)
			(xy 29.392848 -278.399118) (xy 29.343295 -278.416916) (xy 29.291605 -278.42694) (xy 29.238991 -278.428957)
			(xy 29.186686 -278.422919) (xy 29.135915 -278.408967) (xy 29.08787 -278.387428) (xy 29.043675 -278.358808)
			(xy 29.004367 -278.323777) (xy 28.970867 -278.283156) (xy 28.943961 -278.237897) (xy 28.924278 -278.189062)
			(xy 28.912281 -278.137794) (xy 28.908251 -278.085296) (xy 22.051518 -278.085296) (xy 22.051014 -278.111622)
			(xy 22.042977 -278.163658) (xy 22.027091 -278.213857) (xy 22.003728 -278.261042) (xy 21.973436 -278.304108)
			(xy 21.936924 -278.342046) (xy 21.89505 -278.373965) (xy 21.848794 -278.399118) (xy 21.799241 -278.416916)
			(xy 21.747551 -278.42694) (xy 21.694937 -278.428957) (xy 21.642632 -278.422919) (xy 21.591861 -278.408967)
			(xy 21.543816 -278.387428) (xy 21.499621 -278.358808) (xy 21.460313 -278.323777) (xy 21.426813 -278.283156)
			(xy 21.399907 -278.237897) (xy 21.380224 -278.189062) (xy 21.368227 -278.137794) (xy 21.364197 -278.085296)
			(xy 16.086074 -278.085296) (xy 16.086074 -278.935434) (xy 17.264129 -278.935434) (xy 17.268159 -278.882936)
			(xy 17.280156 -278.831668) (xy 17.299839 -278.782833) (xy 17.326745 -278.737574) (xy 17.360245 -278.696953)
			(xy 17.399553 -278.661922) (xy 17.443748 -278.633302) (xy 17.491793 -278.611763) (xy 17.542564 -278.597811)
			(xy 17.594869 -278.591773) (xy 17.647483 -278.59379) (xy 17.699173 -278.603814) (xy 17.748726 -278.621612)
			(xy 17.794982 -278.646765) (xy 17.836856 -278.678684) (xy 17.873368 -278.716622) (xy 17.90366 -278.759688)
			(xy 17.927023 -278.806873) (xy 17.942909 -278.857072) (xy 17.950946 -278.909108) (xy 17.95145 -278.935434)
			(xy 24.808183 -278.935434) (xy 24.812213 -278.882936) (xy 24.82421 -278.831668) (xy 24.843893 -278.782833)
			(xy 24.870799 -278.737574) (xy 24.904299 -278.696953) (xy 24.943607 -278.661922) (xy 24.987802 -278.633302)
			(xy 25.035847 -278.611763) (xy 25.086618 -278.597811) (xy 25.138923 -278.591773) (xy 25.191537 -278.59379)
			(xy 25.243227 -278.603814) (xy 25.29278 -278.621612) (xy 25.339036 -278.646765) (xy 25.38091 -278.678684)
			(xy 25.417422 -278.716622) (xy 25.447714 -278.759688) (xy 25.471077 -278.806873) (xy 25.486963 -278.857072)
			(xy 25.495 -278.909108) (xy 25.495504 -278.935434) (xy 32.351983 -278.935434) (xy 32.356013 -278.882936)
			(xy 32.36801 -278.831668) (xy 32.387693 -278.782833) (xy 32.414599 -278.737574) (xy 32.448099 -278.696953)
			(xy 32.487407 -278.661922) (xy 32.531602 -278.633302) (xy 32.579647 -278.611763) (xy 32.630418 -278.597811)
			(xy 32.682723 -278.591773) (xy 32.735337 -278.59379) (xy 32.787027 -278.603814) (xy 32.83658 -278.621612)
			(xy 32.882836 -278.646765) (xy 32.92471 -278.678684) (xy 32.961222 -278.716622) (xy 32.991514 -278.759688)
			(xy 33.014877 -278.806873) (xy 33.030763 -278.857072) (xy 33.0388 -278.909108) (xy 33.039304 -278.935434)
			(xy 39.896037 -278.935434) (xy 39.900067 -278.882936) (xy 39.912064 -278.831668) (xy 39.931747 -278.782833)
			(xy 39.958653 -278.737574) (xy 39.992153 -278.696953) (xy 40.031461 -278.661922) (xy 40.075656 -278.633302)
			(xy 40.123701 -278.611763) (xy 40.174472 -278.597811) (xy 40.226777 -278.591773) (xy 40.279391 -278.59379)
			(xy 40.331081 -278.603814) (xy 40.380634 -278.621612) (xy 40.42689 -278.646765) (xy 40.468764 -278.678684)
			(xy 40.505276 -278.716622) (xy 40.535568 -278.759688) (xy 40.558931 -278.806873) (xy 40.574817 -278.857072)
			(xy 40.582854 -278.909108) (xy 40.583358 -278.935434) (xy 47.440091 -278.935434) (xy 47.444121 -278.882936)
			(xy 47.456118 -278.831668) (xy 47.475801 -278.782833) (xy 47.502707 -278.737574) (xy 47.536207 -278.696953)
			(xy 47.575515 -278.661922) (xy 47.61971 -278.633302) (xy 47.667755 -278.611763) (xy 47.718526 -278.597811)
			(xy 47.770831 -278.591773) (xy 47.823445 -278.59379) (xy 47.875135 -278.603814) (xy 47.924688 -278.621612)
			(xy 47.970944 -278.646765) (xy 48.012818 -278.678684) (xy 48.04933 -278.716622) (xy 48.079622 -278.759688)
			(xy 48.102985 -278.806873) (xy 48.118871 -278.857072) (xy 48.126908 -278.909108) (xy 48.127412 -278.935434)
			(xy 48.126908 -278.96176) (xy 48.118871 -279.013796) (xy 48.102985 -279.063995) (xy 48.079622 -279.11118)
			(xy 48.04933 -279.154246) (xy 48.012818 -279.192184) (xy 47.970944 -279.224103) (xy 47.924688 -279.249256)
			(xy 47.875135 -279.267054) (xy 47.823445 -279.277078) (xy 47.770831 -279.279095) (xy 47.718526 -279.273057)
			(xy 47.667755 -279.259105) (xy 47.61971 -279.237566) (xy 47.575515 -279.208946) (xy 47.536207 -279.173915)
			(xy 47.502707 -279.133294) (xy 47.475801 -279.088035) (xy 47.456118 -279.0392) (xy 47.444121 -278.987932)
			(xy 47.440091 -278.935434) (xy 40.583358 -278.935434) (xy 40.582854 -278.96176) (xy 40.574817 -279.013796)
			(xy 40.558931 -279.063995) (xy 40.535568 -279.11118) (xy 40.505276 -279.154246) (xy 40.468764 -279.192184)
			(xy 40.42689 -279.224103) (xy 40.380634 -279.249256) (xy 40.331081 -279.267054) (xy 40.279391 -279.277078)
			(xy 40.226777 -279.279095) (xy 40.174472 -279.273057) (xy 40.123701 -279.259105) (xy 40.075656 -279.237566)
			(xy 40.031461 -279.208946) (xy 39.992153 -279.173915) (xy 39.958653 -279.133294) (xy 39.931747 -279.088035)
			(xy 39.912064 -279.0392) (xy 39.900067 -278.987932) (xy 39.896037 -278.935434) (xy 33.039304 -278.935434)
			(xy 33.0388 -278.96176) (xy 33.030763 -279.013796) (xy 33.014877 -279.063995) (xy 32.991514 -279.11118)
			(xy 32.961222 -279.154246) (xy 32.92471 -279.192184) (xy 32.882836 -279.224103) (xy 32.83658 -279.249256)
			(xy 32.787027 -279.267054) (xy 32.735337 -279.277078) (xy 32.682723 -279.279095) (xy 32.630418 -279.273057)
			(xy 32.579647 -279.259105) (xy 32.531602 -279.237566) (xy 32.487407 -279.208946) (xy 32.448099 -279.173915)
			(xy 32.414599 -279.133294) (xy 32.387693 -279.088035) (xy 32.36801 -279.0392) (xy 32.356013 -278.987932)
			(xy 32.351983 -278.935434) (xy 25.495504 -278.935434) (xy 25.495 -278.96176) (xy 25.486963 -279.013796)
			(xy 25.471077 -279.063995) (xy 25.447714 -279.11118) (xy 25.417422 -279.154246) (xy 25.38091 -279.192184)
			(xy 25.339036 -279.224103) (xy 25.29278 -279.249256) (xy 25.243227 -279.267054) (xy 25.191537 -279.277078)
			(xy 25.138923 -279.279095) (xy 25.086618 -279.273057) (xy 25.035847 -279.259105) (xy 24.987802 -279.237566)
			(xy 24.943607 -279.208946) (xy 24.904299 -279.173915) (xy 24.870799 -279.133294) (xy 24.843893 -279.088035)
			(xy 24.82421 -279.0392) (xy 24.812213 -278.987932) (xy 24.808183 -278.935434) (xy 17.95145 -278.935434)
			(xy 17.950946 -278.96176) (xy 17.942909 -279.013796) (xy 17.927023 -279.063995) (xy 17.90366 -279.11118)
			(xy 17.873368 -279.154246) (xy 17.836856 -279.192184) (xy 17.794982 -279.224103) (xy 17.748726 -279.249256)
			(xy 17.699173 -279.267054) (xy 17.647483 -279.277078) (xy 17.594869 -279.279095) (xy 17.542564 -279.273057)
			(xy 17.491793 -279.259105) (xy 17.443748 -279.237566) (xy 17.399553 -279.208946) (xy 17.360245 -279.173915)
			(xy 17.326745 -279.133294) (xy 17.299839 -279.088035) (xy 17.280156 -279.0392) (xy 17.268159 -278.987932)
			(xy 17.264129 -278.935434) (xy 16.086074 -278.935434) (xy 16.086074 -279.785318) (xy 21.364197 -279.785318)
			(xy 21.368227 -279.73282) (xy 21.380224 -279.681552) (xy 21.399907 -279.632717) (xy 21.426813 -279.587458)
			(xy 21.460313 -279.546837) (xy 21.499621 -279.511806) (xy 21.543816 -279.483186) (xy 21.591861 -279.461647)
			(xy 21.642632 -279.447695) (xy 21.694937 -279.441657) (xy 21.747551 -279.443674) (xy 21.799241 -279.453698)
			(xy 21.848794 -279.471496) (xy 21.89505 -279.496649) (xy 21.936924 -279.528568) (xy 21.973436 -279.566506)
			(xy 22.003728 -279.609572) (xy 22.027091 -279.656757) (xy 22.042977 -279.706956) (xy 22.051014 -279.758992)
			(xy 22.051518 -279.785318) (xy 28.908251 -279.785318) (xy 28.912281 -279.73282) (xy 28.924278 -279.681552)
			(xy 28.943961 -279.632717) (xy 28.970867 -279.587458) (xy 29.004367 -279.546837) (xy 29.043675 -279.511806)
			(xy 29.08787 -279.483186) (xy 29.135915 -279.461647) (xy 29.186686 -279.447695) (xy 29.238991 -279.441657)
			(xy 29.291605 -279.443674) (xy 29.343295 -279.453698) (xy 29.392848 -279.471496) (xy 29.439104 -279.496649)
			(xy 29.480978 -279.528568) (xy 29.51749 -279.566506) (xy 29.547782 -279.609572) (xy 29.571145 -279.656757)
			(xy 29.587031 -279.706956) (xy 29.595068 -279.758992) (xy 29.595572 -279.785318) (xy 36.452051 -279.785318)
			(xy 36.456081 -279.73282) (xy 36.468078 -279.681552) (xy 36.487761 -279.632717) (xy 36.514667 -279.587458)
			(xy 36.548167 -279.546837) (xy 36.587475 -279.511806) (xy 36.63167 -279.483186) (xy 36.679715 -279.461647)
			(xy 36.730486 -279.447695) (xy 36.782791 -279.441657) (xy 36.835405 -279.443674) (xy 36.887095 -279.453698)
			(xy 36.936648 -279.471496) (xy 36.982904 -279.496649) (xy 37.024778 -279.528568) (xy 37.06129 -279.566506)
			(xy 37.091582 -279.609572) (xy 37.114945 -279.656757) (xy 37.130831 -279.706956) (xy 37.138868 -279.758992)
			(xy 37.139372 -279.785318) (xy 43.996105 -279.785318) (xy 44.000135 -279.73282) (xy 44.012132 -279.681552)
			(xy 44.031815 -279.632717) (xy 44.058721 -279.587458) (xy 44.092221 -279.546837) (xy 44.131529 -279.511806)
			(xy 44.175724 -279.483186) (xy 44.223769 -279.461647) (xy 44.27454 -279.447695) (xy 44.326845 -279.441657)
			(xy 44.379459 -279.443674) (xy 44.431149 -279.453698) (xy 44.480702 -279.471496) (xy 44.526958 -279.496649)
			(xy 44.568832 -279.528568) (xy 44.605344 -279.566506) (xy 44.635636 -279.609572) (xy 44.658999 -279.656757)
			(xy 44.674885 -279.706956) (xy 44.682922 -279.758992) (xy 44.683426 -279.785318) (xy 51.540159 -279.785318)
			(xy 51.544189 -279.73282) (xy 51.556186 -279.681552) (xy 51.575869 -279.632717) (xy 51.602775 -279.587458)
			(xy 51.636275 -279.546837) (xy 51.675583 -279.511806) (xy 51.719778 -279.483186) (xy 51.767823 -279.461647)
			(xy 51.818594 -279.447695) (xy 51.870899 -279.441657) (xy 51.923513 -279.443674) (xy 51.975203 -279.453698)
			(xy 52.024756 -279.471496) (xy 52.071012 -279.496649) (xy 52.112886 -279.528568) (xy 52.149398 -279.566506)
			(xy 52.17969 -279.609572) (xy 52.203053 -279.656757) (xy 52.218939 -279.706956) (xy 52.226976 -279.758992)
			(xy 52.22748 -279.785318) (xy 52.226976 -279.811644) (xy 52.218939 -279.86368) (xy 52.203053 -279.913879)
			(xy 52.17969 -279.961064) (xy 52.149398 -280.00413) (xy 52.112886 -280.042068) (xy 52.071012 -280.073987)
			(xy 52.024756 -280.09914) (xy 51.975203 -280.116938) (xy 51.923513 -280.126962) (xy 51.870899 -280.128979)
			(xy 51.818594 -280.122941) (xy 51.767823 -280.108989) (xy 51.719778 -280.08745) (xy 51.675583 -280.05883)
			(xy 51.636275 -280.023799) (xy 51.602775 -279.983178) (xy 51.575869 -279.937919) (xy 51.556186 -279.889084)
			(xy 51.544189 -279.837816) (xy 51.540159 -279.785318) (xy 44.683426 -279.785318) (xy 44.682922 -279.811644)
			(xy 44.674885 -279.86368) (xy 44.658999 -279.913879) (xy 44.635636 -279.961064) (xy 44.605344 -280.00413)
			(xy 44.568832 -280.042068) (xy 44.526958 -280.073987) (xy 44.480702 -280.09914) (xy 44.431149 -280.116938)
			(xy 44.379459 -280.126962) (xy 44.326845 -280.128979) (xy 44.27454 -280.122941) (xy 44.223769 -280.108989)
			(xy 44.175724 -280.08745) (xy 44.131529 -280.05883) (xy 44.092221 -280.023799) (xy 44.058721 -279.983178)
			(xy 44.031815 -279.937919) (xy 44.012132 -279.889084) (xy 44.000135 -279.837816) (xy 43.996105 -279.785318)
			(xy 37.139372 -279.785318) (xy 37.138868 -279.811644) (xy 37.130831 -279.86368) (xy 37.114945 -279.913879)
			(xy 37.091582 -279.961064) (xy 37.06129 -280.00413) (xy 37.024778 -280.042068) (xy 36.982904 -280.073987)
			(xy 36.936648 -280.09914) (xy 36.887095 -280.116938) (xy 36.835405 -280.126962) (xy 36.782791 -280.128979)
			(xy 36.730486 -280.122941) (xy 36.679715 -280.108989) (xy 36.63167 -280.08745) (xy 36.587475 -280.05883)
			(xy 36.548167 -280.023799) (xy 36.514667 -279.983178) (xy 36.487761 -279.937919) (xy 36.468078 -279.889084)
			(xy 36.456081 -279.837816) (xy 36.452051 -279.785318) (xy 29.595572 -279.785318) (xy 29.595068 -279.811644)
			(xy 29.587031 -279.86368) (xy 29.571145 -279.913879) (xy 29.547782 -279.961064) (xy 29.51749 -280.00413)
			(xy 29.480978 -280.042068) (xy 29.439104 -280.073987) (xy 29.392848 -280.09914) (xy 29.343295 -280.116938)
			(xy 29.291605 -280.126962) (xy 29.238991 -280.128979) (xy 29.186686 -280.122941) (xy 29.135915 -280.108989)
			(xy 29.08787 -280.08745) (xy 29.043675 -280.05883) (xy 29.004367 -280.023799) (xy 28.970867 -279.983178)
			(xy 28.943961 -279.937919) (xy 28.924278 -279.889084) (xy 28.912281 -279.837816) (xy 28.908251 -279.785318)
			(xy 22.051518 -279.785318) (xy 22.051014 -279.811644) (xy 22.042977 -279.86368) (xy 22.027091 -279.913879)
			(xy 22.003728 -279.961064) (xy 21.973436 -280.00413) (xy 21.936924 -280.042068) (xy 21.89505 -280.073987)
			(xy 21.848794 -280.09914) (xy 21.799241 -280.116938) (xy 21.747551 -280.126962) (xy 21.694937 -280.128979)
			(xy 21.642632 -280.122941) (xy 21.591861 -280.108989) (xy 21.543816 -280.08745) (xy 21.499621 -280.05883)
			(xy 21.460313 -280.023799) (xy 21.426813 -279.983178) (xy 21.399907 -279.937919) (xy 21.380224 -279.889084)
			(xy 21.368227 -279.837816) (xy 21.364197 -279.785318) (xy 16.086074 -279.785318) (xy 16.086074 -280.635202)
			(xy 17.264129 -280.635202) (xy 17.268159 -280.582704) (xy 17.280156 -280.531436) (xy 17.299839 -280.482601)
			(xy 17.326745 -280.437342) (xy 17.360245 -280.396721) (xy 17.399553 -280.36169) (xy 17.443748 -280.33307)
			(xy 17.491793 -280.311531) (xy 17.542564 -280.297579) (xy 17.594869 -280.291541) (xy 17.647483 -280.293558)
			(xy 17.699173 -280.303582) (xy 17.748726 -280.32138) (xy 17.794982 -280.346533) (xy 17.836856 -280.378452)
			(xy 17.873368 -280.41639) (xy 17.90366 -280.459456) (xy 17.927023 -280.506641) (xy 17.942909 -280.55684)
			(xy 17.950946 -280.608876) (xy 17.95145 -280.635202) (xy 24.808183 -280.635202) (xy 24.812213 -280.582704)
			(xy 24.82421 -280.531436) (xy 24.843893 -280.482601) (xy 24.870799 -280.437342) (xy 24.904299 -280.396721)
			(xy 24.943607 -280.36169) (xy 24.987802 -280.33307) (xy 25.035847 -280.311531) (xy 25.086618 -280.297579)
			(xy 25.138923 -280.291541) (xy 25.191537 -280.293558) (xy 25.243227 -280.303582) (xy 25.29278 -280.32138)
			(xy 25.339036 -280.346533) (xy 25.38091 -280.378452) (xy 25.417422 -280.41639) (xy 25.447714 -280.459456)
			(xy 25.471077 -280.506641) (xy 25.486963 -280.55684) (xy 25.495 -280.608876) (xy 25.495504 -280.635202)
			(xy 32.351983 -280.635202) (xy 32.356013 -280.582704) (xy 32.36801 -280.531436) (xy 32.387693 -280.482601)
			(xy 32.414599 -280.437342) (xy 32.448099 -280.396721) (xy 32.487407 -280.36169) (xy 32.531602 -280.33307)
			(xy 32.579647 -280.311531) (xy 32.630418 -280.297579) (xy 32.682723 -280.291541) (xy 32.735337 -280.293558)
			(xy 32.787027 -280.303582) (xy 32.83658 -280.32138) (xy 32.882836 -280.346533) (xy 32.92471 -280.378452)
			(xy 32.961222 -280.41639) (xy 32.991514 -280.459456) (xy 33.014877 -280.506641) (xy 33.030763 -280.55684)
			(xy 33.0388 -280.608876) (xy 33.039304 -280.635202) (xy 39.896037 -280.635202) (xy 39.900067 -280.582704)
			(xy 39.912064 -280.531436) (xy 39.931747 -280.482601) (xy 39.958653 -280.437342) (xy 39.992153 -280.396721)
			(xy 40.031461 -280.36169) (xy 40.075656 -280.33307) (xy 40.123701 -280.311531) (xy 40.174472 -280.297579)
			(xy 40.226777 -280.291541) (xy 40.279391 -280.293558) (xy 40.331081 -280.303582) (xy 40.380634 -280.32138)
			(xy 40.42689 -280.346533) (xy 40.468764 -280.378452) (xy 40.505276 -280.41639) (xy 40.535568 -280.459456)
			(xy 40.558931 -280.506641) (xy 40.574817 -280.55684) (xy 40.582854 -280.608876) (xy 40.583358 -280.635202)
			(xy 47.440091 -280.635202) (xy 47.444121 -280.582704) (xy 47.456118 -280.531436) (xy 47.475801 -280.482601)
			(xy 47.502707 -280.437342) (xy 47.536207 -280.396721) (xy 47.575515 -280.36169) (xy 47.61971 -280.33307)
			(xy 47.667755 -280.311531) (xy 47.718526 -280.297579) (xy 47.770831 -280.291541) (xy 47.823445 -280.293558)
			(xy 47.875135 -280.303582) (xy 47.924688 -280.32138) (xy 47.970944 -280.346533) (xy 48.012818 -280.378452)
			(xy 48.04933 -280.41639) (xy 48.079622 -280.459456) (xy 48.102985 -280.506641) (xy 48.118871 -280.55684)
			(xy 48.126908 -280.608876) (xy 48.127412 -280.635202) (xy 48.126908 -280.661528) (xy 48.118871 -280.713564)
			(xy 48.102985 -280.763763) (xy 48.079622 -280.810948) (xy 48.04933 -280.854014) (xy 48.012818 -280.891952)
			(xy 47.970944 -280.923871) (xy 47.924688 -280.949024) (xy 47.875135 -280.966822) (xy 47.823445 -280.976846)
			(xy 47.770831 -280.978863) (xy 47.718526 -280.972825) (xy 47.667755 -280.958873) (xy 47.61971 -280.937334)
			(xy 47.575515 -280.908714) (xy 47.536207 -280.873683) (xy 47.502707 -280.833062) (xy 47.475801 -280.787803)
			(xy 47.456118 -280.738968) (xy 47.444121 -280.6877) (xy 47.440091 -280.635202) (xy 40.583358 -280.635202)
			(xy 40.582854 -280.661528) (xy 40.574817 -280.713564) (xy 40.558931 -280.763763) (xy 40.535568 -280.810948)
			(xy 40.505276 -280.854014) (xy 40.468764 -280.891952) (xy 40.42689 -280.923871) (xy 40.380634 -280.949024)
			(xy 40.331081 -280.966822) (xy 40.279391 -280.976846) (xy 40.226777 -280.978863) (xy 40.174472 -280.972825)
			(xy 40.123701 -280.958873) (xy 40.075656 -280.937334) (xy 40.031461 -280.908714) (xy 39.992153 -280.873683)
			(xy 39.958653 -280.833062) (xy 39.931747 -280.787803) (xy 39.912064 -280.738968) (xy 39.900067 -280.6877)
			(xy 39.896037 -280.635202) (xy 33.039304 -280.635202) (xy 33.0388 -280.661528) (xy 33.030763 -280.713564)
			(xy 33.014877 -280.763763) (xy 32.991514 -280.810948) (xy 32.961222 -280.854014) (xy 32.92471 -280.891952)
			(xy 32.882836 -280.923871) (xy 32.83658 -280.949024) (xy 32.787027 -280.966822) (xy 32.735337 -280.976846)
			(xy 32.682723 -280.978863) (xy 32.630418 -280.972825) (xy 32.579647 -280.958873) (xy 32.531602 -280.937334)
			(xy 32.487407 -280.908714) (xy 32.448099 -280.873683) (xy 32.414599 -280.833062) (xy 32.387693 -280.787803)
			(xy 32.36801 -280.738968) (xy 32.356013 -280.6877) (xy 32.351983 -280.635202) (xy 25.495504 -280.635202)
			(xy 25.495 -280.661528) (xy 25.486963 -280.713564) (xy 25.471077 -280.763763) (xy 25.447714 -280.810948)
			(xy 25.417422 -280.854014) (xy 25.38091 -280.891952) (xy 25.339036 -280.923871) (xy 25.29278 -280.949024)
			(xy 25.243227 -280.966822) (xy 25.191537 -280.976846) (xy 25.138923 -280.978863) (xy 25.086618 -280.972825)
			(xy 25.035847 -280.958873) (xy 24.987802 -280.937334) (xy 24.943607 -280.908714) (xy 24.904299 -280.873683)
			(xy 24.870799 -280.833062) (xy 24.843893 -280.787803) (xy 24.82421 -280.738968) (xy 24.812213 -280.6877)
			(xy 24.808183 -280.635202) (xy 17.95145 -280.635202) (xy 17.950946 -280.661528) (xy 17.942909 -280.713564)
			(xy 17.927023 -280.763763) (xy 17.90366 -280.810948) (xy 17.873368 -280.854014) (xy 17.836856 -280.891952)
			(xy 17.794982 -280.923871) (xy 17.748726 -280.949024) (xy 17.699173 -280.966822) (xy 17.647483 -280.976846)
			(xy 17.594869 -280.978863) (xy 17.542564 -280.972825) (xy 17.491793 -280.958873) (xy 17.443748 -280.937334)
			(xy 17.399553 -280.908714) (xy 17.360245 -280.873683) (xy 17.326745 -280.833062) (xy 17.299839 -280.787803)
			(xy 17.280156 -280.738968) (xy 17.268159 -280.6877) (xy 17.264129 -280.635202) (xy 16.086074 -280.635202)
			(xy 16.086074 -281.48534) (xy 21.364197 -281.48534) (xy 21.368227 -281.432842) (xy 21.380224 -281.381574)
			(xy 21.399907 -281.332739) (xy 21.426813 -281.28748) (xy 21.460313 -281.246859) (xy 21.499621 -281.211828)
			(xy 21.543816 -281.183208) (xy 21.591861 -281.161669) (xy 21.642632 -281.147717) (xy 21.694937 -281.141679)
			(xy 21.747551 -281.143696) (xy 21.799241 -281.15372) (xy 21.848794 -281.171518) (xy 21.89505 -281.196671)
			(xy 21.936924 -281.22859) (xy 21.973436 -281.266528) (xy 22.003728 -281.309594) (xy 22.027091 -281.356779)
			(xy 22.042977 -281.406978) (xy 22.051014 -281.459014) (xy 22.051518 -281.48534) (xy 28.908251 -281.48534)
			(xy 28.912281 -281.432842) (xy 28.924278 -281.381574) (xy 28.943961 -281.332739) (xy 28.970867 -281.28748)
			(xy 29.004367 -281.246859) (xy 29.043675 -281.211828) (xy 29.08787 -281.183208) (xy 29.135915 -281.161669)
			(xy 29.186686 -281.147717) (xy 29.238991 -281.141679) (xy 29.291605 -281.143696) (xy 29.343295 -281.15372)
			(xy 29.392848 -281.171518) (xy 29.439104 -281.196671) (xy 29.480978 -281.22859) (xy 29.51749 -281.266528)
			(xy 29.547782 -281.309594) (xy 29.571145 -281.356779) (xy 29.587031 -281.406978) (xy 29.595068 -281.459014)
			(xy 29.595572 -281.48534) (xy 36.452051 -281.48534) (xy 36.456081 -281.432842) (xy 36.468078 -281.381574)
			(xy 36.487761 -281.332739) (xy 36.514667 -281.28748) (xy 36.548167 -281.246859) (xy 36.587475 -281.211828)
			(xy 36.63167 -281.183208) (xy 36.679715 -281.161669) (xy 36.730486 -281.147717) (xy 36.782791 -281.141679)
			(xy 36.835405 -281.143696) (xy 36.887095 -281.15372) (xy 36.936648 -281.171518) (xy 36.982904 -281.196671)
			(xy 37.024778 -281.22859) (xy 37.06129 -281.266528) (xy 37.091582 -281.309594) (xy 37.114945 -281.356779)
			(xy 37.130831 -281.406978) (xy 37.138868 -281.459014) (xy 37.139372 -281.48534) (xy 43.996105 -281.48534)
			(xy 44.000135 -281.432842) (xy 44.012132 -281.381574) (xy 44.031815 -281.332739) (xy 44.058721 -281.28748)
			(xy 44.092221 -281.246859) (xy 44.131529 -281.211828) (xy 44.175724 -281.183208) (xy 44.223769 -281.161669)
			(xy 44.27454 -281.147717) (xy 44.326845 -281.141679) (xy 44.379459 -281.143696) (xy 44.431149 -281.15372)
			(xy 44.480702 -281.171518) (xy 44.526958 -281.196671) (xy 44.568832 -281.22859) (xy 44.605344 -281.266528)
			(xy 44.635636 -281.309594) (xy 44.658999 -281.356779) (xy 44.674885 -281.406978) (xy 44.682922 -281.459014)
			(xy 44.683426 -281.48534) (xy 51.540159 -281.48534) (xy 51.544189 -281.432842) (xy 51.556186 -281.381574)
			(xy 51.575869 -281.332739) (xy 51.602775 -281.28748) (xy 51.636275 -281.246859) (xy 51.675583 -281.211828)
			(xy 51.719778 -281.183208) (xy 51.767823 -281.161669) (xy 51.818594 -281.147717) (xy 51.870899 -281.141679)
			(xy 51.923513 -281.143696) (xy 51.975203 -281.15372) (xy 52.024756 -281.171518) (xy 52.071012 -281.196671)
			(xy 52.112886 -281.22859) (xy 52.149398 -281.266528) (xy 52.17969 -281.309594) (xy 52.203053 -281.356779)
			(xy 52.218939 -281.406978) (xy 52.226976 -281.459014) (xy 52.22748 -281.48534) (xy 52.226976 -281.511666)
			(xy 52.218939 -281.563702) (xy 52.203053 -281.613901) (xy 52.17969 -281.661086) (xy 52.149398 -281.704152)
			(xy 52.112886 -281.74209) (xy 52.071012 -281.774009) (xy 52.024756 -281.799162) (xy 51.975203 -281.81696)
			(xy 51.923513 -281.826984) (xy 51.870899 -281.829001) (xy 51.818594 -281.822963) (xy 51.767823 -281.809011)
			(xy 51.719778 -281.787472) (xy 51.675583 -281.758852) (xy 51.636275 -281.723821) (xy 51.602775 -281.6832)
			(xy 51.575869 -281.637941) (xy 51.556186 -281.589106) (xy 51.544189 -281.537838) (xy 51.540159 -281.48534)
			(xy 44.683426 -281.48534) (xy 44.682922 -281.511666) (xy 44.674885 -281.563702) (xy 44.658999 -281.613901)
			(xy 44.635636 -281.661086) (xy 44.605344 -281.704152) (xy 44.568832 -281.74209) (xy 44.526958 -281.774009)
			(xy 44.480702 -281.799162) (xy 44.431149 -281.81696) (xy 44.379459 -281.826984) (xy 44.326845 -281.829001)
			(xy 44.27454 -281.822963) (xy 44.223769 -281.809011) (xy 44.175724 -281.787472) (xy 44.131529 -281.758852)
			(xy 44.092221 -281.723821) (xy 44.058721 -281.6832) (xy 44.031815 -281.637941) (xy 44.012132 -281.589106)
			(xy 44.000135 -281.537838) (xy 43.996105 -281.48534) (xy 37.139372 -281.48534) (xy 37.138868 -281.511666)
			(xy 37.130831 -281.563702) (xy 37.114945 -281.613901) (xy 37.091582 -281.661086) (xy 37.06129 -281.704152)
			(xy 37.024778 -281.74209) (xy 36.982904 -281.774009) (xy 36.936648 -281.799162) (xy 36.887095 -281.81696)
			(xy 36.835405 -281.826984) (xy 36.782791 -281.829001) (xy 36.730486 -281.822963) (xy 36.679715 -281.809011)
			(xy 36.63167 -281.787472) (xy 36.587475 -281.758852) (xy 36.548167 -281.723821) (xy 36.514667 -281.6832)
			(xy 36.487761 -281.637941) (xy 36.468078 -281.589106) (xy 36.456081 -281.537838) (xy 36.452051 -281.48534)
			(xy 29.595572 -281.48534) (xy 29.595068 -281.511666) (xy 29.587031 -281.563702) (xy 29.571145 -281.613901)
			(xy 29.547782 -281.661086) (xy 29.51749 -281.704152) (xy 29.480978 -281.74209) (xy 29.439104 -281.774009)
			(xy 29.392848 -281.799162) (xy 29.343295 -281.81696) (xy 29.291605 -281.826984) (xy 29.238991 -281.829001)
			(xy 29.186686 -281.822963) (xy 29.135915 -281.809011) (xy 29.08787 -281.787472) (xy 29.043675 -281.758852)
			(xy 29.004367 -281.723821) (xy 28.970867 -281.6832) (xy 28.943961 -281.637941) (xy 28.924278 -281.589106)
			(xy 28.912281 -281.537838) (xy 28.908251 -281.48534) (xy 22.051518 -281.48534) (xy 22.051014 -281.511666)
			(xy 22.042977 -281.563702) (xy 22.027091 -281.613901) (xy 22.003728 -281.661086) (xy 21.973436 -281.704152)
			(xy 21.936924 -281.74209) (xy 21.89505 -281.774009) (xy 21.848794 -281.799162) (xy 21.799241 -281.81696)
			(xy 21.747551 -281.826984) (xy 21.694937 -281.829001) (xy 21.642632 -281.822963) (xy 21.591861 -281.809011)
			(xy 21.543816 -281.787472) (xy 21.499621 -281.758852) (xy 21.460313 -281.723821) (xy 21.426813 -281.6832)
			(xy 21.399907 -281.637941) (xy 21.380224 -281.589106) (xy 21.368227 -281.537838) (xy 21.364197 -281.48534)
			(xy 16.086074 -281.48534) (xy 16.086074 -282.335224) (xy 17.264129 -282.335224) (xy 17.268159 -282.282726)
			(xy 17.280156 -282.231458) (xy 17.299839 -282.182623) (xy 17.326745 -282.137364) (xy 17.360245 -282.096743)
			(xy 17.399553 -282.061712) (xy 17.443748 -282.033092) (xy 17.491793 -282.011553) (xy 17.542564 -281.997601)
			(xy 17.594869 -281.991563) (xy 17.647483 -281.99358) (xy 17.699173 -282.003604) (xy 17.748726 -282.021402)
			(xy 17.794982 -282.046555) (xy 17.836856 -282.078474) (xy 17.873368 -282.116412) (xy 17.90366 -282.159478)
			(xy 17.927023 -282.206663) (xy 17.942909 -282.256862) (xy 17.950946 -282.308898) (xy 17.95145 -282.335224)
			(xy 24.808183 -282.335224) (xy 24.812213 -282.282726) (xy 24.82421 -282.231458) (xy 24.843893 -282.182623)
			(xy 24.870799 -282.137364) (xy 24.904299 -282.096743) (xy 24.943607 -282.061712) (xy 24.987802 -282.033092)
			(xy 25.035847 -282.011553) (xy 25.086618 -281.997601) (xy 25.138923 -281.991563) (xy 25.191537 -281.99358)
			(xy 25.243227 -282.003604) (xy 25.29278 -282.021402) (xy 25.339036 -282.046555) (xy 25.38091 -282.078474)
			(xy 25.417422 -282.116412) (xy 25.447714 -282.159478) (xy 25.471077 -282.206663) (xy 25.486963 -282.256862)
			(xy 25.495 -282.308898) (xy 25.495504 -282.335224) (xy 32.351983 -282.335224) (xy 32.356013 -282.282726)
			(xy 32.36801 -282.231458) (xy 32.387693 -282.182623) (xy 32.414599 -282.137364) (xy 32.448099 -282.096743)
			(xy 32.487407 -282.061712) (xy 32.531602 -282.033092) (xy 32.579647 -282.011553) (xy 32.630418 -281.997601)
			(xy 32.682723 -281.991563) (xy 32.735337 -281.99358) (xy 32.787027 -282.003604) (xy 32.83658 -282.021402)
			(xy 32.882836 -282.046555) (xy 32.92471 -282.078474) (xy 32.961222 -282.116412) (xy 32.991514 -282.159478)
			(xy 33.014877 -282.206663) (xy 33.030763 -282.256862) (xy 33.0388 -282.308898) (xy 33.039304 -282.335224)
			(xy 39.896037 -282.335224) (xy 39.900067 -282.282726) (xy 39.912064 -282.231458) (xy 39.931747 -282.182623)
			(xy 39.958653 -282.137364) (xy 39.992153 -282.096743) (xy 40.031461 -282.061712) (xy 40.075656 -282.033092)
			(xy 40.123701 -282.011553) (xy 40.174472 -281.997601) (xy 40.226777 -281.991563) (xy 40.279391 -281.99358)
			(xy 40.331081 -282.003604) (xy 40.380634 -282.021402) (xy 40.42689 -282.046555) (xy 40.468764 -282.078474)
			(xy 40.505276 -282.116412) (xy 40.535568 -282.159478) (xy 40.558931 -282.206663) (xy 40.574817 -282.256862)
			(xy 40.582854 -282.308898) (xy 40.583358 -282.335224) (xy 47.440091 -282.335224) (xy 47.444121 -282.282726)
			(xy 47.456118 -282.231458) (xy 47.475801 -282.182623) (xy 47.502707 -282.137364) (xy 47.536207 -282.096743)
			(xy 47.575515 -282.061712) (xy 47.61971 -282.033092) (xy 47.667755 -282.011553) (xy 47.718526 -281.997601)
			(xy 47.770831 -281.991563) (xy 47.823445 -281.99358) (xy 47.875135 -282.003604) (xy 47.924688 -282.021402)
			(xy 47.970944 -282.046555) (xy 48.012818 -282.078474) (xy 48.04933 -282.116412) (xy 48.079622 -282.159478)
			(xy 48.102985 -282.206663) (xy 48.118871 -282.256862) (xy 48.126908 -282.308898) (xy 48.127412 -282.335224)
			(xy 48.126908 -282.36155) (xy 48.118871 -282.413586) (xy 48.102985 -282.463785) (xy 48.079622 -282.51097)
			(xy 48.04933 -282.554036) (xy 48.012818 -282.591974) (xy 47.970944 -282.623893) (xy 47.924688 -282.649046)
			(xy 47.875135 -282.666844) (xy 47.823445 -282.676868) (xy 47.770831 -282.678885) (xy 47.718526 -282.672847)
			(xy 47.667755 -282.658895) (xy 47.61971 -282.637356) (xy 47.575515 -282.608736) (xy 47.536207 -282.573705)
			(xy 47.502707 -282.533084) (xy 47.475801 -282.487825) (xy 47.456118 -282.43899) (xy 47.444121 -282.387722)
			(xy 47.440091 -282.335224) (xy 40.583358 -282.335224) (xy 40.582854 -282.36155) (xy 40.574817 -282.413586)
			(xy 40.558931 -282.463785) (xy 40.535568 -282.51097) (xy 40.505276 -282.554036) (xy 40.468764 -282.591974)
			(xy 40.42689 -282.623893) (xy 40.380634 -282.649046) (xy 40.331081 -282.666844) (xy 40.279391 -282.676868)
			(xy 40.226777 -282.678885) (xy 40.174472 -282.672847) (xy 40.123701 -282.658895) (xy 40.075656 -282.637356)
			(xy 40.031461 -282.608736) (xy 39.992153 -282.573705) (xy 39.958653 -282.533084) (xy 39.931747 -282.487825)
			(xy 39.912064 -282.43899) (xy 39.900067 -282.387722) (xy 39.896037 -282.335224) (xy 33.039304 -282.335224)
			(xy 33.0388 -282.36155) (xy 33.030763 -282.413586) (xy 33.014877 -282.463785) (xy 32.991514 -282.51097)
			(xy 32.961222 -282.554036) (xy 32.92471 -282.591974) (xy 32.882836 -282.623893) (xy 32.83658 -282.649046)
			(xy 32.787027 -282.666844) (xy 32.735337 -282.676868) (xy 32.682723 -282.678885) (xy 32.630418 -282.672847)
			(xy 32.579647 -282.658895) (xy 32.531602 -282.637356) (xy 32.487407 -282.608736) (xy 32.448099 -282.573705)
			(xy 32.414599 -282.533084) (xy 32.387693 -282.487825) (xy 32.36801 -282.43899) (xy 32.356013 -282.387722)
			(xy 32.351983 -282.335224) (xy 25.495504 -282.335224) (xy 25.495 -282.36155) (xy 25.486963 -282.413586)
			(xy 25.471077 -282.463785) (xy 25.447714 -282.51097) (xy 25.417422 -282.554036) (xy 25.38091 -282.591974)
			(xy 25.339036 -282.623893) (xy 25.29278 -282.649046) (xy 25.243227 -282.666844) (xy 25.191537 -282.676868)
			(xy 25.138923 -282.678885) (xy 25.086618 -282.672847) (xy 25.035847 -282.658895) (xy 24.987802 -282.637356)
			(xy 24.943607 -282.608736) (xy 24.904299 -282.573705) (xy 24.870799 -282.533084) (xy 24.843893 -282.487825)
			(xy 24.82421 -282.43899) (xy 24.812213 -282.387722) (xy 24.808183 -282.335224) (xy 17.95145 -282.335224)
			(xy 17.950946 -282.36155) (xy 17.942909 -282.413586) (xy 17.927023 -282.463785) (xy 17.90366 -282.51097)
			(xy 17.873368 -282.554036) (xy 17.836856 -282.591974) (xy 17.794982 -282.623893) (xy 17.748726 -282.649046)
			(xy 17.699173 -282.666844) (xy 17.647483 -282.676868) (xy 17.594869 -282.678885) (xy 17.542564 -282.672847)
			(xy 17.491793 -282.658895) (xy 17.443748 -282.637356) (xy 17.399553 -282.608736) (xy 17.360245 -282.573705)
			(xy 17.326745 -282.533084) (xy 17.299839 -282.487825) (xy 17.280156 -282.43899) (xy 17.268159 -282.387722)
			(xy 17.264129 -282.335224) (xy 16.086074 -282.335224) (xy 16.086074 -283.185362) (xy 21.364197 -283.185362)
			(xy 21.368227 -283.132864) (xy 21.380224 -283.081596) (xy 21.399907 -283.032761) (xy 21.426813 -282.987502)
			(xy 21.460313 -282.946881) (xy 21.499621 -282.91185) (xy 21.543816 -282.88323) (xy 21.591861 -282.861691)
			(xy 21.642632 -282.847739) (xy 21.694937 -282.841701) (xy 21.747551 -282.843718) (xy 21.799241 -282.853742)
			(xy 21.848794 -282.87154) (xy 21.89505 -282.896693) (xy 21.936924 -282.928612) (xy 21.973436 -282.96655)
			(xy 22.003728 -283.009616) (xy 22.027091 -283.056801) (xy 22.042977 -283.107) (xy 22.051014 -283.159036)
			(xy 22.051518 -283.185362) (xy 28.908251 -283.185362) (xy 28.912281 -283.132864) (xy 28.924278 -283.081596)
			(xy 28.943961 -283.032761) (xy 28.970867 -282.987502) (xy 29.004367 -282.946881) (xy 29.043675 -282.91185)
			(xy 29.08787 -282.88323) (xy 29.135915 -282.861691) (xy 29.186686 -282.847739) (xy 29.238991 -282.841701)
			(xy 29.291605 -282.843718) (xy 29.343295 -282.853742) (xy 29.392848 -282.87154) (xy 29.439104 -282.896693)
			(xy 29.480978 -282.928612) (xy 29.51749 -282.96655) (xy 29.547782 -283.009616) (xy 29.571145 -283.056801)
			(xy 29.587031 -283.107) (xy 29.595068 -283.159036) (xy 29.595572 -283.185362) (xy 36.452051 -283.185362)
			(xy 36.456081 -283.132864) (xy 36.468078 -283.081596) (xy 36.487761 -283.032761) (xy 36.514667 -282.987502)
			(xy 36.548167 -282.946881) (xy 36.587475 -282.91185) (xy 36.63167 -282.88323) (xy 36.679715 -282.861691)
			(xy 36.730486 -282.847739) (xy 36.782791 -282.841701) (xy 36.835405 -282.843718) (xy 36.887095 -282.853742)
			(xy 36.936648 -282.87154) (xy 36.982904 -282.896693) (xy 37.024778 -282.928612) (xy 37.06129 -282.96655)
			(xy 37.091582 -283.009616) (xy 37.114945 -283.056801) (xy 37.130831 -283.107) (xy 37.138868 -283.159036)
			(xy 37.139372 -283.185362) (xy 43.996105 -283.185362) (xy 44.000135 -283.132864) (xy 44.012132 -283.081596)
			(xy 44.031815 -283.032761) (xy 44.058721 -282.987502) (xy 44.092221 -282.946881) (xy 44.131529 -282.91185)
			(xy 44.175724 -282.88323) (xy 44.223769 -282.861691) (xy 44.27454 -282.847739) (xy 44.326845 -282.841701)
			(xy 44.379459 -282.843718) (xy 44.431149 -282.853742) (xy 44.480702 -282.87154) (xy 44.526958 -282.896693)
			(xy 44.568832 -282.928612) (xy 44.605344 -282.96655) (xy 44.635636 -283.009616) (xy 44.658999 -283.056801)
			(xy 44.674885 -283.107) (xy 44.682922 -283.159036) (xy 44.683426 -283.185362) (xy 51.540159 -283.185362)
			(xy 51.544189 -283.132864) (xy 51.556186 -283.081596) (xy 51.575869 -283.032761) (xy 51.602775 -282.987502)
			(xy 51.636275 -282.946881) (xy 51.675583 -282.91185) (xy 51.719778 -282.88323) (xy 51.767823 -282.861691)
			(xy 51.818594 -282.847739) (xy 51.870899 -282.841701) (xy 51.923513 -282.843718) (xy 51.975203 -282.853742)
			(xy 52.024756 -282.87154) (xy 52.071012 -282.896693) (xy 52.112886 -282.928612) (xy 52.149398 -282.96655)
			(xy 52.17969 -283.009616) (xy 52.203053 -283.056801) (xy 52.218939 -283.107) (xy 52.226976 -283.159036)
			(xy 52.22748 -283.185362) (xy 52.226976 -283.211688) (xy 52.218939 -283.263724) (xy 52.203053 -283.313923)
			(xy 52.17969 -283.361108) (xy 52.149398 -283.404174) (xy 52.112886 -283.442112) (xy 52.071012 -283.474031)
			(xy 52.024756 -283.499184) (xy 51.975203 -283.516982) (xy 51.923513 -283.527006) (xy 51.870899 -283.529023)
			(xy 51.818594 -283.522985) (xy 51.767823 -283.509033) (xy 51.719778 -283.487494) (xy 51.675583 -283.458874)
			(xy 51.636275 -283.423843) (xy 51.602775 -283.383222) (xy 51.575869 -283.337963) (xy 51.556186 -283.289128)
			(xy 51.544189 -283.23786) (xy 51.540159 -283.185362) (xy 44.683426 -283.185362) (xy 44.682922 -283.211688)
			(xy 44.674885 -283.263724) (xy 44.658999 -283.313923) (xy 44.635636 -283.361108) (xy 44.605344 -283.404174)
			(xy 44.568832 -283.442112) (xy 44.526958 -283.474031) (xy 44.480702 -283.499184) (xy 44.431149 -283.516982)
			(xy 44.379459 -283.527006) (xy 44.326845 -283.529023) (xy 44.27454 -283.522985) (xy 44.223769 -283.509033)
			(xy 44.175724 -283.487494) (xy 44.131529 -283.458874) (xy 44.092221 -283.423843) (xy 44.058721 -283.383222)
			(xy 44.031815 -283.337963) (xy 44.012132 -283.289128) (xy 44.000135 -283.23786) (xy 43.996105 -283.185362)
			(xy 37.139372 -283.185362) (xy 37.138868 -283.211688) (xy 37.130831 -283.263724) (xy 37.114945 -283.313923)
			(xy 37.091582 -283.361108) (xy 37.06129 -283.404174) (xy 37.024778 -283.442112) (xy 36.982904 -283.474031)
			(xy 36.936648 -283.499184) (xy 36.887095 -283.516982) (xy 36.835405 -283.527006) (xy 36.782791 -283.529023)
			(xy 36.730486 -283.522985) (xy 36.679715 -283.509033) (xy 36.63167 -283.487494) (xy 36.587475 -283.458874)
			(xy 36.548167 -283.423843) (xy 36.514667 -283.383222) (xy 36.487761 -283.337963) (xy 36.468078 -283.289128)
			(xy 36.456081 -283.23786) (xy 36.452051 -283.185362) (xy 29.595572 -283.185362) (xy 29.595068 -283.211688)
			(xy 29.587031 -283.263724) (xy 29.571145 -283.313923) (xy 29.547782 -283.361108) (xy 29.51749 -283.404174)
			(xy 29.480978 -283.442112) (xy 29.439104 -283.474031) (xy 29.392848 -283.499184) (xy 29.343295 -283.516982)
			(xy 29.291605 -283.527006) (xy 29.238991 -283.529023) (xy 29.186686 -283.522985) (xy 29.135915 -283.509033)
			(xy 29.08787 -283.487494) (xy 29.043675 -283.458874) (xy 29.004367 -283.423843) (xy 28.970867 -283.383222)
			(xy 28.943961 -283.337963) (xy 28.924278 -283.289128) (xy 28.912281 -283.23786) (xy 28.908251 -283.185362)
			(xy 22.051518 -283.185362) (xy 22.051014 -283.211688) (xy 22.042977 -283.263724) (xy 22.027091 -283.313923)
			(xy 22.003728 -283.361108) (xy 21.973436 -283.404174) (xy 21.936924 -283.442112) (xy 21.89505 -283.474031)
			(xy 21.848794 -283.499184) (xy 21.799241 -283.516982) (xy 21.747551 -283.527006) (xy 21.694937 -283.529023)
			(xy 21.642632 -283.522985) (xy 21.591861 -283.509033) (xy 21.543816 -283.487494) (xy 21.499621 -283.458874)
			(xy 21.460313 -283.423843) (xy 21.426813 -283.383222) (xy 21.399907 -283.337963) (xy 21.380224 -283.289128)
			(xy 21.368227 -283.23786) (xy 21.364197 -283.185362) (xy 16.086074 -283.185362) (xy 16.086074 -284.035246)
			(xy 17.264129 -284.035246) (xy 17.268159 -283.982748) (xy 17.280156 -283.93148) (xy 17.299839 -283.882645)
			(xy 17.326745 -283.837386) (xy 17.360245 -283.796765) (xy 17.399553 -283.761734) (xy 17.443748 -283.733114)
			(xy 17.491793 -283.711575) (xy 17.542564 -283.697623) (xy 17.594869 -283.691585) (xy 17.647483 -283.693602)
			(xy 17.699173 -283.703626) (xy 17.748726 -283.721424) (xy 17.794982 -283.746577) (xy 17.836856 -283.778496)
			(xy 17.873368 -283.816434) (xy 17.90366 -283.8595) (xy 17.927023 -283.906685) (xy 17.942909 -283.956884)
			(xy 17.950946 -284.00892) (xy 17.95145 -284.035246) (xy 24.808183 -284.035246) (xy 24.812213 -283.982748)
			(xy 24.82421 -283.93148) (xy 24.843893 -283.882645) (xy 24.870799 -283.837386) (xy 24.904299 -283.796765)
			(xy 24.943607 -283.761734) (xy 24.987802 -283.733114) (xy 25.035847 -283.711575) (xy 25.086618 -283.697623)
			(xy 25.138923 -283.691585) (xy 25.191537 -283.693602) (xy 25.243227 -283.703626) (xy 25.29278 -283.721424)
			(xy 25.339036 -283.746577) (xy 25.38091 -283.778496) (xy 25.417422 -283.816434) (xy 25.447714 -283.8595)
			(xy 25.471077 -283.906685) (xy 25.486963 -283.956884) (xy 25.495 -284.00892) (xy 25.495504 -284.035246)
			(xy 32.351983 -284.035246) (xy 32.356013 -283.982748) (xy 32.36801 -283.93148) (xy 32.387693 -283.882645)
			(xy 32.414599 -283.837386) (xy 32.448099 -283.796765) (xy 32.487407 -283.761734) (xy 32.531602 -283.733114)
			(xy 32.579647 -283.711575) (xy 32.630418 -283.697623) (xy 32.682723 -283.691585) (xy 32.735337 -283.693602)
			(xy 32.787027 -283.703626) (xy 32.83658 -283.721424) (xy 32.882836 -283.746577) (xy 32.92471 -283.778496)
			(xy 32.961222 -283.816434) (xy 32.991514 -283.8595) (xy 33.014877 -283.906685) (xy 33.030763 -283.956884)
			(xy 33.0388 -284.00892) (xy 33.039304 -284.035246) (xy 39.896037 -284.035246) (xy 39.900067 -283.982748)
			(xy 39.912064 -283.93148) (xy 39.931747 -283.882645) (xy 39.958653 -283.837386) (xy 39.992153 -283.796765)
			(xy 40.031461 -283.761734) (xy 40.075656 -283.733114) (xy 40.123701 -283.711575) (xy 40.174472 -283.697623)
			(xy 40.226777 -283.691585) (xy 40.279391 -283.693602) (xy 40.331081 -283.703626) (xy 40.380634 -283.721424)
			(xy 40.42689 -283.746577) (xy 40.468764 -283.778496) (xy 40.505276 -283.816434) (xy 40.535568 -283.8595)
			(xy 40.558931 -283.906685) (xy 40.574817 -283.956884) (xy 40.582854 -284.00892) (xy 40.583358 -284.035246)
			(xy 47.440091 -284.035246) (xy 47.444121 -283.982748) (xy 47.456118 -283.93148) (xy 47.475801 -283.882645)
			(xy 47.502707 -283.837386) (xy 47.536207 -283.796765) (xy 47.575515 -283.761734) (xy 47.61971 -283.733114)
			(xy 47.667755 -283.711575) (xy 47.718526 -283.697623) (xy 47.770831 -283.691585) (xy 47.823445 -283.693602)
			(xy 47.875135 -283.703626) (xy 47.924688 -283.721424) (xy 47.970944 -283.746577) (xy 48.012818 -283.778496)
			(xy 48.04933 -283.816434) (xy 48.079622 -283.8595) (xy 48.102985 -283.906685) (xy 48.118871 -283.956884)
			(xy 48.126908 -284.00892) (xy 48.127412 -284.035246) (xy 48.126908 -284.061572) (xy 48.118871 -284.113608)
			(xy 48.102985 -284.163807) (xy 48.079622 -284.210992) (xy 48.04933 -284.254058) (xy 48.012818 -284.291996)
			(xy 47.970944 -284.323915) (xy 47.924688 -284.349068) (xy 47.875135 -284.366866) (xy 47.823445 -284.37689)
			(xy 47.770831 -284.378907) (xy 47.718526 -284.372869) (xy 47.667755 -284.358917) (xy 47.61971 -284.337378)
			(xy 47.575515 -284.308758) (xy 47.536207 -284.273727) (xy 47.502707 -284.233106) (xy 47.475801 -284.187847)
			(xy 47.456118 -284.139012) (xy 47.444121 -284.087744) (xy 47.440091 -284.035246) (xy 40.583358 -284.035246)
			(xy 40.582854 -284.061572) (xy 40.574817 -284.113608) (xy 40.558931 -284.163807) (xy 40.535568 -284.210992)
			(xy 40.505276 -284.254058) (xy 40.468764 -284.291996) (xy 40.42689 -284.323915) (xy 40.380634 -284.349068)
			(xy 40.331081 -284.366866) (xy 40.279391 -284.37689) (xy 40.226777 -284.378907) (xy 40.174472 -284.372869)
			(xy 40.123701 -284.358917) (xy 40.075656 -284.337378) (xy 40.031461 -284.308758) (xy 39.992153 -284.273727)
			(xy 39.958653 -284.233106) (xy 39.931747 -284.187847) (xy 39.912064 -284.139012) (xy 39.900067 -284.087744)
			(xy 39.896037 -284.035246) (xy 33.039304 -284.035246) (xy 33.0388 -284.061572) (xy 33.030763 -284.113608)
			(xy 33.014877 -284.163807) (xy 32.991514 -284.210992) (xy 32.961222 -284.254058) (xy 32.92471 -284.291996)
			(xy 32.882836 -284.323915) (xy 32.83658 -284.349068) (xy 32.787027 -284.366866) (xy 32.735337 -284.37689)
			(xy 32.682723 -284.378907) (xy 32.630418 -284.372869) (xy 32.579647 -284.358917) (xy 32.531602 -284.337378)
			(xy 32.487407 -284.308758) (xy 32.448099 -284.273727) (xy 32.414599 -284.233106) (xy 32.387693 -284.187847)
			(xy 32.36801 -284.139012) (xy 32.356013 -284.087744) (xy 32.351983 -284.035246) (xy 25.495504 -284.035246)
			(xy 25.495 -284.061572) (xy 25.486963 -284.113608) (xy 25.471077 -284.163807) (xy 25.447714 -284.210992)
			(xy 25.417422 -284.254058) (xy 25.38091 -284.291996) (xy 25.339036 -284.323915) (xy 25.29278 -284.349068)
			(xy 25.243227 -284.366866) (xy 25.191537 -284.37689) (xy 25.138923 -284.378907) (xy 25.086618 -284.372869)
			(xy 25.035847 -284.358917) (xy 24.987802 -284.337378) (xy 24.943607 -284.308758) (xy 24.904299 -284.273727)
			(xy 24.870799 -284.233106) (xy 24.843893 -284.187847) (xy 24.82421 -284.139012) (xy 24.812213 -284.087744)
			(xy 24.808183 -284.035246) (xy 17.95145 -284.035246) (xy 17.950946 -284.061572) (xy 17.942909 -284.113608)
			(xy 17.927023 -284.163807) (xy 17.90366 -284.210992) (xy 17.873368 -284.254058) (xy 17.836856 -284.291996)
			(xy 17.794982 -284.323915) (xy 17.748726 -284.349068) (xy 17.699173 -284.366866) (xy 17.647483 -284.37689)
			(xy 17.594869 -284.378907) (xy 17.542564 -284.372869) (xy 17.491793 -284.358917) (xy 17.443748 -284.337378)
			(xy 17.399553 -284.308758) (xy 17.360245 -284.273727) (xy 17.326745 -284.233106) (xy 17.299839 -284.187847)
			(xy 17.280156 -284.139012) (xy 17.268159 -284.087744) (xy 17.264129 -284.035246) (xy 16.086074 -284.035246)
			(xy 16.086074 -284.885384) (xy 21.364197 -284.885384) (xy 21.368227 -284.832886) (xy 21.380224 -284.781618)
			(xy 21.399907 -284.732783) (xy 21.426813 -284.687524) (xy 21.460313 -284.646903) (xy 21.499621 -284.611872)
			(xy 21.543816 -284.583252) (xy 21.591861 -284.561713) (xy 21.642632 -284.547761) (xy 21.694937 -284.541723)
			(xy 21.747551 -284.54374) (xy 21.799241 -284.553764) (xy 21.848794 -284.571562) (xy 21.89505 -284.596715)
			(xy 21.936924 -284.628634) (xy 21.973436 -284.666572) (xy 22.003728 -284.709638) (xy 22.027091 -284.756823)
			(xy 22.042977 -284.807022) (xy 22.051014 -284.859058) (xy 22.051518 -284.885384) (xy 28.908251 -284.885384)
			(xy 28.912281 -284.832886) (xy 28.924278 -284.781618) (xy 28.943961 -284.732783) (xy 28.970867 -284.687524)
			(xy 29.004367 -284.646903) (xy 29.043675 -284.611872) (xy 29.08787 -284.583252) (xy 29.135915 -284.561713)
			(xy 29.186686 -284.547761) (xy 29.238991 -284.541723) (xy 29.291605 -284.54374) (xy 29.343295 -284.553764)
			(xy 29.392848 -284.571562) (xy 29.439104 -284.596715) (xy 29.480978 -284.628634) (xy 29.51749 -284.666572)
			(xy 29.547782 -284.709638) (xy 29.571145 -284.756823) (xy 29.587031 -284.807022) (xy 29.595068 -284.859058)
			(xy 29.595572 -284.885384) (xy 36.452051 -284.885384) (xy 36.456081 -284.832886) (xy 36.468078 -284.781618)
			(xy 36.487761 -284.732783) (xy 36.514667 -284.687524) (xy 36.548167 -284.646903) (xy 36.587475 -284.611872)
			(xy 36.63167 -284.583252) (xy 36.679715 -284.561713) (xy 36.730486 -284.547761) (xy 36.782791 -284.541723)
			(xy 36.835405 -284.54374) (xy 36.887095 -284.553764) (xy 36.936648 -284.571562) (xy 36.982904 -284.596715)
			(xy 37.024778 -284.628634) (xy 37.06129 -284.666572) (xy 37.091582 -284.709638) (xy 37.114945 -284.756823)
			(xy 37.130831 -284.807022) (xy 37.138868 -284.859058) (xy 37.139372 -284.885384) (xy 43.996105 -284.885384)
			(xy 44.000135 -284.832886) (xy 44.012132 -284.781618) (xy 44.031815 -284.732783) (xy 44.058721 -284.687524)
			(xy 44.092221 -284.646903) (xy 44.131529 -284.611872) (xy 44.175724 -284.583252) (xy 44.223769 -284.561713)
			(xy 44.27454 -284.547761) (xy 44.326845 -284.541723) (xy 44.379459 -284.54374) (xy 44.431149 -284.553764)
			(xy 44.480702 -284.571562) (xy 44.526958 -284.596715) (xy 44.568832 -284.628634) (xy 44.605344 -284.666572)
			(xy 44.635636 -284.709638) (xy 44.658999 -284.756823) (xy 44.674885 -284.807022) (xy 44.682922 -284.859058)
			(xy 44.683426 -284.885384) (xy 51.540159 -284.885384) (xy 51.544189 -284.832886) (xy 51.556186 -284.781618)
			(xy 51.575869 -284.732783) (xy 51.602775 -284.687524) (xy 51.636275 -284.646903) (xy 51.675583 -284.611872)
			(xy 51.719778 -284.583252) (xy 51.767823 -284.561713) (xy 51.818594 -284.547761) (xy 51.870899 -284.541723)
			(xy 51.923513 -284.54374) (xy 51.975203 -284.553764) (xy 52.024756 -284.571562) (xy 52.071012 -284.596715)
			(xy 52.112886 -284.628634) (xy 52.149398 -284.666572) (xy 52.17969 -284.709638) (xy 52.203053 -284.756823)
			(xy 52.218939 -284.807022) (xy 52.226976 -284.859058) (xy 52.22748 -284.885384) (xy 52.226976 -284.91171)
			(xy 52.218939 -284.963746) (xy 52.203053 -285.013945) (xy 52.17969 -285.06113) (xy 52.149398 -285.104196)
			(xy 52.112886 -285.142134) (xy 52.071012 -285.174053) (xy 52.024756 -285.199206) (xy 51.975203 -285.217004)
			(xy 51.923513 -285.227028) (xy 51.870899 -285.229045) (xy 51.818594 -285.223007) (xy 51.767823 -285.209055)
			(xy 51.719778 -285.187516) (xy 51.675583 -285.158896) (xy 51.636275 -285.123865) (xy 51.602775 -285.083244)
			(xy 51.575869 -285.037985) (xy 51.556186 -284.98915) (xy 51.544189 -284.937882) (xy 51.540159 -284.885384)
			(xy 44.683426 -284.885384) (xy 44.682922 -284.91171) (xy 44.674885 -284.963746) (xy 44.658999 -285.013945)
			(xy 44.635636 -285.06113) (xy 44.605344 -285.104196) (xy 44.568832 -285.142134) (xy 44.526958 -285.174053)
			(xy 44.480702 -285.199206) (xy 44.431149 -285.217004) (xy 44.379459 -285.227028) (xy 44.326845 -285.229045)
			(xy 44.27454 -285.223007) (xy 44.223769 -285.209055) (xy 44.175724 -285.187516) (xy 44.131529 -285.158896)
			(xy 44.092221 -285.123865) (xy 44.058721 -285.083244) (xy 44.031815 -285.037985) (xy 44.012132 -284.98915)
			(xy 44.000135 -284.937882) (xy 43.996105 -284.885384) (xy 37.139372 -284.885384) (xy 37.138868 -284.91171)
			(xy 37.130831 -284.963746) (xy 37.114945 -285.013945) (xy 37.091582 -285.06113) (xy 37.06129 -285.104196)
			(xy 37.024778 -285.142134) (xy 36.982904 -285.174053) (xy 36.936648 -285.199206) (xy 36.887095 -285.217004)
			(xy 36.835405 -285.227028) (xy 36.782791 -285.229045) (xy 36.730486 -285.223007) (xy 36.679715 -285.209055)
			(xy 36.63167 -285.187516) (xy 36.587475 -285.158896) (xy 36.548167 -285.123865) (xy 36.514667 -285.083244)
			(xy 36.487761 -285.037985) (xy 36.468078 -284.98915) (xy 36.456081 -284.937882) (xy 36.452051 -284.885384)
			(xy 29.595572 -284.885384) (xy 29.595068 -284.91171) (xy 29.587031 -284.963746) (xy 29.571145 -285.013945)
			(xy 29.547782 -285.06113) (xy 29.51749 -285.104196) (xy 29.480978 -285.142134) (xy 29.439104 -285.174053)
			(xy 29.392848 -285.199206) (xy 29.343295 -285.217004) (xy 29.291605 -285.227028) (xy 29.238991 -285.229045)
			(xy 29.186686 -285.223007) (xy 29.135915 -285.209055) (xy 29.08787 -285.187516) (xy 29.043675 -285.158896)
			(xy 29.004367 -285.123865) (xy 28.970867 -285.083244) (xy 28.943961 -285.037985) (xy 28.924278 -284.98915)
			(xy 28.912281 -284.937882) (xy 28.908251 -284.885384) (xy 22.051518 -284.885384) (xy 22.051014 -284.91171)
			(xy 22.042977 -284.963746) (xy 22.027091 -285.013945) (xy 22.003728 -285.06113) (xy 21.973436 -285.104196)
			(xy 21.936924 -285.142134) (xy 21.89505 -285.174053) (xy 21.848794 -285.199206) (xy 21.799241 -285.217004)
			(xy 21.747551 -285.227028) (xy 21.694937 -285.229045) (xy 21.642632 -285.223007) (xy 21.591861 -285.209055)
			(xy 21.543816 -285.187516) (xy 21.499621 -285.158896) (xy 21.460313 -285.123865) (xy 21.426813 -285.083244)
			(xy 21.399907 -285.037985) (xy 21.380224 -284.98915) (xy 21.368227 -284.937882) (xy 21.364197 -284.885384)
			(xy 16.086074 -284.885384) (xy 16.086074 -285.735268) (xy 17.264129 -285.735268) (xy 17.268159 -285.68277)
			(xy 17.280156 -285.631502) (xy 17.299839 -285.582667) (xy 17.326745 -285.537408) (xy 17.360245 -285.496787)
			(xy 17.399553 -285.461756) (xy 17.443748 -285.433136) (xy 17.491793 -285.411597) (xy 17.542564 -285.397645)
			(xy 17.594869 -285.391607) (xy 17.647483 -285.393624) (xy 17.699173 -285.403648) (xy 17.748726 -285.421446)
			(xy 17.794982 -285.446599) (xy 17.836856 -285.478518) (xy 17.873368 -285.516456) (xy 17.90366 -285.559522)
			(xy 17.927023 -285.606707) (xy 17.942909 -285.656906) (xy 17.950946 -285.708942) (xy 17.95145 -285.735268)
			(xy 21.364197 -285.735268) (xy 21.368227 -285.68277) (xy 21.380224 -285.631502) (xy 21.399907 -285.582667)
			(xy 21.426813 -285.537408) (xy 21.460313 -285.496787) (xy 21.499621 -285.461756) (xy 21.543816 -285.433136)
			(xy 21.591861 -285.411597) (xy 21.642632 -285.397645) (xy 21.694937 -285.391607) (xy 21.747551 -285.393624)
			(xy 21.799241 -285.403648) (xy 21.848794 -285.421446) (xy 21.89505 -285.446599) (xy 21.936924 -285.478518)
			(xy 21.973436 -285.516456) (xy 22.003728 -285.559522) (xy 22.027091 -285.606707) (xy 22.042977 -285.656906)
			(xy 22.051014 -285.708942) (xy 22.051518 -285.735268) (xy 24.808183 -285.735268) (xy 24.812213 -285.68277)
			(xy 24.82421 -285.631502) (xy 24.843893 -285.582667) (xy 24.870799 -285.537408) (xy 24.904299 -285.496787)
			(xy 24.943607 -285.461756) (xy 24.987802 -285.433136) (xy 25.035847 -285.411597) (xy 25.086618 -285.397645)
			(xy 25.138923 -285.391607) (xy 25.191537 -285.393624) (xy 25.243227 -285.403648) (xy 25.29278 -285.421446)
			(xy 25.339036 -285.446599) (xy 25.38091 -285.478518) (xy 25.417422 -285.516456) (xy 25.447714 -285.559522)
			(xy 25.471077 -285.606707) (xy 25.486963 -285.656906) (xy 25.495 -285.708942) (xy 25.495504 -285.735268)
			(xy 28.908251 -285.735268) (xy 28.912281 -285.68277) (xy 28.924278 -285.631502) (xy 28.943961 -285.582667)
			(xy 28.970867 -285.537408) (xy 29.004367 -285.496787) (xy 29.043675 -285.461756) (xy 29.08787 -285.433136)
			(xy 29.135915 -285.411597) (xy 29.186686 -285.397645) (xy 29.238991 -285.391607) (xy 29.291605 -285.393624)
			(xy 29.343295 -285.403648) (xy 29.392848 -285.421446) (xy 29.439104 -285.446599) (xy 29.480978 -285.478518)
			(xy 29.51749 -285.516456) (xy 29.547782 -285.559522) (xy 29.571145 -285.606707) (xy 29.587031 -285.656906)
			(xy 29.595068 -285.708942) (xy 29.595572 -285.735268) (xy 32.351983 -285.735268) (xy 32.356013 -285.68277)
			(xy 32.36801 -285.631502) (xy 32.387693 -285.582667) (xy 32.414599 -285.537408) (xy 32.448099 -285.496787)
			(xy 32.487407 -285.461756) (xy 32.531602 -285.433136) (xy 32.579647 -285.411597) (xy 32.630418 -285.397645)
			(xy 32.682723 -285.391607) (xy 32.735337 -285.393624) (xy 32.787027 -285.403648) (xy 32.83658 -285.421446)
			(xy 32.882836 -285.446599) (xy 32.92471 -285.478518) (xy 32.961222 -285.516456) (xy 32.991514 -285.559522)
			(xy 33.014877 -285.606707) (xy 33.030763 -285.656906) (xy 33.0388 -285.708942) (xy 33.039304 -285.735268)
			(xy 36.452051 -285.735268) (xy 36.456081 -285.68277) (xy 36.468078 -285.631502) (xy 36.487761 -285.582667)
			(xy 36.514667 -285.537408) (xy 36.548167 -285.496787) (xy 36.587475 -285.461756) (xy 36.63167 -285.433136)
			(xy 36.679715 -285.411597) (xy 36.730486 -285.397645) (xy 36.782791 -285.391607) (xy 36.835405 -285.393624)
			(xy 36.887095 -285.403648) (xy 36.936648 -285.421446) (xy 36.982904 -285.446599) (xy 37.024778 -285.478518)
			(xy 37.06129 -285.516456) (xy 37.091582 -285.559522) (xy 37.114945 -285.606707) (xy 37.130831 -285.656906)
			(xy 37.138868 -285.708942) (xy 37.139372 -285.735268) (xy 39.896037 -285.735268) (xy 39.900067 -285.68277)
			(xy 39.912064 -285.631502) (xy 39.931747 -285.582667) (xy 39.958653 -285.537408) (xy 39.992153 -285.496787)
			(xy 40.031461 -285.461756) (xy 40.075656 -285.433136) (xy 40.123701 -285.411597) (xy 40.174472 -285.397645)
			(xy 40.226777 -285.391607) (xy 40.279391 -285.393624) (xy 40.331081 -285.403648) (xy 40.380634 -285.421446)
			(xy 40.42689 -285.446599) (xy 40.468764 -285.478518) (xy 40.505276 -285.516456) (xy 40.535568 -285.559522)
			(xy 40.558931 -285.606707) (xy 40.574817 -285.656906) (xy 40.582854 -285.708942) (xy 40.583358 -285.735268)
			(xy 43.996105 -285.735268) (xy 44.000135 -285.68277) (xy 44.012132 -285.631502) (xy 44.031815 -285.582667)
			(xy 44.058721 -285.537408) (xy 44.092221 -285.496787) (xy 44.131529 -285.461756) (xy 44.175724 -285.433136)
			(xy 44.223769 -285.411597) (xy 44.27454 -285.397645) (xy 44.326845 -285.391607) (xy 44.379459 -285.393624)
			(xy 44.431149 -285.403648) (xy 44.480702 -285.421446) (xy 44.526958 -285.446599) (xy 44.568832 -285.478518)
			(xy 44.605344 -285.516456) (xy 44.635636 -285.559522) (xy 44.658999 -285.606707) (xy 44.674885 -285.656906)
			(xy 44.682922 -285.708942) (xy 44.683426 -285.735268) (xy 47.440091 -285.735268) (xy 47.444121 -285.68277)
			(xy 47.456118 -285.631502) (xy 47.475801 -285.582667) (xy 47.502707 -285.537408) (xy 47.536207 -285.496787)
			(xy 47.575515 -285.461756) (xy 47.61971 -285.433136) (xy 47.667755 -285.411597) (xy 47.718526 -285.397645)
			(xy 47.770831 -285.391607) (xy 47.823445 -285.393624) (xy 47.875135 -285.403648) (xy 47.924688 -285.421446)
			(xy 47.970944 -285.446599) (xy 48.012818 -285.478518) (xy 48.04933 -285.516456) (xy 48.079622 -285.559522)
			(xy 48.102985 -285.606707) (xy 48.118871 -285.656906) (xy 48.126908 -285.708942) (xy 48.127412 -285.735268)
			(xy 51.540159 -285.735268) (xy 51.544189 -285.68277) (xy 51.556186 -285.631502) (xy 51.575869 -285.582667)
			(xy 51.602775 -285.537408) (xy 51.636275 -285.496787) (xy 51.675583 -285.461756) (xy 51.719778 -285.433136)
			(xy 51.767823 -285.411597) (xy 51.818594 -285.397645) (xy 51.870899 -285.391607) (xy 51.923513 -285.393624)
			(xy 51.975203 -285.403648) (xy 52.024756 -285.421446) (xy 52.071012 -285.446599) (xy 52.112886 -285.478518)
			(xy 52.149398 -285.516456) (xy 52.17969 -285.559522) (xy 52.203053 -285.606707) (xy 52.218939 -285.656906)
			(xy 52.226976 -285.708942) (xy 52.22748 -285.735268) (xy 52.226976 -285.761594) (xy 52.218939 -285.81363)
			(xy 52.203053 -285.863829) (xy 52.17969 -285.911014) (xy 52.149398 -285.95408) (xy 52.112886 -285.992018)
			(xy 52.071012 -286.023937) (xy 52.024756 -286.04909) (xy 51.975203 -286.066888) (xy 51.923513 -286.076912)
			(xy 51.870899 -286.078929) (xy 51.818594 -286.072891) (xy 51.767823 -286.058939) (xy 51.719778 -286.0374)
			(xy 51.675583 -286.00878) (xy 51.636275 -285.973749) (xy 51.602775 -285.933128) (xy 51.575869 -285.887869)
			(xy 51.556186 -285.839034) (xy 51.544189 -285.787766) (xy 51.540159 -285.735268) (xy 48.127412 -285.735268)
			(xy 48.126908 -285.761594) (xy 48.118871 -285.81363) (xy 48.102985 -285.863829) (xy 48.079622 -285.911014)
			(xy 48.04933 -285.95408) (xy 48.012818 -285.992018) (xy 47.970944 -286.023937) (xy 47.924688 -286.04909)
			(xy 47.875135 -286.066888) (xy 47.823445 -286.076912) (xy 47.770831 -286.078929) (xy 47.718526 -286.072891)
			(xy 47.667755 -286.058939) (xy 47.61971 -286.0374) (xy 47.575515 -286.00878) (xy 47.536207 -285.973749)
			(xy 47.502707 -285.933128) (xy 47.475801 -285.887869) (xy 47.456118 -285.839034) (xy 47.444121 -285.787766)
			(xy 47.440091 -285.735268) (xy 44.683426 -285.735268) (xy 44.682922 -285.761594) (xy 44.674885 -285.81363)
			(xy 44.658999 -285.863829) (xy 44.635636 -285.911014) (xy 44.605344 -285.95408) (xy 44.568832 -285.992018)
			(xy 44.526958 -286.023937) (xy 44.480702 -286.04909) (xy 44.431149 -286.066888) (xy 44.379459 -286.076912)
			(xy 44.326845 -286.078929) (xy 44.27454 -286.072891) (xy 44.223769 -286.058939) (xy 44.175724 -286.0374)
			(xy 44.131529 -286.00878) (xy 44.092221 -285.973749) (xy 44.058721 -285.933128) (xy 44.031815 -285.887869)
			(xy 44.012132 -285.839034) (xy 44.000135 -285.787766) (xy 43.996105 -285.735268) (xy 40.583358 -285.735268)
			(xy 40.582854 -285.761594) (xy 40.574817 -285.81363) (xy 40.558931 -285.863829) (xy 40.535568 -285.911014)
			(xy 40.505276 -285.95408) (xy 40.468764 -285.992018) (xy 40.42689 -286.023937) (xy 40.380634 -286.04909)
			(xy 40.331081 -286.066888) (xy 40.279391 -286.076912) (xy 40.226777 -286.078929) (xy 40.174472 -286.072891)
			(xy 40.123701 -286.058939) (xy 40.075656 -286.0374) (xy 40.031461 -286.00878) (xy 39.992153 -285.973749)
			(xy 39.958653 -285.933128) (xy 39.931747 -285.887869) (xy 39.912064 -285.839034) (xy 39.900067 -285.787766)
			(xy 39.896037 -285.735268) (xy 37.139372 -285.735268) (xy 37.138868 -285.761594) (xy 37.130831 -285.81363)
			(xy 37.114945 -285.863829) (xy 37.091582 -285.911014) (xy 37.06129 -285.95408) (xy 37.024778 -285.992018)
			(xy 36.982904 -286.023937) (xy 36.936648 -286.04909) (xy 36.887095 -286.066888) (xy 36.835405 -286.076912)
			(xy 36.782791 -286.078929) (xy 36.730486 -286.072891) (xy 36.679715 -286.058939) (xy 36.63167 -286.0374)
			(xy 36.587475 -286.00878) (xy 36.548167 -285.973749) (xy 36.514667 -285.933128) (xy 36.487761 -285.887869)
			(xy 36.468078 -285.839034) (xy 36.456081 -285.787766) (xy 36.452051 -285.735268) (xy 33.039304 -285.735268)
			(xy 33.0388 -285.761594) (xy 33.030763 -285.81363) (xy 33.014877 -285.863829) (xy 32.991514 -285.911014)
			(xy 32.961222 -285.95408) (xy 32.92471 -285.992018) (xy 32.882836 -286.023937) (xy 32.83658 -286.04909)
			(xy 32.787027 -286.066888) (xy 32.735337 -286.076912) (xy 32.682723 -286.078929) (xy 32.630418 -286.072891)
			(xy 32.579647 -286.058939) (xy 32.531602 -286.0374) (xy 32.487407 -286.00878) (xy 32.448099 -285.973749)
			(xy 32.414599 -285.933128) (xy 32.387693 -285.887869) (xy 32.36801 -285.839034) (xy 32.356013 -285.787766)
			(xy 32.351983 -285.735268) (xy 29.595572 -285.735268) (xy 29.595068 -285.761594) (xy 29.587031 -285.81363)
			(xy 29.571145 -285.863829) (xy 29.547782 -285.911014) (xy 29.51749 -285.95408) (xy 29.480978 -285.992018)
			(xy 29.439104 -286.023937) (xy 29.392848 -286.04909) (xy 29.343295 -286.066888) (xy 29.291605 -286.076912)
			(xy 29.238991 -286.078929) (xy 29.186686 -286.072891) (xy 29.135915 -286.058939) (xy 29.08787 -286.0374)
			(xy 29.043675 -286.00878) (xy 29.004367 -285.973749) (xy 28.970867 -285.933128) (xy 28.943961 -285.887869)
			(xy 28.924278 -285.839034) (xy 28.912281 -285.787766) (xy 28.908251 -285.735268) (xy 25.495504 -285.735268)
			(xy 25.495 -285.761594) (xy 25.486963 -285.81363) (xy 25.471077 -285.863829) (xy 25.447714 -285.911014)
			(xy 25.417422 -285.95408) (xy 25.38091 -285.992018) (xy 25.339036 -286.023937) (xy 25.29278 -286.04909)
			(xy 25.243227 -286.066888) (xy 25.191537 -286.076912) (xy 25.138923 -286.078929) (xy 25.086618 -286.072891)
			(xy 25.035847 -286.058939) (xy 24.987802 -286.0374) (xy 24.943607 -286.00878) (xy 24.904299 -285.973749)
			(xy 24.870799 -285.933128) (xy 24.843893 -285.887869) (xy 24.82421 -285.839034) (xy 24.812213 -285.787766)
			(xy 24.808183 -285.735268) (xy 22.051518 -285.735268) (xy 22.051014 -285.761594) (xy 22.042977 -285.81363)
			(xy 22.027091 -285.863829) (xy 22.003728 -285.911014) (xy 21.973436 -285.95408) (xy 21.936924 -285.992018)
			(xy 21.89505 -286.023937) (xy 21.848794 -286.04909) (xy 21.799241 -286.066888) (xy 21.747551 -286.076912)
			(xy 21.694937 -286.078929) (xy 21.642632 -286.072891) (xy 21.591861 -286.058939) (xy 21.543816 -286.0374)
			(xy 21.499621 -286.00878) (xy 21.460313 -285.973749) (xy 21.426813 -285.933128) (xy 21.399907 -285.887869)
			(xy 21.380224 -285.839034) (xy 21.368227 -285.787766) (xy 21.364197 -285.735268) (xy 17.95145 -285.735268)
			(xy 17.950946 -285.761594) (xy 17.942909 -285.81363) (xy 17.927023 -285.863829) (xy 17.90366 -285.911014)
			(xy 17.873368 -285.95408) (xy 17.836856 -285.992018) (xy 17.794982 -286.023937) (xy 17.748726 -286.04909)
			(xy 17.699173 -286.066888) (xy 17.647483 -286.076912) (xy 17.594869 -286.078929) (xy 17.542564 -286.072891)
			(xy 17.491793 -286.058939) (xy 17.443748 -286.0374) (xy 17.399553 -286.00878) (xy 17.360245 -285.973749)
			(xy 17.326745 -285.933128) (xy 17.299839 -285.887869) (xy 17.280156 -285.839034) (xy 17.268159 -285.787766)
			(xy 17.264129 -285.735268) (xy 16.086074 -285.735268) (xy 16.086074 -286.585406) (xy 17.264129 -286.585406)
			(xy 17.268159 -286.532908) (xy 17.280156 -286.48164) (xy 17.299839 -286.432805) (xy 17.326745 -286.387546)
			(xy 17.360245 -286.346925) (xy 17.399553 -286.311894) (xy 17.443748 -286.283274) (xy 17.491793 -286.261735)
			(xy 17.542564 -286.247783) (xy 17.594869 -286.241745) (xy 17.647483 -286.243762) (xy 17.699173 -286.253786)
			(xy 17.748726 -286.271584) (xy 17.794982 -286.296737) (xy 17.836856 -286.328656) (xy 17.873368 -286.366594)
			(xy 17.90366 -286.40966) (xy 17.927023 -286.456845) (xy 17.942909 -286.507044) (xy 17.950946 -286.55908)
			(xy 17.95145 -286.585406) (xy 24.808183 -286.585406) (xy 24.812213 -286.532908) (xy 24.82421 -286.48164)
			(xy 24.843893 -286.432805) (xy 24.870799 -286.387546) (xy 24.904299 -286.346925) (xy 24.943607 -286.311894)
			(xy 24.987802 -286.283274) (xy 25.035847 -286.261735) (xy 25.086618 -286.247783) (xy 25.138923 -286.241745)
			(xy 25.191537 -286.243762) (xy 25.243227 -286.253786) (xy 25.29278 -286.271584) (xy 25.339036 -286.296737)
			(xy 25.38091 -286.328656) (xy 25.417422 -286.366594) (xy 25.447714 -286.40966) (xy 25.471077 -286.456845)
			(xy 25.486963 -286.507044) (xy 25.495 -286.55908) (xy 25.495504 -286.585406) (xy 32.351983 -286.585406)
			(xy 32.356013 -286.532908) (xy 32.36801 -286.48164) (xy 32.387693 -286.432805) (xy 32.414599 -286.387546)
			(xy 32.448099 -286.346925) (xy 32.487407 -286.311894) (xy 32.531602 -286.283274) (xy 32.579647 -286.261735)
			(xy 32.630418 -286.247783) (xy 32.682723 -286.241745) (xy 32.735337 -286.243762) (xy 32.787027 -286.253786)
			(xy 32.83658 -286.271584) (xy 32.882836 -286.296737) (xy 32.92471 -286.328656) (xy 32.961222 -286.366594)
			(xy 32.991514 -286.40966) (xy 33.014877 -286.456845) (xy 33.030763 -286.507044) (xy 33.0388 -286.55908)
			(xy 33.039304 -286.585406) (xy 39.896037 -286.585406) (xy 39.900067 -286.532908) (xy 39.912064 -286.48164)
			(xy 39.931747 -286.432805) (xy 39.958653 -286.387546) (xy 39.992153 -286.346925) (xy 40.031461 -286.311894)
			(xy 40.075656 -286.283274) (xy 40.123701 -286.261735) (xy 40.174472 -286.247783) (xy 40.226777 -286.241745)
			(xy 40.279391 -286.243762) (xy 40.331081 -286.253786) (xy 40.380634 -286.271584) (xy 40.42689 -286.296737)
			(xy 40.468764 -286.328656) (xy 40.505276 -286.366594) (xy 40.535568 -286.40966) (xy 40.558931 -286.456845)
			(xy 40.574817 -286.507044) (xy 40.582854 -286.55908) (xy 40.583358 -286.585406) (xy 47.440091 -286.585406)
			(xy 47.444121 -286.532908) (xy 47.456118 -286.48164) (xy 47.475801 -286.432805) (xy 47.502707 -286.387546)
			(xy 47.536207 -286.346925) (xy 47.575515 -286.311894) (xy 47.61971 -286.283274) (xy 47.667755 -286.261735)
			(xy 47.718526 -286.247783) (xy 47.770831 -286.241745) (xy 47.823445 -286.243762) (xy 47.875135 -286.253786)
			(xy 47.924688 -286.271584) (xy 47.970944 -286.296737) (xy 48.012818 -286.328656) (xy 48.04933 -286.366594)
			(xy 48.079622 -286.40966) (xy 48.102985 -286.456845) (xy 48.118871 -286.507044) (xy 48.126908 -286.55908)
			(xy 48.127412 -286.585406) (xy 48.126908 -286.611732) (xy 48.118871 -286.663768) (xy 48.102985 -286.713967)
			(xy 48.079622 -286.761152) (xy 48.04933 -286.804218) (xy 48.012818 -286.842156) (xy 47.970944 -286.874075)
			(xy 47.924688 -286.899228) (xy 47.875135 -286.917026) (xy 47.823445 -286.92705) (xy 47.770831 -286.929067)
			(xy 47.718526 -286.923029) (xy 47.667755 -286.909077) (xy 47.61971 -286.887538) (xy 47.575515 -286.858918)
			(xy 47.536207 -286.823887) (xy 47.502707 -286.783266) (xy 47.475801 -286.738007) (xy 47.456118 -286.689172)
			(xy 47.444121 -286.637904) (xy 47.440091 -286.585406) (xy 40.583358 -286.585406) (xy 40.582854 -286.611732)
			(xy 40.574817 -286.663768) (xy 40.558931 -286.713967) (xy 40.535568 -286.761152) (xy 40.505276 -286.804218)
			(xy 40.468764 -286.842156) (xy 40.42689 -286.874075) (xy 40.380634 -286.899228) (xy 40.331081 -286.917026)
			(xy 40.279391 -286.92705) (xy 40.226777 -286.929067) (xy 40.174472 -286.923029) (xy 40.123701 -286.909077)
			(xy 40.075656 -286.887538) (xy 40.031461 -286.858918) (xy 39.992153 -286.823887) (xy 39.958653 -286.783266)
			(xy 39.931747 -286.738007) (xy 39.912064 -286.689172) (xy 39.900067 -286.637904) (xy 39.896037 -286.585406)
			(xy 33.039304 -286.585406) (xy 33.0388 -286.611732) (xy 33.030763 -286.663768) (xy 33.014877 -286.713967)
			(xy 32.991514 -286.761152) (xy 32.961222 -286.804218) (xy 32.92471 -286.842156) (xy 32.882836 -286.874075)
			(xy 32.83658 -286.899228) (xy 32.787027 -286.917026) (xy 32.735337 -286.92705) (xy 32.682723 -286.929067)
			(xy 32.630418 -286.923029) (xy 32.579647 -286.909077) (xy 32.531602 -286.887538) (xy 32.487407 -286.858918)
			(xy 32.448099 -286.823887) (xy 32.414599 -286.783266) (xy 32.387693 -286.738007) (xy 32.36801 -286.689172)
			(xy 32.356013 -286.637904) (xy 32.351983 -286.585406) (xy 25.495504 -286.585406) (xy 25.495 -286.611732)
			(xy 25.486963 -286.663768) (xy 25.471077 -286.713967) (xy 25.447714 -286.761152) (xy 25.417422 -286.804218)
			(xy 25.38091 -286.842156) (xy 25.339036 -286.874075) (xy 25.29278 -286.899228) (xy 25.243227 -286.917026)
			(xy 25.191537 -286.92705) (xy 25.138923 -286.929067) (xy 25.086618 -286.923029) (xy 25.035847 -286.909077)
			(xy 24.987802 -286.887538) (xy 24.943607 -286.858918) (xy 24.904299 -286.823887) (xy 24.870799 -286.783266)
			(xy 24.843893 -286.738007) (xy 24.82421 -286.689172) (xy 24.812213 -286.637904) (xy 24.808183 -286.585406)
			(xy 17.95145 -286.585406) (xy 17.950946 -286.611732) (xy 17.942909 -286.663768) (xy 17.927023 -286.713967)
			(xy 17.90366 -286.761152) (xy 17.873368 -286.804218) (xy 17.836856 -286.842156) (xy 17.794982 -286.874075)
			(xy 17.748726 -286.899228) (xy 17.699173 -286.917026) (xy 17.647483 -286.92705) (xy 17.594869 -286.929067)
			(xy 17.542564 -286.923029) (xy 17.491793 -286.909077) (xy 17.443748 -286.887538) (xy 17.399553 -286.858918)
			(xy 17.360245 -286.823887) (xy 17.326745 -286.783266) (xy 17.299839 -286.738007) (xy 17.280156 -286.689172)
			(xy 17.268159 -286.637904) (xy 17.264129 -286.585406) (xy 16.086074 -286.585406) (xy 16.086074 -287.43529)
			(xy 21.364197 -287.43529) (xy 21.368227 -287.382792) (xy 21.380224 -287.331524) (xy 21.399907 -287.282689)
			(xy 21.426813 -287.23743) (xy 21.460313 -287.196809) (xy 21.499621 -287.161778) (xy 21.543816 -287.133158)
			(xy 21.591861 -287.111619) (xy 21.642632 -287.097667) (xy 21.694937 -287.091629) (xy 21.747551 -287.093646)
			(xy 21.799241 -287.10367) (xy 21.848794 -287.121468) (xy 21.89505 -287.146621) (xy 21.936924 -287.17854)
			(xy 21.973436 -287.216478) (xy 22.003728 -287.259544) (xy 22.027091 -287.306729) (xy 22.042977 -287.356928)
			(xy 22.051014 -287.408964) (xy 22.051518 -287.43529) (xy 28.908251 -287.43529) (xy 28.912281 -287.382792)
			(xy 28.924278 -287.331524) (xy 28.943961 -287.282689) (xy 28.970867 -287.23743) (xy 29.004367 -287.196809)
			(xy 29.043675 -287.161778) (xy 29.08787 -287.133158) (xy 29.135915 -287.111619) (xy 29.186686 -287.097667)
			(xy 29.238991 -287.091629) (xy 29.291605 -287.093646) (xy 29.343295 -287.10367) (xy 29.392848 -287.121468)
			(xy 29.439104 -287.146621) (xy 29.480978 -287.17854) (xy 29.51749 -287.216478) (xy 29.547782 -287.259544)
			(xy 29.571145 -287.306729) (xy 29.587031 -287.356928) (xy 29.595068 -287.408964) (xy 29.595572 -287.43529)
			(xy 36.452051 -287.43529) (xy 36.456081 -287.382792) (xy 36.468078 -287.331524) (xy 36.487761 -287.282689)
			(xy 36.514667 -287.23743) (xy 36.548167 -287.196809) (xy 36.587475 -287.161778) (xy 36.63167 -287.133158)
			(xy 36.679715 -287.111619) (xy 36.730486 -287.097667) (xy 36.782791 -287.091629) (xy 36.835405 -287.093646)
			(xy 36.887095 -287.10367) (xy 36.936648 -287.121468) (xy 36.982904 -287.146621) (xy 37.024778 -287.17854)
			(xy 37.06129 -287.216478) (xy 37.091582 -287.259544) (xy 37.114945 -287.306729) (xy 37.130831 -287.356928)
			(xy 37.138868 -287.408964) (xy 37.139372 -287.43529) (xy 43.996105 -287.43529) (xy 44.000135 -287.382792)
			(xy 44.012132 -287.331524) (xy 44.031815 -287.282689) (xy 44.058721 -287.23743) (xy 44.092221 -287.196809)
			(xy 44.131529 -287.161778) (xy 44.175724 -287.133158) (xy 44.223769 -287.111619) (xy 44.27454 -287.097667)
			(xy 44.326845 -287.091629) (xy 44.379459 -287.093646) (xy 44.431149 -287.10367) (xy 44.480702 -287.121468)
			(xy 44.526958 -287.146621) (xy 44.568832 -287.17854) (xy 44.605344 -287.216478) (xy 44.635636 -287.259544)
			(xy 44.658999 -287.306729) (xy 44.674885 -287.356928) (xy 44.682922 -287.408964) (xy 44.683426 -287.43529)
			(xy 51.540159 -287.43529) (xy 51.544189 -287.382792) (xy 51.556186 -287.331524) (xy 51.575869 -287.282689)
			(xy 51.602775 -287.23743) (xy 51.636275 -287.196809) (xy 51.675583 -287.161778) (xy 51.719778 -287.133158)
			(xy 51.767823 -287.111619) (xy 51.818594 -287.097667) (xy 51.870899 -287.091629) (xy 51.923513 -287.093646)
			(xy 51.975203 -287.10367) (xy 52.024756 -287.121468) (xy 52.071012 -287.146621) (xy 52.112886 -287.17854)
			(xy 52.149398 -287.216478) (xy 52.17969 -287.259544) (xy 52.203053 -287.306729) (xy 52.218939 -287.356928)
			(xy 52.226976 -287.408964) (xy 52.22748 -287.43529) (xy 52.226976 -287.461616) (xy 52.218939 -287.513652)
			(xy 52.203053 -287.563851) (xy 52.17969 -287.611036) (xy 52.149398 -287.654102) (xy 52.112886 -287.69204)
			(xy 52.071012 -287.723959) (xy 52.024756 -287.749112) (xy 51.975203 -287.76691) (xy 51.923513 -287.776934)
			(xy 51.870899 -287.778951) (xy 51.818594 -287.772913) (xy 51.767823 -287.758961) (xy 51.719778 -287.737422)
			(xy 51.675583 -287.708802) (xy 51.636275 -287.673771) (xy 51.602775 -287.63315) (xy 51.575869 -287.587891)
			(xy 51.556186 -287.539056) (xy 51.544189 -287.487788) (xy 51.540159 -287.43529) (xy 44.683426 -287.43529)
			(xy 44.682922 -287.461616) (xy 44.674885 -287.513652) (xy 44.658999 -287.563851) (xy 44.635636 -287.611036)
			(xy 44.605344 -287.654102) (xy 44.568832 -287.69204) (xy 44.526958 -287.723959) (xy 44.480702 -287.749112)
			(xy 44.431149 -287.76691) (xy 44.379459 -287.776934) (xy 44.326845 -287.778951) (xy 44.27454 -287.772913)
			(xy 44.223769 -287.758961) (xy 44.175724 -287.737422) (xy 44.131529 -287.708802) (xy 44.092221 -287.673771)
			(xy 44.058721 -287.63315) (xy 44.031815 -287.587891) (xy 44.012132 -287.539056) (xy 44.000135 -287.487788)
			(xy 43.996105 -287.43529) (xy 37.139372 -287.43529) (xy 37.138868 -287.461616) (xy 37.130831 -287.513652)
			(xy 37.114945 -287.563851) (xy 37.091582 -287.611036) (xy 37.06129 -287.654102) (xy 37.024778 -287.69204)
			(xy 36.982904 -287.723959) (xy 36.936648 -287.749112) (xy 36.887095 -287.76691) (xy 36.835405 -287.776934)
			(xy 36.782791 -287.778951) (xy 36.730486 -287.772913) (xy 36.679715 -287.758961) (xy 36.63167 -287.737422)
			(xy 36.587475 -287.708802) (xy 36.548167 -287.673771) (xy 36.514667 -287.63315) (xy 36.487761 -287.587891)
			(xy 36.468078 -287.539056) (xy 36.456081 -287.487788) (xy 36.452051 -287.43529) (xy 29.595572 -287.43529)
			(xy 29.595068 -287.461616) (xy 29.587031 -287.513652) (xy 29.571145 -287.563851) (xy 29.547782 -287.611036)
			(xy 29.51749 -287.654102) (xy 29.480978 -287.69204) (xy 29.439104 -287.723959) (xy 29.392848 -287.749112)
			(xy 29.343295 -287.76691) (xy 29.291605 -287.776934) (xy 29.238991 -287.778951) (xy 29.186686 -287.772913)
			(xy 29.135915 -287.758961) (xy 29.08787 -287.737422) (xy 29.043675 -287.708802) (xy 29.004367 -287.673771)
			(xy 28.970867 -287.63315) (xy 28.943961 -287.587891) (xy 28.924278 -287.539056) (xy 28.912281 -287.487788)
			(xy 28.908251 -287.43529) (xy 22.051518 -287.43529) (xy 22.051014 -287.461616) (xy 22.042977 -287.513652)
			(xy 22.027091 -287.563851) (xy 22.003728 -287.611036) (xy 21.973436 -287.654102) (xy 21.936924 -287.69204)
			(xy 21.89505 -287.723959) (xy 21.848794 -287.749112) (xy 21.799241 -287.76691) (xy 21.747551 -287.776934)
			(xy 21.694937 -287.778951) (xy 21.642632 -287.772913) (xy 21.591861 -287.758961) (xy 21.543816 -287.737422)
			(xy 21.499621 -287.708802) (xy 21.460313 -287.673771) (xy 21.426813 -287.63315) (xy 21.399907 -287.587891)
			(xy 21.380224 -287.539056) (xy 21.368227 -287.487788) (xy 21.364197 -287.43529) (xy 16.086074 -287.43529)
			(xy 16.086074 -288.285428) (xy 17.264129 -288.285428) (xy 17.268159 -288.23293) (xy 17.280156 -288.181662)
			(xy 17.299839 -288.132827) (xy 17.326745 -288.087568) (xy 17.360245 -288.046947) (xy 17.399553 -288.011916)
			(xy 17.443748 -287.983296) (xy 17.491793 -287.961757) (xy 17.542564 -287.947805) (xy 17.594869 -287.941767)
			(xy 17.647483 -287.943784) (xy 17.699173 -287.953808) (xy 17.748726 -287.971606) (xy 17.794982 -287.996759)
			(xy 17.836856 -288.028678) (xy 17.873368 -288.066616) (xy 17.90366 -288.109682) (xy 17.927023 -288.156867)
			(xy 17.942909 -288.207066) (xy 17.950946 -288.259102) (xy 17.95145 -288.285428) (xy 24.808183 -288.285428)
			(xy 24.812213 -288.23293) (xy 24.82421 -288.181662) (xy 24.843893 -288.132827) (xy 24.870799 -288.087568)
			(xy 24.904299 -288.046947) (xy 24.943607 -288.011916) (xy 24.987802 -287.983296) (xy 25.035847 -287.961757)
			(xy 25.086618 -287.947805) (xy 25.138923 -287.941767) (xy 25.191537 -287.943784) (xy 25.243227 -287.953808)
			(xy 25.29278 -287.971606) (xy 25.339036 -287.996759) (xy 25.38091 -288.028678) (xy 25.417422 -288.066616)
			(xy 25.447714 -288.109682) (xy 25.471077 -288.156867) (xy 25.486963 -288.207066) (xy 25.495 -288.259102)
			(xy 25.495504 -288.285428) (xy 32.351983 -288.285428) (xy 32.356013 -288.23293) (xy 32.36801 -288.181662)
			(xy 32.387693 -288.132827) (xy 32.414599 -288.087568) (xy 32.448099 -288.046947) (xy 32.487407 -288.011916)
			(xy 32.531602 -287.983296) (xy 32.579647 -287.961757) (xy 32.630418 -287.947805) (xy 32.682723 -287.941767)
			(xy 32.735337 -287.943784) (xy 32.787027 -287.953808) (xy 32.83658 -287.971606) (xy 32.882836 -287.996759)
			(xy 32.92471 -288.028678) (xy 32.961222 -288.066616) (xy 32.991514 -288.109682) (xy 33.014877 -288.156867)
			(xy 33.030763 -288.207066) (xy 33.0388 -288.259102) (xy 33.039304 -288.285428) (xy 39.896037 -288.285428)
			(xy 39.900067 -288.23293) (xy 39.912064 -288.181662) (xy 39.931747 -288.132827) (xy 39.958653 -288.087568)
			(xy 39.992153 -288.046947) (xy 40.031461 -288.011916) (xy 40.075656 -287.983296) (xy 40.123701 -287.961757)
			(xy 40.174472 -287.947805) (xy 40.226777 -287.941767) (xy 40.279391 -287.943784) (xy 40.331081 -287.953808)
			(xy 40.380634 -287.971606) (xy 40.42689 -287.996759) (xy 40.468764 -288.028678) (xy 40.505276 -288.066616)
			(xy 40.535568 -288.109682) (xy 40.558931 -288.156867) (xy 40.574817 -288.207066) (xy 40.582854 -288.259102)
			(xy 40.583358 -288.285428) (xy 47.440091 -288.285428) (xy 47.444121 -288.23293) (xy 47.456118 -288.181662)
			(xy 47.475801 -288.132827) (xy 47.502707 -288.087568) (xy 47.536207 -288.046947) (xy 47.575515 -288.011916)
			(xy 47.61971 -287.983296) (xy 47.667755 -287.961757) (xy 47.718526 -287.947805) (xy 47.770831 -287.941767)
			(xy 47.823445 -287.943784) (xy 47.875135 -287.953808) (xy 47.924688 -287.971606) (xy 47.970944 -287.996759)
			(xy 48.012818 -288.028678) (xy 48.04933 -288.066616) (xy 48.079622 -288.109682) (xy 48.102985 -288.156867)
			(xy 48.118871 -288.207066) (xy 48.126908 -288.259102) (xy 48.127412 -288.285428) (xy 48.126908 -288.311754)
			(xy 48.118871 -288.36379) (xy 48.102985 -288.413989) (xy 48.079622 -288.461174) (xy 48.04933 -288.50424)
			(xy 48.012818 -288.542178) (xy 47.970944 -288.574097) (xy 47.924688 -288.59925) (xy 47.875135 -288.617048)
			(xy 47.823445 -288.627072) (xy 47.770831 -288.629089) (xy 47.718526 -288.623051) (xy 47.667755 -288.609099)
			(xy 47.61971 -288.58756) (xy 47.575515 -288.55894) (xy 47.536207 -288.523909) (xy 47.502707 -288.483288)
			(xy 47.475801 -288.438029) (xy 47.456118 -288.389194) (xy 47.444121 -288.337926) (xy 47.440091 -288.285428)
			(xy 40.583358 -288.285428) (xy 40.582854 -288.311754) (xy 40.574817 -288.36379) (xy 40.558931 -288.413989)
			(xy 40.535568 -288.461174) (xy 40.505276 -288.50424) (xy 40.468764 -288.542178) (xy 40.42689 -288.574097)
			(xy 40.380634 -288.59925) (xy 40.331081 -288.617048) (xy 40.279391 -288.627072) (xy 40.226777 -288.629089)
			(xy 40.174472 -288.623051) (xy 40.123701 -288.609099) (xy 40.075656 -288.58756) (xy 40.031461 -288.55894)
			(xy 39.992153 -288.523909) (xy 39.958653 -288.483288) (xy 39.931747 -288.438029) (xy 39.912064 -288.389194)
			(xy 39.900067 -288.337926) (xy 39.896037 -288.285428) (xy 33.039304 -288.285428) (xy 33.0388 -288.311754)
			(xy 33.030763 -288.36379) (xy 33.014877 -288.413989) (xy 32.991514 -288.461174) (xy 32.961222 -288.50424)
			(xy 32.92471 -288.542178) (xy 32.882836 -288.574097) (xy 32.83658 -288.59925) (xy 32.787027 -288.617048)
			(xy 32.735337 -288.627072) (xy 32.682723 -288.629089) (xy 32.630418 -288.623051) (xy 32.579647 -288.609099)
			(xy 32.531602 -288.58756) (xy 32.487407 -288.55894) (xy 32.448099 -288.523909) (xy 32.414599 -288.483288)
			(xy 32.387693 -288.438029) (xy 32.36801 -288.389194) (xy 32.356013 -288.337926) (xy 32.351983 -288.285428)
			(xy 25.495504 -288.285428) (xy 25.495 -288.311754) (xy 25.486963 -288.36379) (xy 25.471077 -288.413989)
			(xy 25.447714 -288.461174) (xy 25.417422 -288.50424) (xy 25.38091 -288.542178) (xy 25.339036 -288.574097)
			(xy 25.29278 -288.59925) (xy 25.243227 -288.617048) (xy 25.191537 -288.627072) (xy 25.138923 -288.629089)
			(xy 25.086618 -288.623051) (xy 25.035847 -288.609099) (xy 24.987802 -288.58756) (xy 24.943607 -288.55894)
			(xy 24.904299 -288.523909) (xy 24.870799 -288.483288) (xy 24.843893 -288.438029) (xy 24.82421 -288.389194)
			(xy 24.812213 -288.337926) (xy 24.808183 -288.285428) (xy 17.95145 -288.285428) (xy 17.950946 -288.311754)
			(xy 17.942909 -288.36379) (xy 17.927023 -288.413989) (xy 17.90366 -288.461174) (xy 17.873368 -288.50424)
			(xy 17.836856 -288.542178) (xy 17.794982 -288.574097) (xy 17.748726 -288.59925) (xy 17.699173 -288.617048)
			(xy 17.647483 -288.627072) (xy 17.594869 -288.629089) (xy 17.542564 -288.623051) (xy 17.491793 -288.609099)
			(xy 17.443748 -288.58756) (xy 17.399553 -288.55894) (xy 17.360245 -288.523909) (xy 17.326745 -288.483288)
			(xy 17.299839 -288.438029) (xy 17.280156 -288.389194) (xy 17.268159 -288.337926) (xy 17.264129 -288.285428)
			(xy 16.086074 -288.285428) (xy 16.086074 -289.135312) (xy 21.364197 -289.135312) (xy 21.368227 -289.082814)
			(xy 21.380224 -289.031546) (xy 21.399907 -288.982711) (xy 21.426813 -288.937452) (xy 21.460313 -288.896831)
			(xy 21.499621 -288.8618) (xy 21.543816 -288.83318) (xy 21.591861 -288.811641) (xy 21.642632 -288.797689)
			(xy 21.694937 -288.791651) (xy 21.747551 -288.793668) (xy 21.799241 -288.803692) (xy 21.848794 -288.82149)
			(xy 21.89505 -288.846643) (xy 21.936924 -288.878562) (xy 21.973436 -288.9165) (xy 22.003728 -288.959566)
			(xy 22.027091 -289.006751) (xy 22.042977 -289.05695) (xy 22.051014 -289.108986) (xy 22.051518 -289.135312)
			(xy 28.908251 -289.135312) (xy 28.912281 -289.082814) (xy 28.924278 -289.031546) (xy 28.943961 -288.982711)
			(xy 28.970867 -288.937452) (xy 29.004367 -288.896831) (xy 29.043675 -288.8618) (xy 29.08787 -288.83318)
			(xy 29.135915 -288.811641) (xy 29.186686 -288.797689) (xy 29.238991 -288.791651) (xy 29.291605 -288.793668)
			(xy 29.343295 -288.803692) (xy 29.392848 -288.82149) (xy 29.439104 -288.846643) (xy 29.480978 -288.878562)
			(xy 29.51749 -288.9165) (xy 29.547782 -288.959566) (xy 29.571145 -289.006751) (xy 29.587031 -289.05695)
			(xy 29.595068 -289.108986) (xy 29.595572 -289.135312) (xy 36.452051 -289.135312) (xy 36.456081 -289.082814)
			(xy 36.468078 -289.031546) (xy 36.487761 -288.982711) (xy 36.514667 -288.937452) (xy 36.548167 -288.896831)
			(xy 36.587475 -288.8618) (xy 36.63167 -288.83318) (xy 36.679715 -288.811641) (xy 36.730486 -288.797689)
			(xy 36.782791 -288.791651) (xy 36.835405 -288.793668) (xy 36.887095 -288.803692) (xy 36.936648 -288.82149)
			(xy 36.982904 -288.846643) (xy 37.024778 -288.878562) (xy 37.06129 -288.9165) (xy 37.091582 -288.959566)
			(xy 37.114945 -289.006751) (xy 37.130831 -289.05695) (xy 37.138868 -289.108986) (xy 37.139372 -289.135312)
			(xy 43.996105 -289.135312) (xy 44.000135 -289.082814) (xy 44.012132 -289.031546) (xy 44.031815 -288.982711)
			(xy 44.058721 -288.937452) (xy 44.092221 -288.896831) (xy 44.131529 -288.8618) (xy 44.175724 -288.83318)
			(xy 44.223769 -288.811641) (xy 44.27454 -288.797689) (xy 44.326845 -288.791651) (xy 44.379459 -288.793668)
			(xy 44.431149 -288.803692) (xy 44.480702 -288.82149) (xy 44.526958 -288.846643) (xy 44.568832 -288.878562)
			(xy 44.605344 -288.9165) (xy 44.635636 -288.959566) (xy 44.658999 -289.006751) (xy 44.674885 -289.05695)
			(xy 44.682922 -289.108986) (xy 44.683426 -289.135312) (xy 51.540159 -289.135312) (xy 51.544189 -289.082814)
			(xy 51.556186 -289.031546) (xy 51.575869 -288.982711) (xy 51.602775 -288.937452) (xy 51.636275 -288.896831)
			(xy 51.675583 -288.8618) (xy 51.719778 -288.83318) (xy 51.767823 -288.811641) (xy 51.818594 -288.797689)
			(xy 51.870899 -288.791651) (xy 51.923513 -288.793668) (xy 51.975203 -288.803692) (xy 52.024756 -288.82149)
			(xy 52.071012 -288.846643) (xy 52.112886 -288.878562) (xy 52.149398 -288.9165) (xy 52.17969 -288.959566)
			(xy 52.203053 -289.006751) (xy 52.218939 -289.05695) (xy 52.226976 -289.108986) (xy 52.22748 -289.135312)
			(xy 52.226976 -289.161638) (xy 52.218939 -289.213674) (xy 52.203053 -289.263873) (xy 52.17969 -289.311058)
			(xy 52.149398 -289.354124) (xy 52.112886 -289.392062) (xy 52.071012 -289.423981) (xy 52.024756 -289.449134)
			(xy 51.975203 -289.466932) (xy 51.923513 -289.476956) (xy 51.870899 -289.478973) (xy 51.818594 -289.472935)
			(xy 51.767823 -289.458983) (xy 51.719778 -289.437444) (xy 51.675583 -289.408824) (xy 51.636275 -289.373793)
			(xy 51.602775 -289.333172) (xy 51.575869 -289.287913) (xy 51.556186 -289.239078) (xy 51.544189 -289.18781)
			(xy 51.540159 -289.135312) (xy 44.683426 -289.135312) (xy 44.682922 -289.161638) (xy 44.674885 -289.213674)
			(xy 44.658999 -289.263873) (xy 44.635636 -289.311058) (xy 44.605344 -289.354124) (xy 44.568832 -289.392062)
			(xy 44.526958 -289.423981) (xy 44.480702 -289.449134) (xy 44.431149 -289.466932) (xy 44.379459 -289.476956)
			(xy 44.326845 -289.478973) (xy 44.27454 -289.472935) (xy 44.223769 -289.458983) (xy 44.175724 -289.437444)
			(xy 44.131529 -289.408824) (xy 44.092221 -289.373793) (xy 44.058721 -289.333172) (xy 44.031815 -289.287913)
			(xy 44.012132 -289.239078) (xy 44.000135 -289.18781) (xy 43.996105 -289.135312) (xy 37.139372 -289.135312)
			(xy 37.138868 -289.161638) (xy 37.130831 -289.213674) (xy 37.114945 -289.263873) (xy 37.091582 -289.311058)
			(xy 37.06129 -289.354124) (xy 37.024778 -289.392062) (xy 36.982904 -289.423981) (xy 36.936648 -289.449134)
			(xy 36.887095 -289.466932) (xy 36.835405 -289.476956) (xy 36.782791 -289.478973) (xy 36.730486 -289.472935)
			(xy 36.679715 -289.458983) (xy 36.63167 -289.437444) (xy 36.587475 -289.408824) (xy 36.548167 -289.373793)
			(xy 36.514667 -289.333172) (xy 36.487761 -289.287913) (xy 36.468078 -289.239078) (xy 36.456081 -289.18781)
			(xy 36.452051 -289.135312) (xy 29.595572 -289.135312) (xy 29.595068 -289.161638) (xy 29.587031 -289.213674)
			(xy 29.571145 -289.263873) (xy 29.547782 -289.311058) (xy 29.51749 -289.354124) (xy 29.480978 -289.392062)
			(xy 29.439104 -289.423981) (xy 29.392848 -289.449134) (xy 29.343295 -289.466932) (xy 29.291605 -289.476956)
			(xy 29.238991 -289.478973) (xy 29.186686 -289.472935) (xy 29.135915 -289.458983) (xy 29.08787 -289.437444)
			(xy 29.043675 -289.408824) (xy 29.004367 -289.373793) (xy 28.970867 -289.333172) (xy 28.943961 -289.287913)
			(xy 28.924278 -289.239078) (xy 28.912281 -289.18781) (xy 28.908251 -289.135312) (xy 22.051518 -289.135312)
			(xy 22.051014 -289.161638) (xy 22.042977 -289.213674) (xy 22.027091 -289.263873) (xy 22.003728 -289.311058)
			(xy 21.973436 -289.354124) (xy 21.936924 -289.392062) (xy 21.89505 -289.423981) (xy 21.848794 -289.449134)
			(xy 21.799241 -289.466932) (xy 21.747551 -289.476956) (xy 21.694937 -289.478973) (xy 21.642632 -289.472935)
			(xy 21.591861 -289.458983) (xy 21.543816 -289.437444) (xy 21.499621 -289.408824) (xy 21.460313 -289.373793)
			(xy 21.426813 -289.333172) (xy 21.399907 -289.287913) (xy 21.380224 -289.239078) (xy 21.368227 -289.18781)
			(xy 21.364197 -289.135312) (xy 16.086074 -289.135312) (xy 16.086074 -289.98545) (xy 17.264129 -289.98545)
			(xy 17.268159 -289.932952) (xy 17.280156 -289.881684) (xy 17.299839 -289.832849) (xy 17.326745 -289.78759)
			(xy 17.360245 -289.746969) (xy 17.399553 -289.711938) (xy 17.443748 -289.683318) (xy 17.491793 -289.661779)
			(xy 17.542564 -289.647827) (xy 17.594869 -289.641789) (xy 17.647483 -289.643806) (xy 17.699173 -289.65383)
			(xy 17.748726 -289.671628) (xy 17.794982 -289.696781) (xy 17.836856 -289.7287) (xy 17.873368 -289.766638)
			(xy 17.90366 -289.809704) (xy 17.927023 -289.856889) (xy 17.942909 -289.907088) (xy 17.950946 -289.959124)
			(xy 17.95145 -289.98545) (xy 24.808183 -289.98545) (xy 24.812213 -289.932952) (xy 24.82421 -289.881684)
			(xy 24.843893 -289.832849) (xy 24.870799 -289.78759) (xy 24.904299 -289.746969) (xy 24.943607 -289.711938)
			(xy 24.987802 -289.683318) (xy 25.035847 -289.661779) (xy 25.086618 -289.647827) (xy 25.138923 -289.641789)
			(xy 25.191537 -289.643806) (xy 25.243227 -289.65383) (xy 25.29278 -289.671628) (xy 25.339036 -289.696781)
			(xy 25.38091 -289.7287) (xy 25.417422 -289.766638) (xy 25.447714 -289.809704) (xy 25.471077 -289.856889)
			(xy 25.486963 -289.907088) (xy 25.495 -289.959124) (xy 25.495504 -289.98545) (xy 32.351983 -289.98545)
			(xy 32.356013 -289.932952) (xy 32.36801 -289.881684) (xy 32.387693 -289.832849) (xy 32.414599 -289.78759)
			(xy 32.448099 -289.746969) (xy 32.487407 -289.711938) (xy 32.531602 -289.683318) (xy 32.579647 -289.661779)
			(xy 32.630418 -289.647827) (xy 32.682723 -289.641789) (xy 32.735337 -289.643806) (xy 32.787027 -289.65383)
			(xy 32.83658 -289.671628) (xy 32.882836 -289.696781) (xy 32.92471 -289.7287) (xy 32.961222 -289.766638)
			(xy 32.991514 -289.809704) (xy 33.014877 -289.856889) (xy 33.030763 -289.907088) (xy 33.0388 -289.959124)
			(xy 33.039304 -289.98545) (xy 39.896037 -289.98545) (xy 39.900067 -289.932952) (xy 39.912064 -289.881684)
			(xy 39.931747 -289.832849) (xy 39.958653 -289.78759) (xy 39.992153 -289.746969) (xy 40.031461 -289.711938)
			(xy 40.075656 -289.683318) (xy 40.123701 -289.661779) (xy 40.174472 -289.647827) (xy 40.226777 -289.641789)
			(xy 40.279391 -289.643806) (xy 40.331081 -289.65383) (xy 40.380634 -289.671628) (xy 40.42689 -289.696781)
			(xy 40.468764 -289.7287) (xy 40.505276 -289.766638) (xy 40.535568 -289.809704) (xy 40.558931 -289.856889)
			(xy 40.574817 -289.907088) (xy 40.582854 -289.959124) (xy 40.583358 -289.98545) (xy 47.440091 -289.98545)
			(xy 47.444121 -289.932952) (xy 47.456118 -289.881684) (xy 47.475801 -289.832849) (xy 47.502707 -289.78759)
			(xy 47.536207 -289.746969) (xy 47.575515 -289.711938) (xy 47.61971 -289.683318) (xy 47.667755 -289.661779)
			(xy 47.718526 -289.647827) (xy 47.770831 -289.641789) (xy 47.823445 -289.643806) (xy 47.875135 -289.65383)
			(xy 47.924688 -289.671628) (xy 47.970944 -289.696781) (xy 48.012818 -289.7287) (xy 48.04933 -289.766638)
			(xy 48.079622 -289.809704) (xy 48.102985 -289.856889) (xy 48.118871 -289.907088) (xy 48.126908 -289.959124)
			(xy 48.127412 -289.98545) (xy 48.126908 -290.011776) (xy 48.118871 -290.063812) (xy 48.102985 -290.114011)
			(xy 48.079622 -290.161196) (xy 48.04933 -290.204262) (xy 48.012818 -290.2422) (xy 47.970944 -290.274119)
			(xy 47.924688 -290.299272) (xy 47.875135 -290.31707) (xy 47.823445 -290.327094) (xy 47.770831 -290.329111)
			(xy 47.718526 -290.323073) (xy 47.667755 -290.309121) (xy 47.61971 -290.287582) (xy 47.575515 -290.258962)
			(xy 47.536207 -290.223931) (xy 47.502707 -290.18331) (xy 47.475801 -290.138051) (xy 47.456118 -290.089216)
			(xy 47.444121 -290.037948) (xy 47.440091 -289.98545) (xy 40.583358 -289.98545) (xy 40.582854 -290.011776)
			(xy 40.574817 -290.063812) (xy 40.558931 -290.114011) (xy 40.535568 -290.161196) (xy 40.505276 -290.204262)
			(xy 40.468764 -290.2422) (xy 40.42689 -290.274119) (xy 40.380634 -290.299272) (xy 40.331081 -290.31707)
			(xy 40.279391 -290.327094) (xy 40.226777 -290.329111) (xy 40.174472 -290.323073) (xy 40.123701 -290.309121)
			(xy 40.075656 -290.287582) (xy 40.031461 -290.258962) (xy 39.992153 -290.223931) (xy 39.958653 -290.18331)
			(xy 39.931747 -290.138051) (xy 39.912064 -290.089216) (xy 39.900067 -290.037948) (xy 39.896037 -289.98545)
			(xy 33.039304 -289.98545) (xy 33.0388 -290.011776) (xy 33.030763 -290.063812) (xy 33.014877 -290.114011)
			(xy 32.991514 -290.161196) (xy 32.961222 -290.204262) (xy 32.92471 -290.2422) (xy 32.882836 -290.274119)
			(xy 32.83658 -290.299272) (xy 32.787027 -290.31707) (xy 32.735337 -290.327094) (xy 32.682723 -290.329111)
			(xy 32.630418 -290.323073) (xy 32.579647 -290.309121) (xy 32.531602 -290.287582) (xy 32.487407 -290.258962)
			(xy 32.448099 -290.223931) (xy 32.414599 -290.18331) (xy 32.387693 -290.138051) (xy 32.36801 -290.089216)
			(xy 32.356013 -290.037948) (xy 32.351983 -289.98545) (xy 25.495504 -289.98545) (xy 25.495 -290.011776)
			(xy 25.486963 -290.063812) (xy 25.471077 -290.114011) (xy 25.447714 -290.161196) (xy 25.417422 -290.204262)
			(xy 25.38091 -290.2422) (xy 25.339036 -290.274119) (xy 25.29278 -290.299272) (xy 25.243227 -290.31707)
			(xy 25.191537 -290.327094) (xy 25.138923 -290.329111) (xy 25.086618 -290.323073) (xy 25.035847 -290.309121)
			(xy 24.987802 -290.287582) (xy 24.943607 -290.258962) (xy 24.904299 -290.223931) (xy 24.870799 -290.18331)
			(xy 24.843893 -290.138051) (xy 24.82421 -290.089216) (xy 24.812213 -290.037948) (xy 24.808183 -289.98545)
			(xy 17.95145 -289.98545) (xy 17.950946 -290.011776) (xy 17.942909 -290.063812) (xy 17.927023 -290.114011)
			(xy 17.90366 -290.161196) (xy 17.873368 -290.204262) (xy 17.836856 -290.2422) (xy 17.794982 -290.274119)
			(xy 17.748726 -290.299272) (xy 17.699173 -290.31707) (xy 17.647483 -290.327094) (xy 17.594869 -290.329111)
			(xy 17.542564 -290.323073) (xy 17.491793 -290.309121) (xy 17.443748 -290.287582) (xy 17.399553 -290.258962)
			(xy 17.360245 -290.223931) (xy 17.326745 -290.18331) (xy 17.299839 -290.138051) (xy 17.280156 -290.089216)
			(xy 17.268159 -290.037948) (xy 17.264129 -289.98545) (xy 16.086074 -289.98545) (xy 16.086074 -290.835334)
			(xy 21.364197 -290.835334) (xy 21.368227 -290.782836) (xy 21.380224 -290.731568) (xy 21.399907 -290.682733)
			(xy 21.426813 -290.637474) (xy 21.460313 -290.596853) (xy 21.499621 -290.561822) (xy 21.543816 -290.533202)
			(xy 21.591861 -290.511663) (xy 21.642632 -290.497711) (xy 21.694937 -290.491673) (xy 21.747551 -290.49369)
			(xy 21.799241 -290.503714) (xy 21.848794 -290.521512) (xy 21.89505 -290.546665) (xy 21.936924 -290.578584)
			(xy 21.973436 -290.616522) (xy 22.003728 -290.659588) (xy 22.027091 -290.706773) (xy 22.042977 -290.756972)
			(xy 22.051014 -290.809008) (xy 22.051518 -290.835334) (xy 28.908251 -290.835334) (xy 28.912281 -290.782836)
			(xy 28.924278 -290.731568) (xy 28.943961 -290.682733) (xy 28.970867 -290.637474) (xy 29.004367 -290.596853)
			(xy 29.043675 -290.561822) (xy 29.08787 -290.533202) (xy 29.135915 -290.511663) (xy 29.186686 -290.497711)
			(xy 29.238991 -290.491673) (xy 29.291605 -290.49369) (xy 29.343295 -290.503714) (xy 29.392848 -290.521512)
			(xy 29.439104 -290.546665) (xy 29.480978 -290.578584) (xy 29.51749 -290.616522) (xy 29.547782 -290.659588)
			(xy 29.571145 -290.706773) (xy 29.587031 -290.756972) (xy 29.595068 -290.809008) (xy 29.595572 -290.835334)
			(xy 36.452051 -290.835334) (xy 36.456081 -290.782836) (xy 36.468078 -290.731568) (xy 36.487761 -290.682733)
			(xy 36.514667 -290.637474) (xy 36.548167 -290.596853) (xy 36.587475 -290.561822) (xy 36.63167 -290.533202)
			(xy 36.679715 -290.511663) (xy 36.730486 -290.497711) (xy 36.782791 -290.491673) (xy 36.835405 -290.49369)
			(xy 36.887095 -290.503714) (xy 36.936648 -290.521512) (xy 36.982904 -290.546665) (xy 37.024778 -290.578584)
			(xy 37.06129 -290.616522) (xy 37.091582 -290.659588) (xy 37.114945 -290.706773) (xy 37.130831 -290.756972)
			(xy 37.138868 -290.809008) (xy 37.139372 -290.835334) (xy 43.996105 -290.835334) (xy 44.000135 -290.782836)
			(xy 44.012132 -290.731568) (xy 44.031815 -290.682733) (xy 44.058721 -290.637474) (xy 44.092221 -290.596853)
			(xy 44.131529 -290.561822) (xy 44.175724 -290.533202) (xy 44.223769 -290.511663) (xy 44.27454 -290.497711)
			(xy 44.326845 -290.491673) (xy 44.379459 -290.49369) (xy 44.431149 -290.503714) (xy 44.480702 -290.521512)
			(xy 44.526958 -290.546665) (xy 44.568832 -290.578584) (xy 44.605344 -290.616522) (xy 44.635636 -290.659588)
			(xy 44.658999 -290.706773) (xy 44.674885 -290.756972) (xy 44.682922 -290.809008) (xy 44.683426 -290.835334)
			(xy 51.540159 -290.835334) (xy 51.544189 -290.782836) (xy 51.556186 -290.731568) (xy 51.575869 -290.682733)
			(xy 51.602775 -290.637474) (xy 51.636275 -290.596853) (xy 51.675583 -290.561822) (xy 51.719778 -290.533202)
			(xy 51.767823 -290.511663) (xy 51.818594 -290.497711) (xy 51.870899 -290.491673) (xy 51.923513 -290.49369)
			(xy 51.975203 -290.503714) (xy 52.024756 -290.521512) (xy 52.071012 -290.546665) (xy 52.112886 -290.578584)
			(xy 52.149398 -290.616522) (xy 52.17969 -290.659588) (xy 52.203053 -290.706773) (xy 52.218939 -290.756972)
			(xy 52.226976 -290.809008) (xy 52.22748 -290.835334) (xy 52.226976 -290.86166) (xy 52.218939 -290.913696)
			(xy 52.203053 -290.963895) (xy 52.17969 -291.01108) (xy 52.149398 -291.054146) (xy 52.112886 -291.092084)
			(xy 52.071012 -291.124003) (xy 52.024756 -291.149156) (xy 51.975203 -291.166954) (xy 51.923513 -291.176978)
			(xy 51.870899 -291.178995) (xy 51.818594 -291.172957) (xy 51.767823 -291.159005) (xy 51.719778 -291.137466)
			(xy 51.675583 -291.108846) (xy 51.636275 -291.073815) (xy 51.602775 -291.033194) (xy 51.575869 -290.987935)
			(xy 51.556186 -290.9391) (xy 51.544189 -290.887832) (xy 51.540159 -290.835334) (xy 44.683426 -290.835334)
			(xy 44.682922 -290.86166) (xy 44.674885 -290.913696) (xy 44.658999 -290.963895) (xy 44.635636 -291.01108)
			(xy 44.605344 -291.054146) (xy 44.568832 -291.092084) (xy 44.526958 -291.124003) (xy 44.480702 -291.149156)
			(xy 44.431149 -291.166954) (xy 44.379459 -291.176978) (xy 44.326845 -291.178995) (xy 44.27454 -291.172957)
			(xy 44.223769 -291.159005) (xy 44.175724 -291.137466) (xy 44.131529 -291.108846) (xy 44.092221 -291.073815)
			(xy 44.058721 -291.033194) (xy 44.031815 -290.987935) (xy 44.012132 -290.9391) (xy 44.000135 -290.887832)
			(xy 43.996105 -290.835334) (xy 37.139372 -290.835334) (xy 37.138868 -290.86166) (xy 37.130831 -290.913696)
			(xy 37.114945 -290.963895) (xy 37.091582 -291.01108) (xy 37.06129 -291.054146) (xy 37.024778 -291.092084)
			(xy 36.982904 -291.124003) (xy 36.936648 -291.149156) (xy 36.887095 -291.166954) (xy 36.835405 -291.176978)
			(xy 36.782791 -291.178995) (xy 36.730486 -291.172957) (xy 36.679715 -291.159005) (xy 36.63167 -291.137466)
			(xy 36.587475 -291.108846) (xy 36.548167 -291.073815) (xy 36.514667 -291.033194) (xy 36.487761 -290.987935)
			(xy 36.468078 -290.9391) (xy 36.456081 -290.887832) (xy 36.452051 -290.835334) (xy 29.595572 -290.835334)
			(xy 29.595068 -290.86166) (xy 29.587031 -290.913696) (xy 29.571145 -290.963895) (xy 29.547782 -291.01108)
			(xy 29.51749 -291.054146) (xy 29.480978 -291.092084) (xy 29.439104 -291.124003) (xy 29.392848 -291.149156)
			(xy 29.343295 -291.166954) (xy 29.291605 -291.176978) (xy 29.238991 -291.178995) (xy 29.186686 -291.172957)
			(xy 29.135915 -291.159005) (xy 29.08787 -291.137466) (xy 29.043675 -291.108846) (xy 29.004367 -291.073815)
			(xy 28.970867 -291.033194) (xy 28.943961 -290.987935) (xy 28.924278 -290.9391) (xy 28.912281 -290.887832)
			(xy 28.908251 -290.835334) (xy 22.051518 -290.835334) (xy 22.051014 -290.86166) (xy 22.042977 -290.913696)
			(xy 22.027091 -290.963895) (xy 22.003728 -291.01108) (xy 21.973436 -291.054146) (xy 21.936924 -291.092084)
			(xy 21.89505 -291.124003) (xy 21.848794 -291.149156) (xy 21.799241 -291.166954) (xy 21.747551 -291.176978)
			(xy 21.694937 -291.178995) (xy 21.642632 -291.172957) (xy 21.591861 -291.159005) (xy 21.543816 -291.137466)
			(xy 21.499621 -291.108846) (xy 21.460313 -291.073815) (xy 21.426813 -291.033194) (xy 21.399907 -290.987935)
			(xy 21.380224 -290.9391) (xy 21.368227 -290.887832) (xy 21.364197 -290.835334) (xy 16.086074 -290.835334)
			(xy 16.086074 -291.685218) (xy 17.264129 -291.685218) (xy 17.268159 -291.63272) (xy 17.280156 -291.581452)
			(xy 17.299839 -291.532617) (xy 17.326745 -291.487358) (xy 17.360245 -291.446737) (xy 17.399553 -291.411706)
			(xy 17.443748 -291.383086) (xy 17.491793 -291.361547) (xy 17.542564 -291.347595) (xy 17.594869 -291.341557)
			(xy 17.647483 -291.343574) (xy 17.699173 -291.353598) (xy 17.748726 -291.371396) (xy 17.794982 -291.396549)
			(xy 17.836856 -291.428468) (xy 17.873368 -291.466406) (xy 17.90366 -291.509472) (xy 17.927023 -291.556657)
			(xy 17.942909 -291.606856) (xy 17.950946 -291.658892) (xy 17.95145 -291.685218) (xy 24.808183 -291.685218)
			(xy 24.812213 -291.63272) (xy 24.82421 -291.581452) (xy 24.843893 -291.532617) (xy 24.870799 -291.487358)
			(xy 24.904299 -291.446737) (xy 24.943607 -291.411706) (xy 24.987802 -291.383086) (xy 25.035847 -291.361547)
			(xy 25.086618 -291.347595) (xy 25.138923 -291.341557) (xy 25.191537 -291.343574) (xy 25.243227 -291.353598)
			(xy 25.29278 -291.371396) (xy 25.339036 -291.396549) (xy 25.38091 -291.428468) (xy 25.417422 -291.466406)
			(xy 25.447714 -291.509472) (xy 25.471077 -291.556657) (xy 25.486963 -291.606856) (xy 25.495 -291.658892)
			(xy 25.495504 -291.685218) (xy 32.351983 -291.685218) (xy 32.356013 -291.63272) (xy 32.36801 -291.581452)
			(xy 32.387693 -291.532617) (xy 32.414599 -291.487358) (xy 32.448099 -291.446737) (xy 32.487407 -291.411706)
			(xy 32.531602 -291.383086) (xy 32.579647 -291.361547) (xy 32.630418 -291.347595) (xy 32.682723 -291.341557)
			(xy 32.735337 -291.343574) (xy 32.787027 -291.353598) (xy 32.83658 -291.371396) (xy 32.882836 -291.396549)
			(xy 32.92471 -291.428468) (xy 32.961222 -291.466406) (xy 32.991514 -291.509472) (xy 33.014877 -291.556657)
			(xy 33.030763 -291.606856) (xy 33.0388 -291.658892) (xy 33.039304 -291.685218) (xy 39.896037 -291.685218)
			(xy 39.900067 -291.63272) (xy 39.912064 -291.581452) (xy 39.931747 -291.532617) (xy 39.958653 -291.487358)
			(xy 39.992153 -291.446737) (xy 40.031461 -291.411706) (xy 40.075656 -291.383086) (xy 40.123701 -291.361547)
			(xy 40.174472 -291.347595) (xy 40.226777 -291.341557) (xy 40.279391 -291.343574) (xy 40.331081 -291.353598)
			(xy 40.380634 -291.371396) (xy 40.42689 -291.396549) (xy 40.468764 -291.428468) (xy 40.505276 -291.466406)
			(xy 40.535568 -291.509472) (xy 40.558931 -291.556657) (xy 40.574817 -291.606856) (xy 40.582854 -291.658892)
			(xy 40.583358 -291.685218) (xy 47.440091 -291.685218) (xy 47.444121 -291.63272) (xy 47.456118 -291.581452)
			(xy 47.475801 -291.532617) (xy 47.502707 -291.487358) (xy 47.536207 -291.446737) (xy 47.575515 -291.411706)
			(xy 47.61971 -291.383086) (xy 47.667755 -291.361547) (xy 47.718526 -291.347595) (xy 47.770831 -291.341557)
			(xy 47.823445 -291.343574) (xy 47.875135 -291.353598) (xy 47.924688 -291.371396) (xy 47.970944 -291.396549)
			(xy 48.012818 -291.428468) (xy 48.04933 -291.466406) (xy 48.079622 -291.509472) (xy 48.102985 -291.556657)
			(xy 48.118871 -291.606856) (xy 48.126908 -291.658892) (xy 48.127412 -291.685218) (xy 48.126908 -291.711544)
			(xy 48.118871 -291.76358) (xy 48.102985 -291.813779) (xy 48.079622 -291.860964) (xy 48.04933 -291.90403)
			(xy 48.012818 -291.941968) (xy 47.970944 -291.973887) (xy 47.924688 -291.99904) (xy 47.875135 -292.016838)
			(xy 47.823445 -292.026862) (xy 47.770831 -292.028879) (xy 47.718526 -292.022841) (xy 47.667755 -292.008889)
			(xy 47.61971 -291.98735) (xy 47.575515 -291.95873) (xy 47.536207 -291.923699) (xy 47.502707 -291.883078)
			(xy 47.475801 -291.837819) (xy 47.456118 -291.788984) (xy 47.444121 -291.737716) (xy 47.440091 -291.685218)
			(xy 40.583358 -291.685218) (xy 40.582854 -291.711544) (xy 40.574817 -291.76358) (xy 40.558931 -291.813779)
			(xy 40.535568 -291.860964) (xy 40.505276 -291.90403) (xy 40.468764 -291.941968) (xy 40.42689 -291.973887)
			(xy 40.380634 -291.99904) (xy 40.331081 -292.016838) (xy 40.279391 -292.026862) (xy 40.226777 -292.028879)
			(xy 40.174472 -292.022841) (xy 40.123701 -292.008889) (xy 40.075656 -291.98735) (xy 40.031461 -291.95873)
			(xy 39.992153 -291.923699) (xy 39.958653 -291.883078) (xy 39.931747 -291.837819) (xy 39.912064 -291.788984)
			(xy 39.900067 -291.737716) (xy 39.896037 -291.685218) (xy 33.039304 -291.685218) (xy 33.0388 -291.711544)
			(xy 33.030763 -291.76358) (xy 33.014877 -291.813779) (xy 32.991514 -291.860964) (xy 32.961222 -291.90403)
			(xy 32.92471 -291.941968) (xy 32.882836 -291.973887) (xy 32.83658 -291.99904) (xy 32.787027 -292.016838)
			(xy 32.735337 -292.026862) (xy 32.682723 -292.028879) (xy 32.630418 -292.022841) (xy 32.579647 -292.008889)
			(xy 32.531602 -291.98735) (xy 32.487407 -291.95873) (xy 32.448099 -291.923699) (xy 32.414599 -291.883078)
			(xy 32.387693 -291.837819) (xy 32.36801 -291.788984) (xy 32.356013 -291.737716) (xy 32.351983 -291.685218)
			(xy 25.495504 -291.685218) (xy 25.495 -291.711544) (xy 25.486963 -291.76358) (xy 25.471077 -291.813779)
			(xy 25.447714 -291.860964) (xy 25.417422 -291.90403) (xy 25.38091 -291.941968) (xy 25.339036 -291.973887)
			(xy 25.29278 -291.99904) (xy 25.243227 -292.016838) (xy 25.191537 -292.026862) (xy 25.138923 -292.028879)
			(xy 25.086618 -292.022841) (xy 25.035847 -292.008889) (xy 24.987802 -291.98735) (xy 24.943607 -291.95873)
			(xy 24.904299 -291.923699) (xy 24.870799 -291.883078) (xy 24.843893 -291.837819) (xy 24.82421 -291.788984)
			(xy 24.812213 -291.737716) (xy 24.808183 -291.685218) (xy 17.95145 -291.685218) (xy 17.950946 -291.711544)
			(xy 17.942909 -291.76358) (xy 17.927023 -291.813779) (xy 17.90366 -291.860964) (xy 17.873368 -291.90403)
			(xy 17.836856 -291.941968) (xy 17.794982 -291.973887) (xy 17.748726 -291.99904) (xy 17.699173 -292.016838)
			(xy 17.647483 -292.026862) (xy 17.594869 -292.028879) (xy 17.542564 -292.022841) (xy 17.491793 -292.008889)
			(xy 17.443748 -291.98735) (xy 17.399553 -291.95873) (xy 17.360245 -291.923699) (xy 17.326745 -291.883078)
			(xy 17.299839 -291.837819) (xy 17.280156 -291.788984) (xy 17.268159 -291.737716) (xy 17.264129 -291.685218)
			(xy 16.086074 -291.685218) (xy 16.086074 -292.535356) (xy 21.364197 -292.535356) (xy 21.368227 -292.482858)
			(xy 21.380224 -292.43159) (xy 21.399907 -292.382755) (xy 21.426813 -292.337496) (xy 21.460313 -292.296875)
			(xy 21.499621 -292.261844) (xy 21.543816 -292.233224) (xy 21.591861 -292.211685) (xy 21.642632 -292.197733)
			(xy 21.694937 -292.191695) (xy 21.747551 -292.193712) (xy 21.799241 -292.203736) (xy 21.848794 -292.221534)
			(xy 21.89505 -292.246687) (xy 21.936924 -292.278606) (xy 21.973436 -292.316544) (xy 22.003728 -292.35961)
			(xy 22.027091 -292.406795) (xy 22.042977 -292.456994) (xy 22.051014 -292.50903) (xy 22.051518 -292.535356)
			(xy 28.908251 -292.535356) (xy 28.912281 -292.482858) (xy 28.924278 -292.43159) (xy 28.943961 -292.382755)
			(xy 28.970867 -292.337496) (xy 29.004367 -292.296875) (xy 29.043675 -292.261844) (xy 29.08787 -292.233224)
			(xy 29.135915 -292.211685) (xy 29.186686 -292.197733) (xy 29.238991 -292.191695) (xy 29.291605 -292.193712)
			(xy 29.343295 -292.203736) (xy 29.392848 -292.221534) (xy 29.439104 -292.246687) (xy 29.480978 -292.278606)
			(xy 29.51749 -292.316544) (xy 29.547782 -292.35961) (xy 29.571145 -292.406795) (xy 29.587031 -292.456994)
			(xy 29.595068 -292.50903) (xy 29.595572 -292.535356) (xy 36.452051 -292.535356) (xy 36.456081 -292.482858)
			(xy 36.468078 -292.43159) (xy 36.487761 -292.382755) (xy 36.514667 -292.337496) (xy 36.548167 -292.296875)
			(xy 36.587475 -292.261844) (xy 36.63167 -292.233224) (xy 36.679715 -292.211685) (xy 36.730486 -292.197733)
			(xy 36.782791 -292.191695) (xy 36.835405 -292.193712) (xy 36.887095 -292.203736) (xy 36.936648 -292.221534)
			(xy 36.982904 -292.246687) (xy 37.024778 -292.278606) (xy 37.06129 -292.316544) (xy 37.091582 -292.35961)
			(xy 37.114945 -292.406795) (xy 37.130831 -292.456994) (xy 37.138868 -292.50903) (xy 37.139372 -292.535356)
			(xy 43.996105 -292.535356) (xy 44.000135 -292.482858) (xy 44.012132 -292.43159) (xy 44.031815 -292.382755)
			(xy 44.058721 -292.337496) (xy 44.092221 -292.296875) (xy 44.131529 -292.261844) (xy 44.175724 -292.233224)
			(xy 44.223769 -292.211685) (xy 44.27454 -292.197733) (xy 44.326845 -292.191695) (xy 44.379459 -292.193712)
			(xy 44.431149 -292.203736) (xy 44.480702 -292.221534) (xy 44.526958 -292.246687) (xy 44.568832 -292.278606)
			(xy 44.605344 -292.316544) (xy 44.635636 -292.35961) (xy 44.658999 -292.406795) (xy 44.674885 -292.456994)
			(xy 44.682922 -292.50903) (xy 44.683426 -292.535356) (xy 51.540159 -292.535356) (xy 51.544189 -292.482858)
			(xy 51.556186 -292.43159) (xy 51.575869 -292.382755) (xy 51.602775 -292.337496) (xy 51.636275 -292.296875)
			(xy 51.675583 -292.261844) (xy 51.719778 -292.233224) (xy 51.767823 -292.211685) (xy 51.818594 -292.197733)
			(xy 51.870899 -292.191695) (xy 51.923513 -292.193712) (xy 51.975203 -292.203736) (xy 52.024756 -292.221534)
			(xy 52.071012 -292.246687) (xy 52.112886 -292.278606) (xy 52.149398 -292.316544) (xy 52.17969 -292.35961)
			(xy 52.203053 -292.406795) (xy 52.218939 -292.456994) (xy 52.226976 -292.50903) (xy 52.22748 -292.535356)
			(xy 52.226976 -292.561682) (xy 52.218939 -292.613718) (xy 52.203053 -292.663917) (xy 52.17969 -292.711102)
			(xy 52.149398 -292.754168) (xy 52.112886 -292.792106) (xy 52.071012 -292.824025) (xy 52.024756 -292.849178)
			(xy 51.975203 -292.866976) (xy 51.923513 -292.877) (xy 51.870899 -292.879017) (xy 51.818594 -292.872979)
			(xy 51.767823 -292.859027) (xy 51.719778 -292.837488) (xy 51.675583 -292.808868) (xy 51.636275 -292.773837)
			(xy 51.602775 -292.733216) (xy 51.575869 -292.687957) (xy 51.556186 -292.639122) (xy 51.544189 -292.587854)
			(xy 51.540159 -292.535356) (xy 44.683426 -292.535356) (xy 44.682922 -292.561682) (xy 44.674885 -292.613718)
			(xy 44.658999 -292.663917) (xy 44.635636 -292.711102) (xy 44.605344 -292.754168) (xy 44.568832 -292.792106)
			(xy 44.526958 -292.824025) (xy 44.480702 -292.849178) (xy 44.431149 -292.866976) (xy 44.379459 -292.877)
			(xy 44.326845 -292.879017) (xy 44.27454 -292.872979) (xy 44.223769 -292.859027) (xy 44.175724 -292.837488)
			(xy 44.131529 -292.808868) (xy 44.092221 -292.773837) (xy 44.058721 -292.733216) (xy 44.031815 -292.687957)
			(xy 44.012132 -292.639122) (xy 44.000135 -292.587854) (xy 43.996105 -292.535356) (xy 37.139372 -292.535356)
			(xy 37.138868 -292.561682) (xy 37.130831 -292.613718) (xy 37.114945 -292.663917) (xy 37.091582 -292.711102)
			(xy 37.06129 -292.754168) (xy 37.024778 -292.792106) (xy 36.982904 -292.824025) (xy 36.936648 -292.849178)
			(xy 36.887095 -292.866976) (xy 36.835405 -292.877) (xy 36.782791 -292.879017) (xy 36.730486 -292.872979)
			(xy 36.679715 -292.859027) (xy 36.63167 -292.837488) (xy 36.587475 -292.808868) (xy 36.548167 -292.773837)
			(xy 36.514667 -292.733216) (xy 36.487761 -292.687957) (xy 36.468078 -292.639122) (xy 36.456081 -292.587854)
			(xy 36.452051 -292.535356) (xy 29.595572 -292.535356) (xy 29.595068 -292.561682) (xy 29.587031 -292.613718)
			(xy 29.571145 -292.663917) (xy 29.547782 -292.711102) (xy 29.51749 -292.754168) (xy 29.480978 -292.792106)
			(xy 29.439104 -292.824025) (xy 29.392848 -292.849178) (xy 29.343295 -292.866976) (xy 29.291605 -292.877)
			(xy 29.238991 -292.879017) (xy 29.186686 -292.872979) (xy 29.135915 -292.859027) (xy 29.08787 -292.837488)
			(xy 29.043675 -292.808868) (xy 29.004367 -292.773837) (xy 28.970867 -292.733216) (xy 28.943961 -292.687957)
			(xy 28.924278 -292.639122) (xy 28.912281 -292.587854) (xy 28.908251 -292.535356) (xy 22.051518 -292.535356)
			(xy 22.051014 -292.561682) (xy 22.042977 -292.613718) (xy 22.027091 -292.663917) (xy 22.003728 -292.711102)
			(xy 21.973436 -292.754168) (xy 21.936924 -292.792106) (xy 21.89505 -292.824025) (xy 21.848794 -292.849178)
			(xy 21.799241 -292.866976) (xy 21.747551 -292.877) (xy 21.694937 -292.879017) (xy 21.642632 -292.872979)
			(xy 21.591861 -292.859027) (xy 21.543816 -292.837488) (xy 21.499621 -292.808868) (xy 21.460313 -292.773837)
			(xy 21.426813 -292.733216) (xy 21.399907 -292.687957) (xy 21.380224 -292.639122) (xy 21.368227 -292.587854)
			(xy 21.364197 -292.535356) (xy 16.086074 -292.535356) (xy 16.086074 -293.38524) (xy 17.264129 -293.38524)
			(xy 17.268159 -293.332742) (xy 17.280156 -293.281474) (xy 17.299839 -293.232639) (xy 17.326745 -293.18738)
			(xy 17.360245 -293.146759) (xy 17.399553 -293.111728) (xy 17.443748 -293.083108) (xy 17.491793 -293.061569)
			(xy 17.542564 -293.047617) (xy 17.594869 -293.041579) (xy 17.647483 -293.043596) (xy 17.699173 -293.05362)
			(xy 17.748726 -293.071418) (xy 17.794982 -293.096571) (xy 17.836856 -293.12849) (xy 17.873368 -293.166428)
			(xy 17.90366 -293.209494) (xy 17.927023 -293.256679) (xy 17.942909 -293.306878) (xy 17.950946 -293.358914)
			(xy 17.95145 -293.38524) (xy 24.808183 -293.38524) (xy 24.812213 -293.332742) (xy 24.82421 -293.281474)
			(xy 24.843893 -293.232639) (xy 24.870799 -293.18738) (xy 24.904299 -293.146759) (xy 24.943607 -293.111728)
			(xy 24.987802 -293.083108) (xy 25.035847 -293.061569) (xy 25.086618 -293.047617) (xy 25.138923 -293.041579)
			(xy 25.191537 -293.043596) (xy 25.243227 -293.05362) (xy 25.29278 -293.071418) (xy 25.339036 -293.096571)
			(xy 25.38091 -293.12849) (xy 25.417422 -293.166428) (xy 25.447714 -293.209494) (xy 25.471077 -293.256679)
			(xy 25.486963 -293.306878) (xy 25.495 -293.358914) (xy 25.495504 -293.38524) (xy 32.351983 -293.38524)
			(xy 32.356013 -293.332742) (xy 32.36801 -293.281474) (xy 32.387693 -293.232639) (xy 32.414599 -293.18738)
			(xy 32.448099 -293.146759) (xy 32.487407 -293.111728) (xy 32.531602 -293.083108) (xy 32.579647 -293.061569)
			(xy 32.630418 -293.047617) (xy 32.682723 -293.041579) (xy 32.735337 -293.043596) (xy 32.787027 -293.05362)
			(xy 32.83658 -293.071418) (xy 32.882836 -293.096571) (xy 32.92471 -293.12849) (xy 32.961222 -293.166428)
			(xy 32.991514 -293.209494) (xy 33.014877 -293.256679) (xy 33.030763 -293.306878) (xy 33.0388 -293.358914)
			(xy 33.039304 -293.38524) (xy 39.896037 -293.38524) (xy 39.900067 -293.332742) (xy 39.912064 -293.281474)
			(xy 39.931747 -293.232639) (xy 39.958653 -293.18738) (xy 39.992153 -293.146759) (xy 40.031461 -293.111728)
			(xy 40.075656 -293.083108) (xy 40.123701 -293.061569) (xy 40.174472 -293.047617) (xy 40.226777 -293.041579)
			(xy 40.279391 -293.043596) (xy 40.331081 -293.05362) (xy 40.380634 -293.071418) (xy 40.42689 -293.096571)
			(xy 40.468764 -293.12849) (xy 40.505276 -293.166428) (xy 40.535568 -293.209494) (xy 40.558931 -293.256679)
			(xy 40.574817 -293.306878) (xy 40.582854 -293.358914) (xy 40.583358 -293.38524) (xy 47.440091 -293.38524)
			(xy 47.444121 -293.332742) (xy 47.456118 -293.281474) (xy 47.475801 -293.232639) (xy 47.502707 -293.18738)
			(xy 47.536207 -293.146759) (xy 47.575515 -293.111728) (xy 47.61971 -293.083108) (xy 47.667755 -293.061569)
			(xy 47.718526 -293.047617) (xy 47.770831 -293.041579) (xy 47.823445 -293.043596) (xy 47.875135 -293.05362)
			(xy 47.924688 -293.071418) (xy 47.970944 -293.096571) (xy 48.012818 -293.12849) (xy 48.04933 -293.166428)
			(xy 48.079622 -293.209494) (xy 48.102985 -293.256679) (xy 48.118871 -293.306878) (xy 48.126908 -293.358914)
			(xy 48.127412 -293.38524) (xy 48.126908 -293.411566) (xy 48.118871 -293.463602) (xy 48.102985 -293.513801)
			(xy 48.079622 -293.560986) (xy 48.04933 -293.604052) (xy 48.012818 -293.64199) (xy 47.970944 -293.673909)
			(xy 47.924688 -293.699062) (xy 47.875135 -293.71686) (xy 47.823445 -293.726884) (xy 47.770831 -293.728901)
			(xy 47.718526 -293.722863) (xy 47.667755 -293.708911) (xy 47.61971 -293.687372) (xy 47.575515 -293.658752)
			(xy 47.536207 -293.623721) (xy 47.502707 -293.5831) (xy 47.475801 -293.537841) (xy 47.456118 -293.489006)
			(xy 47.444121 -293.437738) (xy 47.440091 -293.38524) (xy 40.583358 -293.38524) (xy 40.582854 -293.411566)
			(xy 40.574817 -293.463602) (xy 40.558931 -293.513801) (xy 40.535568 -293.560986) (xy 40.505276 -293.604052)
			(xy 40.468764 -293.64199) (xy 40.42689 -293.673909) (xy 40.380634 -293.699062) (xy 40.331081 -293.71686)
			(xy 40.279391 -293.726884) (xy 40.226777 -293.728901) (xy 40.174472 -293.722863) (xy 40.123701 -293.708911)
			(xy 40.075656 -293.687372) (xy 40.031461 -293.658752) (xy 39.992153 -293.623721) (xy 39.958653 -293.5831)
			(xy 39.931747 -293.537841) (xy 39.912064 -293.489006) (xy 39.900067 -293.437738) (xy 39.896037 -293.38524)
			(xy 33.039304 -293.38524) (xy 33.0388 -293.411566) (xy 33.030763 -293.463602) (xy 33.014877 -293.513801)
			(xy 32.991514 -293.560986) (xy 32.961222 -293.604052) (xy 32.92471 -293.64199) (xy 32.882836 -293.673909)
			(xy 32.83658 -293.699062) (xy 32.787027 -293.71686) (xy 32.735337 -293.726884) (xy 32.682723 -293.728901)
			(xy 32.630418 -293.722863) (xy 32.579647 -293.708911) (xy 32.531602 -293.687372) (xy 32.487407 -293.658752)
			(xy 32.448099 -293.623721) (xy 32.414599 -293.5831) (xy 32.387693 -293.537841) (xy 32.36801 -293.489006)
			(xy 32.356013 -293.437738) (xy 32.351983 -293.38524) (xy 25.495504 -293.38524) (xy 25.495 -293.411566)
			(xy 25.486963 -293.463602) (xy 25.471077 -293.513801) (xy 25.447714 -293.560986) (xy 25.417422 -293.604052)
			(xy 25.38091 -293.64199) (xy 25.339036 -293.673909) (xy 25.29278 -293.699062) (xy 25.243227 -293.71686)
			(xy 25.191537 -293.726884) (xy 25.138923 -293.728901) (xy 25.086618 -293.722863) (xy 25.035847 -293.708911)
			(xy 24.987802 -293.687372) (xy 24.943607 -293.658752) (xy 24.904299 -293.623721) (xy 24.870799 -293.5831)
			(xy 24.843893 -293.537841) (xy 24.82421 -293.489006) (xy 24.812213 -293.437738) (xy 24.808183 -293.38524)
			(xy 17.95145 -293.38524) (xy 17.950946 -293.411566) (xy 17.942909 -293.463602) (xy 17.927023 -293.513801)
			(xy 17.90366 -293.560986) (xy 17.873368 -293.604052) (xy 17.836856 -293.64199) (xy 17.794982 -293.673909)
			(xy 17.748726 -293.699062) (xy 17.699173 -293.71686) (xy 17.647483 -293.726884) (xy 17.594869 -293.728901)
			(xy 17.542564 -293.722863) (xy 17.491793 -293.708911) (xy 17.443748 -293.687372) (xy 17.399553 -293.658752)
			(xy 17.360245 -293.623721) (xy 17.326745 -293.5831) (xy 17.299839 -293.537841) (xy 17.280156 -293.489006)
			(xy 17.268159 -293.437738) (xy 17.264129 -293.38524) (xy 16.086074 -293.38524) (xy 16.086074 -294.235378)
			(xy 21.364197 -294.235378) (xy 21.368227 -294.18288) (xy 21.380224 -294.131612) (xy 21.399907 -294.082777)
			(xy 21.426813 -294.037518) (xy 21.460313 -293.996897) (xy 21.499621 -293.961866) (xy 21.543816 -293.933246)
			(xy 21.591861 -293.911707) (xy 21.642632 -293.897755) (xy 21.694937 -293.891717) (xy 21.747551 -293.893734)
			(xy 21.799241 -293.903758) (xy 21.848794 -293.921556) (xy 21.89505 -293.946709) (xy 21.936924 -293.978628)
			(xy 21.973436 -294.016566) (xy 22.003728 -294.059632) (xy 22.027091 -294.106817) (xy 22.042977 -294.157016)
			(xy 22.051014 -294.209052) (xy 22.051518 -294.235378) (xy 28.908251 -294.235378) (xy 28.912281 -294.18288)
			(xy 28.924278 -294.131612) (xy 28.943961 -294.082777) (xy 28.970867 -294.037518) (xy 29.004367 -293.996897)
			(xy 29.043675 -293.961866) (xy 29.08787 -293.933246) (xy 29.135915 -293.911707) (xy 29.186686 -293.897755)
			(xy 29.238991 -293.891717) (xy 29.291605 -293.893734) (xy 29.343295 -293.903758) (xy 29.392848 -293.921556)
			(xy 29.439104 -293.946709) (xy 29.480978 -293.978628) (xy 29.51749 -294.016566) (xy 29.547782 -294.059632)
			(xy 29.571145 -294.106817) (xy 29.587031 -294.157016) (xy 29.595068 -294.209052) (xy 29.595572 -294.235378)
			(xy 36.452051 -294.235378) (xy 36.456081 -294.18288) (xy 36.468078 -294.131612) (xy 36.487761 -294.082777)
			(xy 36.514667 -294.037518) (xy 36.548167 -293.996897) (xy 36.587475 -293.961866) (xy 36.63167 -293.933246)
			(xy 36.679715 -293.911707) (xy 36.730486 -293.897755) (xy 36.782791 -293.891717) (xy 36.835405 -293.893734)
			(xy 36.887095 -293.903758) (xy 36.936648 -293.921556) (xy 36.982904 -293.946709) (xy 37.024778 -293.978628)
			(xy 37.06129 -294.016566) (xy 37.091582 -294.059632) (xy 37.114945 -294.106817) (xy 37.130831 -294.157016)
			(xy 37.138868 -294.209052) (xy 37.139372 -294.235378) (xy 43.996105 -294.235378) (xy 44.000135 -294.18288)
			(xy 44.012132 -294.131612) (xy 44.031815 -294.082777) (xy 44.058721 -294.037518) (xy 44.092221 -293.996897)
			(xy 44.131529 -293.961866) (xy 44.175724 -293.933246) (xy 44.223769 -293.911707) (xy 44.27454 -293.897755)
			(xy 44.326845 -293.891717) (xy 44.379459 -293.893734) (xy 44.431149 -293.903758) (xy 44.480702 -293.921556)
			(xy 44.526958 -293.946709) (xy 44.568832 -293.978628) (xy 44.605344 -294.016566) (xy 44.635636 -294.059632)
			(xy 44.658999 -294.106817) (xy 44.674885 -294.157016) (xy 44.682922 -294.209052) (xy 44.683426 -294.235378)
			(xy 51.540159 -294.235378) (xy 51.544189 -294.18288) (xy 51.556186 -294.131612) (xy 51.575869 -294.082777)
			(xy 51.602775 -294.037518) (xy 51.636275 -293.996897) (xy 51.675583 -293.961866) (xy 51.719778 -293.933246)
			(xy 51.767823 -293.911707) (xy 51.818594 -293.897755) (xy 51.870899 -293.891717) (xy 51.923513 -293.893734)
			(xy 51.975203 -293.903758) (xy 52.024756 -293.921556) (xy 52.071012 -293.946709) (xy 52.112886 -293.978628)
			(xy 52.149398 -294.016566) (xy 52.17969 -294.059632) (xy 52.203053 -294.106817) (xy 52.218939 -294.157016)
			(xy 52.226976 -294.209052) (xy 52.22748 -294.235378) (xy 52.226976 -294.261704) (xy 52.218939 -294.31374)
			(xy 52.203053 -294.363939) (xy 52.17969 -294.411124) (xy 52.149398 -294.45419) (xy 52.112886 -294.492128)
			(xy 52.071012 -294.524047) (xy 52.024756 -294.5492) (xy 51.975203 -294.566998) (xy 51.923513 -294.577022)
			(xy 51.870899 -294.579039) (xy 51.818594 -294.573001) (xy 51.767823 -294.559049) (xy 51.719778 -294.53751)
			(xy 51.675583 -294.50889) (xy 51.636275 -294.473859) (xy 51.602775 -294.433238) (xy 51.575869 -294.387979)
			(xy 51.556186 -294.339144) (xy 51.544189 -294.287876) (xy 51.540159 -294.235378) (xy 44.683426 -294.235378)
			(xy 44.682922 -294.261704) (xy 44.674885 -294.31374) (xy 44.658999 -294.363939) (xy 44.635636 -294.411124)
			(xy 44.605344 -294.45419) (xy 44.568832 -294.492128) (xy 44.526958 -294.524047) (xy 44.480702 -294.5492)
			(xy 44.431149 -294.566998) (xy 44.379459 -294.577022) (xy 44.326845 -294.579039) (xy 44.27454 -294.573001)
			(xy 44.223769 -294.559049) (xy 44.175724 -294.53751) (xy 44.131529 -294.50889) (xy 44.092221 -294.473859)
			(xy 44.058721 -294.433238) (xy 44.031815 -294.387979) (xy 44.012132 -294.339144) (xy 44.000135 -294.287876)
			(xy 43.996105 -294.235378) (xy 37.139372 -294.235378) (xy 37.138868 -294.261704) (xy 37.130831 -294.31374)
			(xy 37.114945 -294.363939) (xy 37.091582 -294.411124) (xy 37.06129 -294.45419) (xy 37.024778 -294.492128)
			(xy 36.982904 -294.524047) (xy 36.936648 -294.5492) (xy 36.887095 -294.566998) (xy 36.835405 -294.577022)
			(xy 36.782791 -294.579039) (xy 36.730486 -294.573001) (xy 36.679715 -294.559049) (xy 36.63167 -294.53751)
			(xy 36.587475 -294.50889) (xy 36.548167 -294.473859) (xy 36.514667 -294.433238) (xy 36.487761 -294.387979)
			(xy 36.468078 -294.339144) (xy 36.456081 -294.287876) (xy 36.452051 -294.235378) (xy 29.595572 -294.235378)
			(xy 29.595068 -294.261704) (xy 29.587031 -294.31374) (xy 29.571145 -294.363939) (xy 29.547782 -294.411124)
			(xy 29.51749 -294.45419) (xy 29.480978 -294.492128) (xy 29.439104 -294.524047) (xy 29.392848 -294.5492)
			(xy 29.343295 -294.566998) (xy 29.291605 -294.577022) (xy 29.238991 -294.579039) (xy 29.186686 -294.573001)
			(xy 29.135915 -294.559049) (xy 29.08787 -294.53751) (xy 29.043675 -294.50889) (xy 29.004367 -294.473859)
			(xy 28.970867 -294.433238) (xy 28.943961 -294.387979) (xy 28.924278 -294.339144) (xy 28.912281 -294.287876)
			(xy 28.908251 -294.235378) (xy 22.051518 -294.235378) (xy 22.051014 -294.261704) (xy 22.042977 -294.31374)
			(xy 22.027091 -294.363939) (xy 22.003728 -294.411124) (xy 21.973436 -294.45419) (xy 21.936924 -294.492128)
			(xy 21.89505 -294.524047) (xy 21.848794 -294.5492) (xy 21.799241 -294.566998) (xy 21.747551 -294.577022)
			(xy 21.694937 -294.579039) (xy 21.642632 -294.573001) (xy 21.591861 -294.559049) (xy 21.543816 -294.53751)
			(xy 21.499621 -294.50889) (xy 21.460313 -294.473859) (xy 21.426813 -294.433238) (xy 21.399907 -294.387979)
			(xy 21.380224 -294.339144) (xy 21.368227 -294.287876) (xy 21.364197 -294.235378) (xy 16.086074 -294.235378)
			(xy 16.086074 -295.085262) (xy 17.264129 -295.085262) (xy 17.268159 -295.032764) (xy 17.280156 -294.981496)
			(xy 17.299839 -294.932661) (xy 17.326745 -294.887402) (xy 17.360245 -294.846781) (xy 17.399553 -294.81175)
			(xy 17.443748 -294.78313) (xy 17.491793 -294.761591) (xy 17.542564 -294.747639) (xy 17.594869 -294.741601)
			(xy 17.647483 -294.743618) (xy 17.699173 -294.753642) (xy 17.748726 -294.77144) (xy 17.794982 -294.796593)
			(xy 17.836856 -294.828512) (xy 17.873368 -294.86645) (xy 17.90366 -294.909516) (xy 17.927023 -294.956701)
			(xy 17.942909 -295.0069) (xy 17.950946 -295.058936) (xy 17.95145 -295.085262) (xy 21.364197 -295.085262)
			(xy 21.368227 -295.032764) (xy 21.380224 -294.981496) (xy 21.399907 -294.932661) (xy 21.426813 -294.887402)
			(xy 21.460313 -294.846781) (xy 21.499621 -294.81175) (xy 21.543816 -294.78313) (xy 21.591861 -294.761591)
			(xy 21.642632 -294.747639) (xy 21.694937 -294.741601) (xy 21.747551 -294.743618) (xy 21.799241 -294.753642)
			(xy 21.848794 -294.77144) (xy 21.89505 -294.796593) (xy 21.936924 -294.828512) (xy 21.973436 -294.86645)
			(xy 22.003728 -294.909516) (xy 22.027091 -294.956701) (xy 22.042977 -295.0069) (xy 22.051014 -295.058936)
			(xy 22.051518 -295.085262) (xy 24.808183 -295.085262) (xy 24.812213 -295.032764) (xy 24.82421 -294.981496)
			(xy 24.843893 -294.932661) (xy 24.870799 -294.887402) (xy 24.904299 -294.846781) (xy 24.943607 -294.81175)
			(xy 24.987802 -294.78313) (xy 25.035847 -294.761591) (xy 25.086618 -294.747639) (xy 25.138923 -294.741601)
			(xy 25.191537 -294.743618) (xy 25.243227 -294.753642) (xy 25.29278 -294.77144) (xy 25.339036 -294.796593)
			(xy 25.38091 -294.828512) (xy 25.417422 -294.86645) (xy 25.447714 -294.909516) (xy 25.471077 -294.956701)
			(xy 25.486963 -295.0069) (xy 25.495 -295.058936) (xy 25.495504 -295.085262) (xy 28.908251 -295.085262)
			(xy 28.912281 -295.032764) (xy 28.924278 -294.981496) (xy 28.943961 -294.932661) (xy 28.970867 -294.887402)
			(xy 29.004367 -294.846781) (xy 29.043675 -294.81175) (xy 29.08787 -294.78313) (xy 29.135915 -294.761591)
			(xy 29.186686 -294.747639) (xy 29.238991 -294.741601) (xy 29.291605 -294.743618) (xy 29.343295 -294.753642)
			(xy 29.392848 -294.77144) (xy 29.439104 -294.796593) (xy 29.480978 -294.828512) (xy 29.51749 -294.86645)
			(xy 29.547782 -294.909516) (xy 29.571145 -294.956701) (xy 29.587031 -295.0069) (xy 29.595068 -295.058936)
			(xy 29.595572 -295.085262) (xy 32.351983 -295.085262) (xy 32.356013 -295.032764) (xy 32.36801 -294.981496)
			(xy 32.387693 -294.932661) (xy 32.414599 -294.887402) (xy 32.448099 -294.846781) (xy 32.487407 -294.81175)
			(xy 32.531602 -294.78313) (xy 32.579647 -294.761591) (xy 32.630418 -294.747639) (xy 32.682723 -294.741601)
			(xy 32.735337 -294.743618) (xy 32.787027 -294.753642) (xy 32.83658 -294.77144) (xy 32.882836 -294.796593)
			(xy 32.92471 -294.828512) (xy 32.961222 -294.86645) (xy 32.991514 -294.909516) (xy 33.014877 -294.956701)
			(xy 33.030763 -295.0069) (xy 33.0388 -295.058936) (xy 33.039304 -295.085262) (xy 36.452051 -295.085262)
			(xy 36.456081 -295.032764) (xy 36.468078 -294.981496) (xy 36.487761 -294.932661) (xy 36.514667 -294.887402)
			(xy 36.548167 -294.846781) (xy 36.587475 -294.81175) (xy 36.63167 -294.78313) (xy 36.679715 -294.761591)
			(xy 36.730486 -294.747639) (xy 36.782791 -294.741601) (xy 36.835405 -294.743618) (xy 36.887095 -294.753642)
			(xy 36.936648 -294.77144) (xy 36.982904 -294.796593) (xy 37.024778 -294.828512) (xy 37.06129 -294.86645)
			(xy 37.091582 -294.909516) (xy 37.114945 -294.956701) (xy 37.130831 -295.0069) (xy 37.138868 -295.058936)
			(xy 37.139372 -295.085262) (xy 39.896037 -295.085262) (xy 39.900067 -295.032764) (xy 39.912064 -294.981496)
			(xy 39.931747 -294.932661) (xy 39.958653 -294.887402) (xy 39.992153 -294.846781) (xy 40.031461 -294.81175)
			(xy 40.075656 -294.78313) (xy 40.123701 -294.761591) (xy 40.174472 -294.747639) (xy 40.226777 -294.741601)
			(xy 40.279391 -294.743618) (xy 40.331081 -294.753642) (xy 40.380634 -294.77144) (xy 40.42689 -294.796593)
			(xy 40.468764 -294.828512) (xy 40.505276 -294.86645) (xy 40.535568 -294.909516) (xy 40.558931 -294.956701)
			(xy 40.574817 -295.0069) (xy 40.582854 -295.058936) (xy 40.583358 -295.085262) (xy 43.996105 -295.085262)
			(xy 44.000135 -295.032764) (xy 44.012132 -294.981496) (xy 44.031815 -294.932661) (xy 44.058721 -294.887402)
			(xy 44.092221 -294.846781) (xy 44.131529 -294.81175) (xy 44.175724 -294.78313) (xy 44.223769 -294.761591)
			(xy 44.27454 -294.747639) (xy 44.326845 -294.741601) (xy 44.379459 -294.743618) (xy 44.431149 -294.753642)
			(xy 44.480702 -294.77144) (xy 44.526958 -294.796593) (xy 44.568832 -294.828512) (xy 44.605344 -294.86645)
			(xy 44.635636 -294.909516) (xy 44.658999 -294.956701) (xy 44.674885 -295.0069) (xy 44.682922 -295.058936)
			(xy 44.683426 -295.085262) (xy 47.440091 -295.085262) (xy 47.444121 -295.032764) (xy 47.456118 -294.981496)
			(xy 47.475801 -294.932661) (xy 47.502707 -294.887402) (xy 47.536207 -294.846781) (xy 47.575515 -294.81175)
			(xy 47.61971 -294.78313) (xy 47.667755 -294.761591) (xy 47.718526 -294.747639) (xy 47.770831 -294.741601)
			(xy 47.823445 -294.743618) (xy 47.875135 -294.753642) (xy 47.924688 -294.77144) (xy 47.970944 -294.796593)
			(xy 48.012818 -294.828512) (xy 48.04933 -294.86645) (xy 48.079622 -294.909516) (xy 48.102985 -294.956701)
			(xy 48.118871 -295.0069) (xy 48.126908 -295.058936) (xy 48.127412 -295.085262) (xy 51.540159 -295.085262)
			(xy 51.544189 -295.032764) (xy 51.556186 -294.981496) (xy 51.575869 -294.932661) (xy 51.602775 -294.887402)
			(xy 51.636275 -294.846781) (xy 51.675583 -294.81175) (xy 51.719778 -294.78313) (xy 51.767823 -294.761591)
			(xy 51.818594 -294.747639) (xy 51.870899 -294.741601) (xy 51.923513 -294.743618) (xy 51.975203 -294.753642)
			(xy 52.024756 -294.77144) (xy 52.071012 -294.796593) (xy 52.112886 -294.828512) (xy 52.149398 -294.86645)
			(xy 52.17969 -294.909516) (xy 52.203053 -294.956701) (xy 52.218939 -295.0069) (xy 52.226976 -295.058936)
			(xy 52.22748 -295.085262) (xy 52.226976 -295.111588) (xy 52.218939 -295.163624) (xy 52.203053 -295.213823)
			(xy 52.17969 -295.261008) (xy 52.149398 -295.304074) (xy 52.112886 -295.342012) (xy 52.071012 -295.373931)
			(xy 52.024756 -295.399084) (xy 51.975203 -295.416882) (xy 51.923513 -295.426906) (xy 51.870899 -295.428923)
			(xy 51.818594 -295.422885) (xy 51.767823 -295.408933) (xy 51.719778 -295.387394) (xy 51.675583 -295.358774)
			(xy 51.636275 -295.323743) (xy 51.602775 -295.283122) (xy 51.575869 -295.237863) (xy 51.556186 -295.189028)
			(xy 51.544189 -295.13776) (xy 51.540159 -295.085262) (xy 48.127412 -295.085262) (xy 48.126908 -295.111588)
			(xy 48.118871 -295.163624) (xy 48.102985 -295.213823) (xy 48.079622 -295.261008) (xy 48.04933 -295.304074)
			(xy 48.012818 -295.342012) (xy 47.970944 -295.373931) (xy 47.924688 -295.399084) (xy 47.875135 -295.416882)
			(xy 47.823445 -295.426906) (xy 47.770831 -295.428923) (xy 47.718526 -295.422885) (xy 47.667755 -295.408933)
			(xy 47.61971 -295.387394) (xy 47.575515 -295.358774) (xy 47.536207 -295.323743) (xy 47.502707 -295.283122)
			(xy 47.475801 -295.237863) (xy 47.456118 -295.189028) (xy 47.444121 -295.13776) (xy 47.440091 -295.085262)
			(xy 44.683426 -295.085262) (xy 44.682922 -295.111588) (xy 44.674885 -295.163624) (xy 44.658999 -295.213823)
			(xy 44.635636 -295.261008) (xy 44.605344 -295.304074) (xy 44.568832 -295.342012) (xy 44.526958 -295.373931)
			(xy 44.480702 -295.399084) (xy 44.431149 -295.416882) (xy 44.379459 -295.426906) (xy 44.326845 -295.428923)
			(xy 44.27454 -295.422885) (xy 44.223769 -295.408933) (xy 44.175724 -295.387394) (xy 44.131529 -295.358774)
			(xy 44.092221 -295.323743) (xy 44.058721 -295.283122) (xy 44.031815 -295.237863) (xy 44.012132 -295.189028)
			(xy 44.000135 -295.13776) (xy 43.996105 -295.085262) (xy 40.583358 -295.085262) (xy 40.582854 -295.111588)
			(xy 40.574817 -295.163624) (xy 40.558931 -295.213823) (xy 40.535568 -295.261008) (xy 40.505276 -295.304074)
			(xy 40.468764 -295.342012) (xy 40.42689 -295.373931) (xy 40.380634 -295.399084) (xy 40.331081 -295.416882)
			(xy 40.279391 -295.426906) (xy 40.226777 -295.428923) (xy 40.174472 -295.422885) (xy 40.123701 -295.408933)
			(xy 40.075656 -295.387394) (xy 40.031461 -295.358774) (xy 39.992153 -295.323743) (xy 39.958653 -295.283122)
			(xy 39.931747 -295.237863) (xy 39.912064 -295.189028) (xy 39.900067 -295.13776) (xy 39.896037 -295.085262)
			(xy 37.139372 -295.085262) (xy 37.138868 -295.111588) (xy 37.130831 -295.163624) (xy 37.114945 -295.213823)
			(xy 37.091582 -295.261008) (xy 37.06129 -295.304074) (xy 37.024778 -295.342012) (xy 36.982904 -295.373931)
			(xy 36.936648 -295.399084) (xy 36.887095 -295.416882) (xy 36.835405 -295.426906) (xy 36.782791 -295.428923)
			(xy 36.730486 -295.422885) (xy 36.679715 -295.408933) (xy 36.63167 -295.387394) (xy 36.587475 -295.358774)
			(xy 36.548167 -295.323743) (xy 36.514667 -295.283122) (xy 36.487761 -295.237863) (xy 36.468078 -295.189028)
			(xy 36.456081 -295.13776) (xy 36.452051 -295.085262) (xy 33.039304 -295.085262) (xy 33.0388 -295.111588)
			(xy 33.030763 -295.163624) (xy 33.014877 -295.213823) (xy 32.991514 -295.261008) (xy 32.961222 -295.304074)
			(xy 32.92471 -295.342012) (xy 32.882836 -295.373931) (xy 32.83658 -295.399084) (xy 32.787027 -295.416882)
			(xy 32.735337 -295.426906) (xy 32.682723 -295.428923) (xy 32.630418 -295.422885) (xy 32.579647 -295.408933)
			(xy 32.531602 -295.387394) (xy 32.487407 -295.358774) (xy 32.448099 -295.323743) (xy 32.414599 -295.283122)
			(xy 32.387693 -295.237863) (xy 32.36801 -295.189028) (xy 32.356013 -295.13776) (xy 32.351983 -295.085262)
			(xy 29.595572 -295.085262) (xy 29.595068 -295.111588) (xy 29.587031 -295.163624) (xy 29.571145 -295.213823)
			(xy 29.547782 -295.261008) (xy 29.51749 -295.304074) (xy 29.480978 -295.342012) (xy 29.439104 -295.373931)
			(xy 29.392848 -295.399084) (xy 29.343295 -295.416882) (xy 29.291605 -295.426906) (xy 29.238991 -295.428923)
			(xy 29.186686 -295.422885) (xy 29.135915 -295.408933) (xy 29.08787 -295.387394) (xy 29.043675 -295.358774)
			(xy 29.004367 -295.323743) (xy 28.970867 -295.283122) (xy 28.943961 -295.237863) (xy 28.924278 -295.189028)
			(xy 28.912281 -295.13776) (xy 28.908251 -295.085262) (xy 25.495504 -295.085262) (xy 25.495 -295.111588)
			(xy 25.486963 -295.163624) (xy 25.471077 -295.213823) (xy 25.447714 -295.261008) (xy 25.417422 -295.304074)
			(xy 25.38091 -295.342012) (xy 25.339036 -295.373931) (xy 25.29278 -295.399084) (xy 25.243227 -295.416882)
			(xy 25.191537 -295.426906) (xy 25.138923 -295.428923) (xy 25.086618 -295.422885) (xy 25.035847 -295.408933)
			(xy 24.987802 -295.387394) (xy 24.943607 -295.358774) (xy 24.904299 -295.323743) (xy 24.870799 -295.283122)
			(xy 24.843893 -295.237863) (xy 24.82421 -295.189028) (xy 24.812213 -295.13776) (xy 24.808183 -295.085262)
			(xy 22.051518 -295.085262) (xy 22.051014 -295.111588) (xy 22.042977 -295.163624) (xy 22.027091 -295.213823)
			(xy 22.003728 -295.261008) (xy 21.973436 -295.304074) (xy 21.936924 -295.342012) (xy 21.89505 -295.373931)
			(xy 21.848794 -295.399084) (xy 21.799241 -295.416882) (xy 21.747551 -295.426906) (xy 21.694937 -295.428923)
			(xy 21.642632 -295.422885) (xy 21.591861 -295.408933) (xy 21.543816 -295.387394) (xy 21.499621 -295.358774)
			(xy 21.460313 -295.323743) (xy 21.426813 -295.283122) (xy 21.399907 -295.237863) (xy 21.380224 -295.189028)
			(xy 21.368227 -295.13776) (xy 21.364197 -295.085262) (xy 17.95145 -295.085262) (xy 17.950946 -295.111588)
			(xy 17.942909 -295.163624) (xy 17.927023 -295.213823) (xy 17.90366 -295.261008) (xy 17.873368 -295.304074)
			(xy 17.836856 -295.342012) (xy 17.794982 -295.373931) (xy 17.748726 -295.399084) (xy 17.699173 -295.416882)
			(xy 17.647483 -295.426906) (xy 17.594869 -295.428923) (xy 17.542564 -295.422885) (xy 17.491793 -295.408933)
			(xy 17.443748 -295.387394) (xy 17.399553 -295.358774) (xy 17.360245 -295.323743) (xy 17.326745 -295.283122)
			(xy 17.299839 -295.237863) (xy 17.280156 -295.189028) (xy 17.268159 -295.13776) (xy 17.264129 -295.085262)
			(xy 16.086074 -295.085262) (xy 16.086074 -295.9354) (xy 17.264129 -295.9354) (xy 17.268159 -295.882902)
			(xy 17.280156 -295.831634) (xy 17.299839 -295.782799) (xy 17.326745 -295.73754) (xy 17.360245 -295.696919)
			(xy 17.399553 -295.661888) (xy 17.443748 -295.633268) (xy 17.491793 -295.611729) (xy 17.542564 -295.597777)
			(xy 17.594869 -295.591739) (xy 17.647483 -295.593756) (xy 17.699173 -295.60378) (xy 17.748726 -295.621578)
			(xy 17.794982 -295.646731) (xy 17.836856 -295.67865) (xy 17.873368 -295.716588) (xy 17.90366 -295.759654)
			(xy 17.927023 -295.806839) (xy 17.942909 -295.857038) (xy 17.950946 -295.909074) (xy 17.95145 -295.9354)
			(xy 24.808183 -295.9354) (xy 24.812213 -295.882902) (xy 24.82421 -295.831634) (xy 24.843893 -295.782799)
			(xy 24.870799 -295.73754) (xy 24.904299 -295.696919) (xy 24.943607 -295.661888) (xy 24.987802 -295.633268)
			(xy 25.035847 -295.611729) (xy 25.086618 -295.597777) (xy 25.138923 -295.591739) (xy 25.191537 -295.593756)
			(xy 25.243227 -295.60378) (xy 25.29278 -295.621578) (xy 25.339036 -295.646731) (xy 25.38091 -295.67865)
			(xy 25.417422 -295.716588) (xy 25.447714 -295.759654) (xy 25.471077 -295.806839) (xy 25.486963 -295.857038)
			(xy 25.495 -295.909074) (xy 25.495504 -295.9354) (xy 32.351983 -295.9354) (xy 32.356013 -295.882902)
			(xy 32.36801 -295.831634) (xy 32.387693 -295.782799) (xy 32.414599 -295.73754) (xy 32.448099 -295.696919)
			(xy 32.487407 -295.661888) (xy 32.531602 -295.633268) (xy 32.579647 -295.611729) (xy 32.630418 -295.597777)
			(xy 32.682723 -295.591739) (xy 32.735337 -295.593756) (xy 32.787027 -295.60378) (xy 32.83658 -295.621578)
			(xy 32.882836 -295.646731) (xy 32.92471 -295.67865) (xy 32.961222 -295.716588) (xy 32.991514 -295.759654)
			(xy 33.014877 -295.806839) (xy 33.030763 -295.857038) (xy 33.0388 -295.909074) (xy 33.039304 -295.9354)
			(xy 39.896037 -295.9354) (xy 39.900067 -295.882902) (xy 39.912064 -295.831634) (xy 39.931747 -295.782799)
			(xy 39.958653 -295.73754) (xy 39.992153 -295.696919) (xy 40.031461 -295.661888) (xy 40.075656 -295.633268)
			(xy 40.123701 -295.611729) (xy 40.174472 -295.597777) (xy 40.226777 -295.591739) (xy 40.279391 -295.593756)
			(xy 40.331081 -295.60378) (xy 40.380634 -295.621578) (xy 40.42689 -295.646731) (xy 40.468764 -295.67865)
			(xy 40.505276 -295.716588) (xy 40.535568 -295.759654) (xy 40.558931 -295.806839) (xy 40.574817 -295.857038)
			(xy 40.582854 -295.909074) (xy 40.583358 -295.9354) (xy 47.440091 -295.9354) (xy 47.444121 -295.882902)
			(xy 47.456118 -295.831634) (xy 47.475801 -295.782799) (xy 47.502707 -295.73754) (xy 47.536207 -295.696919)
			(xy 47.575515 -295.661888) (xy 47.61971 -295.633268) (xy 47.667755 -295.611729) (xy 47.718526 -295.597777)
			(xy 47.770831 -295.591739) (xy 47.823445 -295.593756) (xy 47.875135 -295.60378) (xy 47.924688 -295.621578)
			(xy 47.970944 -295.646731) (xy 48.012818 -295.67865) (xy 48.04933 -295.716588) (xy 48.079622 -295.759654)
			(xy 48.102985 -295.806839) (xy 48.118871 -295.857038) (xy 48.126908 -295.909074) (xy 48.127412 -295.9354)
			(xy 48.126908 -295.961726) (xy 48.118871 -296.013762) (xy 48.102985 -296.063961) (xy 48.079622 -296.111146)
			(xy 48.04933 -296.154212) (xy 48.012818 -296.19215) (xy 47.970944 -296.224069) (xy 47.924688 -296.249222)
			(xy 47.875135 -296.26702) (xy 47.823445 -296.277044) (xy 47.770831 -296.279061) (xy 47.718526 -296.273023)
			(xy 47.667755 -296.259071) (xy 47.61971 -296.237532) (xy 47.575515 -296.208912) (xy 47.536207 -296.173881)
			(xy 47.502707 -296.13326) (xy 47.475801 -296.088001) (xy 47.456118 -296.039166) (xy 47.444121 -295.987898)
			(xy 47.440091 -295.9354) (xy 40.583358 -295.9354) (xy 40.582854 -295.961726) (xy 40.574817 -296.013762)
			(xy 40.558931 -296.063961) (xy 40.535568 -296.111146) (xy 40.505276 -296.154212) (xy 40.468764 -296.19215)
			(xy 40.42689 -296.224069) (xy 40.380634 -296.249222) (xy 40.331081 -296.26702) (xy 40.279391 -296.277044)
			(xy 40.226777 -296.279061) (xy 40.174472 -296.273023) (xy 40.123701 -296.259071) (xy 40.075656 -296.237532)
			(xy 40.031461 -296.208912) (xy 39.992153 -296.173881) (xy 39.958653 -296.13326) (xy 39.931747 -296.088001)
			(xy 39.912064 -296.039166) (xy 39.900067 -295.987898) (xy 39.896037 -295.9354) (xy 33.039304 -295.9354)
			(xy 33.0388 -295.961726) (xy 33.030763 -296.013762) (xy 33.014877 -296.063961) (xy 32.991514 -296.111146)
			(xy 32.961222 -296.154212) (xy 32.92471 -296.19215) (xy 32.882836 -296.224069) (xy 32.83658 -296.249222)
			(xy 32.787027 -296.26702) (xy 32.735337 -296.277044) (xy 32.682723 -296.279061) (xy 32.630418 -296.273023)
			(xy 32.579647 -296.259071) (xy 32.531602 -296.237532) (xy 32.487407 -296.208912) (xy 32.448099 -296.173881)
			(xy 32.414599 -296.13326) (xy 32.387693 -296.088001) (xy 32.36801 -296.039166) (xy 32.356013 -295.987898)
			(xy 32.351983 -295.9354) (xy 25.495504 -295.9354) (xy 25.495 -295.961726) (xy 25.486963 -296.013762)
			(xy 25.471077 -296.063961) (xy 25.447714 -296.111146) (xy 25.417422 -296.154212) (xy 25.38091 -296.19215)
			(xy 25.339036 -296.224069) (xy 25.29278 -296.249222) (xy 25.243227 -296.26702) (xy 25.191537 -296.277044)
			(xy 25.138923 -296.279061) (xy 25.086618 -296.273023) (xy 25.035847 -296.259071) (xy 24.987802 -296.237532)
			(xy 24.943607 -296.208912) (xy 24.904299 -296.173881) (xy 24.870799 -296.13326) (xy 24.843893 -296.088001)
			(xy 24.82421 -296.039166) (xy 24.812213 -295.987898) (xy 24.808183 -295.9354) (xy 17.95145 -295.9354)
			(xy 17.950946 -295.961726) (xy 17.942909 -296.013762) (xy 17.927023 -296.063961) (xy 17.90366 -296.111146)
			(xy 17.873368 -296.154212) (xy 17.836856 -296.19215) (xy 17.794982 -296.224069) (xy 17.748726 -296.249222)
			(xy 17.699173 -296.26702) (xy 17.647483 -296.277044) (xy 17.594869 -296.279061) (xy 17.542564 -296.273023)
			(xy 17.491793 -296.259071) (xy 17.443748 -296.237532) (xy 17.399553 -296.208912) (xy 17.360245 -296.173881)
			(xy 17.326745 -296.13326) (xy 17.299839 -296.088001) (xy 17.280156 -296.039166) (xy 17.268159 -295.987898)
			(xy 17.264129 -295.9354) (xy 16.086074 -295.9354) (xy 16.086074 -296.785284) (xy 21.364197 -296.785284)
			(xy 21.368227 -296.732786) (xy 21.380224 -296.681518) (xy 21.399907 -296.632683) (xy 21.426813 -296.587424)
			(xy 21.460313 -296.546803) (xy 21.499621 -296.511772) (xy 21.543816 -296.483152) (xy 21.591861 -296.461613)
			(xy 21.642632 -296.447661) (xy 21.694937 -296.441623) (xy 21.747551 -296.44364) (xy 21.799241 -296.453664)
			(xy 21.848794 -296.471462) (xy 21.89505 -296.496615) (xy 21.936924 -296.528534) (xy 21.973436 -296.566472)
			(xy 22.003728 -296.609538) (xy 22.027091 -296.656723) (xy 22.042977 -296.706922) (xy 22.051014 -296.758958)
			(xy 22.051518 -296.785284) (xy 28.908251 -296.785284) (xy 28.912281 -296.732786) (xy 28.924278 -296.681518)
			(xy 28.943961 -296.632683) (xy 28.970867 -296.587424) (xy 29.004367 -296.546803) (xy 29.043675 -296.511772)
			(xy 29.08787 -296.483152) (xy 29.135915 -296.461613) (xy 29.186686 -296.447661) (xy 29.238991 -296.441623)
			(xy 29.291605 -296.44364) (xy 29.343295 -296.453664) (xy 29.392848 -296.471462) (xy 29.439104 -296.496615)
			(xy 29.480978 -296.528534) (xy 29.51749 -296.566472) (xy 29.547782 -296.609538) (xy 29.571145 -296.656723)
			(xy 29.587031 -296.706922) (xy 29.595068 -296.758958) (xy 29.595572 -296.785284) (xy 36.452051 -296.785284)
			(xy 36.456081 -296.732786) (xy 36.468078 -296.681518) (xy 36.487761 -296.632683) (xy 36.514667 -296.587424)
			(xy 36.548167 -296.546803) (xy 36.587475 -296.511772) (xy 36.63167 -296.483152) (xy 36.679715 -296.461613)
			(xy 36.730486 -296.447661) (xy 36.782791 -296.441623) (xy 36.835405 -296.44364) (xy 36.887095 -296.453664)
			(xy 36.936648 -296.471462) (xy 36.982904 -296.496615) (xy 37.024778 -296.528534) (xy 37.06129 -296.566472)
			(xy 37.091582 -296.609538) (xy 37.114945 -296.656723) (xy 37.130831 -296.706922) (xy 37.138868 -296.758958)
			(xy 37.139372 -296.785284) (xy 43.996105 -296.785284) (xy 44.000135 -296.732786) (xy 44.012132 -296.681518)
			(xy 44.031815 -296.632683) (xy 44.058721 -296.587424) (xy 44.092221 -296.546803) (xy 44.131529 -296.511772)
			(xy 44.175724 -296.483152) (xy 44.223769 -296.461613) (xy 44.27454 -296.447661) (xy 44.326845 -296.441623)
			(xy 44.379459 -296.44364) (xy 44.431149 -296.453664) (xy 44.480702 -296.471462) (xy 44.526958 -296.496615)
			(xy 44.568832 -296.528534) (xy 44.605344 -296.566472) (xy 44.635636 -296.609538) (xy 44.658999 -296.656723)
			(xy 44.674885 -296.706922) (xy 44.682922 -296.758958) (xy 44.683426 -296.785284) (xy 51.540159 -296.785284)
			(xy 51.544189 -296.732786) (xy 51.556186 -296.681518) (xy 51.575869 -296.632683) (xy 51.602775 -296.587424)
			(xy 51.636275 -296.546803) (xy 51.675583 -296.511772) (xy 51.719778 -296.483152) (xy 51.767823 -296.461613)
			(xy 51.818594 -296.447661) (xy 51.870899 -296.441623) (xy 51.923513 -296.44364) (xy 51.975203 -296.453664)
			(xy 52.024756 -296.471462) (xy 52.071012 -296.496615) (xy 52.112886 -296.528534) (xy 52.149398 -296.566472)
			(xy 52.17969 -296.609538) (xy 52.203053 -296.656723) (xy 52.218939 -296.706922) (xy 52.226976 -296.758958)
			(xy 52.22748 -296.785284) (xy 52.226976 -296.81161) (xy 52.218939 -296.863646) (xy 52.203053 -296.913845)
			(xy 52.17969 -296.96103) (xy 52.149398 -297.004096) (xy 52.112886 -297.042034) (xy 52.071012 -297.073953)
			(xy 52.024756 -297.099106) (xy 51.975203 -297.116904) (xy 51.923513 -297.126928) (xy 51.870899 -297.128945)
			(xy 51.818594 -297.122907) (xy 51.767823 -297.108955) (xy 51.719778 -297.087416) (xy 51.675583 -297.058796)
			(xy 51.636275 -297.023765) (xy 51.602775 -296.983144) (xy 51.575869 -296.937885) (xy 51.556186 -296.88905)
			(xy 51.544189 -296.837782) (xy 51.540159 -296.785284) (xy 44.683426 -296.785284) (xy 44.682922 -296.81161)
			(xy 44.674885 -296.863646) (xy 44.658999 -296.913845) (xy 44.635636 -296.96103) (xy 44.605344 -297.004096)
			(xy 44.568832 -297.042034) (xy 44.526958 -297.073953) (xy 44.480702 -297.099106) (xy 44.431149 -297.116904)
			(xy 44.379459 -297.126928) (xy 44.326845 -297.128945) (xy 44.27454 -297.122907) (xy 44.223769 -297.108955)
			(xy 44.175724 -297.087416) (xy 44.131529 -297.058796) (xy 44.092221 -297.023765) (xy 44.058721 -296.983144)
			(xy 44.031815 -296.937885) (xy 44.012132 -296.88905) (xy 44.000135 -296.837782) (xy 43.996105 -296.785284)
			(xy 37.139372 -296.785284) (xy 37.138868 -296.81161) (xy 37.130831 -296.863646) (xy 37.114945 -296.913845)
			(xy 37.091582 -296.96103) (xy 37.06129 -297.004096) (xy 37.024778 -297.042034) (xy 36.982904 -297.073953)
			(xy 36.936648 -297.099106) (xy 36.887095 -297.116904) (xy 36.835405 -297.126928) (xy 36.782791 -297.128945)
			(xy 36.730486 -297.122907) (xy 36.679715 -297.108955) (xy 36.63167 -297.087416) (xy 36.587475 -297.058796)
			(xy 36.548167 -297.023765) (xy 36.514667 -296.983144) (xy 36.487761 -296.937885) (xy 36.468078 -296.88905)
			(xy 36.456081 -296.837782) (xy 36.452051 -296.785284) (xy 29.595572 -296.785284) (xy 29.595068 -296.81161)
			(xy 29.587031 -296.863646) (xy 29.571145 -296.913845) (xy 29.547782 -296.96103) (xy 29.51749 -297.004096)
			(xy 29.480978 -297.042034) (xy 29.439104 -297.073953) (xy 29.392848 -297.099106) (xy 29.343295 -297.116904)
			(xy 29.291605 -297.126928) (xy 29.238991 -297.128945) (xy 29.186686 -297.122907) (xy 29.135915 -297.108955)
			(xy 29.08787 -297.087416) (xy 29.043675 -297.058796) (xy 29.004367 -297.023765) (xy 28.970867 -296.983144)
			(xy 28.943961 -296.937885) (xy 28.924278 -296.88905) (xy 28.912281 -296.837782) (xy 28.908251 -296.785284)
			(xy 22.051518 -296.785284) (xy 22.051014 -296.81161) (xy 22.042977 -296.863646) (xy 22.027091 -296.913845)
			(xy 22.003728 -296.96103) (xy 21.973436 -297.004096) (xy 21.936924 -297.042034) (xy 21.89505 -297.073953)
			(xy 21.848794 -297.099106) (xy 21.799241 -297.116904) (xy 21.747551 -297.126928) (xy 21.694937 -297.128945)
			(xy 21.642632 -297.122907) (xy 21.591861 -297.108955) (xy 21.543816 -297.087416) (xy 21.499621 -297.058796)
			(xy 21.460313 -297.023765) (xy 21.426813 -296.983144) (xy 21.399907 -296.937885) (xy 21.380224 -296.88905)
			(xy 21.368227 -296.837782) (xy 21.364197 -296.785284) (xy 16.086074 -296.785284) (xy 16.086074 -297.635422)
			(xy 17.264129 -297.635422) (xy 17.268159 -297.582924) (xy 17.280156 -297.531656) (xy 17.299839 -297.482821)
			(xy 17.326745 -297.437562) (xy 17.360245 -297.396941) (xy 17.399553 -297.36191) (xy 17.443748 -297.33329)
			(xy 17.491793 -297.311751) (xy 17.542564 -297.297799) (xy 17.594869 -297.291761) (xy 17.647483 -297.293778)
			(xy 17.699173 -297.303802) (xy 17.748726 -297.3216) (xy 17.794982 -297.346753) (xy 17.836856 -297.378672)
			(xy 17.873368 -297.41661) (xy 17.90366 -297.459676) (xy 17.927023 -297.506861) (xy 17.942909 -297.55706)
			(xy 17.950946 -297.609096) (xy 17.95145 -297.635422) (xy 24.808183 -297.635422) (xy 24.812213 -297.582924)
			(xy 24.82421 -297.531656) (xy 24.843893 -297.482821) (xy 24.870799 -297.437562) (xy 24.904299 -297.396941)
			(xy 24.943607 -297.36191) (xy 24.987802 -297.33329) (xy 25.035847 -297.311751) (xy 25.086618 -297.297799)
			(xy 25.138923 -297.291761) (xy 25.191537 -297.293778) (xy 25.243227 -297.303802) (xy 25.29278 -297.3216)
			(xy 25.339036 -297.346753) (xy 25.38091 -297.378672) (xy 25.417422 -297.41661) (xy 25.447714 -297.459676)
			(xy 25.471077 -297.506861) (xy 25.486963 -297.55706) (xy 25.495 -297.609096) (xy 25.495504 -297.635422)
			(xy 32.351983 -297.635422) (xy 32.356013 -297.582924) (xy 32.36801 -297.531656) (xy 32.387693 -297.482821)
			(xy 32.414599 -297.437562) (xy 32.448099 -297.396941) (xy 32.487407 -297.36191) (xy 32.531602 -297.33329)
			(xy 32.579647 -297.311751) (xy 32.630418 -297.297799) (xy 32.682723 -297.291761) (xy 32.735337 -297.293778)
			(xy 32.787027 -297.303802) (xy 32.83658 -297.3216) (xy 32.882836 -297.346753) (xy 32.92471 -297.378672)
			(xy 32.961222 -297.41661) (xy 32.991514 -297.459676) (xy 33.014877 -297.506861) (xy 33.030763 -297.55706)
			(xy 33.0388 -297.609096) (xy 33.039304 -297.635422) (xy 39.896037 -297.635422) (xy 39.900067 -297.582924)
			(xy 39.912064 -297.531656) (xy 39.931747 -297.482821) (xy 39.958653 -297.437562) (xy 39.992153 -297.396941)
			(xy 40.031461 -297.36191) (xy 40.075656 -297.33329) (xy 40.123701 -297.311751) (xy 40.174472 -297.297799)
			(xy 40.226777 -297.291761) (xy 40.279391 -297.293778) (xy 40.331081 -297.303802) (xy 40.380634 -297.3216)
			(xy 40.42689 -297.346753) (xy 40.468764 -297.378672) (xy 40.505276 -297.41661) (xy 40.535568 -297.459676)
			(xy 40.558931 -297.506861) (xy 40.574817 -297.55706) (xy 40.582854 -297.609096) (xy 40.583358 -297.635422)
			(xy 47.440091 -297.635422) (xy 47.444121 -297.582924) (xy 47.456118 -297.531656) (xy 47.475801 -297.482821)
			(xy 47.502707 -297.437562) (xy 47.536207 -297.396941) (xy 47.575515 -297.36191) (xy 47.61971 -297.33329)
			(xy 47.667755 -297.311751) (xy 47.718526 -297.297799) (xy 47.770831 -297.291761) (xy 47.823445 -297.293778)
			(xy 47.875135 -297.303802) (xy 47.924688 -297.3216) (xy 47.970944 -297.346753) (xy 48.012818 -297.378672)
			(xy 48.04933 -297.41661) (xy 48.079622 -297.459676) (xy 48.102985 -297.506861) (xy 48.118871 -297.55706)
			(xy 48.126908 -297.609096) (xy 48.127412 -297.635422) (xy 48.126908 -297.661748) (xy 48.118871 -297.713784)
			(xy 48.102985 -297.763983) (xy 48.079622 -297.811168) (xy 48.04933 -297.854234) (xy 48.012818 -297.892172)
			(xy 47.970944 -297.924091) (xy 47.924688 -297.949244) (xy 47.875135 -297.967042) (xy 47.823445 -297.977066)
			(xy 47.770831 -297.979083) (xy 47.718526 -297.973045) (xy 47.667755 -297.959093) (xy 47.61971 -297.937554)
			(xy 47.575515 -297.908934) (xy 47.536207 -297.873903) (xy 47.502707 -297.833282) (xy 47.475801 -297.788023)
			(xy 47.456118 -297.739188) (xy 47.444121 -297.68792) (xy 47.440091 -297.635422) (xy 40.583358 -297.635422)
			(xy 40.582854 -297.661748) (xy 40.574817 -297.713784) (xy 40.558931 -297.763983) (xy 40.535568 -297.811168)
			(xy 40.505276 -297.854234) (xy 40.468764 -297.892172) (xy 40.42689 -297.924091) (xy 40.380634 -297.949244)
			(xy 40.331081 -297.967042) (xy 40.279391 -297.977066) (xy 40.226777 -297.979083) (xy 40.174472 -297.973045)
			(xy 40.123701 -297.959093) (xy 40.075656 -297.937554) (xy 40.031461 -297.908934) (xy 39.992153 -297.873903)
			(xy 39.958653 -297.833282) (xy 39.931747 -297.788023) (xy 39.912064 -297.739188) (xy 39.900067 -297.68792)
			(xy 39.896037 -297.635422) (xy 33.039304 -297.635422) (xy 33.0388 -297.661748) (xy 33.030763 -297.713784)
			(xy 33.014877 -297.763983) (xy 32.991514 -297.811168) (xy 32.961222 -297.854234) (xy 32.92471 -297.892172)
			(xy 32.882836 -297.924091) (xy 32.83658 -297.949244) (xy 32.787027 -297.967042) (xy 32.735337 -297.977066)
			(xy 32.682723 -297.979083) (xy 32.630418 -297.973045) (xy 32.579647 -297.959093) (xy 32.531602 -297.937554)
			(xy 32.487407 -297.908934) (xy 32.448099 -297.873903) (xy 32.414599 -297.833282) (xy 32.387693 -297.788023)
			(xy 32.36801 -297.739188) (xy 32.356013 -297.68792) (xy 32.351983 -297.635422) (xy 25.495504 -297.635422)
			(xy 25.495 -297.661748) (xy 25.486963 -297.713784) (xy 25.471077 -297.763983) (xy 25.447714 -297.811168)
			(xy 25.417422 -297.854234) (xy 25.38091 -297.892172) (xy 25.339036 -297.924091) (xy 25.29278 -297.949244)
			(xy 25.243227 -297.967042) (xy 25.191537 -297.977066) (xy 25.138923 -297.979083) (xy 25.086618 -297.973045)
			(xy 25.035847 -297.959093) (xy 24.987802 -297.937554) (xy 24.943607 -297.908934) (xy 24.904299 -297.873903)
			(xy 24.870799 -297.833282) (xy 24.843893 -297.788023) (xy 24.82421 -297.739188) (xy 24.812213 -297.68792)
			(xy 24.808183 -297.635422) (xy 17.95145 -297.635422) (xy 17.950946 -297.661748) (xy 17.942909 -297.713784)
			(xy 17.927023 -297.763983) (xy 17.90366 -297.811168) (xy 17.873368 -297.854234) (xy 17.836856 -297.892172)
			(xy 17.794982 -297.924091) (xy 17.748726 -297.949244) (xy 17.699173 -297.967042) (xy 17.647483 -297.977066)
			(xy 17.594869 -297.979083) (xy 17.542564 -297.973045) (xy 17.491793 -297.959093) (xy 17.443748 -297.937554)
			(xy 17.399553 -297.908934) (xy 17.360245 -297.873903) (xy 17.326745 -297.833282) (xy 17.299839 -297.788023)
			(xy 17.280156 -297.739188) (xy 17.268159 -297.68792) (xy 17.264129 -297.635422) (xy 16.086074 -297.635422)
			(xy 16.086074 -298.485306) (xy 21.364197 -298.485306) (xy 21.368227 -298.432808) (xy 21.380224 -298.38154)
			(xy 21.399907 -298.332705) (xy 21.426813 -298.287446) (xy 21.460313 -298.246825) (xy 21.499621 -298.211794)
			(xy 21.543816 -298.183174) (xy 21.591861 -298.161635) (xy 21.642632 -298.147683) (xy 21.694937 -298.141645)
			(xy 21.747551 -298.143662) (xy 21.799241 -298.153686) (xy 21.848794 -298.171484) (xy 21.89505 -298.196637)
			(xy 21.936924 -298.228556) (xy 21.973436 -298.266494) (xy 22.003728 -298.30956) (xy 22.027091 -298.356745)
			(xy 22.042977 -298.406944) (xy 22.051014 -298.45898) (xy 22.051518 -298.485306) (xy 28.908251 -298.485306)
			(xy 28.912281 -298.432808) (xy 28.924278 -298.38154) (xy 28.943961 -298.332705) (xy 28.970867 -298.287446)
			(xy 29.004367 -298.246825) (xy 29.043675 -298.211794) (xy 29.08787 -298.183174) (xy 29.135915 -298.161635)
			(xy 29.186686 -298.147683) (xy 29.238991 -298.141645) (xy 29.291605 -298.143662) (xy 29.343295 -298.153686)
			(xy 29.392848 -298.171484) (xy 29.439104 -298.196637) (xy 29.480978 -298.228556) (xy 29.51749 -298.266494)
			(xy 29.547782 -298.30956) (xy 29.571145 -298.356745) (xy 29.587031 -298.406944) (xy 29.595068 -298.45898)
			(xy 29.595572 -298.485306) (xy 36.452051 -298.485306) (xy 36.456081 -298.432808) (xy 36.468078 -298.38154)
			(xy 36.487761 -298.332705) (xy 36.514667 -298.287446) (xy 36.548167 -298.246825) (xy 36.587475 -298.211794)
			(xy 36.63167 -298.183174) (xy 36.679715 -298.161635) (xy 36.730486 -298.147683) (xy 36.782791 -298.141645)
			(xy 36.835405 -298.143662) (xy 36.887095 -298.153686) (xy 36.936648 -298.171484) (xy 36.982904 -298.196637)
			(xy 37.024778 -298.228556) (xy 37.06129 -298.266494) (xy 37.091582 -298.30956) (xy 37.114945 -298.356745)
			(xy 37.130831 -298.406944) (xy 37.138868 -298.45898) (xy 37.139372 -298.485306) (xy 43.996105 -298.485306)
			(xy 44.000135 -298.432808) (xy 44.012132 -298.38154) (xy 44.031815 -298.332705) (xy 44.058721 -298.287446)
			(xy 44.092221 -298.246825) (xy 44.131529 -298.211794) (xy 44.175724 -298.183174) (xy 44.223769 -298.161635)
			(xy 44.27454 -298.147683) (xy 44.326845 -298.141645) (xy 44.379459 -298.143662) (xy 44.431149 -298.153686)
			(xy 44.480702 -298.171484) (xy 44.526958 -298.196637) (xy 44.568832 -298.228556) (xy 44.605344 -298.266494)
			(xy 44.635636 -298.30956) (xy 44.658999 -298.356745) (xy 44.674885 -298.406944) (xy 44.682922 -298.45898)
			(xy 44.683426 -298.485306) (xy 51.540159 -298.485306) (xy 51.544189 -298.432808) (xy 51.556186 -298.38154)
			(xy 51.575869 -298.332705) (xy 51.602775 -298.287446) (xy 51.636275 -298.246825) (xy 51.675583 -298.211794)
			(xy 51.719778 -298.183174) (xy 51.767823 -298.161635) (xy 51.818594 -298.147683) (xy 51.870899 -298.141645)
			(xy 51.923513 -298.143662) (xy 51.975203 -298.153686) (xy 52.024756 -298.171484) (xy 52.071012 -298.196637)
			(xy 52.112886 -298.228556) (xy 52.149398 -298.266494) (xy 52.17969 -298.30956) (xy 52.203053 -298.356745)
			(xy 52.218939 -298.406944) (xy 52.226976 -298.45898) (xy 52.22748 -298.485306) (xy 52.226976 -298.511632)
			(xy 52.218939 -298.563668) (xy 52.203053 -298.613867) (xy 52.17969 -298.661052) (xy 52.149398 -298.704118)
			(xy 52.112886 -298.742056) (xy 52.071012 -298.773975) (xy 52.024756 -298.799128) (xy 51.975203 -298.816926)
			(xy 51.923513 -298.82695) (xy 51.870899 -298.828967) (xy 51.818594 -298.822929) (xy 51.767823 -298.808977)
			(xy 51.719778 -298.787438) (xy 51.675583 -298.758818) (xy 51.636275 -298.723787) (xy 51.602775 -298.683166)
			(xy 51.575869 -298.637907) (xy 51.556186 -298.589072) (xy 51.544189 -298.537804) (xy 51.540159 -298.485306)
			(xy 44.683426 -298.485306) (xy 44.682922 -298.511632) (xy 44.674885 -298.563668) (xy 44.658999 -298.613867)
			(xy 44.635636 -298.661052) (xy 44.605344 -298.704118) (xy 44.568832 -298.742056) (xy 44.526958 -298.773975)
			(xy 44.480702 -298.799128) (xy 44.431149 -298.816926) (xy 44.379459 -298.82695) (xy 44.326845 -298.828967)
			(xy 44.27454 -298.822929) (xy 44.223769 -298.808977) (xy 44.175724 -298.787438) (xy 44.131529 -298.758818)
			(xy 44.092221 -298.723787) (xy 44.058721 -298.683166) (xy 44.031815 -298.637907) (xy 44.012132 -298.589072)
			(xy 44.000135 -298.537804) (xy 43.996105 -298.485306) (xy 37.139372 -298.485306) (xy 37.138868 -298.511632)
			(xy 37.130831 -298.563668) (xy 37.114945 -298.613867) (xy 37.091582 -298.661052) (xy 37.06129 -298.704118)
			(xy 37.024778 -298.742056) (xy 36.982904 -298.773975) (xy 36.936648 -298.799128) (xy 36.887095 -298.816926)
			(xy 36.835405 -298.82695) (xy 36.782791 -298.828967) (xy 36.730486 -298.822929) (xy 36.679715 -298.808977)
			(xy 36.63167 -298.787438) (xy 36.587475 -298.758818) (xy 36.548167 -298.723787) (xy 36.514667 -298.683166)
			(xy 36.487761 -298.637907) (xy 36.468078 -298.589072) (xy 36.456081 -298.537804) (xy 36.452051 -298.485306)
			(xy 29.595572 -298.485306) (xy 29.595068 -298.511632) (xy 29.587031 -298.563668) (xy 29.571145 -298.613867)
			(xy 29.547782 -298.661052) (xy 29.51749 -298.704118) (xy 29.480978 -298.742056) (xy 29.439104 -298.773975)
			(xy 29.392848 -298.799128) (xy 29.343295 -298.816926) (xy 29.291605 -298.82695) (xy 29.238991 -298.828967)
			(xy 29.186686 -298.822929) (xy 29.135915 -298.808977) (xy 29.08787 -298.787438) (xy 29.043675 -298.758818)
			(xy 29.004367 -298.723787) (xy 28.970867 -298.683166) (xy 28.943961 -298.637907) (xy 28.924278 -298.589072)
			(xy 28.912281 -298.537804) (xy 28.908251 -298.485306) (xy 22.051518 -298.485306) (xy 22.051014 -298.511632)
			(xy 22.042977 -298.563668) (xy 22.027091 -298.613867) (xy 22.003728 -298.661052) (xy 21.973436 -298.704118)
			(xy 21.936924 -298.742056) (xy 21.89505 -298.773975) (xy 21.848794 -298.799128) (xy 21.799241 -298.816926)
			(xy 21.747551 -298.82695) (xy 21.694937 -298.828967) (xy 21.642632 -298.822929) (xy 21.591861 -298.808977)
			(xy 21.543816 -298.787438) (xy 21.499621 -298.758818) (xy 21.460313 -298.723787) (xy 21.426813 -298.683166)
			(xy 21.399907 -298.637907) (xy 21.380224 -298.589072) (xy 21.368227 -298.537804) (xy 21.364197 -298.485306)
			(xy 16.086074 -298.485306) (xy 16.086074 -299.335444) (xy 17.264129 -299.335444) (xy 17.268159 -299.282946)
			(xy 17.280156 -299.231678) (xy 17.299839 -299.182843) (xy 17.326745 -299.137584) (xy 17.360245 -299.096963)
			(xy 17.399553 -299.061932) (xy 17.443748 -299.033312) (xy 17.491793 -299.011773) (xy 17.542564 -298.997821)
			(xy 17.594869 -298.991783) (xy 17.647483 -298.9938) (xy 17.699173 -299.003824) (xy 17.748726 -299.021622)
			(xy 17.794982 -299.046775) (xy 17.836856 -299.078694) (xy 17.873368 -299.116632) (xy 17.90366 -299.159698)
			(xy 17.927023 -299.206883) (xy 17.942909 -299.257082) (xy 17.950946 -299.309118) (xy 17.95145 -299.335444)
			(xy 24.808183 -299.335444) (xy 24.812213 -299.282946) (xy 24.82421 -299.231678) (xy 24.843893 -299.182843)
			(xy 24.870799 -299.137584) (xy 24.904299 -299.096963) (xy 24.943607 -299.061932) (xy 24.987802 -299.033312)
			(xy 25.035847 -299.011773) (xy 25.086618 -298.997821) (xy 25.138923 -298.991783) (xy 25.191537 -298.9938)
			(xy 25.243227 -299.003824) (xy 25.29278 -299.021622) (xy 25.339036 -299.046775) (xy 25.38091 -299.078694)
			(xy 25.417422 -299.116632) (xy 25.447714 -299.159698) (xy 25.471077 -299.206883) (xy 25.486963 -299.257082)
			(xy 25.495 -299.309118) (xy 25.495504 -299.335444) (xy 32.351983 -299.335444) (xy 32.356013 -299.282946)
			(xy 32.36801 -299.231678) (xy 32.387693 -299.182843) (xy 32.414599 -299.137584) (xy 32.448099 -299.096963)
			(xy 32.487407 -299.061932) (xy 32.531602 -299.033312) (xy 32.579647 -299.011773) (xy 32.630418 -298.997821)
			(xy 32.682723 -298.991783) (xy 32.735337 -298.9938) (xy 32.787027 -299.003824) (xy 32.83658 -299.021622)
			(xy 32.882836 -299.046775) (xy 32.92471 -299.078694) (xy 32.961222 -299.116632) (xy 32.991514 -299.159698)
			(xy 33.014877 -299.206883) (xy 33.030763 -299.257082) (xy 33.0388 -299.309118) (xy 33.039304 -299.335444)
			(xy 39.896037 -299.335444) (xy 39.900067 -299.282946) (xy 39.912064 -299.231678) (xy 39.931747 -299.182843)
			(xy 39.958653 -299.137584) (xy 39.992153 -299.096963) (xy 40.031461 -299.061932) (xy 40.075656 -299.033312)
			(xy 40.123701 -299.011773) (xy 40.174472 -298.997821) (xy 40.226777 -298.991783) (xy 40.279391 -298.9938)
			(xy 40.331081 -299.003824) (xy 40.380634 -299.021622) (xy 40.42689 -299.046775) (xy 40.468764 -299.078694)
			(xy 40.505276 -299.116632) (xy 40.535568 -299.159698) (xy 40.558931 -299.206883) (xy 40.574817 -299.257082)
			(xy 40.582854 -299.309118) (xy 40.583358 -299.335444) (xy 47.440091 -299.335444) (xy 47.444121 -299.282946)
			(xy 47.456118 -299.231678) (xy 47.475801 -299.182843) (xy 47.502707 -299.137584) (xy 47.536207 -299.096963)
			(xy 47.575515 -299.061932) (xy 47.61971 -299.033312) (xy 47.667755 -299.011773) (xy 47.718526 -298.997821)
			(xy 47.770831 -298.991783) (xy 47.823445 -298.9938) (xy 47.875135 -299.003824) (xy 47.924688 -299.021622)
			(xy 47.970944 -299.046775) (xy 48.012818 -299.078694) (xy 48.04933 -299.116632) (xy 48.079622 -299.159698)
			(xy 48.102985 -299.206883) (xy 48.118871 -299.257082) (xy 48.126908 -299.309118) (xy 48.127412 -299.335444)
			(xy 48.126908 -299.36177) (xy 48.118871 -299.413806) (xy 48.102985 -299.464005) (xy 48.079622 -299.51119)
			(xy 48.04933 -299.554256) (xy 48.012818 -299.592194) (xy 47.970944 -299.624113) (xy 47.924688 -299.649266)
			(xy 47.875135 -299.667064) (xy 47.823445 -299.677088) (xy 47.770831 -299.679105) (xy 47.718526 -299.673067)
			(xy 47.667755 -299.659115) (xy 47.61971 -299.637576) (xy 47.575515 -299.608956) (xy 47.536207 -299.573925)
			(xy 47.502707 -299.533304) (xy 47.475801 -299.488045) (xy 47.456118 -299.43921) (xy 47.444121 -299.387942)
			(xy 47.440091 -299.335444) (xy 40.583358 -299.335444) (xy 40.582854 -299.36177) (xy 40.574817 -299.413806)
			(xy 40.558931 -299.464005) (xy 40.535568 -299.51119) (xy 40.505276 -299.554256) (xy 40.468764 -299.592194)
			(xy 40.42689 -299.624113) (xy 40.380634 -299.649266) (xy 40.331081 -299.667064) (xy 40.279391 -299.677088)
			(xy 40.226777 -299.679105) (xy 40.174472 -299.673067) (xy 40.123701 -299.659115) (xy 40.075656 -299.637576)
			(xy 40.031461 -299.608956) (xy 39.992153 -299.573925) (xy 39.958653 -299.533304) (xy 39.931747 -299.488045)
			(xy 39.912064 -299.43921) (xy 39.900067 -299.387942) (xy 39.896037 -299.335444) (xy 33.039304 -299.335444)
			(xy 33.0388 -299.36177) (xy 33.030763 -299.413806) (xy 33.014877 -299.464005) (xy 32.991514 -299.51119)
			(xy 32.961222 -299.554256) (xy 32.92471 -299.592194) (xy 32.882836 -299.624113) (xy 32.83658 -299.649266)
			(xy 32.787027 -299.667064) (xy 32.735337 -299.677088) (xy 32.682723 -299.679105) (xy 32.630418 -299.673067)
			(xy 32.579647 -299.659115) (xy 32.531602 -299.637576) (xy 32.487407 -299.608956) (xy 32.448099 -299.573925)
			(xy 32.414599 -299.533304) (xy 32.387693 -299.488045) (xy 32.36801 -299.43921) (xy 32.356013 -299.387942)
			(xy 32.351983 -299.335444) (xy 25.495504 -299.335444) (xy 25.495 -299.36177) (xy 25.486963 -299.413806)
			(xy 25.471077 -299.464005) (xy 25.447714 -299.51119) (xy 25.417422 -299.554256) (xy 25.38091 -299.592194)
			(xy 25.339036 -299.624113) (xy 25.29278 -299.649266) (xy 25.243227 -299.667064) (xy 25.191537 -299.677088)
			(xy 25.138923 -299.679105) (xy 25.086618 -299.673067) (xy 25.035847 -299.659115) (xy 24.987802 -299.637576)
			(xy 24.943607 -299.608956) (xy 24.904299 -299.573925) (xy 24.870799 -299.533304) (xy 24.843893 -299.488045)
			(xy 24.82421 -299.43921) (xy 24.812213 -299.387942) (xy 24.808183 -299.335444) (xy 17.95145 -299.335444)
			(xy 17.950946 -299.36177) (xy 17.942909 -299.413806) (xy 17.927023 -299.464005) (xy 17.90366 -299.51119)
			(xy 17.873368 -299.554256) (xy 17.836856 -299.592194) (xy 17.794982 -299.624113) (xy 17.748726 -299.649266)
			(xy 17.699173 -299.667064) (xy 17.647483 -299.677088) (xy 17.594869 -299.679105) (xy 17.542564 -299.673067)
			(xy 17.491793 -299.659115) (xy 17.443748 -299.637576) (xy 17.399553 -299.608956) (xy 17.360245 -299.573925)
			(xy 17.326745 -299.533304) (xy 17.299839 -299.488045) (xy 17.280156 -299.43921) (xy 17.268159 -299.387942)
			(xy 17.264129 -299.335444) (xy 16.086074 -299.335444) (xy 16.086074 -300.185328) (xy 21.364197 -300.185328)
			(xy 21.368227 -300.13283) (xy 21.380224 -300.081562) (xy 21.399907 -300.032727) (xy 21.426813 -299.987468)
			(xy 21.460313 -299.946847) (xy 21.499621 -299.911816) (xy 21.543816 -299.883196) (xy 21.591861 -299.861657)
			(xy 21.642632 -299.847705) (xy 21.694937 -299.841667) (xy 21.747551 -299.843684) (xy 21.799241 -299.853708)
			(xy 21.848794 -299.871506) (xy 21.89505 -299.896659) (xy 21.936924 -299.928578) (xy 21.973436 -299.966516)
			(xy 22.003728 -300.009582) (xy 22.027091 -300.056767) (xy 22.042977 -300.106966) (xy 22.051014 -300.159002)
			(xy 22.051518 -300.185328) (xy 28.908251 -300.185328) (xy 28.912281 -300.13283) (xy 28.924278 -300.081562)
			(xy 28.943961 -300.032727) (xy 28.970867 -299.987468) (xy 29.004367 -299.946847) (xy 29.043675 -299.911816)
			(xy 29.08787 -299.883196) (xy 29.135915 -299.861657) (xy 29.186686 -299.847705) (xy 29.238991 -299.841667)
			(xy 29.291605 -299.843684) (xy 29.343295 -299.853708) (xy 29.392848 -299.871506) (xy 29.439104 -299.896659)
			(xy 29.480978 -299.928578) (xy 29.51749 -299.966516) (xy 29.547782 -300.009582) (xy 29.571145 -300.056767)
			(xy 29.587031 -300.106966) (xy 29.595068 -300.159002) (xy 29.595572 -300.185328) (xy 36.452051 -300.185328)
			(xy 36.456081 -300.13283) (xy 36.468078 -300.081562) (xy 36.487761 -300.032727) (xy 36.514667 -299.987468)
			(xy 36.548167 -299.946847) (xy 36.587475 -299.911816) (xy 36.63167 -299.883196) (xy 36.679715 -299.861657)
			(xy 36.730486 -299.847705) (xy 36.782791 -299.841667) (xy 36.835405 -299.843684) (xy 36.887095 -299.853708)
			(xy 36.936648 -299.871506) (xy 36.982904 -299.896659) (xy 37.024778 -299.928578) (xy 37.06129 -299.966516)
			(xy 37.091582 -300.009582) (xy 37.114945 -300.056767) (xy 37.130831 -300.106966) (xy 37.138868 -300.159002)
			(xy 37.139372 -300.185328) (xy 43.996105 -300.185328) (xy 44.000135 -300.13283) (xy 44.012132 -300.081562)
			(xy 44.031815 -300.032727) (xy 44.058721 -299.987468) (xy 44.092221 -299.946847) (xy 44.131529 -299.911816)
			(xy 44.175724 -299.883196) (xy 44.223769 -299.861657) (xy 44.27454 -299.847705) (xy 44.326845 -299.841667)
			(xy 44.379459 -299.843684) (xy 44.431149 -299.853708) (xy 44.480702 -299.871506) (xy 44.526958 -299.896659)
			(xy 44.568832 -299.928578) (xy 44.605344 -299.966516) (xy 44.635636 -300.009582) (xy 44.658999 -300.056767)
			(xy 44.674885 -300.106966) (xy 44.682922 -300.159002) (xy 44.683426 -300.185328) (xy 51.540159 -300.185328)
			(xy 51.544189 -300.13283) (xy 51.556186 -300.081562) (xy 51.575869 -300.032727) (xy 51.602775 -299.987468)
			(xy 51.636275 -299.946847) (xy 51.675583 -299.911816) (xy 51.719778 -299.883196) (xy 51.767823 -299.861657)
			(xy 51.818594 -299.847705) (xy 51.870899 -299.841667) (xy 51.923513 -299.843684) (xy 51.975203 -299.853708)
			(xy 52.024756 -299.871506) (xy 52.071012 -299.896659) (xy 52.112886 -299.928578) (xy 52.149398 -299.966516)
			(xy 52.17969 -300.009582) (xy 52.203053 -300.056767) (xy 52.218939 -300.106966) (xy 52.226976 -300.159002)
			(xy 52.22748 -300.185328) (xy 52.226976 -300.211654) (xy 52.218939 -300.26369) (xy 52.203053 -300.313889)
			(xy 52.17969 -300.361074) (xy 52.149398 -300.40414) (xy 52.112886 -300.442078) (xy 52.071012 -300.473997)
			(xy 52.024756 -300.49915) (xy 51.975203 -300.516948) (xy 51.923513 -300.526972) (xy 51.870899 -300.528989)
			(xy 51.818594 -300.522951) (xy 51.767823 -300.508999) (xy 51.719778 -300.48746) (xy 51.675583 -300.45884)
			(xy 51.636275 -300.423809) (xy 51.602775 -300.383188) (xy 51.575869 -300.337929) (xy 51.556186 -300.289094)
			(xy 51.544189 -300.237826) (xy 51.540159 -300.185328) (xy 44.683426 -300.185328) (xy 44.682922 -300.211654)
			(xy 44.674885 -300.26369) (xy 44.658999 -300.313889) (xy 44.635636 -300.361074) (xy 44.605344 -300.40414)
			(xy 44.568832 -300.442078) (xy 44.526958 -300.473997) (xy 44.480702 -300.49915) (xy 44.431149 -300.516948)
			(xy 44.379459 -300.526972) (xy 44.326845 -300.528989) (xy 44.27454 -300.522951) (xy 44.223769 -300.508999)
			(xy 44.175724 -300.48746) (xy 44.131529 -300.45884) (xy 44.092221 -300.423809) (xy 44.058721 -300.383188)
			(xy 44.031815 -300.337929) (xy 44.012132 -300.289094) (xy 44.000135 -300.237826) (xy 43.996105 -300.185328)
			(xy 37.139372 -300.185328) (xy 37.138868 -300.211654) (xy 37.130831 -300.26369) (xy 37.114945 -300.313889)
			(xy 37.091582 -300.361074) (xy 37.06129 -300.40414) (xy 37.024778 -300.442078) (xy 36.982904 -300.473997)
			(xy 36.936648 -300.49915) (xy 36.887095 -300.516948) (xy 36.835405 -300.526972) (xy 36.782791 -300.528989)
			(xy 36.730486 -300.522951) (xy 36.679715 -300.508999) (xy 36.63167 -300.48746) (xy 36.587475 -300.45884)
			(xy 36.548167 -300.423809) (xy 36.514667 -300.383188) (xy 36.487761 -300.337929) (xy 36.468078 -300.289094)
			(xy 36.456081 -300.237826) (xy 36.452051 -300.185328) (xy 29.595572 -300.185328) (xy 29.595068 -300.211654)
			(xy 29.587031 -300.26369) (xy 29.571145 -300.313889) (xy 29.547782 -300.361074) (xy 29.51749 -300.40414)
			(xy 29.480978 -300.442078) (xy 29.439104 -300.473997) (xy 29.392848 -300.49915) (xy 29.343295 -300.516948)
			(xy 29.291605 -300.526972) (xy 29.238991 -300.528989) (xy 29.186686 -300.522951) (xy 29.135915 -300.508999)
			(xy 29.08787 -300.48746) (xy 29.043675 -300.45884) (xy 29.004367 -300.423809) (xy 28.970867 -300.383188)
			(xy 28.943961 -300.337929) (xy 28.924278 -300.289094) (xy 28.912281 -300.237826) (xy 28.908251 -300.185328)
			(xy 22.051518 -300.185328) (xy 22.051014 -300.211654) (xy 22.042977 -300.26369) (xy 22.027091 -300.313889)
			(xy 22.003728 -300.361074) (xy 21.973436 -300.40414) (xy 21.936924 -300.442078) (xy 21.89505 -300.473997)
			(xy 21.848794 -300.49915) (xy 21.799241 -300.516948) (xy 21.747551 -300.526972) (xy 21.694937 -300.528989)
			(xy 21.642632 -300.522951) (xy 21.591861 -300.508999) (xy 21.543816 -300.48746) (xy 21.499621 -300.45884)
			(xy 21.460313 -300.423809) (xy 21.426813 -300.383188) (xy 21.399907 -300.337929) (xy 21.380224 -300.289094)
			(xy 21.368227 -300.237826) (xy 21.364197 -300.185328) (xy 16.086074 -300.185328) (xy 16.086074 -301.035212)
			(xy 17.264129 -301.035212) (xy 17.268159 -300.982714) (xy 17.280156 -300.931446) (xy 17.299839 -300.882611)
			(xy 17.326745 -300.837352) (xy 17.360245 -300.796731) (xy 17.399553 -300.7617) (xy 17.443748 -300.73308)
			(xy 17.491793 -300.711541) (xy 17.542564 -300.697589) (xy 17.594869 -300.691551) (xy 17.647483 -300.693568)
			(xy 17.699173 -300.703592) (xy 17.748726 -300.72139) (xy 17.794982 -300.746543) (xy 17.836856 -300.778462)
			(xy 17.873368 -300.8164) (xy 17.90366 -300.859466) (xy 17.927023 -300.906651) (xy 17.942909 -300.95685)
			(xy 17.950946 -301.008886) (xy 17.95145 -301.035212) (xy 24.808183 -301.035212) (xy 24.812213 -300.982714)
			(xy 24.82421 -300.931446) (xy 24.843893 -300.882611) (xy 24.870799 -300.837352) (xy 24.904299 -300.796731)
			(xy 24.943607 -300.7617) (xy 24.987802 -300.73308) (xy 25.035847 -300.711541) (xy 25.086618 -300.697589)
			(xy 25.138923 -300.691551) (xy 25.191537 -300.693568) (xy 25.243227 -300.703592) (xy 25.29278 -300.72139)
			(xy 25.339036 -300.746543) (xy 25.38091 -300.778462) (xy 25.417422 -300.8164) (xy 25.447714 -300.859466)
			(xy 25.471077 -300.906651) (xy 25.486963 -300.95685) (xy 25.495 -301.008886) (xy 25.495504 -301.035212)
			(xy 32.351983 -301.035212) (xy 32.356013 -300.982714) (xy 32.36801 -300.931446) (xy 32.387693 -300.882611)
			(xy 32.414599 -300.837352) (xy 32.448099 -300.796731) (xy 32.487407 -300.7617) (xy 32.531602 -300.73308)
			(xy 32.579647 -300.711541) (xy 32.630418 -300.697589) (xy 32.682723 -300.691551) (xy 32.735337 -300.693568)
			(xy 32.787027 -300.703592) (xy 32.83658 -300.72139) (xy 32.882836 -300.746543) (xy 32.92471 -300.778462)
			(xy 32.961222 -300.8164) (xy 32.991514 -300.859466) (xy 33.014877 -300.906651) (xy 33.030763 -300.95685)
			(xy 33.0388 -301.008886) (xy 33.039304 -301.035212) (xy 39.896037 -301.035212) (xy 39.900067 -300.982714)
			(xy 39.912064 -300.931446) (xy 39.931747 -300.882611) (xy 39.958653 -300.837352) (xy 39.992153 -300.796731)
			(xy 40.031461 -300.7617) (xy 40.075656 -300.73308) (xy 40.123701 -300.711541) (xy 40.174472 -300.697589)
			(xy 40.226777 -300.691551) (xy 40.279391 -300.693568) (xy 40.331081 -300.703592) (xy 40.380634 -300.72139)
			(xy 40.42689 -300.746543) (xy 40.468764 -300.778462) (xy 40.505276 -300.8164) (xy 40.535568 -300.859466)
			(xy 40.558931 -300.906651) (xy 40.574817 -300.95685) (xy 40.582854 -301.008886) (xy 40.583358 -301.035212)
			(xy 47.440091 -301.035212) (xy 47.444121 -300.982714) (xy 47.456118 -300.931446) (xy 47.475801 -300.882611)
			(xy 47.502707 -300.837352) (xy 47.536207 -300.796731) (xy 47.575515 -300.7617) (xy 47.61971 -300.73308)
			(xy 47.667755 -300.711541) (xy 47.718526 -300.697589) (xy 47.770831 -300.691551) (xy 47.823445 -300.693568)
			(xy 47.875135 -300.703592) (xy 47.924688 -300.72139) (xy 47.970944 -300.746543) (xy 48.012818 -300.778462)
			(xy 48.04933 -300.8164) (xy 48.079622 -300.859466) (xy 48.102985 -300.906651) (xy 48.118871 -300.95685)
			(xy 48.126908 -301.008886) (xy 48.127412 -301.035212) (xy 48.126908 -301.061538) (xy 48.118871 -301.113574)
			(xy 48.102985 -301.163773) (xy 48.079622 -301.210958) (xy 48.04933 -301.254024) (xy 48.012818 -301.291962)
			(xy 47.970944 -301.323881) (xy 47.924688 -301.349034) (xy 47.875135 -301.366832) (xy 47.823445 -301.376856)
			(xy 47.770831 -301.378873) (xy 47.718526 -301.372835) (xy 47.667755 -301.358883) (xy 47.61971 -301.337344)
			(xy 47.575515 -301.308724) (xy 47.536207 -301.273693) (xy 47.502707 -301.233072) (xy 47.475801 -301.187813)
			(xy 47.456118 -301.138978) (xy 47.444121 -301.08771) (xy 47.440091 -301.035212) (xy 40.583358 -301.035212)
			(xy 40.582854 -301.061538) (xy 40.574817 -301.113574) (xy 40.558931 -301.163773) (xy 40.535568 -301.210958)
			(xy 40.505276 -301.254024) (xy 40.468764 -301.291962) (xy 40.42689 -301.323881) (xy 40.380634 -301.349034)
			(xy 40.331081 -301.366832) (xy 40.279391 -301.376856) (xy 40.226777 -301.378873) (xy 40.174472 -301.372835)
			(xy 40.123701 -301.358883) (xy 40.075656 -301.337344) (xy 40.031461 -301.308724) (xy 39.992153 -301.273693)
			(xy 39.958653 -301.233072) (xy 39.931747 -301.187813) (xy 39.912064 -301.138978) (xy 39.900067 -301.08771)
			(xy 39.896037 -301.035212) (xy 33.039304 -301.035212) (xy 33.0388 -301.061538) (xy 33.030763 -301.113574)
			(xy 33.014877 -301.163773) (xy 32.991514 -301.210958) (xy 32.961222 -301.254024) (xy 32.92471 -301.291962)
			(xy 32.882836 -301.323881) (xy 32.83658 -301.349034) (xy 32.787027 -301.366832) (xy 32.735337 -301.376856)
			(xy 32.682723 -301.378873) (xy 32.630418 -301.372835) (xy 32.579647 -301.358883) (xy 32.531602 -301.337344)
			(xy 32.487407 -301.308724) (xy 32.448099 -301.273693) (xy 32.414599 -301.233072) (xy 32.387693 -301.187813)
			(xy 32.36801 -301.138978) (xy 32.356013 -301.08771) (xy 32.351983 -301.035212) (xy 25.495504 -301.035212)
			(xy 25.495 -301.061538) (xy 25.486963 -301.113574) (xy 25.471077 -301.163773) (xy 25.447714 -301.210958)
			(xy 25.417422 -301.254024) (xy 25.38091 -301.291962) (xy 25.339036 -301.323881) (xy 25.29278 -301.349034)
			(xy 25.243227 -301.366832) (xy 25.191537 -301.376856) (xy 25.138923 -301.378873) (xy 25.086618 -301.372835)
			(xy 25.035847 -301.358883) (xy 24.987802 -301.337344) (xy 24.943607 -301.308724) (xy 24.904299 -301.273693)
			(xy 24.870799 -301.233072) (xy 24.843893 -301.187813) (xy 24.82421 -301.138978) (xy 24.812213 -301.08771)
			(xy 24.808183 -301.035212) (xy 17.95145 -301.035212) (xy 17.950946 -301.061538) (xy 17.942909 -301.113574)
			(xy 17.927023 -301.163773) (xy 17.90366 -301.210958) (xy 17.873368 -301.254024) (xy 17.836856 -301.291962)
			(xy 17.794982 -301.323881) (xy 17.748726 -301.349034) (xy 17.699173 -301.366832) (xy 17.647483 -301.376856)
			(xy 17.594869 -301.378873) (xy 17.542564 -301.372835) (xy 17.491793 -301.358883) (xy 17.443748 -301.337344)
			(xy 17.399553 -301.308724) (xy 17.360245 -301.273693) (xy 17.326745 -301.233072) (xy 17.299839 -301.187813)
			(xy 17.280156 -301.138978) (xy 17.268159 -301.08771) (xy 17.264129 -301.035212) (xy 16.086074 -301.035212)
			(xy 16.086074 -301.88535) (xy 21.364197 -301.88535) (xy 21.368227 -301.832852) (xy 21.380224 -301.781584)
			(xy 21.399907 -301.732749) (xy 21.426813 -301.68749) (xy 21.460313 -301.646869) (xy 21.499621 -301.611838)
			(xy 21.543816 -301.583218) (xy 21.591861 -301.561679) (xy 21.642632 -301.547727) (xy 21.694937 -301.541689)
			(xy 21.747551 -301.543706) (xy 21.799241 -301.55373) (xy 21.848794 -301.571528) (xy 21.89505 -301.596681)
			(xy 21.936924 -301.6286) (xy 21.973436 -301.666538) (xy 22.003728 -301.709604) (xy 22.027091 -301.756789)
			(xy 22.042977 -301.806988) (xy 22.051014 -301.859024) (xy 22.051518 -301.88535) (xy 28.908251 -301.88535)
			(xy 28.912281 -301.832852) (xy 28.924278 -301.781584) (xy 28.943961 -301.732749) (xy 28.970867 -301.68749)
			(xy 29.004367 -301.646869) (xy 29.043675 -301.611838) (xy 29.08787 -301.583218) (xy 29.135915 -301.561679)
			(xy 29.186686 -301.547727) (xy 29.238991 -301.541689) (xy 29.291605 -301.543706) (xy 29.343295 -301.55373)
			(xy 29.392848 -301.571528) (xy 29.439104 -301.596681) (xy 29.480978 -301.6286) (xy 29.51749 -301.666538)
			(xy 29.547782 -301.709604) (xy 29.571145 -301.756789) (xy 29.587031 -301.806988) (xy 29.595068 -301.859024)
			(xy 29.595572 -301.88535) (xy 36.452051 -301.88535) (xy 36.456081 -301.832852) (xy 36.468078 -301.781584)
			(xy 36.487761 -301.732749) (xy 36.514667 -301.68749) (xy 36.548167 -301.646869) (xy 36.587475 -301.611838)
			(xy 36.63167 -301.583218) (xy 36.679715 -301.561679) (xy 36.730486 -301.547727) (xy 36.782791 -301.541689)
			(xy 36.835405 -301.543706) (xy 36.887095 -301.55373) (xy 36.936648 -301.571528) (xy 36.982904 -301.596681)
			(xy 37.024778 -301.6286) (xy 37.06129 -301.666538) (xy 37.091582 -301.709604) (xy 37.114945 -301.756789)
			(xy 37.130831 -301.806988) (xy 37.138868 -301.859024) (xy 37.139372 -301.88535) (xy 43.996105 -301.88535)
			(xy 44.000135 -301.832852) (xy 44.012132 -301.781584) (xy 44.031815 -301.732749) (xy 44.058721 -301.68749)
			(xy 44.092221 -301.646869) (xy 44.131529 -301.611838) (xy 44.175724 -301.583218) (xy 44.223769 -301.561679)
			(xy 44.27454 -301.547727) (xy 44.326845 -301.541689) (xy 44.379459 -301.543706) (xy 44.431149 -301.55373)
			(xy 44.480702 -301.571528) (xy 44.526958 -301.596681) (xy 44.568832 -301.6286) (xy 44.605344 -301.666538)
			(xy 44.635636 -301.709604) (xy 44.658999 -301.756789) (xy 44.674885 -301.806988) (xy 44.682922 -301.859024)
			(xy 44.683426 -301.88535) (xy 51.540159 -301.88535) (xy 51.544189 -301.832852) (xy 51.556186 -301.781584)
			(xy 51.575869 -301.732749) (xy 51.602775 -301.68749) (xy 51.636275 -301.646869) (xy 51.675583 -301.611838)
			(xy 51.719778 -301.583218) (xy 51.767823 -301.561679) (xy 51.818594 -301.547727) (xy 51.870899 -301.541689)
			(xy 51.923513 -301.543706) (xy 51.975203 -301.55373) (xy 52.024756 -301.571528) (xy 52.071012 -301.596681)
			(xy 52.112886 -301.6286) (xy 52.149398 -301.666538) (xy 52.17969 -301.709604) (xy 52.203053 -301.756789)
			(xy 52.218939 -301.806988) (xy 52.226976 -301.859024) (xy 52.22748 -301.88535) (xy 52.226976 -301.911676)
			(xy 52.218939 -301.963712) (xy 52.203053 -302.013911) (xy 52.17969 -302.061096) (xy 52.149398 -302.104162)
			(xy 52.112886 -302.1421) (xy 52.071012 -302.174019) (xy 52.024756 -302.199172) (xy 51.975203 -302.21697)
			(xy 51.923513 -302.226994) (xy 51.870899 -302.229011) (xy 51.818594 -302.222973) (xy 51.767823 -302.209021)
			(xy 51.719778 -302.187482) (xy 51.675583 -302.158862) (xy 51.636275 -302.123831) (xy 51.602775 -302.08321)
			(xy 51.575869 -302.037951) (xy 51.556186 -301.989116) (xy 51.544189 -301.937848) (xy 51.540159 -301.88535)
			(xy 44.683426 -301.88535) (xy 44.682922 -301.911676) (xy 44.674885 -301.963712) (xy 44.658999 -302.013911)
			(xy 44.635636 -302.061096) (xy 44.605344 -302.104162) (xy 44.568832 -302.1421) (xy 44.526958 -302.174019)
			(xy 44.480702 -302.199172) (xy 44.431149 -302.21697) (xy 44.379459 -302.226994) (xy 44.326845 -302.229011)
			(xy 44.27454 -302.222973) (xy 44.223769 -302.209021) (xy 44.175724 -302.187482) (xy 44.131529 -302.158862)
			(xy 44.092221 -302.123831) (xy 44.058721 -302.08321) (xy 44.031815 -302.037951) (xy 44.012132 -301.989116)
			(xy 44.000135 -301.937848) (xy 43.996105 -301.88535) (xy 37.139372 -301.88535) (xy 37.138868 -301.911676)
			(xy 37.130831 -301.963712) (xy 37.114945 -302.013911) (xy 37.091582 -302.061096) (xy 37.06129 -302.104162)
			(xy 37.024778 -302.1421) (xy 36.982904 -302.174019) (xy 36.936648 -302.199172) (xy 36.887095 -302.21697)
			(xy 36.835405 -302.226994) (xy 36.782791 -302.229011) (xy 36.730486 -302.222973) (xy 36.679715 -302.209021)
			(xy 36.63167 -302.187482) (xy 36.587475 -302.158862) (xy 36.548167 -302.123831) (xy 36.514667 -302.08321)
			(xy 36.487761 -302.037951) (xy 36.468078 -301.989116) (xy 36.456081 -301.937848) (xy 36.452051 -301.88535)
			(xy 29.595572 -301.88535) (xy 29.595068 -301.911676) (xy 29.587031 -301.963712) (xy 29.571145 -302.013911)
			(xy 29.547782 -302.061096) (xy 29.51749 -302.104162) (xy 29.480978 -302.1421) (xy 29.439104 -302.174019)
			(xy 29.392848 -302.199172) (xy 29.343295 -302.21697) (xy 29.291605 -302.226994) (xy 29.238991 -302.229011)
			(xy 29.186686 -302.222973) (xy 29.135915 -302.209021) (xy 29.08787 -302.187482) (xy 29.043675 -302.158862)
			(xy 29.004367 -302.123831) (xy 28.970867 -302.08321) (xy 28.943961 -302.037951) (xy 28.924278 -301.989116)
			(xy 28.912281 -301.937848) (xy 28.908251 -301.88535) (xy 22.051518 -301.88535) (xy 22.051014 -301.911676)
			(xy 22.042977 -301.963712) (xy 22.027091 -302.013911) (xy 22.003728 -302.061096) (xy 21.973436 -302.104162)
			(xy 21.936924 -302.1421) (xy 21.89505 -302.174019) (xy 21.848794 -302.199172) (xy 21.799241 -302.21697)
			(xy 21.747551 -302.226994) (xy 21.694937 -302.229011) (xy 21.642632 -302.222973) (xy 21.591861 -302.209021)
			(xy 21.543816 -302.187482) (xy 21.499621 -302.158862) (xy 21.460313 -302.123831) (xy 21.426813 -302.08321)
			(xy 21.399907 -302.037951) (xy 21.380224 -301.989116) (xy 21.368227 -301.937848) (xy 21.364197 -301.88535)
			(xy 16.086074 -301.88535) (xy 16.086074 -302.735234) (xy 17.264129 -302.735234) (xy 17.268159 -302.682736)
			(xy 17.280156 -302.631468) (xy 17.299839 -302.582633) (xy 17.326745 -302.537374) (xy 17.360245 -302.496753)
			(xy 17.399553 -302.461722) (xy 17.443748 -302.433102) (xy 17.491793 -302.411563) (xy 17.542564 -302.397611)
			(xy 17.594869 -302.391573) (xy 17.647483 -302.39359) (xy 17.699173 -302.403614) (xy 17.748726 -302.421412)
			(xy 17.794982 -302.446565) (xy 17.836856 -302.478484) (xy 17.873368 -302.516422) (xy 17.90366 -302.559488)
			(xy 17.927023 -302.606673) (xy 17.942909 -302.656872) (xy 17.950946 -302.708908) (xy 17.95145 -302.735234)
			(xy 24.808183 -302.735234) (xy 24.812213 -302.682736) (xy 24.82421 -302.631468) (xy 24.843893 -302.582633)
			(xy 24.870799 -302.537374) (xy 24.904299 -302.496753) (xy 24.943607 -302.461722) (xy 24.987802 -302.433102)
			(xy 25.035847 -302.411563) (xy 25.086618 -302.397611) (xy 25.138923 -302.391573) (xy 25.191537 -302.39359)
			(xy 25.243227 -302.403614) (xy 25.29278 -302.421412) (xy 25.339036 -302.446565) (xy 25.38091 -302.478484)
			(xy 25.417422 -302.516422) (xy 25.447714 -302.559488) (xy 25.471077 -302.606673) (xy 25.486963 -302.656872)
			(xy 25.495 -302.708908) (xy 25.495504 -302.735234) (xy 32.351983 -302.735234) (xy 32.356013 -302.682736)
			(xy 32.36801 -302.631468) (xy 32.387693 -302.582633) (xy 32.414599 -302.537374) (xy 32.448099 -302.496753)
			(xy 32.487407 -302.461722) (xy 32.531602 -302.433102) (xy 32.579647 -302.411563) (xy 32.630418 -302.397611)
			(xy 32.682723 -302.391573) (xy 32.735337 -302.39359) (xy 32.787027 -302.403614) (xy 32.83658 -302.421412)
			(xy 32.882836 -302.446565) (xy 32.92471 -302.478484) (xy 32.961222 -302.516422) (xy 32.991514 -302.559488)
			(xy 33.014877 -302.606673) (xy 33.030763 -302.656872) (xy 33.0388 -302.708908) (xy 33.039304 -302.735234)
			(xy 39.896037 -302.735234) (xy 39.900067 -302.682736) (xy 39.912064 -302.631468) (xy 39.931747 -302.582633)
			(xy 39.958653 -302.537374) (xy 39.992153 -302.496753) (xy 40.031461 -302.461722) (xy 40.075656 -302.433102)
			(xy 40.123701 -302.411563) (xy 40.174472 -302.397611) (xy 40.226777 -302.391573) (xy 40.279391 -302.39359)
			(xy 40.331081 -302.403614) (xy 40.380634 -302.421412) (xy 40.42689 -302.446565) (xy 40.468764 -302.478484)
			(xy 40.505276 -302.516422) (xy 40.535568 -302.559488) (xy 40.558931 -302.606673) (xy 40.574817 -302.656872)
			(xy 40.582854 -302.708908) (xy 40.583358 -302.735234) (xy 47.440091 -302.735234) (xy 47.444121 -302.682736)
			(xy 47.456118 -302.631468) (xy 47.475801 -302.582633) (xy 47.502707 -302.537374) (xy 47.536207 -302.496753)
			(xy 47.575515 -302.461722) (xy 47.61971 -302.433102) (xy 47.667755 -302.411563) (xy 47.718526 -302.397611)
			(xy 47.770831 -302.391573) (xy 47.823445 -302.39359) (xy 47.875135 -302.403614) (xy 47.924688 -302.421412)
			(xy 47.970944 -302.446565) (xy 48.012818 -302.478484) (xy 48.04933 -302.516422) (xy 48.079622 -302.559488)
			(xy 48.102985 -302.606673) (xy 48.118871 -302.656872) (xy 48.126908 -302.708908) (xy 48.127412 -302.735234)
			(xy 48.126908 -302.76156) (xy 48.118871 -302.813596) (xy 48.102985 -302.863795) (xy 48.079622 -302.91098)
			(xy 48.04933 -302.954046) (xy 48.012818 -302.991984) (xy 47.970944 -303.023903) (xy 47.924688 -303.049056)
			(xy 47.875135 -303.066854) (xy 47.823445 -303.076878) (xy 47.770831 -303.078895) (xy 47.718526 -303.072857)
			(xy 47.667755 -303.058905) (xy 47.61971 -303.037366) (xy 47.575515 -303.008746) (xy 47.536207 -302.973715)
			(xy 47.502707 -302.933094) (xy 47.475801 -302.887835) (xy 47.456118 -302.839) (xy 47.444121 -302.787732)
			(xy 47.440091 -302.735234) (xy 40.583358 -302.735234) (xy 40.582854 -302.76156) (xy 40.574817 -302.813596)
			(xy 40.558931 -302.863795) (xy 40.535568 -302.91098) (xy 40.505276 -302.954046) (xy 40.468764 -302.991984)
			(xy 40.42689 -303.023903) (xy 40.380634 -303.049056) (xy 40.331081 -303.066854) (xy 40.279391 -303.076878)
			(xy 40.226777 -303.078895) (xy 40.174472 -303.072857) (xy 40.123701 -303.058905) (xy 40.075656 -303.037366)
			(xy 40.031461 -303.008746) (xy 39.992153 -302.973715) (xy 39.958653 -302.933094) (xy 39.931747 -302.887835)
			(xy 39.912064 -302.839) (xy 39.900067 -302.787732) (xy 39.896037 -302.735234) (xy 33.039304 -302.735234)
			(xy 33.0388 -302.76156) (xy 33.030763 -302.813596) (xy 33.014877 -302.863795) (xy 32.991514 -302.91098)
			(xy 32.961222 -302.954046) (xy 32.92471 -302.991984) (xy 32.882836 -303.023903) (xy 32.83658 -303.049056)
			(xy 32.787027 -303.066854) (xy 32.735337 -303.076878) (xy 32.682723 -303.078895) (xy 32.630418 -303.072857)
			(xy 32.579647 -303.058905) (xy 32.531602 -303.037366) (xy 32.487407 -303.008746) (xy 32.448099 -302.973715)
			(xy 32.414599 -302.933094) (xy 32.387693 -302.887835) (xy 32.36801 -302.839) (xy 32.356013 -302.787732)
			(xy 32.351983 -302.735234) (xy 25.495504 -302.735234) (xy 25.495 -302.76156) (xy 25.486963 -302.813596)
			(xy 25.471077 -302.863795) (xy 25.447714 -302.91098) (xy 25.417422 -302.954046) (xy 25.38091 -302.991984)
			(xy 25.339036 -303.023903) (xy 25.29278 -303.049056) (xy 25.243227 -303.066854) (xy 25.191537 -303.076878)
			(xy 25.138923 -303.078895) (xy 25.086618 -303.072857) (xy 25.035847 -303.058905) (xy 24.987802 -303.037366)
			(xy 24.943607 -303.008746) (xy 24.904299 -302.973715) (xy 24.870799 -302.933094) (xy 24.843893 -302.887835)
			(xy 24.82421 -302.839) (xy 24.812213 -302.787732) (xy 24.808183 -302.735234) (xy 17.95145 -302.735234)
			(xy 17.950946 -302.76156) (xy 17.942909 -302.813596) (xy 17.927023 -302.863795) (xy 17.90366 -302.91098)
			(xy 17.873368 -302.954046) (xy 17.836856 -302.991984) (xy 17.794982 -303.023903) (xy 17.748726 -303.049056)
			(xy 17.699173 -303.066854) (xy 17.647483 -303.076878) (xy 17.594869 -303.078895) (xy 17.542564 -303.072857)
			(xy 17.491793 -303.058905) (xy 17.443748 -303.037366) (xy 17.399553 -303.008746) (xy 17.360245 -302.973715)
			(xy 17.326745 -302.933094) (xy 17.299839 -302.887835) (xy 17.280156 -302.839) (xy 17.268159 -302.787732)
			(xy 17.264129 -302.735234) (xy 16.086074 -302.735234) (xy 16.086074 -303.585372) (xy 21.364197 -303.585372)
			(xy 21.368227 -303.532874) (xy 21.380224 -303.481606) (xy 21.399907 -303.432771) (xy 21.426813 -303.387512)
			(xy 21.460313 -303.346891) (xy 21.499621 -303.31186) (xy 21.543816 -303.28324) (xy 21.591861 -303.261701)
			(xy 21.642632 -303.247749) (xy 21.694937 -303.241711) (xy 21.747551 -303.243728) (xy 21.799241 -303.253752)
			(xy 21.848794 -303.27155) (xy 21.89505 -303.296703) (xy 21.936924 -303.328622) (xy 21.973436 -303.36656)
			(xy 22.003728 -303.409626) (xy 22.027091 -303.456811) (xy 22.042977 -303.50701) (xy 22.051014 -303.559046)
			(xy 22.051518 -303.585372) (xy 28.908251 -303.585372) (xy 28.912281 -303.532874) (xy 28.924278 -303.481606)
			(xy 28.943961 -303.432771) (xy 28.970867 -303.387512) (xy 29.004367 -303.346891) (xy 29.043675 -303.31186)
			(xy 29.08787 -303.28324) (xy 29.135915 -303.261701) (xy 29.186686 -303.247749) (xy 29.238991 -303.241711)
			(xy 29.291605 -303.243728) (xy 29.343295 -303.253752) (xy 29.392848 -303.27155) (xy 29.439104 -303.296703)
			(xy 29.480978 -303.328622) (xy 29.51749 -303.36656) (xy 29.547782 -303.409626) (xy 29.571145 -303.456811)
			(xy 29.587031 -303.50701) (xy 29.595068 -303.559046) (xy 29.595572 -303.585372) (xy 36.452051 -303.585372)
			(xy 36.456081 -303.532874) (xy 36.468078 -303.481606) (xy 36.487761 -303.432771) (xy 36.514667 -303.387512)
			(xy 36.548167 -303.346891) (xy 36.587475 -303.31186) (xy 36.63167 -303.28324) (xy 36.679715 -303.261701)
			(xy 36.730486 -303.247749) (xy 36.782791 -303.241711) (xy 36.835405 -303.243728) (xy 36.887095 -303.253752)
			(xy 36.936648 -303.27155) (xy 36.982904 -303.296703) (xy 37.024778 -303.328622) (xy 37.06129 -303.36656)
			(xy 37.091582 -303.409626) (xy 37.114945 -303.456811) (xy 37.130831 -303.50701) (xy 37.138868 -303.559046)
			(xy 37.139372 -303.585372) (xy 43.996105 -303.585372) (xy 44.000135 -303.532874) (xy 44.012132 -303.481606)
			(xy 44.031815 -303.432771) (xy 44.058721 -303.387512) (xy 44.092221 -303.346891) (xy 44.131529 -303.31186)
			(xy 44.175724 -303.28324) (xy 44.223769 -303.261701) (xy 44.27454 -303.247749) (xy 44.326845 -303.241711)
			(xy 44.379459 -303.243728) (xy 44.431149 -303.253752) (xy 44.480702 -303.27155) (xy 44.526958 -303.296703)
			(xy 44.568832 -303.328622) (xy 44.605344 -303.36656) (xy 44.635636 -303.409626) (xy 44.658999 -303.456811)
			(xy 44.674885 -303.50701) (xy 44.682922 -303.559046) (xy 44.683426 -303.585372) (xy 51.540159 -303.585372)
			(xy 51.544189 -303.532874) (xy 51.556186 -303.481606) (xy 51.575869 -303.432771) (xy 51.602775 -303.387512)
			(xy 51.636275 -303.346891) (xy 51.675583 -303.31186) (xy 51.719778 -303.28324) (xy 51.767823 -303.261701)
			(xy 51.818594 -303.247749) (xy 51.870899 -303.241711) (xy 51.923513 -303.243728) (xy 51.975203 -303.253752)
			(xy 52.024756 -303.27155) (xy 52.071012 -303.296703) (xy 52.112886 -303.328622) (xy 52.149398 -303.36656)
			(xy 52.17969 -303.409626) (xy 52.203053 -303.456811) (xy 52.218939 -303.50701) (xy 52.226976 -303.559046)
			(xy 52.22748 -303.585372) (xy 52.226976 -303.611698) (xy 52.218939 -303.663734) (xy 52.203053 -303.713933)
			(xy 52.17969 -303.761118) (xy 52.149398 -303.804184) (xy 52.112886 -303.842122) (xy 52.071012 -303.874041)
			(xy 52.024756 -303.899194) (xy 51.975203 -303.916992) (xy 51.923513 -303.927016) (xy 51.870899 -303.929033)
			(xy 51.818594 -303.922995) (xy 51.767823 -303.909043) (xy 51.719778 -303.887504) (xy 51.675583 -303.858884)
			(xy 51.636275 -303.823853) (xy 51.602775 -303.783232) (xy 51.575869 -303.737973) (xy 51.556186 -303.689138)
			(xy 51.544189 -303.63787) (xy 51.540159 -303.585372) (xy 44.683426 -303.585372) (xy 44.682922 -303.611698)
			(xy 44.674885 -303.663734) (xy 44.658999 -303.713933) (xy 44.635636 -303.761118) (xy 44.605344 -303.804184)
			(xy 44.568832 -303.842122) (xy 44.526958 -303.874041) (xy 44.480702 -303.899194) (xy 44.431149 -303.916992)
			(xy 44.379459 -303.927016) (xy 44.326845 -303.929033) (xy 44.27454 -303.922995) (xy 44.223769 -303.909043)
			(xy 44.175724 -303.887504) (xy 44.131529 -303.858884) (xy 44.092221 -303.823853) (xy 44.058721 -303.783232)
			(xy 44.031815 -303.737973) (xy 44.012132 -303.689138) (xy 44.000135 -303.63787) (xy 43.996105 -303.585372)
			(xy 37.139372 -303.585372) (xy 37.138868 -303.611698) (xy 37.130831 -303.663734) (xy 37.114945 -303.713933)
			(xy 37.091582 -303.761118) (xy 37.06129 -303.804184) (xy 37.024778 -303.842122) (xy 36.982904 -303.874041)
			(xy 36.936648 -303.899194) (xy 36.887095 -303.916992) (xy 36.835405 -303.927016) (xy 36.782791 -303.929033)
			(xy 36.730486 -303.922995) (xy 36.679715 -303.909043) (xy 36.63167 -303.887504) (xy 36.587475 -303.858884)
			(xy 36.548167 -303.823853) (xy 36.514667 -303.783232) (xy 36.487761 -303.737973) (xy 36.468078 -303.689138)
			(xy 36.456081 -303.63787) (xy 36.452051 -303.585372) (xy 29.595572 -303.585372) (xy 29.595068 -303.611698)
			(xy 29.587031 -303.663734) (xy 29.571145 -303.713933) (xy 29.547782 -303.761118) (xy 29.51749 -303.804184)
			(xy 29.480978 -303.842122) (xy 29.439104 -303.874041) (xy 29.392848 -303.899194) (xy 29.343295 -303.916992)
			(xy 29.291605 -303.927016) (xy 29.238991 -303.929033) (xy 29.186686 -303.922995) (xy 29.135915 -303.909043)
			(xy 29.08787 -303.887504) (xy 29.043675 -303.858884) (xy 29.004367 -303.823853) (xy 28.970867 -303.783232)
			(xy 28.943961 -303.737973) (xy 28.924278 -303.689138) (xy 28.912281 -303.63787) (xy 28.908251 -303.585372)
			(xy 22.051518 -303.585372) (xy 22.051014 -303.611698) (xy 22.042977 -303.663734) (xy 22.027091 -303.713933)
			(xy 22.003728 -303.761118) (xy 21.973436 -303.804184) (xy 21.936924 -303.842122) (xy 21.89505 -303.874041)
			(xy 21.848794 -303.899194) (xy 21.799241 -303.916992) (xy 21.747551 -303.927016) (xy 21.694937 -303.929033)
			(xy 21.642632 -303.922995) (xy 21.591861 -303.909043) (xy 21.543816 -303.887504) (xy 21.499621 -303.858884)
			(xy 21.460313 -303.823853) (xy 21.426813 -303.783232) (xy 21.399907 -303.737973) (xy 21.380224 -303.689138)
			(xy 21.368227 -303.63787) (xy 21.364197 -303.585372) (xy 16.086074 -303.585372) (xy 16.086074 -304.435256)
			(xy 17.264129 -304.435256) (xy 17.268159 -304.382758) (xy 17.280156 -304.33149) (xy 17.299839 -304.282655)
			(xy 17.326745 -304.237396) (xy 17.360245 -304.196775) (xy 17.399553 -304.161744) (xy 17.443748 -304.133124)
			(xy 17.491793 -304.111585) (xy 17.542564 -304.097633) (xy 17.594869 -304.091595) (xy 17.647483 -304.093612)
			(xy 17.699173 -304.103636) (xy 17.748726 -304.121434) (xy 17.794982 -304.146587) (xy 17.836856 -304.178506)
			(xy 17.873368 -304.216444) (xy 17.90366 -304.25951) (xy 17.927023 -304.306695) (xy 17.942909 -304.356894)
			(xy 17.950946 -304.40893) (xy 17.95145 -304.435256) (xy 21.364197 -304.435256) (xy 21.368227 -304.382758)
			(xy 21.380224 -304.33149) (xy 21.399907 -304.282655) (xy 21.426813 -304.237396) (xy 21.460313 -304.196775)
			(xy 21.499621 -304.161744) (xy 21.543816 -304.133124) (xy 21.591861 -304.111585) (xy 21.642632 -304.097633)
			(xy 21.694937 -304.091595) (xy 21.747551 -304.093612) (xy 21.799241 -304.103636) (xy 21.848794 -304.121434)
			(xy 21.89505 -304.146587) (xy 21.936924 -304.178506) (xy 21.973436 -304.216444) (xy 22.003728 -304.25951)
			(xy 22.027091 -304.306695) (xy 22.042977 -304.356894) (xy 22.051014 -304.40893) (xy 22.051518 -304.435256)
			(xy 24.808183 -304.435256) (xy 24.812213 -304.382758) (xy 24.82421 -304.33149) (xy 24.843893 -304.282655)
			(xy 24.870799 -304.237396) (xy 24.904299 -304.196775) (xy 24.943607 -304.161744) (xy 24.987802 -304.133124)
			(xy 25.035847 -304.111585) (xy 25.086618 -304.097633) (xy 25.138923 -304.091595) (xy 25.191537 -304.093612)
			(xy 25.243227 -304.103636) (xy 25.29278 -304.121434) (xy 25.339036 -304.146587) (xy 25.38091 -304.178506)
			(xy 25.417422 -304.216444) (xy 25.447714 -304.25951) (xy 25.471077 -304.306695) (xy 25.486963 -304.356894)
			(xy 25.495 -304.40893) (xy 25.495504 -304.435256) (xy 28.908251 -304.435256) (xy 28.912281 -304.382758)
			(xy 28.924278 -304.33149) (xy 28.943961 -304.282655) (xy 28.970867 -304.237396) (xy 29.004367 -304.196775)
			(xy 29.043675 -304.161744) (xy 29.08787 -304.133124) (xy 29.135915 -304.111585) (xy 29.186686 -304.097633)
			(xy 29.238991 -304.091595) (xy 29.291605 -304.093612) (xy 29.343295 -304.103636) (xy 29.392848 -304.121434)
			(xy 29.439104 -304.146587) (xy 29.480978 -304.178506) (xy 29.51749 -304.216444) (xy 29.547782 -304.25951)
			(xy 29.571145 -304.306695) (xy 29.587031 -304.356894) (xy 29.595068 -304.40893) (xy 29.595572 -304.435256)
			(xy 32.351983 -304.435256) (xy 32.356013 -304.382758) (xy 32.36801 -304.33149) (xy 32.387693 -304.282655)
			(xy 32.414599 -304.237396) (xy 32.448099 -304.196775) (xy 32.487407 -304.161744) (xy 32.531602 -304.133124)
			(xy 32.579647 -304.111585) (xy 32.630418 -304.097633) (xy 32.682723 -304.091595) (xy 32.735337 -304.093612)
			(xy 32.787027 -304.103636) (xy 32.83658 -304.121434) (xy 32.882836 -304.146587) (xy 32.92471 -304.178506)
			(xy 32.961222 -304.216444) (xy 32.991514 -304.25951) (xy 33.014877 -304.306695) (xy 33.030763 -304.356894)
			(xy 33.0388 -304.40893) (xy 33.039304 -304.435256) (xy 36.452051 -304.435256) (xy 36.456081 -304.382758)
			(xy 36.468078 -304.33149) (xy 36.487761 -304.282655) (xy 36.514667 -304.237396) (xy 36.548167 -304.196775)
			(xy 36.587475 -304.161744) (xy 36.63167 -304.133124) (xy 36.679715 -304.111585) (xy 36.730486 -304.097633)
			(xy 36.782791 -304.091595) (xy 36.835405 -304.093612) (xy 36.887095 -304.103636) (xy 36.936648 -304.121434)
			(xy 36.982904 -304.146587) (xy 37.024778 -304.178506) (xy 37.06129 -304.216444) (xy 37.091582 -304.25951)
			(xy 37.114945 -304.306695) (xy 37.130831 -304.356894) (xy 37.138868 -304.40893) (xy 37.139372 -304.435256)
			(xy 39.896037 -304.435256) (xy 39.900067 -304.382758) (xy 39.912064 -304.33149) (xy 39.931747 -304.282655)
			(xy 39.958653 -304.237396) (xy 39.992153 -304.196775) (xy 40.031461 -304.161744) (xy 40.075656 -304.133124)
			(xy 40.123701 -304.111585) (xy 40.174472 -304.097633) (xy 40.226777 -304.091595) (xy 40.279391 -304.093612)
			(xy 40.331081 -304.103636) (xy 40.380634 -304.121434) (xy 40.42689 -304.146587) (xy 40.468764 -304.178506)
			(xy 40.505276 -304.216444) (xy 40.535568 -304.25951) (xy 40.558931 -304.306695) (xy 40.574817 -304.356894)
			(xy 40.582854 -304.40893) (xy 40.583358 -304.435256) (xy 43.996105 -304.435256) (xy 44.000135 -304.382758)
			(xy 44.012132 -304.33149) (xy 44.031815 -304.282655) (xy 44.058721 -304.237396) (xy 44.092221 -304.196775)
			(xy 44.131529 -304.161744) (xy 44.175724 -304.133124) (xy 44.223769 -304.111585) (xy 44.27454 -304.097633)
			(xy 44.326845 -304.091595) (xy 44.379459 -304.093612) (xy 44.431149 -304.103636) (xy 44.480702 -304.121434)
			(xy 44.526958 -304.146587) (xy 44.568832 -304.178506) (xy 44.605344 -304.216444) (xy 44.635636 -304.25951)
			(xy 44.658999 -304.306695) (xy 44.674885 -304.356894) (xy 44.682922 -304.40893) (xy 44.683426 -304.435256)
			(xy 47.440091 -304.435256) (xy 47.444121 -304.382758) (xy 47.456118 -304.33149) (xy 47.475801 -304.282655)
			(xy 47.502707 -304.237396) (xy 47.536207 -304.196775) (xy 47.575515 -304.161744) (xy 47.61971 -304.133124)
			(xy 47.667755 -304.111585) (xy 47.718526 -304.097633) (xy 47.770831 -304.091595) (xy 47.823445 -304.093612)
			(xy 47.875135 -304.103636) (xy 47.924688 -304.121434) (xy 47.970944 -304.146587) (xy 48.012818 -304.178506)
			(xy 48.04933 -304.216444) (xy 48.079622 -304.25951) (xy 48.102985 -304.306695) (xy 48.118871 -304.356894)
			(xy 48.126908 -304.40893) (xy 48.127412 -304.435256) (xy 51.540159 -304.435256) (xy 51.544189 -304.382758)
			(xy 51.556186 -304.33149) (xy 51.575869 -304.282655) (xy 51.602775 -304.237396) (xy 51.636275 -304.196775)
			(xy 51.675583 -304.161744) (xy 51.719778 -304.133124) (xy 51.767823 -304.111585) (xy 51.818594 -304.097633)
			(xy 51.870899 -304.091595) (xy 51.923513 -304.093612) (xy 51.975203 -304.103636) (xy 52.024756 -304.121434)
			(xy 52.071012 -304.146587) (xy 52.112886 -304.178506) (xy 52.149398 -304.216444) (xy 52.17969 -304.25951)
			(xy 52.203053 -304.306695) (xy 52.218939 -304.356894) (xy 52.226976 -304.40893) (xy 52.22748 -304.435256)
			(xy 52.226976 -304.461582) (xy 52.218939 -304.513618) (xy 52.203053 -304.563817) (xy 52.17969 -304.611002)
			(xy 52.149398 -304.654068) (xy 52.112886 -304.692006) (xy 52.071012 -304.723925) (xy 52.024756 -304.749078)
			(xy 51.975203 -304.766876) (xy 51.923513 -304.7769) (xy 51.870899 -304.778917) (xy 51.818594 -304.772879)
			(xy 51.767823 -304.758927) (xy 51.719778 -304.737388) (xy 51.675583 -304.708768) (xy 51.636275 -304.673737)
			(xy 51.602775 -304.633116) (xy 51.575869 -304.587857) (xy 51.556186 -304.539022) (xy 51.544189 -304.487754)
			(xy 51.540159 -304.435256) (xy 48.127412 -304.435256) (xy 48.126908 -304.461582) (xy 48.118871 -304.513618)
			(xy 48.102985 -304.563817) (xy 48.079622 -304.611002) (xy 48.04933 -304.654068) (xy 48.012818 -304.692006)
			(xy 47.970944 -304.723925) (xy 47.924688 -304.749078) (xy 47.875135 -304.766876) (xy 47.823445 -304.7769)
			(xy 47.770831 -304.778917) (xy 47.718526 -304.772879) (xy 47.667755 -304.758927) (xy 47.61971 -304.737388)
			(xy 47.575515 -304.708768) (xy 47.536207 -304.673737) (xy 47.502707 -304.633116) (xy 47.475801 -304.587857)
			(xy 47.456118 -304.539022) (xy 47.444121 -304.487754) (xy 47.440091 -304.435256) (xy 44.683426 -304.435256)
			(xy 44.682922 -304.461582) (xy 44.674885 -304.513618) (xy 44.658999 -304.563817) (xy 44.635636 -304.611002)
			(xy 44.605344 -304.654068) (xy 44.568832 -304.692006) (xy 44.526958 -304.723925) (xy 44.480702 -304.749078)
			(xy 44.431149 -304.766876) (xy 44.379459 -304.7769) (xy 44.326845 -304.778917) (xy 44.27454 -304.772879)
			(xy 44.223769 -304.758927) (xy 44.175724 -304.737388) (xy 44.131529 -304.708768) (xy 44.092221 -304.673737)
			(xy 44.058721 -304.633116) (xy 44.031815 -304.587857) (xy 44.012132 -304.539022) (xy 44.000135 -304.487754)
			(xy 43.996105 -304.435256) (xy 40.583358 -304.435256) (xy 40.582854 -304.461582) (xy 40.574817 -304.513618)
			(xy 40.558931 -304.563817) (xy 40.535568 -304.611002) (xy 40.505276 -304.654068) (xy 40.468764 -304.692006)
			(xy 40.42689 -304.723925) (xy 40.380634 -304.749078) (xy 40.331081 -304.766876) (xy 40.279391 -304.7769)
			(xy 40.226777 -304.778917) (xy 40.174472 -304.772879) (xy 40.123701 -304.758927) (xy 40.075656 -304.737388)
			(xy 40.031461 -304.708768) (xy 39.992153 -304.673737) (xy 39.958653 -304.633116) (xy 39.931747 -304.587857)
			(xy 39.912064 -304.539022) (xy 39.900067 -304.487754) (xy 39.896037 -304.435256) (xy 37.139372 -304.435256)
			(xy 37.138868 -304.461582) (xy 37.130831 -304.513618) (xy 37.114945 -304.563817) (xy 37.091582 -304.611002)
			(xy 37.06129 -304.654068) (xy 37.024778 -304.692006) (xy 36.982904 -304.723925) (xy 36.936648 -304.749078)
			(xy 36.887095 -304.766876) (xy 36.835405 -304.7769) (xy 36.782791 -304.778917) (xy 36.730486 -304.772879)
			(xy 36.679715 -304.758927) (xy 36.63167 -304.737388) (xy 36.587475 -304.708768) (xy 36.548167 -304.673737)
			(xy 36.514667 -304.633116) (xy 36.487761 -304.587857) (xy 36.468078 -304.539022) (xy 36.456081 -304.487754)
			(xy 36.452051 -304.435256) (xy 33.039304 -304.435256) (xy 33.0388 -304.461582) (xy 33.030763 -304.513618)
			(xy 33.014877 -304.563817) (xy 32.991514 -304.611002) (xy 32.961222 -304.654068) (xy 32.92471 -304.692006)
			(xy 32.882836 -304.723925) (xy 32.83658 -304.749078) (xy 32.787027 -304.766876) (xy 32.735337 -304.7769)
			(xy 32.682723 -304.778917) (xy 32.630418 -304.772879) (xy 32.579647 -304.758927) (xy 32.531602 -304.737388)
			(xy 32.487407 -304.708768) (xy 32.448099 -304.673737) (xy 32.414599 -304.633116) (xy 32.387693 -304.587857)
			(xy 32.36801 -304.539022) (xy 32.356013 -304.487754) (xy 32.351983 -304.435256) (xy 29.595572 -304.435256)
			(xy 29.595068 -304.461582) (xy 29.587031 -304.513618) (xy 29.571145 -304.563817) (xy 29.547782 -304.611002)
			(xy 29.51749 -304.654068) (xy 29.480978 -304.692006) (xy 29.439104 -304.723925) (xy 29.392848 -304.749078)
			(xy 29.343295 -304.766876) (xy 29.291605 -304.7769) (xy 29.238991 -304.778917) (xy 29.186686 -304.772879)
			(xy 29.135915 -304.758927) (xy 29.08787 -304.737388) (xy 29.043675 -304.708768) (xy 29.004367 -304.673737)
			(xy 28.970867 -304.633116) (xy 28.943961 -304.587857) (xy 28.924278 -304.539022) (xy 28.912281 -304.487754)
			(xy 28.908251 -304.435256) (xy 25.495504 -304.435256) (xy 25.495 -304.461582) (xy 25.486963 -304.513618)
			(xy 25.471077 -304.563817) (xy 25.447714 -304.611002) (xy 25.417422 -304.654068) (xy 25.38091 -304.692006)
			(xy 25.339036 -304.723925) (xy 25.29278 -304.749078) (xy 25.243227 -304.766876) (xy 25.191537 -304.7769)
			(xy 25.138923 -304.778917) (xy 25.086618 -304.772879) (xy 25.035847 -304.758927) (xy 24.987802 -304.737388)
			(xy 24.943607 -304.708768) (xy 24.904299 -304.673737) (xy 24.870799 -304.633116) (xy 24.843893 -304.587857)
			(xy 24.82421 -304.539022) (xy 24.812213 -304.487754) (xy 24.808183 -304.435256) (xy 22.051518 -304.435256)
			(xy 22.051014 -304.461582) (xy 22.042977 -304.513618) (xy 22.027091 -304.563817) (xy 22.003728 -304.611002)
			(xy 21.973436 -304.654068) (xy 21.936924 -304.692006) (xy 21.89505 -304.723925) (xy 21.848794 -304.749078)
			(xy 21.799241 -304.766876) (xy 21.747551 -304.7769) (xy 21.694937 -304.778917) (xy 21.642632 -304.772879)
			(xy 21.591861 -304.758927) (xy 21.543816 -304.737388) (xy 21.499621 -304.708768) (xy 21.460313 -304.673737)
			(xy 21.426813 -304.633116) (xy 21.399907 -304.587857) (xy 21.380224 -304.539022) (xy 21.368227 -304.487754)
			(xy 21.364197 -304.435256) (xy 17.95145 -304.435256) (xy 17.950946 -304.461582) (xy 17.942909 -304.513618)
			(xy 17.927023 -304.563817) (xy 17.90366 -304.611002) (xy 17.873368 -304.654068) (xy 17.836856 -304.692006)
			(xy 17.794982 -304.723925) (xy 17.748726 -304.749078) (xy 17.699173 -304.766876) (xy 17.647483 -304.7769)
			(xy 17.594869 -304.778917) (xy 17.542564 -304.772879) (xy 17.491793 -304.758927) (xy 17.443748 -304.737388)
			(xy 17.399553 -304.708768) (xy 17.360245 -304.673737) (xy 17.326745 -304.633116) (xy 17.299839 -304.587857)
			(xy 17.280156 -304.539022) (xy 17.268159 -304.487754) (xy 17.264129 -304.435256) (xy 16.086074 -304.435256)
			(xy 16.086074 -305.285394) (xy 17.264129 -305.285394) (xy 17.268159 -305.232896) (xy 17.280156 -305.181628)
			(xy 17.299839 -305.132793) (xy 17.326745 -305.087534) (xy 17.360245 -305.046913) (xy 17.399553 -305.011882)
			(xy 17.443748 -304.983262) (xy 17.491793 -304.961723) (xy 17.542564 -304.947771) (xy 17.594869 -304.941733)
			(xy 17.647483 -304.94375) (xy 17.699173 -304.953774) (xy 17.748726 -304.971572) (xy 17.794982 -304.996725)
			(xy 17.836856 -305.028644) (xy 17.873368 -305.066582) (xy 17.90366 -305.109648) (xy 17.927023 -305.156833)
			(xy 17.942909 -305.207032) (xy 17.950946 -305.259068) (xy 17.95145 -305.285394) (xy 24.808183 -305.285394)
			(xy 24.812213 -305.232896) (xy 24.82421 -305.181628) (xy 24.843893 -305.132793) (xy 24.870799 -305.087534)
			(xy 24.904299 -305.046913) (xy 24.943607 -305.011882) (xy 24.987802 -304.983262) (xy 25.035847 -304.961723)
			(xy 25.086618 -304.947771) (xy 25.138923 -304.941733) (xy 25.191537 -304.94375) (xy 25.243227 -304.953774)
			(xy 25.29278 -304.971572) (xy 25.339036 -304.996725) (xy 25.38091 -305.028644) (xy 25.417422 -305.066582)
			(xy 25.447714 -305.109648) (xy 25.471077 -305.156833) (xy 25.486963 -305.207032) (xy 25.495 -305.259068)
			(xy 25.495504 -305.285394) (xy 32.351983 -305.285394) (xy 32.356013 -305.232896) (xy 32.36801 -305.181628)
			(xy 32.387693 -305.132793) (xy 32.414599 -305.087534) (xy 32.448099 -305.046913) (xy 32.487407 -305.011882)
			(xy 32.531602 -304.983262) (xy 32.579647 -304.961723) (xy 32.630418 -304.947771) (xy 32.682723 -304.941733)
			(xy 32.735337 -304.94375) (xy 32.787027 -304.953774) (xy 32.83658 -304.971572) (xy 32.882836 -304.996725)
			(xy 32.92471 -305.028644) (xy 32.961222 -305.066582) (xy 32.991514 -305.109648) (xy 33.014877 -305.156833)
			(xy 33.030763 -305.207032) (xy 33.0388 -305.259068) (xy 33.039304 -305.285394) (xy 39.896037 -305.285394)
			(xy 39.900067 -305.232896) (xy 39.912064 -305.181628) (xy 39.931747 -305.132793) (xy 39.958653 -305.087534)
			(xy 39.992153 -305.046913) (xy 40.031461 -305.011882) (xy 40.075656 -304.983262) (xy 40.123701 -304.961723)
			(xy 40.174472 -304.947771) (xy 40.226777 -304.941733) (xy 40.279391 -304.94375) (xy 40.331081 -304.953774)
			(xy 40.380634 -304.971572) (xy 40.42689 -304.996725) (xy 40.468764 -305.028644) (xy 40.505276 -305.066582)
			(xy 40.535568 -305.109648) (xy 40.558931 -305.156833) (xy 40.574817 -305.207032) (xy 40.582854 -305.259068)
			(xy 40.583358 -305.285394) (xy 47.440091 -305.285394) (xy 47.444121 -305.232896) (xy 47.456118 -305.181628)
			(xy 47.475801 -305.132793) (xy 47.502707 -305.087534) (xy 47.536207 -305.046913) (xy 47.575515 -305.011882)
			(xy 47.61971 -304.983262) (xy 47.667755 -304.961723) (xy 47.718526 -304.947771) (xy 47.770831 -304.941733)
			(xy 47.823445 -304.94375) (xy 47.875135 -304.953774) (xy 47.924688 -304.971572) (xy 47.970944 -304.996725)
			(xy 48.012818 -305.028644) (xy 48.04933 -305.066582) (xy 48.079622 -305.109648) (xy 48.102985 -305.156833)
			(xy 48.118871 -305.207032) (xy 48.126908 -305.259068) (xy 48.127412 -305.285394) (xy 48.126908 -305.31172)
			(xy 48.118871 -305.363756) (xy 48.102985 -305.413955) (xy 48.079622 -305.46114) (xy 48.04933 -305.504206)
			(xy 48.012818 -305.542144) (xy 47.970944 -305.574063) (xy 47.924688 -305.599216) (xy 47.875135 -305.617014)
			(xy 47.823445 -305.627038) (xy 47.770831 -305.629055) (xy 47.718526 -305.623017) (xy 47.667755 -305.609065)
			(xy 47.61971 -305.587526) (xy 47.575515 -305.558906) (xy 47.536207 -305.523875) (xy 47.502707 -305.483254)
			(xy 47.475801 -305.437995) (xy 47.456118 -305.38916) (xy 47.444121 -305.337892) (xy 47.440091 -305.285394)
			(xy 40.583358 -305.285394) (xy 40.582854 -305.31172) (xy 40.574817 -305.363756) (xy 40.558931 -305.413955)
			(xy 40.535568 -305.46114) (xy 40.505276 -305.504206) (xy 40.468764 -305.542144) (xy 40.42689 -305.574063)
			(xy 40.380634 -305.599216) (xy 40.331081 -305.617014) (xy 40.279391 -305.627038) (xy 40.226777 -305.629055)
			(xy 40.174472 -305.623017) (xy 40.123701 -305.609065) (xy 40.075656 -305.587526) (xy 40.031461 -305.558906)
			(xy 39.992153 -305.523875) (xy 39.958653 -305.483254) (xy 39.931747 -305.437995) (xy 39.912064 -305.38916)
			(xy 39.900067 -305.337892) (xy 39.896037 -305.285394) (xy 33.039304 -305.285394) (xy 33.0388 -305.31172)
			(xy 33.030763 -305.363756) (xy 33.014877 -305.413955) (xy 32.991514 -305.46114) (xy 32.961222 -305.504206)
			(xy 32.92471 -305.542144) (xy 32.882836 -305.574063) (xy 32.83658 -305.599216) (xy 32.787027 -305.617014)
			(xy 32.735337 -305.627038) (xy 32.682723 -305.629055) (xy 32.630418 -305.623017) (xy 32.579647 -305.609065)
			(xy 32.531602 -305.587526) (xy 32.487407 -305.558906) (xy 32.448099 -305.523875) (xy 32.414599 -305.483254)
			(xy 32.387693 -305.437995) (xy 32.36801 -305.38916) (xy 32.356013 -305.337892) (xy 32.351983 -305.285394)
			(xy 25.495504 -305.285394) (xy 25.495 -305.31172) (xy 25.486963 -305.363756) (xy 25.471077 -305.413955)
			(xy 25.447714 -305.46114) (xy 25.417422 -305.504206) (xy 25.38091 -305.542144) (xy 25.339036 -305.574063)
			(xy 25.29278 -305.599216) (xy 25.243227 -305.617014) (xy 25.191537 -305.627038) (xy 25.138923 -305.629055)
			(xy 25.086618 -305.623017) (xy 25.035847 -305.609065) (xy 24.987802 -305.587526) (xy 24.943607 -305.558906)
			(xy 24.904299 -305.523875) (xy 24.870799 -305.483254) (xy 24.843893 -305.437995) (xy 24.82421 -305.38916)
			(xy 24.812213 -305.337892) (xy 24.808183 -305.285394) (xy 17.95145 -305.285394) (xy 17.950946 -305.31172)
			(xy 17.942909 -305.363756) (xy 17.927023 -305.413955) (xy 17.90366 -305.46114) (xy 17.873368 -305.504206)
			(xy 17.836856 -305.542144) (xy 17.794982 -305.574063) (xy 17.748726 -305.599216) (xy 17.699173 -305.617014)
			(xy 17.647483 -305.627038) (xy 17.594869 -305.629055) (xy 17.542564 -305.623017) (xy 17.491793 -305.609065)
			(xy 17.443748 -305.587526) (xy 17.399553 -305.558906) (xy 17.360245 -305.523875) (xy 17.326745 -305.483254)
			(xy 17.299839 -305.437995) (xy 17.280156 -305.38916) (xy 17.268159 -305.337892) (xy 17.264129 -305.285394)
			(xy 16.086074 -305.285394) (xy 16.086074 -306.135278) (xy 21.364197 -306.135278) (xy 21.368227 -306.08278)
			(xy 21.380224 -306.031512) (xy 21.399907 -305.982677) (xy 21.426813 -305.937418) (xy 21.460313 -305.896797)
			(xy 21.499621 -305.861766) (xy 21.543816 -305.833146) (xy 21.591861 -305.811607) (xy 21.642632 -305.797655)
			(xy 21.694937 -305.791617) (xy 21.747551 -305.793634) (xy 21.799241 -305.803658) (xy 21.848794 -305.821456)
			(xy 21.89505 -305.846609) (xy 21.936924 -305.878528) (xy 21.973436 -305.916466) (xy 22.003728 -305.959532)
			(xy 22.027091 -306.006717) (xy 22.042977 -306.056916) (xy 22.051014 -306.108952) (xy 22.051518 -306.135278)
			(xy 28.908251 -306.135278) (xy 28.912281 -306.08278) (xy 28.924278 -306.031512) (xy 28.943961 -305.982677)
			(xy 28.970867 -305.937418) (xy 29.004367 -305.896797) (xy 29.043675 -305.861766) (xy 29.08787 -305.833146)
			(xy 29.135915 -305.811607) (xy 29.186686 -305.797655) (xy 29.238991 -305.791617) (xy 29.291605 -305.793634)
			(xy 29.343295 -305.803658) (xy 29.392848 -305.821456) (xy 29.439104 -305.846609) (xy 29.480978 -305.878528)
			(xy 29.51749 -305.916466) (xy 29.547782 -305.959532) (xy 29.571145 -306.006717) (xy 29.587031 -306.056916)
			(xy 29.595068 -306.108952) (xy 29.595572 -306.135278) (xy 36.452051 -306.135278) (xy 36.456081 -306.08278)
			(xy 36.468078 -306.031512) (xy 36.487761 -305.982677) (xy 36.514667 -305.937418) (xy 36.548167 -305.896797)
			(xy 36.587475 -305.861766) (xy 36.63167 -305.833146) (xy 36.679715 -305.811607) (xy 36.730486 -305.797655)
			(xy 36.782791 -305.791617) (xy 36.835405 -305.793634) (xy 36.887095 -305.803658) (xy 36.936648 -305.821456)
			(xy 36.982904 -305.846609) (xy 37.024778 -305.878528) (xy 37.06129 -305.916466) (xy 37.091582 -305.959532)
			(xy 37.114945 -306.006717) (xy 37.130831 -306.056916) (xy 37.138868 -306.108952) (xy 37.139372 -306.135278)
			(xy 43.996105 -306.135278) (xy 44.000135 -306.08278) (xy 44.012132 -306.031512) (xy 44.031815 -305.982677)
			(xy 44.058721 -305.937418) (xy 44.092221 -305.896797) (xy 44.131529 -305.861766) (xy 44.175724 -305.833146)
			(xy 44.223769 -305.811607) (xy 44.27454 -305.797655) (xy 44.326845 -305.791617) (xy 44.379459 -305.793634)
			(xy 44.431149 -305.803658) (xy 44.480702 -305.821456) (xy 44.526958 -305.846609) (xy 44.568832 -305.878528)
			(xy 44.605344 -305.916466) (xy 44.635636 -305.959532) (xy 44.658999 -306.006717) (xy 44.674885 -306.056916)
			(xy 44.682922 -306.108952) (xy 44.683426 -306.135278) (xy 51.540159 -306.135278) (xy 51.544189 -306.08278)
			(xy 51.556186 -306.031512) (xy 51.575869 -305.982677) (xy 51.602775 -305.937418) (xy 51.636275 -305.896797)
			(xy 51.675583 -305.861766) (xy 51.719778 -305.833146) (xy 51.767823 -305.811607) (xy 51.818594 -305.797655)
			(xy 51.870899 -305.791617) (xy 51.923513 -305.793634) (xy 51.975203 -305.803658) (xy 52.024756 -305.821456)
			(xy 52.071012 -305.846609) (xy 52.112886 -305.878528) (xy 52.149398 -305.916466) (xy 52.17969 -305.959532)
			(xy 52.203053 -306.006717) (xy 52.218939 -306.056916) (xy 52.226976 -306.108952) (xy 52.22748 -306.135278)
			(xy 52.226976 -306.161604) (xy 52.218939 -306.21364) (xy 52.203053 -306.263839) (xy 52.17969 -306.311024)
			(xy 52.149398 -306.35409) (xy 52.112886 -306.392028) (xy 52.071012 -306.423947) (xy 52.024756 -306.4491)
			(xy 51.975203 -306.466898) (xy 51.923513 -306.476922) (xy 51.870899 -306.478939) (xy 51.818594 -306.472901)
			(xy 51.767823 -306.458949) (xy 51.719778 -306.43741) (xy 51.675583 -306.40879) (xy 51.636275 -306.373759)
			(xy 51.602775 -306.333138) (xy 51.575869 -306.287879) (xy 51.556186 -306.239044) (xy 51.544189 -306.187776)
			(xy 51.540159 -306.135278) (xy 44.683426 -306.135278) (xy 44.682922 -306.161604) (xy 44.674885 -306.21364)
			(xy 44.658999 -306.263839) (xy 44.635636 -306.311024) (xy 44.605344 -306.35409) (xy 44.568832 -306.392028)
			(xy 44.526958 -306.423947) (xy 44.480702 -306.4491) (xy 44.431149 -306.466898) (xy 44.379459 -306.476922)
			(xy 44.326845 -306.478939) (xy 44.27454 -306.472901) (xy 44.223769 -306.458949) (xy 44.175724 -306.43741)
			(xy 44.131529 -306.40879) (xy 44.092221 -306.373759) (xy 44.058721 -306.333138) (xy 44.031815 -306.287879)
			(xy 44.012132 -306.239044) (xy 44.000135 -306.187776) (xy 43.996105 -306.135278) (xy 37.139372 -306.135278)
			(xy 37.138868 -306.161604) (xy 37.130831 -306.21364) (xy 37.114945 -306.263839) (xy 37.091582 -306.311024)
			(xy 37.06129 -306.35409) (xy 37.024778 -306.392028) (xy 36.982904 -306.423947) (xy 36.936648 -306.4491)
			(xy 36.887095 -306.466898) (xy 36.835405 -306.476922) (xy 36.782791 -306.478939) (xy 36.730486 -306.472901)
			(xy 36.679715 -306.458949) (xy 36.63167 -306.43741) (xy 36.587475 -306.40879) (xy 36.548167 -306.373759)
			(xy 36.514667 -306.333138) (xy 36.487761 -306.287879) (xy 36.468078 -306.239044) (xy 36.456081 -306.187776)
			(xy 36.452051 -306.135278) (xy 29.595572 -306.135278) (xy 29.595068 -306.161604) (xy 29.587031 -306.21364)
			(xy 29.571145 -306.263839) (xy 29.547782 -306.311024) (xy 29.51749 -306.35409) (xy 29.480978 -306.392028)
			(xy 29.439104 -306.423947) (xy 29.392848 -306.4491) (xy 29.343295 -306.466898) (xy 29.291605 -306.476922)
			(xy 29.238991 -306.478939) (xy 29.186686 -306.472901) (xy 29.135915 -306.458949) (xy 29.08787 -306.43741)
			(xy 29.043675 -306.40879) (xy 29.004367 -306.373759) (xy 28.970867 -306.333138) (xy 28.943961 -306.287879)
			(xy 28.924278 -306.239044) (xy 28.912281 -306.187776) (xy 28.908251 -306.135278) (xy 22.051518 -306.135278)
			(xy 22.051014 -306.161604) (xy 22.042977 -306.21364) (xy 22.027091 -306.263839) (xy 22.003728 -306.311024)
			(xy 21.973436 -306.35409) (xy 21.936924 -306.392028) (xy 21.89505 -306.423947) (xy 21.848794 -306.4491)
			(xy 21.799241 -306.466898) (xy 21.747551 -306.476922) (xy 21.694937 -306.478939) (xy 21.642632 -306.472901)
			(xy 21.591861 -306.458949) (xy 21.543816 -306.43741) (xy 21.499621 -306.40879) (xy 21.460313 -306.373759)
			(xy 21.426813 -306.333138) (xy 21.399907 -306.287879) (xy 21.380224 -306.239044) (xy 21.368227 -306.187776)
			(xy 21.364197 -306.135278) (xy 16.086074 -306.135278) (xy 16.086074 -306.985416) (xy 17.264129 -306.985416)
			(xy 17.268159 -306.932918) (xy 17.280156 -306.88165) (xy 17.299839 -306.832815) (xy 17.326745 -306.787556)
			(xy 17.360245 -306.746935) (xy 17.399553 -306.711904) (xy 17.443748 -306.683284) (xy 17.491793 -306.661745)
			(xy 17.542564 -306.647793) (xy 17.594869 -306.641755) (xy 17.647483 -306.643772) (xy 17.699173 -306.653796)
			(xy 17.748726 -306.671594) (xy 17.794982 -306.696747) (xy 17.836856 -306.728666) (xy 17.873368 -306.766604)
			(xy 17.90366 -306.80967) (xy 17.927023 -306.856855) (xy 17.942909 -306.907054) (xy 17.950946 -306.95909)
			(xy 17.95145 -306.985416) (xy 24.808183 -306.985416) (xy 24.812213 -306.932918) (xy 24.82421 -306.88165)
			(xy 24.843893 -306.832815) (xy 24.870799 -306.787556) (xy 24.904299 -306.746935) (xy 24.943607 -306.711904)
			(xy 24.987802 -306.683284) (xy 25.035847 -306.661745) (xy 25.086618 -306.647793) (xy 25.138923 -306.641755)
			(xy 25.191537 -306.643772) (xy 25.243227 -306.653796) (xy 25.29278 -306.671594) (xy 25.339036 -306.696747)
			(xy 25.38091 -306.728666) (xy 25.417422 -306.766604) (xy 25.447714 -306.80967) (xy 25.471077 -306.856855)
			(xy 25.486963 -306.907054) (xy 25.495 -306.95909) (xy 25.495504 -306.985416) (xy 32.351983 -306.985416)
			(xy 32.356013 -306.932918) (xy 32.36801 -306.88165) (xy 32.387693 -306.832815) (xy 32.414599 -306.787556)
			(xy 32.448099 -306.746935) (xy 32.487407 -306.711904) (xy 32.531602 -306.683284) (xy 32.579647 -306.661745)
			(xy 32.630418 -306.647793) (xy 32.682723 -306.641755) (xy 32.735337 -306.643772) (xy 32.787027 -306.653796)
			(xy 32.83658 -306.671594) (xy 32.882836 -306.696747) (xy 32.92471 -306.728666) (xy 32.961222 -306.766604)
			(xy 32.991514 -306.80967) (xy 33.014877 -306.856855) (xy 33.030763 -306.907054) (xy 33.0388 -306.95909)
			(xy 33.039304 -306.985416) (xy 39.896037 -306.985416) (xy 39.900067 -306.932918) (xy 39.912064 -306.88165)
			(xy 39.931747 -306.832815) (xy 39.958653 -306.787556) (xy 39.992153 -306.746935) (xy 40.031461 -306.711904)
			(xy 40.075656 -306.683284) (xy 40.123701 -306.661745) (xy 40.174472 -306.647793) (xy 40.226777 -306.641755)
			(xy 40.279391 -306.643772) (xy 40.331081 -306.653796) (xy 40.380634 -306.671594) (xy 40.42689 -306.696747)
			(xy 40.468764 -306.728666) (xy 40.505276 -306.766604) (xy 40.535568 -306.80967) (xy 40.558931 -306.856855)
			(xy 40.574817 -306.907054) (xy 40.582854 -306.95909) (xy 40.583358 -306.985416) (xy 47.440091 -306.985416)
			(xy 47.444121 -306.932918) (xy 47.456118 -306.88165) (xy 47.475801 -306.832815) (xy 47.502707 -306.787556)
			(xy 47.536207 -306.746935) (xy 47.575515 -306.711904) (xy 47.61971 -306.683284) (xy 47.667755 -306.661745)
			(xy 47.718526 -306.647793) (xy 47.770831 -306.641755) (xy 47.823445 -306.643772) (xy 47.875135 -306.653796)
			(xy 47.924688 -306.671594) (xy 47.970944 -306.696747) (xy 48.012818 -306.728666) (xy 48.04933 -306.766604)
			(xy 48.079622 -306.80967) (xy 48.102985 -306.856855) (xy 48.118871 -306.907054) (xy 48.126908 -306.95909)
			(xy 48.127412 -306.985416) (xy 48.126908 -307.011742) (xy 48.118871 -307.063778) (xy 48.102985 -307.113977)
			(xy 48.079622 -307.161162) (xy 48.04933 -307.204228) (xy 48.012818 -307.242166) (xy 47.970944 -307.274085)
			(xy 47.924688 -307.299238) (xy 47.875135 -307.317036) (xy 47.823445 -307.32706) (xy 47.770831 -307.329077)
			(xy 47.718526 -307.323039) (xy 47.667755 -307.309087) (xy 47.61971 -307.287548) (xy 47.575515 -307.258928)
			(xy 47.536207 -307.223897) (xy 47.502707 -307.183276) (xy 47.475801 -307.138017) (xy 47.456118 -307.089182)
			(xy 47.444121 -307.037914) (xy 47.440091 -306.985416) (xy 40.583358 -306.985416) (xy 40.582854 -307.011742)
			(xy 40.574817 -307.063778) (xy 40.558931 -307.113977) (xy 40.535568 -307.161162) (xy 40.505276 -307.204228)
			(xy 40.468764 -307.242166) (xy 40.42689 -307.274085) (xy 40.380634 -307.299238) (xy 40.331081 -307.317036)
			(xy 40.279391 -307.32706) (xy 40.226777 -307.329077) (xy 40.174472 -307.323039) (xy 40.123701 -307.309087)
			(xy 40.075656 -307.287548) (xy 40.031461 -307.258928) (xy 39.992153 -307.223897) (xy 39.958653 -307.183276)
			(xy 39.931747 -307.138017) (xy 39.912064 -307.089182) (xy 39.900067 -307.037914) (xy 39.896037 -306.985416)
			(xy 33.039304 -306.985416) (xy 33.0388 -307.011742) (xy 33.030763 -307.063778) (xy 33.014877 -307.113977)
			(xy 32.991514 -307.161162) (xy 32.961222 -307.204228) (xy 32.92471 -307.242166) (xy 32.882836 -307.274085)
			(xy 32.83658 -307.299238) (xy 32.787027 -307.317036) (xy 32.735337 -307.32706) (xy 32.682723 -307.329077)
			(xy 32.630418 -307.323039) (xy 32.579647 -307.309087) (xy 32.531602 -307.287548) (xy 32.487407 -307.258928)
			(xy 32.448099 -307.223897) (xy 32.414599 -307.183276) (xy 32.387693 -307.138017) (xy 32.36801 -307.089182)
			(xy 32.356013 -307.037914) (xy 32.351983 -306.985416) (xy 25.495504 -306.985416) (xy 25.495 -307.011742)
			(xy 25.486963 -307.063778) (xy 25.471077 -307.113977) (xy 25.447714 -307.161162) (xy 25.417422 -307.204228)
			(xy 25.38091 -307.242166) (xy 25.339036 -307.274085) (xy 25.29278 -307.299238) (xy 25.243227 -307.317036)
			(xy 25.191537 -307.32706) (xy 25.138923 -307.329077) (xy 25.086618 -307.323039) (xy 25.035847 -307.309087)
			(xy 24.987802 -307.287548) (xy 24.943607 -307.258928) (xy 24.904299 -307.223897) (xy 24.870799 -307.183276)
			(xy 24.843893 -307.138017) (xy 24.82421 -307.089182) (xy 24.812213 -307.037914) (xy 24.808183 -306.985416)
			(xy 17.95145 -306.985416) (xy 17.950946 -307.011742) (xy 17.942909 -307.063778) (xy 17.927023 -307.113977)
			(xy 17.90366 -307.161162) (xy 17.873368 -307.204228) (xy 17.836856 -307.242166) (xy 17.794982 -307.274085)
			(xy 17.748726 -307.299238) (xy 17.699173 -307.317036) (xy 17.647483 -307.32706) (xy 17.594869 -307.329077)
			(xy 17.542564 -307.323039) (xy 17.491793 -307.309087) (xy 17.443748 -307.287548) (xy 17.399553 -307.258928)
			(xy 17.360245 -307.223897) (xy 17.326745 -307.183276) (xy 17.299839 -307.138017) (xy 17.280156 -307.089182)
			(xy 17.268159 -307.037914) (xy 17.264129 -306.985416) (xy 16.086074 -306.985416) (xy 16.086074 -307.8353)
			(xy 21.364197 -307.8353) (xy 21.368227 -307.782802) (xy 21.380224 -307.731534) (xy 21.399907 -307.682699)
			(xy 21.426813 -307.63744) (xy 21.460313 -307.596819) (xy 21.499621 -307.561788) (xy 21.543816 -307.533168)
			(xy 21.591861 -307.511629) (xy 21.642632 -307.497677) (xy 21.694937 -307.491639) (xy 21.747551 -307.493656)
			(xy 21.799241 -307.50368) (xy 21.848794 -307.521478) (xy 21.89505 -307.546631) (xy 21.936924 -307.57855)
			(xy 21.973436 -307.616488) (xy 22.003728 -307.659554) (xy 22.027091 -307.706739) (xy 22.042977 -307.756938)
			(xy 22.051014 -307.808974) (xy 22.051518 -307.8353) (xy 28.908251 -307.8353) (xy 28.912281 -307.782802)
			(xy 28.924278 -307.731534) (xy 28.943961 -307.682699) (xy 28.970867 -307.63744) (xy 29.004367 -307.596819)
			(xy 29.043675 -307.561788) (xy 29.08787 -307.533168) (xy 29.135915 -307.511629) (xy 29.186686 -307.497677)
			(xy 29.238991 -307.491639) (xy 29.291605 -307.493656) (xy 29.343295 -307.50368) (xy 29.392848 -307.521478)
			(xy 29.439104 -307.546631) (xy 29.480978 -307.57855) (xy 29.51749 -307.616488) (xy 29.547782 -307.659554)
			(xy 29.571145 -307.706739) (xy 29.587031 -307.756938) (xy 29.595068 -307.808974) (xy 29.595572 -307.8353)
			(xy 36.452051 -307.8353) (xy 36.456081 -307.782802) (xy 36.468078 -307.731534) (xy 36.487761 -307.682699)
			(xy 36.514667 -307.63744) (xy 36.548167 -307.596819) (xy 36.587475 -307.561788) (xy 36.63167 -307.533168)
			(xy 36.679715 -307.511629) (xy 36.730486 -307.497677) (xy 36.782791 -307.491639) (xy 36.835405 -307.493656)
			(xy 36.887095 -307.50368) (xy 36.936648 -307.521478) (xy 36.982904 -307.546631) (xy 37.024778 -307.57855)
			(xy 37.06129 -307.616488) (xy 37.091582 -307.659554) (xy 37.114945 -307.706739) (xy 37.130831 -307.756938)
			(xy 37.138868 -307.808974) (xy 37.139372 -307.8353) (xy 43.996105 -307.8353) (xy 44.000135 -307.782802)
			(xy 44.012132 -307.731534) (xy 44.031815 -307.682699) (xy 44.058721 -307.63744) (xy 44.092221 -307.596819)
			(xy 44.131529 -307.561788) (xy 44.175724 -307.533168) (xy 44.223769 -307.511629) (xy 44.27454 -307.497677)
			(xy 44.326845 -307.491639) (xy 44.379459 -307.493656) (xy 44.431149 -307.50368) (xy 44.480702 -307.521478)
			(xy 44.526958 -307.546631) (xy 44.568832 -307.57855) (xy 44.605344 -307.616488) (xy 44.635636 -307.659554)
			(xy 44.658999 -307.706739) (xy 44.674885 -307.756938) (xy 44.682922 -307.808974) (xy 44.683426 -307.8353)
			(xy 51.540159 -307.8353) (xy 51.544189 -307.782802) (xy 51.556186 -307.731534) (xy 51.575869 -307.682699)
			(xy 51.602775 -307.63744) (xy 51.636275 -307.596819) (xy 51.675583 -307.561788) (xy 51.719778 -307.533168)
			(xy 51.767823 -307.511629) (xy 51.818594 -307.497677) (xy 51.870899 -307.491639) (xy 51.923513 -307.493656)
			(xy 51.975203 -307.50368) (xy 52.024756 -307.521478) (xy 52.071012 -307.546631) (xy 52.112886 -307.57855)
			(xy 52.149398 -307.616488) (xy 52.17969 -307.659554) (xy 52.203053 -307.706739) (xy 52.218939 -307.756938)
			(xy 52.226976 -307.808974) (xy 52.22748 -307.8353) (xy 52.226976 -307.861626) (xy 52.218939 -307.913662)
			(xy 52.203053 -307.963861) (xy 52.17969 -308.011046) (xy 52.149398 -308.054112) (xy 52.112886 -308.09205)
			(xy 52.071012 -308.123969) (xy 52.024756 -308.149122) (xy 51.975203 -308.16692) (xy 51.923513 -308.176944)
			(xy 51.870899 -308.178961) (xy 51.818594 -308.172923) (xy 51.767823 -308.158971) (xy 51.719778 -308.137432)
			(xy 51.675583 -308.108812) (xy 51.636275 -308.073781) (xy 51.602775 -308.03316) (xy 51.575869 -307.987901)
			(xy 51.556186 -307.939066) (xy 51.544189 -307.887798) (xy 51.540159 -307.8353) (xy 44.683426 -307.8353)
			(xy 44.682922 -307.861626) (xy 44.674885 -307.913662) (xy 44.658999 -307.963861) (xy 44.635636 -308.011046)
			(xy 44.605344 -308.054112) (xy 44.568832 -308.09205) (xy 44.526958 -308.123969) (xy 44.480702 -308.149122)
			(xy 44.431149 -308.16692) (xy 44.379459 -308.176944) (xy 44.326845 -308.178961) (xy 44.27454 -308.172923)
			(xy 44.223769 -308.158971) (xy 44.175724 -308.137432) (xy 44.131529 -308.108812) (xy 44.092221 -308.073781)
			(xy 44.058721 -308.03316) (xy 44.031815 -307.987901) (xy 44.012132 -307.939066) (xy 44.000135 -307.887798)
			(xy 43.996105 -307.8353) (xy 37.139372 -307.8353) (xy 37.138868 -307.861626) (xy 37.130831 -307.913662)
			(xy 37.114945 -307.963861) (xy 37.091582 -308.011046) (xy 37.06129 -308.054112) (xy 37.024778 -308.09205)
			(xy 36.982904 -308.123969) (xy 36.936648 -308.149122) (xy 36.887095 -308.16692) (xy 36.835405 -308.176944)
			(xy 36.782791 -308.178961) (xy 36.730486 -308.172923) (xy 36.679715 -308.158971) (xy 36.63167 -308.137432)
			(xy 36.587475 -308.108812) (xy 36.548167 -308.073781) (xy 36.514667 -308.03316) (xy 36.487761 -307.987901)
			(xy 36.468078 -307.939066) (xy 36.456081 -307.887798) (xy 36.452051 -307.8353) (xy 29.595572 -307.8353)
			(xy 29.595068 -307.861626) (xy 29.587031 -307.913662) (xy 29.571145 -307.963861) (xy 29.547782 -308.011046)
			(xy 29.51749 -308.054112) (xy 29.480978 -308.09205) (xy 29.439104 -308.123969) (xy 29.392848 -308.149122)
			(xy 29.343295 -308.16692) (xy 29.291605 -308.176944) (xy 29.238991 -308.178961) (xy 29.186686 -308.172923)
			(xy 29.135915 -308.158971) (xy 29.08787 -308.137432) (xy 29.043675 -308.108812) (xy 29.004367 -308.073781)
			(xy 28.970867 -308.03316) (xy 28.943961 -307.987901) (xy 28.924278 -307.939066) (xy 28.912281 -307.887798)
			(xy 28.908251 -307.8353) (xy 22.051518 -307.8353) (xy 22.051014 -307.861626) (xy 22.042977 -307.913662)
			(xy 22.027091 -307.963861) (xy 22.003728 -308.011046) (xy 21.973436 -308.054112) (xy 21.936924 -308.09205)
			(xy 21.89505 -308.123969) (xy 21.848794 -308.149122) (xy 21.799241 -308.16692) (xy 21.747551 -308.176944)
			(xy 21.694937 -308.178961) (xy 21.642632 -308.172923) (xy 21.591861 -308.158971) (xy 21.543816 -308.137432)
			(xy 21.499621 -308.108812) (xy 21.460313 -308.073781) (xy 21.426813 -308.03316) (xy 21.399907 -307.987901)
			(xy 21.380224 -307.939066) (xy 21.368227 -307.887798) (xy 21.364197 -307.8353) (xy 16.086074 -307.8353)
			(xy 16.086074 -308.685438) (xy 17.264129 -308.685438) (xy 17.268159 -308.63294) (xy 17.280156 -308.581672)
			(xy 17.299839 -308.532837) (xy 17.326745 -308.487578) (xy 17.360245 -308.446957) (xy 17.399553 -308.411926)
			(xy 17.443748 -308.383306) (xy 17.491793 -308.361767) (xy 17.542564 -308.347815) (xy 17.594869 -308.341777)
			(xy 17.647483 -308.343794) (xy 17.699173 -308.353818) (xy 17.748726 -308.371616) (xy 17.794982 -308.396769)
			(xy 17.836856 -308.428688) (xy 17.873368 -308.466626) (xy 17.90366 -308.509692) (xy 17.927023 -308.556877)
			(xy 17.942909 -308.607076) (xy 17.950946 -308.659112) (xy 17.95145 -308.685438) (xy 24.808183 -308.685438)
			(xy 24.812213 -308.63294) (xy 24.82421 -308.581672) (xy 24.843893 -308.532837) (xy 24.870799 -308.487578)
			(xy 24.904299 -308.446957) (xy 24.943607 -308.411926) (xy 24.987802 -308.383306) (xy 25.035847 -308.361767)
			(xy 25.086618 -308.347815) (xy 25.138923 -308.341777) (xy 25.191537 -308.343794) (xy 25.243227 -308.353818)
			(xy 25.29278 -308.371616) (xy 25.339036 -308.396769) (xy 25.38091 -308.428688) (xy 25.417422 -308.466626)
			(xy 25.447714 -308.509692) (xy 25.471077 -308.556877) (xy 25.486963 -308.607076) (xy 25.495 -308.659112)
			(xy 25.495504 -308.685438) (xy 32.351983 -308.685438) (xy 32.356013 -308.63294) (xy 32.36801 -308.581672)
			(xy 32.387693 -308.532837) (xy 32.414599 -308.487578) (xy 32.448099 -308.446957) (xy 32.487407 -308.411926)
			(xy 32.531602 -308.383306) (xy 32.579647 -308.361767) (xy 32.630418 -308.347815) (xy 32.682723 -308.341777)
			(xy 32.735337 -308.343794) (xy 32.787027 -308.353818) (xy 32.83658 -308.371616) (xy 32.882836 -308.396769)
			(xy 32.92471 -308.428688) (xy 32.961222 -308.466626) (xy 32.991514 -308.509692) (xy 33.014877 -308.556877)
			(xy 33.030763 -308.607076) (xy 33.0388 -308.659112) (xy 33.039304 -308.685438) (xy 39.896037 -308.685438)
			(xy 39.900067 -308.63294) (xy 39.912064 -308.581672) (xy 39.931747 -308.532837) (xy 39.958653 -308.487578)
			(xy 39.992153 -308.446957) (xy 40.031461 -308.411926) (xy 40.075656 -308.383306) (xy 40.123701 -308.361767)
			(xy 40.174472 -308.347815) (xy 40.226777 -308.341777) (xy 40.279391 -308.343794) (xy 40.331081 -308.353818)
			(xy 40.380634 -308.371616) (xy 40.42689 -308.396769) (xy 40.468764 -308.428688) (xy 40.505276 -308.466626)
			(xy 40.535568 -308.509692) (xy 40.558931 -308.556877) (xy 40.574817 -308.607076) (xy 40.582854 -308.659112)
			(xy 40.583358 -308.685438) (xy 47.440091 -308.685438) (xy 47.444121 -308.63294) (xy 47.456118 -308.581672)
			(xy 47.475801 -308.532837) (xy 47.502707 -308.487578) (xy 47.536207 -308.446957) (xy 47.575515 -308.411926)
			(xy 47.61971 -308.383306) (xy 47.667755 -308.361767) (xy 47.718526 -308.347815) (xy 47.770831 -308.341777)
			(xy 47.823445 -308.343794) (xy 47.875135 -308.353818) (xy 47.924688 -308.371616) (xy 47.970944 -308.396769)
			(xy 48.012818 -308.428688) (xy 48.04933 -308.466626) (xy 48.079622 -308.509692) (xy 48.102985 -308.556877)
			(xy 48.118871 -308.607076) (xy 48.126908 -308.659112) (xy 48.127412 -308.685438) (xy 48.126908 -308.711764)
			(xy 48.118871 -308.7638) (xy 48.102985 -308.813999) (xy 48.079622 -308.861184) (xy 48.04933 -308.90425)
			(xy 48.012818 -308.942188) (xy 47.970944 -308.974107) (xy 47.924688 -308.99926) (xy 47.875135 -309.017058)
			(xy 47.823445 -309.027082) (xy 47.770831 -309.029099) (xy 47.718526 -309.023061) (xy 47.667755 -309.009109)
			(xy 47.61971 -308.98757) (xy 47.575515 -308.95895) (xy 47.536207 -308.923919) (xy 47.502707 -308.883298)
			(xy 47.475801 -308.838039) (xy 47.456118 -308.789204) (xy 47.444121 -308.737936) (xy 47.440091 -308.685438)
			(xy 40.583358 -308.685438) (xy 40.582854 -308.711764) (xy 40.574817 -308.7638) (xy 40.558931 -308.813999)
			(xy 40.535568 -308.861184) (xy 40.505276 -308.90425) (xy 40.468764 -308.942188) (xy 40.42689 -308.974107)
			(xy 40.380634 -308.99926) (xy 40.331081 -309.017058) (xy 40.279391 -309.027082) (xy 40.226777 -309.029099)
			(xy 40.174472 -309.023061) (xy 40.123701 -309.009109) (xy 40.075656 -308.98757) (xy 40.031461 -308.95895)
			(xy 39.992153 -308.923919) (xy 39.958653 -308.883298) (xy 39.931747 -308.838039) (xy 39.912064 -308.789204)
			(xy 39.900067 -308.737936) (xy 39.896037 -308.685438) (xy 33.039304 -308.685438) (xy 33.0388 -308.711764)
			(xy 33.030763 -308.7638) (xy 33.014877 -308.813999) (xy 32.991514 -308.861184) (xy 32.961222 -308.90425)
			(xy 32.92471 -308.942188) (xy 32.882836 -308.974107) (xy 32.83658 -308.99926) (xy 32.787027 -309.017058)
			(xy 32.735337 -309.027082) (xy 32.682723 -309.029099) (xy 32.630418 -309.023061) (xy 32.579647 -309.009109)
			(xy 32.531602 -308.98757) (xy 32.487407 -308.95895) (xy 32.448099 -308.923919) (xy 32.414599 -308.883298)
			(xy 32.387693 -308.838039) (xy 32.36801 -308.789204) (xy 32.356013 -308.737936) (xy 32.351983 -308.685438)
			(xy 25.495504 -308.685438) (xy 25.495 -308.711764) (xy 25.486963 -308.7638) (xy 25.471077 -308.813999)
			(xy 25.447714 -308.861184) (xy 25.417422 -308.90425) (xy 25.38091 -308.942188) (xy 25.339036 -308.974107)
			(xy 25.29278 -308.99926) (xy 25.243227 -309.017058) (xy 25.191537 -309.027082) (xy 25.138923 -309.029099)
			(xy 25.086618 -309.023061) (xy 25.035847 -309.009109) (xy 24.987802 -308.98757) (xy 24.943607 -308.95895)
			(xy 24.904299 -308.923919) (xy 24.870799 -308.883298) (xy 24.843893 -308.838039) (xy 24.82421 -308.789204)
			(xy 24.812213 -308.737936) (xy 24.808183 -308.685438) (xy 17.95145 -308.685438) (xy 17.950946 -308.711764)
			(xy 17.942909 -308.7638) (xy 17.927023 -308.813999) (xy 17.90366 -308.861184) (xy 17.873368 -308.90425)
			(xy 17.836856 -308.942188) (xy 17.794982 -308.974107) (xy 17.748726 -308.99926) (xy 17.699173 -309.017058)
			(xy 17.647483 -309.027082) (xy 17.594869 -309.029099) (xy 17.542564 -309.023061) (xy 17.491793 -309.009109)
			(xy 17.443748 -308.98757) (xy 17.399553 -308.95895) (xy 17.360245 -308.923919) (xy 17.326745 -308.883298)
			(xy 17.299839 -308.838039) (xy 17.280156 -308.789204) (xy 17.268159 -308.737936) (xy 17.264129 -308.685438)
			(xy 16.086074 -308.685438) (xy 16.086074 -309.535322) (xy 21.364197 -309.535322) (xy 21.368227 -309.482824)
			(xy 21.380224 -309.431556) (xy 21.399907 -309.382721) (xy 21.426813 -309.337462) (xy 21.460313 -309.296841)
			(xy 21.499621 -309.26181) (xy 21.543816 -309.23319) (xy 21.591861 -309.211651) (xy 21.642632 -309.197699)
			(xy 21.694937 -309.191661) (xy 21.747551 -309.193678) (xy 21.799241 -309.203702) (xy 21.848794 -309.2215)
			(xy 21.89505 -309.246653) (xy 21.936924 -309.278572) (xy 21.973436 -309.31651) (xy 22.003728 -309.359576)
			(xy 22.027091 -309.406761) (xy 22.042977 -309.45696) (xy 22.051014 -309.508996) (xy 22.051518 -309.535322)
			(xy 28.908251 -309.535322) (xy 28.912281 -309.482824) (xy 28.924278 -309.431556) (xy 28.943961 -309.382721)
			(xy 28.970867 -309.337462) (xy 29.004367 -309.296841) (xy 29.043675 -309.26181) (xy 29.08787 -309.23319)
			(xy 29.135915 -309.211651) (xy 29.186686 -309.197699) (xy 29.238991 -309.191661) (xy 29.291605 -309.193678)
			(xy 29.343295 -309.203702) (xy 29.392848 -309.2215) (xy 29.439104 -309.246653) (xy 29.480978 -309.278572)
			(xy 29.51749 -309.31651) (xy 29.547782 -309.359576) (xy 29.571145 -309.406761) (xy 29.587031 -309.45696)
			(xy 29.595068 -309.508996) (xy 29.595572 -309.535322) (xy 36.452051 -309.535322) (xy 36.456081 -309.482824)
			(xy 36.468078 -309.431556) (xy 36.487761 -309.382721) (xy 36.514667 -309.337462) (xy 36.548167 -309.296841)
			(xy 36.587475 -309.26181) (xy 36.63167 -309.23319) (xy 36.679715 -309.211651) (xy 36.730486 -309.197699)
			(xy 36.782791 -309.191661) (xy 36.835405 -309.193678) (xy 36.887095 -309.203702) (xy 36.936648 -309.2215)
			(xy 36.982904 -309.246653) (xy 37.024778 -309.278572) (xy 37.06129 -309.31651) (xy 37.091582 -309.359576)
			(xy 37.114945 -309.406761) (xy 37.130831 -309.45696) (xy 37.138868 -309.508996) (xy 37.139372 -309.535322)
			(xy 43.996105 -309.535322) (xy 44.000135 -309.482824) (xy 44.012132 -309.431556) (xy 44.031815 -309.382721)
			(xy 44.058721 -309.337462) (xy 44.092221 -309.296841) (xy 44.131529 -309.26181) (xy 44.175724 -309.23319)
			(xy 44.223769 -309.211651) (xy 44.27454 -309.197699) (xy 44.326845 -309.191661) (xy 44.379459 -309.193678)
			(xy 44.431149 -309.203702) (xy 44.480702 -309.2215) (xy 44.526958 -309.246653) (xy 44.568832 -309.278572)
			(xy 44.605344 -309.31651) (xy 44.635636 -309.359576) (xy 44.658999 -309.406761) (xy 44.674885 -309.45696)
			(xy 44.682922 -309.508996) (xy 44.683426 -309.535322) (xy 51.540159 -309.535322) (xy 51.544189 -309.482824)
			(xy 51.556186 -309.431556) (xy 51.575869 -309.382721) (xy 51.602775 -309.337462) (xy 51.636275 -309.296841)
			(xy 51.675583 -309.26181) (xy 51.719778 -309.23319) (xy 51.767823 -309.211651) (xy 51.818594 -309.197699)
			(xy 51.870899 -309.191661) (xy 51.923513 -309.193678) (xy 51.975203 -309.203702) (xy 52.024756 -309.2215)
			(xy 52.071012 -309.246653) (xy 52.112886 -309.278572) (xy 52.149398 -309.31651) (xy 52.17969 -309.359576)
			(xy 52.203053 -309.406761) (xy 52.218939 -309.45696) (xy 52.226976 -309.508996) (xy 52.22748 -309.535322)
			(xy 52.226976 -309.561648) (xy 52.218939 -309.613684) (xy 52.203053 -309.663883) (xy 52.17969 -309.711068)
			(xy 52.149398 -309.754134) (xy 52.112886 -309.792072) (xy 52.071012 -309.823991) (xy 52.024756 -309.849144)
			(xy 51.975203 -309.866942) (xy 51.923513 -309.876966) (xy 51.870899 -309.878983) (xy 51.818594 -309.872945)
			(xy 51.767823 -309.858993) (xy 51.719778 -309.837454) (xy 51.675583 -309.808834) (xy 51.636275 -309.773803)
			(xy 51.602775 -309.733182) (xy 51.575869 -309.687923) (xy 51.556186 -309.639088) (xy 51.544189 -309.58782)
			(xy 51.540159 -309.535322) (xy 44.683426 -309.535322) (xy 44.682922 -309.561648) (xy 44.674885 -309.613684)
			(xy 44.658999 -309.663883) (xy 44.635636 -309.711068) (xy 44.605344 -309.754134) (xy 44.568832 -309.792072)
			(xy 44.526958 -309.823991) (xy 44.480702 -309.849144) (xy 44.431149 -309.866942) (xy 44.379459 -309.876966)
			(xy 44.326845 -309.878983) (xy 44.27454 -309.872945) (xy 44.223769 -309.858993) (xy 44.175724 -309.837454)
			(xy 44.131529 -309.808834) (xy 44.092221 -309.773803) (xy 44.058721 -309.733182) (xy 44.031815 -309.687923)
			(xy 44.012132 -309.639088) (xy 44.000135 -309.58782) (xy 43.996105 -309.535322) (xy 37.139372 -309.535322)
			(xy 37.138868 -309.561648) (xy 37.130831 -309.613684) (xy 37.114945 -309.663883) (xy 37.091582 -309.711068)
			(xy 37.06129 -309.754134) (xy 37.024778 -309.792072) (xy 36.982904 -309.823991) (xy 36.936648 -309.849144)
			(xy 36.887095 -309.866942) (xy 36.835405 -309.876966) (xy 36.782791 -309.878983) (xy 36.730486 -309.872945)
			(xy 36.679715 -309.858993) (xy 36.63167 -309.837454) (xy 36.587475 -309.808834) (xy 36.548167 -309.773803)
			(xy 36.514667 -309.733182) (xy 36.487761 -309.687923) (xy 36.468078 -309.639088) (xy 36.456081 -309.58782)
			(xy 36.452051 -309.535322) (xy 29.595572 -309.535322) (xy 29.595068 -309.561648) (xy 29.587031 -309.613684)
			(xy 29.571145 -309.663883) (xy 29.547782 -309.711068) (xy 29.51749 -309.754134) (xy 29.480978 -309.792072)
			(xy 29.439104 -309.823991) (xy 29.392848 -309.849144) (xy 29.343295 -309.866942) (xy 29.291605 -309.876966)
			(xy 29.238991 -309.878983) (xy 29.186686 -309.872945) (xy 29.135915 -309.858993) (xy 29.08787 -309.837454)
			(xy 29.043675 -309.808834) (xy 29.004367 -309.773803) (xy 28.970867 -309.733182) (xy 28.943961 -309.687923)
			(xy 28.924278 -309.639088) (xy 28.912281 -309.58782) (xy 28.908251 -309.535322) (xy 22.051518 -309.535322)
			(xy 22.051014 -309.561648) (xy 22.042977 -309.613684) (xy 22.027091 -309.663883) (xy 22.003728 -309.711068)
			(xy 21.973436 -309.754134) (xy 21.936924 -309.792072) (xy 21.89505 -309.823991) (xy 21.848794 -309.849144)
			(xy 21.799241 -309.866942) (xy 21.747551 -309.876966) (xy 21.694937 -309.878983) (xy 21.642632 -309.872945)
			(xy 21.591861 -309.858993) (xy 21.543816 -309.837454) (xy 21.499621 -309.808834) (xy 21.460313 -309.773803)
			(xy 21.426813 -309.733182) (xy 21.399907 -309.687923) (xy 21.380224 -309.639088) (xy 21.368227 -309.58782)
			(xy 21.364197 -309.535322) (xy 16.086074 -309.535322) (xy 16.086074 -310.385206) (xy 17.264129 -310.385206)
			(xy 17.268159 -310.332708) (xy 17.280156 -310.28144) (xy 17.299839 -310.232605) (xy 17.326745 -310.187346)
			(xy 17.360245 -310.146725) (xy 17.399553 -310.111694) (xy 17.443748 -310.083074) (xy 17.491793 -310.061535)
			(xy 17.542564 -310.047583) (xy 17.594869 -310.041545) (xy 17.647483 -310.043562) (xy 17.699173 -310.053586)
			(xy 17.748726 -310.071384) (xy 17.794982 -310.096537) (xy 17.836856 -310.128456) (xy 17.873368 -310.166394)
			(xy 17.90366 -310.20946) (xy 17.927023 -310.256645) (xy 17.942909 -310.306844) (xy 17.950946 -310.35888)
			(xy 17.95145 -310.385206) (xy 24.808183 -310.385206) (xy 24.812213 -310.332708) (xy 24.82421 -310.28144)
			(xy 24.843893 -310.232605) (xy 24.870799 -310.187346) (xy 24.904299 -310.146725) (xy 24.943607 -310.111694)
			(xy 24.987802 -310.083074) (xy 25.035847 -310.061535) (xy 25.086618 -310.047583) (xy 25.138923 -310.041545)
			(xy 25.191537 -310.043562) (xy 25.243227 -310.053586) (xy 25.29278 -310.071384) (xy 25.339036 -310.096537)
			(xy 25.38091 -310.128456) (xy 25.417422 -310.166394) (xy 25.447714 -310.20946) (xy 25.471077 -310.256645)
			(xy 25.486963 -310.306844) (xy 25.495 -310.35888) (xy 25.495504 -310.385206) (xy 32.351983 -310.385206)
			(xy 32.356013 -310.332708) (xy 32.36801 -310.28144) (xy 32.387693 -310.232605) (xy 32.414599 -310.187346)
			(xy 32.448099 -310.146725) (xy 32.487407 -310.111694) (xy 32.531602 -310.083074) (xy 32.579647 -310.061535)
			(xy 32.630418 -310.047583) (xy 32.682723 -310.041545) (xy 32.735337 -310.043562) (xy 32.787027 -310.053586)
			(xy 32.83658 -310.071384) (xy 32.882836 -310.096537) (xy 32.92471 -310.128456) (xy 32.961222 -310.166394)
			(xy 32.991514 -310.20946) (xy 33.014877 -310.256645) (xy 33.030763 -310.306844) (xy 33.0388 -310.35888)
			(xy 33.039304 -310.385206) (xy 39.896037 -310.385206) (xy 39.900067 -310.332708) (xy 39.912064 -310.28144)
			(xy 39.931747 -310.232605) (xy 39.958653 -310.187346) (xy 39.992153 -310.146725) (xy 40.031461 -310.111694)
			(xy 40.075656 -310.083074) (xy 40.123701 -310.061535) (xy 40.174472 -310.047583) (xy 40.226777 -310.041545)
			(xy 40.279391 -310.043562) (xy 40.331081 -310.053586) (xy 40.380634 -310.071384) (xy 40.42689 -310.096537)
			(xy 40.468764 -310.128456) (xy 40.505276 -310.166394) (xy 40.535568 -310.20946) (xy 40.558931 -310.256645)
			(xy 40.574817 -310.306844) (xy 40.582854 -310.35888) (xy 40.583358 -310.385206) (xy 47.440091 -310.385206)
			(xy 47.444121 -310.332708) (xy 47.456118 -310.28144) (xy 47.475801 -310.232605) (xy 47.502707 -310.187346)
			(xy 47.536207 -310.146725) (xy 47.575515 -310.111694) (xy 47.61971 -310.083074) (xy 47.667755 -310.061535)
			(xy 47.718526 -310.047583) (xy 47.770831 -310.041545) (xy 47.823445 -310.043562) (xy 47.875135 -310.053586)
			(xy 47.924688 -310.071384) (xy 47.970944 -310.096537) (xy 48.012818 -310.128456) (xy 48.04933 -310.166394)
			(xy 48.079622 -310.20946) (xy 48.102985 -310.256645) (xy 48.118871 -310.306844) (xy 48.126908 -310.35888)
			(xy 48.127412 -310.385206) (xy 48.126908 -310.411532) (xy 48.118871 -310.463568) (xy 48.102985 -310.513767)
			(xy 48.079622 -310.560952) (xy 48.04933 -310.604018) (xy 48.012818 -310.641956) (xy 47.970944 -310.673875)
			(xy 47.924688 -310.699028) (xy 47.875135 -310.716826) (xy 47.823445 -310.72685) (xy 47.770831 -310.728867)
			(xy 47.718526 -310.722829) (xy 47.667755 -310.708877) (xy 47.61971 -310.687338) (xy 47.575515 -310.658718)
			(xy 47.536207 -310.623687) (xy 47.502707 -310.583066) (xy 47.475801 -310.537807) (xy 47.456118 -310.488972)
			(xy 47.444121 -310.437704) (xy 47.440091 -310.385206) (xy 40.583358 -310.385206) (xy 40.582854 -310.411532)
			(xy 40.574817 -310.463568) (xy 40.558931 -310.513767) (xy 40.535568 -310.560952) (xy 40.505276 -310.604018)
			(xy 40.468764 -310.641956) (xy 40.42689 -310.673875) (xy 40.380634 -310.699028) (xy 40.331081 -310.716826)
			(xy 40.279391 -310.72685) (xy 40.226777 -310.728867) (xy 40.174472 -310.722829) (xy 40.123701 -310.708877)
			(xy 40.075656 -310.687338) (xy 40.031461 -310.658718) (xy 39.992153 -310.623687) (xy 39.958653 -310.583066)
			(xy 39.931747 -310.537807) (xy 39.912064 -310.488972) (xy 39.900067 -310.437704) (xy 39.896037 -310.385206)
			(xy 33.039304 -310.385206) (xy 33.0388 -310.411532) (xy 33.030763 -310.463568) (xy 33.014877 -310.513767)
			(xy 32.991514 -310.560952) (xy 32.961222 -310.604018) (xy 32.92471 -310.641956) (xy 32.882836 -310.673875)
			(xy 32.83658 -310.699028) (xy 32.787027 -310.716826) (xy 32.735337 -310.72685) (xy 32.682723 -310.728867)
			(xy 32.630418 -310.722829) (xy 32.579647 -310.708877) (xy 32.531602 -310.687338) (xy 32.487407 -310.658718)
			(xy 32.448099 -310.623687) (xy 32.414599 -310.583066) (xy 32.387693 -310.537807) (xy 32.36801 -310.488972)
			(xy 32.356013 -310.437704) (xy 32.351983 -310.385206) (xy 25.495504 -310.385206) (xy 25.495 -310.411532)
			(xy 25.486963 -310.463568) (xy 25.471077 -310.513767) (xy 25.447714 -310.560952) (xy 25.417422 -310.604018)
			(xy 25.38091 -310.641956) (xy 25.339036 -310.673875) (xy 25.29278 -310.699028) (xy 25.243227 -310.716826)
			(xy 25.191537 -310.72685) (xy 25.138923 -310.728867) (xy 25.086618 -310.722829) (xy 25.035847 -310.708877)
			(xy 24.987802 -310.687338) (xy 24.943607 -310.658718) (xy 24.904299 -310.623687) (xy 24.870799 -310.583066)
			(xy 24.843893 -310.537807) (xy 24.82421 -310.488972) (xy 24.812213 -310.437704) (xy 24.808183 -310.385206)
			(xy 17.95145 -310.385206) (xy 17.950946 -310.411532) (xy 17.942909 -310.463568) (xy 17.927023 -310.513767)
			(xy 17.90366 -310.560952) (xy 17.873368 -310.604018) (xy 17.836856 -310.641956) (xy 17.794982 -310.673875)
			(xy 17.748726 -310.699028) (xy 17.699173 -310.716826) (xy 17.647483 -310.72685) (xy 17.594869 -310.728867)
			(xy 17.542564 -310.722829) (xy 17.491793 -310.708877) (xy 17.443748 -310.687338) (xy 17.399553 -310.658718)
			(xy 17.360245 -310.623687) (xy 17.326745 -310.583066) (xy 17.299839 -310.537807) (xy 17.280156 -310.488972)
			(xy 17.268159 -310.437704) (xy 17.264129 -310.385206) (xy 16.086074 -310.385206) (xy 16.086074 -311.235344)
			(xy 21.364197 -311.235344) (xy 21.368227 -311.182846) (xy 21.380224 -311.131578) (xy 21.399907 -311.082743)
			(xy 21.426813 -311.037484) (xy 21.460313 -310.996863) (xy 21.499621 -310.961832) (xy 21.543816 -310.933212)
			(xy 21.591861 -310.911673) (xy 21.642632 -310.897721) (xy 21.694937 -310.891683) (xy 21.747551 -310.8937)
			(xy 21.799241 -310.903724) (xy 21.848794 -310.921522) (xy 21.89505 -310.946675) (xy 21.936924 -310.978594)
			(xy 21.973436 -311.016532) (xy 22.003728 -311.059598) (xy 22.027091 -311.106783) (xy 22.042977 -311.156982)
			(xy 22.051014 -311.209018) (xy 22.051518 -311.235344) (xy 28.908251 -311.235344) (xy 28.912281 -311.182846)
			(xy 28.924278 -311.131578) (xy 28.943961 -311.082743) (xy 28.970867 -311.037484) (xy 29.004367 -310.996863)
			(xy 29.043675 -310.961832) (xy 29.08787 -310.933212) (xy 29.135915 -310.911673) (xy 29.186686 -310.897721)
			(xy 29.238991 -310.891683) (xy 29.291605 -310.8937) (xy 29.343295 -310.903724) (xy 29.392848 -310.921522)
			(xy 29.439104 -310.946675) (xy 29.480978 -310.978594) (xy 29.51749 -311.016532) (xy 29.547782 -311.059598)
			(xy 29.571145 -311.106783) (xy 29.587031 -311.156982) (xy 29.595068 -311.209018) (xy 29.595572 -311.235344)
			(xy 36.452051 -311.235344) (xy 36.456081 -311.182846) (xy 36.468078 -311.131578) (xy 36.487761 -311.082743)
			(xy 36.514667 -311.037484) (xy 36.548167 -310.996863) (xy 36.587475 -310.961832) (xy 36.63167 -310.933212)
			(xy 36.679715 -310.911673) (xy 36.730486 -310.897721) (xy 36.782791 -310.891683) (xy 36.835405 -310.8937)
			(xy 36.887095 -310.903724) (xy 36.936648 -310.921522) (xy 36.982904 -310.946675) (xy 37.024778 -310.978594)
			(xy 37.06129 -311.016532) (xy 37.091582 -311.059598) (xy 37.114945 -311.106783) (xy 37.130831 -311.156982)
			(xy 37.138868 -311.209018) (xy 37.139372 -311.235344) (xy 43.996105 -311.235344) (xy 44.000135 -311.182846)
			(xy 44.012132 -311.131578) (xy 44.031815 -311.082743) (xy 44.058721 -311.037484) (xy 44.092221 -310.996863)
			(xy 44.131529 -310.961832) (xy 44.175724 -310.933212) (xy 44.223769 -310.911673) (xy 44.27454 -310.897721)
			(xy 44.326845 -310.891683) (xy 44.379459 -310.8937) (xy 44.431149 -310.903724) (xy 44.480702 -310.921522)
			(xy 44.526958 -310.946675) (xy 44.568832 -310.978594) (xy 44.605344 -311.016532) (xy 44.635636 -311.059598)
			(xy 44.658999 -311.106783) (xy 44.674885 -311.156982) (xy 44.682922 -311.209018) (xy 44.683426 -311.235344)
			(xy 51.540159 -311.235344) (xy 51.544189 -311.182846) (xy 51.556186 -311.131578) (xy 51.575869 -311.082743)
			(xy 51.602775 -311.037484) (xy 51.636275 -310.996863) (xy 51.675583 -310.961832) (xy 51.719778 -310.933212)
			(xy 51.767823 -310.911673) (xy 51.818594 -310.897721) (xy 51.870899 -310.891683) (xy 51.923513 -310.8937)
			(xy 51.975203 -310.903724) (xy 52.024756 -310.921522) (xy 52.071012 -310.946675) (xy 52.112886 -310.978594)
			(xy 52.149398 -311.016532) (xy 52.17969 -311.059598) (xy 52.203053 -311.106783) (xy 52.218939 -311.156982)
			(xy 52.226976 -311.209018) (xy 52.22748 -311.235344) (xy 52.226976 -311.26167) (xy 52.218939 -311.313706)
			(xy 52.203053 -311.363905) (xy 52.17969 -311.41109) (xy 52.149398 -311.454156) (xy 52.112886 -311.492094)
			(xy 52.071012 -311.524013) (xy 52.024756 -311.549166) (xy 51.975203 -311.566964) (xy 51.923513 -311.576988)
			(xy 51.870899 -311.579005) (xy 51.818594 -311.572967) (xy 51.767823 -311.559015) (xy 51.719778 -311.537476)
			(xy 51.675583 -311.508856) (xy 51.636275 -311.473825) (xy 51.602775 -311.433204) (xy 51.575869 -311.387945)
			(xy 51.556186 -311.33911) (xy 51.544189 -311.287842) (xy 51.540159 -311.235344) (xy 44.683426 -311.235344)
			(xy 44.682922 -311.26167) (xy 44.674885 -311.313706) (xy 44.658999 -311.363905) (xy 44.635636 -311.41109)
			(xy 44.605344 -311.454156) (xy 44.568832 -311.492094) (xy 44.526958 -311.524013) (xy 44.480702 -311.549166)
			(xy 44.431149 -311.566964) (xy 44.379459 -311.576988) (xy 44.326845 -311.579005) (xy 44.27454 -311.572967)
			(xy 44.223769 -311.559015) (xy 44.175724 -311.537476) (xy 44.131529 -311.508856) (xy 44.092221 -311.473825)
			(xy 44.058721 -311.433204) (xy 44.031815 -311.387945) (xy 44.012132 -311.33911) (xy 44.000135 -311.287842)
			(xy 43.996105 -311.235344) (xy 37.139372 -311.235344) (xy 37.138868 -311.26167) (xy 37.130831 -311.313706)
			(xy 37.114945 -311.363905) (xy 37.091582 -311.41109) (xy 37.06129 -311.454156) (xy 37.024778 -311.492094)
			(xy 36.982904 -311.524013) (xy 36.936648 -311.549166) (xy 36.887095 -311.566964) (xy 36.835405 -311.576988)
			(xy 36.782791 -311.579005) (xy 36.730486 -311.572967) (xy 36.679715 -311.559015) (xy 36.63167 -311.537476)
			(xy 36.587475 -311.508856) (xy 36.548167 -311.473825) (xy 36.514667 -311.433204) (xy 36.487761 -311.387945)
			(xy 36.468078 -311.33911) (xy 36.456081 -311.287842) (xy 36.452051 -311.235344) (xy 29.595572 -311.235344)
			(xy 29.595068 -311.26167) (xy 29.587031 -311.313706) (xy 29.571145 -311.363905) (xy 29.547782 -311.41109)
			(xy 29.51749 -311.454156) (xy 29.480978 -311.492094) (xy 29.439104 -311.524013) (xy 29.392848 -311.549166)
			(xy 29.343295 -311.566964) (xy 29.291605 -311.576988) (xy 29.238991 -311.579005) (xy 29.186686 -311.572967)
			(xy 29.135915 -311.559015) (xy 29.08787 -311.537476) (xy 29.043675 -311.508856) (xy 29.004367 -311.473825)
			(xy 28.970867 -311.433204) (xy 28.943961 -311.387945) (xy 28.924278 -311.33911) (xy 28.912281 -311.287842)
			(xy 28.908251 -311.235344) (xy 22.051518 -311.235344) (xy 22.051014 -311.26167) (xy 22.042977 -311.313706)
			(xy 22.027091 -311.363905) (xy 22.003728 -311.41109) (xy 21.973436 -311.454156) (xy 21.936924 -311.492094)
			(xy 21.89505 -311.524013) (xy 21.848794 -311.549166) (xy 21.799241 -311.566964) (xy 21.747551 -311.576988)
			(xy 21.694937 -311.579005) (xy 21.642632 -311.572967) (xy 21.591861 -311.559015) (xy 21.543816 -311.537476)
			(xy 21.499621 -311.508856) (xy 21.460313 -311.473825) (xy 21.426813 -311.433204) (xy 21.399907 -311.387945)
			(xy 21.380224 -311.33911) (xy 21.368227 -311.287842) (xy 21.364197 -311.235344) (xy 16.086074 -311.235344)
			(xy 16.086074 -311.926478) (xy 16.086074 -311.928002) (xy 16.091426 -312.085228) (xy 17.264129 -312.085228)
			(xy 17.268159 -312.03273) (xy 17.280156 -311.981462) (xy 17.299839 -311.932627) (xy 17.326745 -311.887368)
			(xy 17.360245 -311.846747) (xy 17.399553 -311.811716) (xy 17.443748 -311.783096) (xy 17.491793 -311.761557)
			(xy 17.542564 -311.747605) (xy 17.594869 -311.741567) (xy 17.647483 -311.743584) (xy 17.699173 -311.753608)
			(xy 17.748726 -311.771406) (xy 17.794982 -311.796559) (xy 17.836856 -311.828478) (xy 17.873368 -311.866416)
			(xy 17.90366 -311.909482) (xy 17.927023 -311.956667) (xy 17.942909 -312.006866) (xy 17.950946 -312.058902)
			(xy 17.95145 -312.085228) (xy 24.808183 -312.085228) (xy 24.812213 -312.03273) (xy 24.82421 -311.981462)
			(xy 24.843893 -311.932627) (xy 24.870799 -311.887368) (xy 24.904299 -311.846747) (xy 24.943607 -311.811716)
			(xy 24.987802 -311.783096) (xy 25.035847 -311.761557) (xy 25.086618 -311.747605) (xy 25.138923 -311.741567)
			(xy 25.191537 -311.743584) (xy 25.243227 -311.753608) (xy 25.29278 -311.771406) (xy 25.339036 -311.796559)
			(xy 25.38091 -311.828478) (xy 25.417422 -311.866416) (xy 25.447714 -311.909482) (xy 25.471077 -311.956667)
			(xy 25.486963 -312.006866) (xy 25.495 -312.058902) (xy 25.495504 -312.085228) (xy 32.351983 -312.085228)
			(xy 32.356013 -312.03273) (xy 32.36801 -311.981462) (xy 32.387693 -311.932627) (xy 32.414599 -311.887368)
			(xy 32.448099 -311.846747) (xy 32.487407 -311.811716) (xy 32.531602 -311.783096) (xy 32.579647 -311.761557)
			(xy 32.630418 -311.747605) (xy 32.682723 -311.741567) (xy 32.735337 -311.743584) (xy 32.787027 -311.753608)
			(xy 32.83658 -311.771406) (xy 32.882836 -311.796559) (xy 32.92471 -311.828478) (xy 32.961222 -311.866416)
			(xy 32.991514 -311.909482) (xy 33.014877 -311.956667) (xy 33.030763 -312.006866) (xy 33.0388 -312.058902)
			(xy 33.039304 -312.085228) (xy 39.896037 -312.085228) (xy 39.900067 -312.03273) (xy 39.912064 -311.981462)
			(xy 39.931747 -311.932627) (xy 39.958653 -311.887368) (xy 39.992153 -311.846747) (xy 40.031461 -311.811716)
			(xy 40.075656 -311.783096) (xy 40.123701 -311.761557) (xy 40.174472 -311.747605) (xy 40.226777 -311.741567)
			(xy 40.279391 -311.743584) (xy 40.331081 -311.753608) (xy 40.380634 -311.771406) (xy 40.42689 -311.796559)
			(xy 40.468764 -311.828478) (xy 40.505276 -311.866416) (xy 40.535568 -311.909482) (xy 40.558931 -311.956667)
			(xy 40.574817 -312.006866) (xy 40.582854 -312.058902) (xy 40.583358 -312.085228) (xy 47.440091 -312.085228)
			(xy 47.444121 -312.03273) (xy 47.456118 -311.981462) (xy 47.475801 -311.932627) (xy 47.502707 -311.887368)
			(xy 47.536207 -311.846747) (xy 47.575515 -311.811716) (xy 47.61971 -311.783096) (xy 47.667755 -311.761557)
			(xy 47.718526 -311.747605) (xy 47.770831 -311.741567) (xy 47.823445 -311.743584) (xy 47.875135 -311.753608)
			(xy 47.924688 -311.771406) (xy 47.970944 -311.796559) (xy 48.012818 -311.828478) (xy 48.04933 -311.866416)
			(xy 48.079622 -311.909482) (xy 48.102985 -311.956667) (xy 48.118871 -312.006866) (xy 48.126908 -312.058902)
			(xy 48.127412 -312.085228) (xy 48.126908 -312.111554) (xy 48.118871 -312.16359) (xy 48.102985 -312.213789)
			(xy 48.079622 -312.260974) (xy 48.04933 -312.30404) (xy 48.012818 -312.341978) (xy 47.970944 -312.373897)
			(xy 47.924688 -312.39905) (xy 47.875135 -312.416848) (xy 47.823445 -312.426872) (xy 47.770831 -312.428889)
			(xy 47.718526 -312.422851) (xy 47.667755 -312.408899) (xy 47.61971 -312.38736) (xy 47.575515 -312.35874)
			(xy 47.536207 -312.323709) (xy 47.502707 -312.283088) (xy 47.475801 -312.237829) (xy 47.456118 -312.188994)
			(xy 47.444121 -312.137726) (xy 47.440091 -312.085228) (xy 40.583358 -312.085228) (xy 40.582854 -312.111554)
			(xy 40.574817 -312.16359) (xy 40.558931 -312.213789) (xy 40.535568 -312.260974) (xy 40.505276 -312.30404)
			(xy 40.468764 -312.341978) (xy 40.42689 -312.373897) (xy 40.380634 -312.39905) (xy 40.331081 -312.416848)
			(xy 40.279391 -312.426872) (xy 40.226777 -312.428889) (xy 40.174472 -312.422851) (xy 40.123701 -312.408899)
			(xy 40.075656 -312.38736) (xy 40.031461 -312.35874) (xy 39.992153 -312.323709) (xy 39.958653 -312.283088)
			(xy 39.931747 -312.237829) (xy 39.912064 -312.188994) (xy 39.900067 -312.137726) (xy 39.896037 -312.085228)
			(xy 33.039304 -312.085228) (xy 33.0388 -312.111554) (xy 33.030763 -312.16359) (xy 33.014877 -312.213789)
			(xy 32.991514 -312.260974) (xy 32.961222 -312.30404) (xy 32.92471 -312.341978) (xy 32.882836 -312.373897)
			(xy 32.83658 -312.39905) (xy 32.787027 -312.416848) (xy 32.735337 -312.426872) (xy 32.682723 -312.428889)
			(xy 32.630418 -312.422851) (xy 32.579647 -312.408899) (xy 32.531602 -312.38736) (xy 32.487407 -312.35874)
			(xy 32.448099 -312.323709) (xy 32.414599 -312.283088) (xy 32.387693 -312.237829) (xy 32.36801 -312.188994)
			(xy 32.356013 -312.137726) (xy 32.351983 -312.085228) (xy 25.495504 -312.085228) (xy 25.495 -312.111554)
			(xy 25.486963 -312.16359) (xy 25.471077 -312.213789) (xy 25.447714 -312.260974) (xy 25.417422 -312.30404)
			(xy 25.38091 -312.341978) (xy 25.339036 -312.373897) (xy 25.29278 -312.39905) (xy 25.243227 -312.416848)
			(xy 25.191537 -312.426872) (xy 25.138923 -312.428889) (xy 25.086618 -312.422851) (xy 25.035847 -312.408899)
			(xy 24.987802 -312.38736) (xy 24.943607 -312.35874) (xy 24.904299 -312.323709) (xy 24.870799 -312.283088)
			(xy 24.843893 -312.237829) (xy 24.82421 -312.188994) (xy 24.812213 -312.137726) (xy 24.808183 -312.085228)
			(xy 17.95145 -312.085228) (xy 17.950946 -312.111554) (xy 17.942909 -312.16359) (xy 17.927023 -312.213789)
			(xy 17.90366 -312.260974) (xy 17.873368 -312.30404) (xy 17.836856 -312.341978) (xy 17.794982 -312.373897)
			(xy 17.748726 -312.39905) (xy 17.699173 -312.416848) (xy 17.647483 -312.426872) (xy 17.594869 -312.428889)
			(xy 17.542564 -312.422851) (xy 17.491793 -312.408899) (xy 17.443748 -312.38736) (xy 17.399553 -312.35874)
			(xy 17.360245 -312.323709) (xy 17.326745 -312.283088) (xy 17.299839 -312.237829) (xy 17.280156 -312.188994)
			(xy 17.268159 -312.137726) (xy 17.264129 -312.085228) (xy 16.091426 -312.085228) (xy 16.094202 -312.166762)
			(xy 16.094456 -312.186574) (xy 16.094265 -312.21043) (xy 16.090451 -312.257989) (xy 16.086836 -312.28157)
			(xy 16.086074 -312.285634) (xy 16.086074 -312.693812) (xy 16.088614 -312.701686) (xy 16.10102 -312.74131)
			(xy 16.11568 -312.823035) (xy 16.117824 -312.8645) (xy 16.120241 -312.935366) (xy 21.364197 -312.935366)
			(xy 21.368227 -312.882868) (xy 21.380224 -312.8316) (xy 21.399907 -312.782765) (xy 21.426813 -312.737506)
			(xy 21.460313 -312.696885) (xy 21.499621 -312.661854) (xy 21.543816 -312.633234) (xy 21.591861 -312.611695)
			(xy 21.642632 -312.597743) (xy 21.694937 -312.591705) (xy 21.747551 -312.593722) (xy 21.799241 -312.603746)
			(xy 21.848794 -312.621544) (xy 21.89505 -312.646697) (xy 21.936924 -312.678616) (xy 21.973436 -312.716554)
			(xy 22.003728 -312.75962) (xy 22.027091 -312.806805) (xy 22.042977 -312.857004) (xy 22.051014 -312.90904)
			(xy 22.051518 -312.935366) (xy 28.908251 -312.935366) (xy 28.912281 -312.882868) (xy 28.924278 -312.8316)
			(xy 28.943961 -312.782765) (xy 28.970867 -312.737506) (xy 29.004367 -312.696885) (xy 29.043675 -312.661854)
			(xy 29.08787 -312.633234) (xy 29.135915 -312.611695) (xy 29.186686 -312.597743) (xy 29.238991 -312.591705)
			(xy 29.291605 -312.593722) (xy 29.343295 -312.603746) (xy 29.392848 -312.621544) (xy 29.439104 -312.646697)
			(xy 29.480978 -312.678616) (xy 29.51749 -312.716554) (xy 29.547782 -312.75962) (xy 29.571145 -312.806805)
			(xy 29.587031 -312.857004) (xy 29.595068 -312.90904) (xy 29.595572 -312.935366) (xy 36.452051 -312.935366)
			(xy 36.456081 -312.882868) (xy 36.468078 -312.8316) (xy 36.487761 -312.782765) (xy 36.514667 -312.737506)
			(xy 36.548167 -312.696885) (xy 36.587475 -312.661854) (xy 36.63167 -312.633234) (xy 36.679715 -312.611695)
			(xy 36.730486 -312.597743) (xy 36.782791 -312.591705) (xy 36.835405 -312.593722) (xy 36.887095 -312.603746)
			(xy 36.936648 -312.621544) (xy 36.982904 -312.646697) (xy 37.024778 -312.678616) (xy 37.06129 -312.716554)
			(xy 37.091582 -312.75962) (xy 37.114945 -312.806805) (xy 37.130831 -312.857004) (xy 37.138868 -312.90904)
			(xy 37.139372 -312.935366) (xy 43.996105 -312.935366) (xy 44.000135 -312.882868) (xy 44.012132 -312.8316)
			(xy 44.031815 -312.782765) (xy 44.058721 -312.737506) (xy 44.092221 -312.696885) (xy 44.131529 -312.661854)
			(xy 44.175724 -312.633234) (xy 44.223769 -312.611695) (xy 44.27454 -312.597743) (xy 44.326845 -312.591705)
			(xy 44.379459 -312.593722) (xy 44.431149 -312.603746) (xy 44.480702 -312.621544) (xy 44.526958 -312.646697)
			(xy 44.568832 -312.678616) (xy 44.605344 -312.716554) (xy 44.635636 -312.75962) (xy 44.658999 -312.806805)
			(xy 44.674885 -312.857004) (xy 44.682922 -312.90904) (xy 44.683426 -312.935366) (xy 51.540159 -312.935366)
			(xy 51.544189 -312.882868) (xy 51.556186 -312.8316) (xy 51.575869 -312.782765) (xy 51.602775 -312.737506)
			(xy 51.636275 -312.696885) (xy 51.675583 -312.661854) (xy 51.719778 -312.633234) (xy 51.767823 -312.611695)
			(xy 51.818594 -312.597743) (xy 51.870899 -312.591705) (xy 51.923513 -312.593722) (xy 51.975203 -312.603746)
			(xy 52.024756 -312.621544) (xy 52.071012 -312.646697) (xy 52.112886 -312.678616) (xy 52.149398 -312.716554)
			(xy 52.17969 -312.75962) (xy 52.203053 -312.806805) (xy 52.218939 -312.857004) (xy 52.226976 -312.90904)
			(xy 52.22748 -312.935366) (xy 52.226976 -312.961692) (xy 52.218939 -313.013728) (xy 52.203053 -313.063927)
			(xy 52.17969 -313.111112) (xy 52.149398 -313.154178) (xy 52.112886 -313.192116) (xy 52.071012 -313.224035)
			(xy 52.024756 -313.249188) (xy 51.975203 -313.266986) (xy 51.923513 -313.27701) (xy 51.870899 -313.279027)
			(xy 51.818594 -313.272989) (xy 51.767823 -313.259037) (xy 51.719778 -313.237498) (xy 51.675583 -313.208878)
			(xy 51.636275 -313.173847) (xy 51.602775 -313.133226) (xy 51.575869 -313.087967) (xy 51.556186 -313.039132)
			(xy 51.544189 -312.987864) (xy 51.540159 -312.935366) (xy 44.683426 -312.935366) (xy 44.682922 -312.961692)
			(xy 44.674885 -313.013728) (xy 44.658999 -313.063927) (xy 44.635636 -313.111112) (xy 44.605344 -313.154178)
			(xy 44.568832 -313.192116) (xy 44.526958 -313.224035) (xy 44.480702 -313.249188) (xy 44.431149 -313.266986)
			(xy 44.379459 -313.27701) (xy 44.326845 -313.279027) (xy 44.27454 -313.272989) (xy 44.223769 -313.259037)
			(xy 44.175724 -313.237498) (xy 44.131529 -313.208878) (xy 44.092221 -313.173847) (xy 44.058721 -313.133226)
			(xy 44.031815 -313.087967) (xy 44.012132 -313.039132) (xy 44.000135 -312.987864) (xy 43.996105 -312.935366)
			(xy 37.139372 -312.935366) (xy 37.138868 -312.961692) (xy 37.130831 -313.013728) (xy 37.114945 -313.063927)
			(xy 37.091582 -313.111112) (xy 37.06129 -313.154178) (xy 37.024778 -313.192116) (xy 36.982904 -313.224035)
			(xy 36.936648 -313.249188) (xy 36.887095 -313.266986) (xy 36.835405 -313.27701) (xy 36.782791 -313.279027)
			(xy 36.730486 -313.272989) (xy 36.679715 -313.259037) (xy 36.63167 -313.237498) (xy 36.587475 -313.208878)
			(xy 36.548167 -313.173847) (xy 36.514667 -313.133226) (xy 36.487761 -313.087967) (xy 36.468078 -313.039132)
			(xy 36.456081 -312.987864) (xy 36.452051 -312.935366) (xy 29.595572 -312.935366) (xy 29.595068 -312.961692)
			(xy 29.587031 -313.013728) (xy 29.571145 -313.063927) (xy 29.547782 -313.111112) (xy 29.51749 -313.154178)
			(xy 29.480978 -313.192116) (xy 29.439104 -313.224035) (xy 29.392848 -313.249188) (xy 29.343295 -313.266986)
			(xy 29.291605 -313.27701) (xy 29.238991 -313.279027) (xy 29.186686 -313.272989) (xy 29.135915 -313.259037)
			(xy 29.08787 -313.237498) (xy 29.043675 -313.208878) (xy 29.004367 -313.173847) (xy 28.970867 -313.133226)
			(xy 28.943961 -313.087967) (xy 28.924278 -313.039132) (xy 28.912281 -312.987864) (xy 28.908251 -312.935366)
			(xy 22.051518 -312.935366) (xy 22.051014 -312.961692) (xy 22.042977 -313.013728) (xy 22.027091 -313.063927)
			(xy 22.003728 -313.111112) (xy 21.973436 -313.154178) (xy 21.936924 -313.192116) (xy 21.89505 -313.224035)
			(xy 21.848794 -313.249188) (xy 21.799241 -313.266986) (xy 21.747551 -313.27701) (xy 21.694937 -313.279027)
			(xy 21.642632 -313.272989) (xy 21.591861 -313.259037) (xy 21.543816 -313.237498) (xy 21.499621 -313.208878)
			(xy 21.460313 -313.173847) (xy 21.426813 -313.133226) (xy 21.399907 -313.087967) (xy 21.380224 -313.039132)
			(xy 21.368227 -312.987864) (xy 21.364197 -312.935366) (xy 16.120241 -312.935366) (xy 16.132302 -313.288934)
			(xy 16.132556 -313.308746) (xy 16.132006 -313.34613) (xy 16.12245 -313.420284) (xy 16.103426 -313.49259)
			(xy 16.089884 -313.52744) (xy 16.086074 -313.536584) (xy 16.086074 -313.78525) (xy 17.264129 -313.78525)
			(xy 17.268159 -313.732752) (xy 17.280156 -313.681484) (xy 17.299839 -313.632649) (xy 17.326745 -313.58739)
			(xy 17.360245 -313.546769) (xy 17.399553 -313.511738) (xy 17.443748 -313.483118) (xy 17.491793 -313.461579)
			(xy 17.542564 -313.447627) (xy 17.594869 -313.441589) (xy 17.647483 -313.443606) (xy 17.699173 -313.45363)
			(xy 17.748726 -313.471428) (xy 17.794982 -313.496581) (xy 17.836856 -313.5285) (xy 17.873368 -313.566438)
			(xy 17.90366 -313.609504) (xy 17.927023 -313.656689) (xy 17.942909 -313.706888) (xy 17.950946 -313.758924)
			(xy 17.95145 -313.78525) (xy 21.364197 -313.78525) (xy 21.368227 -313.732752) (xy 21.380224 -313.681484)
			(xy 21.399907 -313.632649) (xy 21.426813 -313.58739) (xy 21.460313 -313.546769) (xy 21.499621 -313.511738)
			(xy 21.543816 -313.483118) (xy 21.591861 -313.461579) (xy 21.642632 -313.447627) (xy 21.694937 -313.441589)
			(xy 21.747551 -313.443606) (xy 21.799241 -313.45363) (xy 21.848794 -313.471428) (xy 21.89505 -313.496581)
			(xy 21.936924 -313.5285) (xy 21.973436 -313.566438) (xy 22.003728 -313.609504) (xy 22.027091 -313.656689)
			(xy 22.042977 -313.706888) (xy 22.051014 -313.758924) (xy 22.051518 -313.78525) (xy 24.808183 -313.78525)
			(xy 24.812213 -313.732752) (xy 24.82421 -313.681484) (xy 24.843893 -313.632649) (xy 24.870799 -313.58739)
			(xy 24.904299 -313.546769) (xy 24.943607 -313.511738) (xy 24.987802 -313.483118) (xy 25.035847 -313.461579)
			(xy 25.086618 -313.447627) (xy 25.138923 -313.441589) (xy 25.191537 -313.443606) (xy 25.243227 -313.45363)
			(xy 25.29278 -313.471428) (xy 25.339036 -313.496581) (xy 25.38091 -313.5285) (xy 25.417422 -313.566438)
			(xy 25.447714 -313.609504) (xy 25.471077 -313.656689) (xy 25.486963 -313.706888) (xy 25.495 -313.758924)
			(xy 25.495504 -313.78525) (xy 28.908251 -313.78525) (xy 28.912281 -313.732752) (xy 28.924278 -313.681484)
			(xy 28.943961 -313.632649) (xy 28.970867 -313.58739) (xy 29.004367 -313.546769) (xy 29.043675 -313.511738)
			(xy 29.08787 -313.483118) (xy 29.135915 -313.461579) (xy 29.186686 -313.447627) (xy 29.238991 -313.441589)
			(xy 29.291605 -313.443606) (xy 29.343295 -313.45363) (xy 29.392848 -313.471428) (xy 29.439104 -313.496581)
			(xy 29.480978 -313.5285) (xy 29.51749 -313.566438) (xy 29.547782 -313.609504) (xy 29.571145 -313.656689)
			(xy 29.587031 -313.706888) (xy 29.595068 -313.758924) (xy 29.595572 -313.78525) (xy 32.351983 -313.78525)
			(xy 32.356013 -313.732752) (xy 32.36801 -313.681484) (xy 32.387693 -313.632649) (xy 32.414599 -313.58739)
			(xy 32.448099 -313.546769) (xy 32.487407 -313.511738) (xy 32.531602 -313.483118) (xy 32.579647 -313.461579)
			(xy 32.630418 -313.447627) (xy 32.682723 -313.441589) (xy 32.735337 -313.443606) (xy 32.787027 -313.45363)
			(xy 32.83658 -313.471428) (xy 32.882836 -313.496581) (xy 32.92471 -313.5285) (xy 32.961222 -313.566438)
			(xy 32.991514 -313.609504) (xy 33.014877 -313.656689) (xy 33.030763 -313.706888) (xy 33.0388 -313.758924)
			(xy 33.039304 -313.78525) (xy 36.452051 -313.78525) (xy 36.456081 -313.732752) (xy 36.468078 -313.681484)
			(xy 36.487761 -313.632649) (xy 36.514667 -313.58739) (xy 36.548167 -313.546769) (xy 36.587475 -313.511738)
			(xy 36.63167 -313.483118) (xy 36.679715 -313.461579) (xy 36.730486 -313.447627) (xy 36.782791 -313.441589)
			(xy 36.835405 -313.443606) (xy 36.887095 -313.45363) (xy 36.936648 -313.471428) (xy 36.982904 -313.496581)
			(xy 37.024778 -313.5285) (xy 37.06129 -313.566438) (xy 37.091582 -313.609504) (xy 37.114945 -313.656689)
			(xy 37.130831 -313.706888) (xy 37.138868 -313.758924) (xy 37.139372 -313.78525) (xy 39.896037 -313.78525)
			(xy 39.900067 -313.732752) (xy 39.912064 -313.681484) (xy 39.931747 -313.632649) (xy 39.958653 -313.58739)
			(xy 39.992153 -313.546769) (xy 40.031461 -313.511738) (xy 40.075656 -313.483118) (xy 40.123701 -313.461579)
			(xy 40.174472 -313.447627) (xy 40.226777 -313.441589) (xy 40.279391 -313.443606) (xy 40.331081 -313.45363)
			(xy 40.380634 -313.471428) (xy 40.42689 -313.496581) (xy 40.468764 -313.5285) (xy 40.505276 -313.566438)
			(xy 40.535568 -313.609504) (xy 40.558931 -313.656689) (xy 40.574817 -313.706888) (xy 40.582854 -313.758924)
			(xy 40.583358 -313.78525) (xy 43.996105 -313.78525) (xy 44.000135 -313.732752) (xy 44.012132 -313.681484)
			(xy 44.031815 -313.632649) (xy 44.058721 -313.58739) (xy 44.092221 -313.546769) (xy 44.131529 -313.511738)
			(xy 44.175724 -313.483118) (xy 44.223769 -313.461579) (xy 44.27454 -313.447627) (xy 44.326845 -313.441589)
			(xy 44.379459 -313.443606) (xy 44.431149 -313.45363) (xy 44.480702 -313.471428) (xy 44.526958 -313.496581)
			(xy 44.568832 -313.5285) (xy 44.605344 -313.566438) (xy 44.635636 -313.609504) (xy 44.658999 -313.656689)
			(xy 44.674885 -313.706888) (xy 44.682922 -313.758924) (xy 44.683426 -313.78525) (xy 47.440091 -313.78525)
			(xy 47.444121 -313.732752) (xy 47.456118 -313.681484) (xy 47.475801 -313.632649) (xy 47.502707 -313.58739)
			(xy 47.536207 -313.546769) (xy 47.575515 -313.511738) (xy 47.61971 -313.483118) (xy 47.667755 -313.461579)
			(xy 47.718526 -313.447627) (xy 47.770831 -313.441589) (xy 47.823445 -313.443606) (xy 47.875135 -313.45363)
			(xy 47.924688 -313.471428) (xy 47.970944 -313.496581) (xy 48.012818 -313.5285) (xy 48.04933 -313.566438)
			(xy 48.079622 -313.609504) (xy 48.102985 -313.656689) (xy 48.118871 -313.706888) (xy 48.126908 -313.758924)
			(xy 48.127412 -313.78525) (xy 51.540159 -313.78525) (xy 51.544189 -313.732752) (xy 51.556186 -313.681484)
			(xy 51.575869 -313.632649) (xy 51.602775 -313.58739) (xy 51.636275 -313.546769) (xy 51.675583 -313.511738)
			(xy 51.719778 -313.483118) (xy 51.767823 -313.461579) (xy 51.818594 -313.447627) (xy 51.870899 -313.441589)
			(xy 51.923513 -313.443606) (xy 51.975203 -313.45363) (xy 52.024756 -313.471428) (xy 52.071012 -313.496581)
			(xy 52.112886 -313.5285) (xy 52.149398 -313.566438) (xy 52.17969 -313.609504) (xy 52.203053 -313.656689)
			(xy 52.218939 -313.706888) (xy 52.226976 -313.758924) (xy 52.22748 -313.78525) (xy 52.226976 -313.811576)
			(xy 52.218939 -313.863612) (xy 52.203053 -313.913811) (xy 52.17969 -313.960996) (xy 52.149398 -314.004062)
			(xy 52.112886 -314.042) (xy 52.071012 -314.073919) (xy 52.024756 -314.099072) (xy 51.975203 -314.11687)
			(xy 51.923513 -314.126894) (xy 51.870899 -314.128911) (xy 51.818594 -314.122873) (xy 51.767823 -314.108921)
			(xy 51.719778 -314.087382) (xy 51.675583 -314.058762) (xy 51.636275 -314.023731) (xy 51.602775 -313.98311)
			(xy 51.575869 -313.937851) (xy 51.556186 -313.889016) (xy 51.544189 -313.837748) (xy 51.540159 -313.78525)
			(xy 48.127412 -313.78525) (xy 48.126908 -313.811576) (xy 48.118871 -313.863612) (xy 48.102985 -313.913811)
			(xy 48.079622 -313.960996) (xy 48.04933 -314.004062) (xy 48.012818 -314.042) (xy 47.970944 -314.073919)
			(xy 47.924688 -314.099072) (xy 47.875135 -314.11687) (xy 47.823445 -314.126894) (xy 47.770831 -314.128911)
			(xy 47.718526 -314.122873) (xy 47.667755 -314.108921) (xy 47.61971 -314.087382) (xy 47.575515 -314.058762)
			(xy 47.536207 -314.023731) (xy 47.502707 -313.98311) (xy 47.475801 -313.937851) (xy 47.456118 -313.889016)
			(xy 47.444121 -313.837748) (xy 47.440091 -313.78525) (xy 44.683426 -313.78525) (xy 44.682922 -313.811576)
			(xy 44.674885 -313.863612) (xy 44.658999 -313.913811) (xy 44.635636 -313.960996) (xy 44.605344 -314.004062)
			(xy 44.568832 -314.042) (xy 44.526958 -314.073919) (xy 44.480702 -314.099072) (xy 44.431149 -314.11687)
			(xy 44.379459 -314.126894) (xy 44.326845 -314.128911) (xy 44.27454 -314.122873) (xy 44.223769 -314.108921)
			(xy 44.175724 -314.087382) (xy 44.131529 -314.058762) (xy 44.092221 -314.023731) (xy 44.058721 -313.98311)
			(xy 44.031815 -313.937851) (xy 44.012132 -313.889016) (xy 44.000135 -313.837748) (xy 43.996105 -313.78525)
			(xy 40.583358 -313.78525) (xy 40.582854 -313.811576) (xy 40.574817 -313.863612) (xy 40.558931 -313.913811)
			(xy 40.535568 -313.960996) (xy 40.505276 -314.004062) (xy 40.468764 -314.042) (xy 40.42689 -314.073919)
			(xy 40.380634 -314.099072) (xy 40.331081 -314.11687) (xy 40.279391 -314.126894) (xy 40.226777 -314.128911)
			(xy 40.174472 -314.122873) (xy 40.123701 -314.108921) (xy 40.075656 -314.087382) (xy 40.031461 -314.058762)
			(xy 39.992153 -314.023731) (xy 39.958653 -313.98311) (xy 39.931747 -313.937851) (xy 39.912064 -313.889016)
			(xy 39.900067 -313.837748) (xy 39.896037 -313.78525) (xy 37.139372 -313.78525) (xy 37.138868 -313.811576)
			(xy 37.130831 -313.863612) (xy 37.114945 -313.913811) (xy 37.091582 -313.960996) (xy 37.06129 -314.004062)
			(xy 37.024778 -314.042) (xy 36.982904 -314.073919) (xy 36.936648 -314.099072) (xy 36.887095 -314.11687)
			(xy 36.835405 -314.126894) (xy 36.782791 -314.128911) (xy 36.730486 -314.122873) (xy 36.679715 -314.108921)
			(xy 36.63167 -314.087382) (xy 36.587475 -314.058762) (xy 36.548167 -314.023731) (xy 36.514667 -313.98311)
			(xy 36.487761 -313.937851) (xy 36.468078 -313.889016) (xy 36.456081 -313.837748) (xy 36.452051 -313.78525)
			(xy 33.039304 -313.78525) (xy 33.0388 -313.811576) (xy 33.030763 -313.863612) (xy 33.014877 -313.913811)
			(xy 32.991514 -313.960996) (xy 32.961222 -314.004062) (xy 32.92471 -314.042) (xy 32.882836 -314.073919)
			(xy 32.83658 -314.099072) (xy 32.787027 -314.11687) (xy 32.735337 -314.126894) (xy 32.682723 -314.128911)
			(xy 32.630418 -314.122873) (xy 32.579647 -314.108921) (xy 32.531602 -314.087382) (xy 32.487407 -314.058762)
			(xy 32.448099 -314.023731) (xy 32.414599 -313.98311) (xy 32.387693 -313.937851) (xy 32.36801 -313.889016)
			(xy 32.356013 -313.837748) (xy 32.351983 -313.78525) (xy 29.595572 -313.78525) (xy 29.595068 -313.811576)
			(xy 29.587031 -313.863612) (xy 29.571145 -313.913811) (xy 29.547782 -313.960996) (xy 29.51749 -314.004062)
			(xy 29.480978 -314.042) (xy 29.439104 -314.073919) (xy 29.392848 -314.099072) (xy 29.343295 -314.11687)
			(xy 29.291605 -314.126894) (xy 29.238991 -314.128911) (xy 29.186686 -314.122873) (xy 29.135915 -314.108921)
			(xy 29.08787 -314.087382) (xy 29.043675 -314.058762) (xy 29.004367 -314.023731) (xy 28.970867 -313.98311)
			(xy 28.943961 -313.937851) (xy 28.924278 -313.889016) (xy 28.912281 -313.837748) (xy 28.908251 -313.78525)
			(xy 25.495504 -313.78525) (xy 25.495 -313.811576) (xy 25.486963 -313.863612) (xy 25.471077 -313.913811)
			(xy 25.447714 -313.960996) (xy 25.417422 -314.004062) (xy 25.38091 -314.042) (xy 25.339036 -314.073919)
			(xy 25.29278 -314.099072) (xy 25.243227 -314.11687) (xy 25.191537 -314.126894) (xy 25.138923 -314.128911)
			(xy 25.086618 -314.122873) (xy 25.035847 -314.108921) (xy 24.987802 -314.087382) (xy 24.943607 -314.058762)
			(xy 24.904299 -314.023731) (xy 24.870799 -313.98311) (xy 24.843893 -313.937851) (xy 24.82421 -313.889016)
			(xy 24.812213 -313.837748) (xy 24.808183 -313.78525) (xy 22.051518 -313.78525) (xy 22.051014 -313.811576)
			(xy 22.042977 -313.863612) (xy 22.027091 -313.913811) (xy 22.003728 -313.960996) (xy 21.973436 -314.004062)
			(xy 21.936924 -314.042) (xy 21.89505 -314.073919) (xy 21.848794 -314.099072) (xy 21.799241 -314.11687)
			(xy 21.747551 -314.126894) (xy 21.694937 -314.128911) (xy 21.642632 -314.122873) (xy 21.591861 -314.108921)
			(xy 21.543816 -314.087382) (xy 21.499621 -314.058762) (xy 21.460313 -314.023731) (xy 21.426813 -313.98311)
			(xy 21.399907 -313.937851) (xy 21.380224 -313.889016) (xy 21.368227 -313.837748) (xy 21.364197 -313.78525)
			(xy 17.95145 -313.78525) (xy 17.950946 -313.811576) (xy 17.942909 -313.863612) (xy 17.927023 -313.913811)
			(xy 17.90366 -313.960996) (xy 17.873368 -314.004062) (xy 17.836856 -314.042) (xy 17.794982 -314.073919)
			(xy 17.748726 -314.099072) (xy 17.699173 -314.11687) (xy 17.647483 -314.126894) (xy 17.594869 -314.128911)
			(xy 17.542564 -314.122873) (xy 17.491793 -314.108921) (xy 17.443748 -314.087382) (xy 17.399553 -314.058762)
			(xy 17.360245 -314.023731) (xy 17.326745 -313.98311) (xy 17.299839 -313.937851) (xy 17.280156 -313.889016)
			(xy 17.268159 -313.837748) (xy 17.264129 -313.78525) (xy 16.086074 -313.78525) (xy 16.086074 -314.1726)
			(xy 16.08709 -314.182506) (xy 16.177186 -314.635388) (xy 17.264129 -314.635388) (xy 17.268159 -314.58289)
			(xy 17.280156 -314.531622) (xy 17.299839 -314.482787) (xy 17.326745 -314.437528) (xy 17.360245 -314.396907)
			(xy 17.399553 -314.361876) (xy 17.443748 -314.333256) (xy 17.491793 -314.311717) (xy 17.542564 -314.297765)
			(xy 17.594869 -314.291727) (xy 17.647483 -314.293744) (xy 17.699173 -314.303768) (xy 17.748726 -314.321566)
			(xy 17.794982 -314.346719) (xy 17.836856 -314.378638) (xy 17.873368 -314.416576) (xy 17.90366 -314.459642)
			(xy 17.927023 -314.506827) (xy 17.942909 -314.557026) (xy 17.950946 -314.609062) (xy 17.95145 -314.635388)
			(xy 24.808183 -314.635388) (xy 24.812213 -314.58289) (xy 24.82421 -314.531622) (xy 24.843893 -314.482787)
			(xy 24.870799 -314.437528) (xy 24.904299 -314.396907) (xy 24.943607 -314.361876) (xy 24.987802 -314.333256)
			(xy 25.035847 -314.311717) (xy 25.086618 -314.297765) (xy 25.138923 -314.291727) (xy 25.191537 -314.293744)
			(xy 25.243227 -314.303768) (xy 25.29278 -314.321566) (xy 25.339036 -314.346719) (xy 25.38091 -314.378638)
			(xy 25.417422 -314.416576) (xy 25.447714 -314.459642) (xy 25.471077 -314.506827) (xy 25.486963 -314.557026)
			(xy 25.495 -314.609062) (xy 25.495504 -314.635388) (xy 32.351983 -314.635388) (xy 32.356013 -314.58289)
			(xy 32.36801 -314.531622) (xy 32.387693 -314.482787) (xy 32.414599 -314.437528) (xy 32.448099 -314.396907)
			(xy 32.487407 -314.361876) (xy 32.531602 -314.333256) (xy 32.579647 -314.311717) (xy 32.630418 -314.297765)
			(xy 32.682723 -314.291727) (xy 32.735337 -314.293744) (xy 32.787027 -314.303768) (xy 32.83658 -314.321566)
			(xy 32.882836 -314.346719) (xy 32.92471 -314.378638) (xy 32.961222 -314.416576) (xy 32.991514 -314.459642)
			(xy 33.014877 -314.506827) (xy 33.030763 -314.557026) (xy 33.0388 -314.609062) (xy 33.039304 -314.635388)
			(xy 39.896037 -314.635388) (xy 39.900067 -314.58289) (xy 39.912064 -314.531622) (xy 39.931747 -314.482787)
			(xy 39.958653 -314.437528) (xy 39.992153 -314.396907) (xy 40.031461 -314.361876) (xy 40.075656 -314.333256)
			(xy 40.123701 -314.311717) (xy 40.174472 -314.297765) (xy 40.226777 -314.291727) (xy 40.279391 -314.293744)
			(xy 40.331081 -314.303768) (xy 40.380634 -314.321566) (xy 40.42689 -314.346719) (xy 40.468764 -314.378638)
			(xy 40.505276 -314.416576) (xy 40.535568 -314.459642) (xy 40.558931 -314.506827) (xy 40.574817 -314.557026)
			(xy 40.582854 -314.609062) (xy 40.583358 -314.635388) (xy 47.440091 -314.635388) (xy 47.444121 -314.58289)
			(xy 47.456118 -314.531622) (xy 47.475801 -314.482787) (xy 47.502707 -314.437528) (xy 47.536207 -314.396907)
			(xy 47.575515 -314.361876) (xy 47.61971 -314.333256) (xy 47.667755 -314.311717) (xy 47.718526 -314.297765)
			(xy 47.770831 -314.291727) (xy 47.823445 -314.293744) (xy 47.875135 -314.303768) (xy 47.924688 -314.321566)
			(xy 47.970944 -314.346719) (xy 48.012818 -314.378638) (xy 48.04933 -314.416576) (xy 48.079622 -314.459642)
			(xy 48.102985 -314.506827) (xy 48.118871 -314.557026) (xy 48.126908 -314.609062) (xy 48.127412 -314.635388)
			(xy 48.126908 -314.661714) (xy 48.118871 -314.71375) (xy 48.102985 -314.763949) (xy 48.079622 -314.811134)
			(xy 48.04933 -314.8542) (xy 48.012818 -314.892138) (xy 47.970944 -314.924057) (xy 47.924688 -314.94921)
			(xy 47.875135 -314.967008) (xy 47.823445 -314.977032) (xy 47.770831 -314.979049) (xy 47.718526 -314.973011)
			(xy 47.667755 -314.959059) (xy 47.61971 -314.93752) (xy 47.575515 -314.9089) (xy 47.536207 -314.873869)
			(xy 47.502707 -314.833248) (xy 47.475801 -314.787989) (xy 47.456118 -314.739154) (xy 47.444121 -314.687886)
			(xy 47.440091 -314.635388) (xy 40.583358 -314.635388) (xy 40.582854 -314.661714) (xy 40.574817 -314.71375)
			(xy 40.558931 -314.763949) (xy 40.535568 -314.811134) (xy 40.505276 -314.8542) (xy 40.468764 -314.892138)
			(xy 40.42689 -314.924057) (xy 40.380634 -314.94921) (xy 40.331081 -314.967008) (xy 40.279391 -314.977032)
			(xy 40.226777 -314.979049) (xy 40.174472 -314.973011) (xy 40.123701 -314.959059) (xy 40.075656 -314.93752)
			(xy 40.031461 -314.9089) (xy 39.992153 -314.873869) (xy 39.958653 -314.833248) (xy 39.931747 -314.787989)
			(xy 39.912064 -314.739154) (xy 39.900067 -314.687886) (xy 39.896037 -314.635388) (xy 33.039304 -314.635388)
			(xy 33.0388 -314.661714) (xy 33.030763 -314.71375) (xy 33.014877 -314.763949) (xy 32.991514 -314.811134)
			(xy 32.961222 -314.8542) (xy 32.92471 -314.892138) (xy 32.882836 -314.924057) (xy 32.83658 -314.94921)
			(xy 32.787027 -314.967008) (xy 32.735337 -314.977032) (xy 32.682723 -314.979049) (xy 32.630418 -314.973011)
			(xy 32.579647 -314.959059) (xy 32.531602 -314.93752) (xy 32.487407 -314.9089) (xy 32.448099 -314.873869)
			(xy 32.414599 -314.833248) (xy 32.387693 -314.787989) (xy 32.36801 -314.739154) (xy 32.356013 -314.687886)
			(xy 32.351983 -314.635388) (xy 25.495504 -314.635388) (xy 25.495 -314.661714) (xy 25.486963 -314.71375)
			(xy 25.471077 -314.763949) (xy 25.447714 -314.811134) (xy 25.417422 -314.8542) (xy 25.38091 -314.892138)
			(xy 25.339036 -314.924057) (xy 25.29278 -314.94921) (xy 25.243227 -314.967008) (xy 25.191537 -314.977032)
			(xy 25.138923 -314.979049) (xy 25.086618 -314.973011) (xy 25.035847 -314.959059) (xy 24.987802 -314.93752)
			(xy 24.943607 -314.9089) (xy 24.904299 -314.873869) (xy 24.870799 -314.833248) (xy 24.843893 -314.787989)
			(xy 24.82421 -314.739154) (xy 24.812213 -314.687886) (xy 24.808183 -314.635388) (xy 17.95145 -314.635388)
			(xy 17.950946 -314.661714) (xy 17.942909 -314.71375) (xy 17.927023 -314.763949) (xy 17.90366 -314.811134)
			(xy 17.873368 -314.8542) (xy 17.836856 -314.892138) (xy 17.794982 -314.924057) (xy 17.748726 -314.94921)
			(xy 17.699173 -314.967008) (xy 17.647483 -314.977032) (xy 17.594869 -314.979049) (xy 17.542564 -314.973011)
			(xy 17.491793 -314.959059) (xy 17.443748 -314.93752) (xy 17.399553 -314.9089) (xy 17.360245 -314.873869)
			(xy 17.326745 -314.833248) (xy 17.299839 -314.787989) (xy 17.280156 -314.739154) (xy 17.268159 -314.687886)
			(xy 17.264129 -314.635388) (xy 16.177186 -314.635388) (xy 16.346262 -315.485272) (xy 21.364197 -315.485272)
			(xy 21.368227 -315.432774) (xy 21.380224 -315.381506) (xy 21.399907 -315.332671) (xy 21.426813 -315.287412)
			(xy 21.460313 -315.246791) (xy 21.499621 -315.21176) (xy 21.543816 -315.18314) (xy 21.591861 -315.161601)
			(xy 21.642632 -315.147649) (xy 21.694937 -315.141611) (xy 21.747551 -315.143628) (xy 21.799241 -315.153652)
			(xy 21.848794 -315.17145) (xy 21.89505 -315.196603) (xy 21.936924 -315.228522) (xy 21.973436 -315.26646)
			(xy 22.003728 -315.309526) (xy 22.027091 -315.356711) (xy 22.042977 -315.40691) (xy 22.051014 -315.458946)
			(xy 22.051518 -315.485272) (xy 28.908251 -315.485272) (xy 28.912281 -315.432774) (xy 28.924278 -315.381506)
			(xy 28.943961 -315.332671) (xy 28.970867 -315.287412) (xy 29.004367 -315.246791) (xy 29.043675 -315.21176)
			(xy 29.08787 -315.18314) (xy 29.135915 -315.161601) (xy 29.186686 -315.147649) (xy 29.238991 -315.141611)
			(xy 29.291605 -315.143628) (xy 29.343295 -315.153652) (xy 29.392848 -315.17145) (xy 29.439104 -315.196603)
			(xy 29.480978 -315.228522) (xy 29.51749 -315.26646) (xy 29.547782 -315.309526) (xy 29.571145 -315.356711)
			(xy 29.587031 -315.40691) (xy 29.595068 -315.458946) (xy 29.595572 -315.485272) (xy 36.452051 -315.485272)
			(xy 36.456081 -315.432774) (xy 36.468078 -315.381506) (xy 36.487761 -315.332671) (xy 36.514667 -315.287412)
			(xy 36.548167 -315.246791) (xy 36.587475 -315.21176) (xy 36.63167 -315.18314) (xy 36.679715 -315.161601)
			(xy 36.730486 -315.147649) (xy 36.782791 -315.141611) (xy 36.835405 -315.143628) (xy 36.887095 -315.153652)
			(xy 36.936648 -315.17145) (xy 36.982904 -315.196603) (xy 37.024778 -315.228522) (xy 37.06129 -315.26646)
			(xy 37.091582 -315.309526) (xy 37.114945 -315.356711) (xy 37.130831 -315.40691) (xy 37.138868 -315.458946)
			(xy 37.139372 -315.485272) (xy 43.996105 -315.485272) (xy 44.000135 -315.432774) (xy 44.012132 -315.381506)
			(xy 44.031815 -315.332671) (xy 44.058721 -315.287412) (xy 44.092221 -315.246791) (xy 44.131529 -315.21176)
			(xy 44.175724 -315.18314) (xy 44.223769 -315.161601) (xy 44.27454 -315.147649) (xy 44.326845 -315.141611)
			(xy 44.379459 -315.143628) (xy 44.431149 -315.153652) (xy 44.480702 -315.17145) (xy 44.526958 -315.196603)
			(xy 44.568832 -315.228522) (xy 44.605344 -315.26646) (xy 44.635636 -315.309526) (xy 44.658999 -315.356711)
			(xy 44.674885 -315.40691) (xy 44.682922 -315.458946) (xy 44.683426 -315.485272) (xy 51.540159 -315.485272)
			(xy 51.544189 -315.432774) (xy 51.556186 -315.381506) (xy 51.575869 -315.332671) (xy 51.602775 -315.287412)
			(xy 51.636275 -315.246791) (xy 51.675583 -315.21176) (xy 51.719778 -315.18314) (xy 51.767823 -315.161601)
			(xy 51.818594 -315.147649) (xy 51.870899 -315.141611) (xy 51.923513 -315.143628) (xy 51.975203 -315.153652)
			(xy 52.024756 -315.17145) (xy 52.071012 -315.196603) (xy 52.112886 -315.228522) (xy 52.149398 -315.26646)
			(xy 52.17969 -315.309526) (xy 52.203053 -315.356711) (xy 52.218939 -315.40691) (xy 52.226976 -315.458946)
			(xy 52.22748 -315.485272) (xy 52.226976 -315.511598) (xy 52.218939 -315.563634) (xy 52.203053 -315.613833)
			(xy 52.17969 -315.661018) (xy 52.149398 -315.704084) (xy 52.112886 -315.742022) (xy 52.071012 -315.773941)
			(xy 52.024756 -315.799094) (xy 51.975203 -315.816892) (xy 51.923513 -315.826916) (xy 51.870899 -315.828933)
			(xy 51.818594 -315.822895) (xy 51.767823 -315.808943) (xy 51.719778 -315.787404) (xy 51.675583 -315.758784)
			(xy 51.636275 -315.723753) (xy 51.602775 -315.683132) (xy 51.575869 -315.637873) (xy 51.556186 -315.589038)
			(xy 51.544189 -315.53777) (xy 51.540159 -315.485272) (xy 44.683426 -315.485272) (xy 44.682922 -315.511598)
			(xy 44.674885 -315.563634) (xy 44.658999 -315.613833) (xy 44.635636 -315.661018) (xy 44.605344 -315.704084)
			(xy 44.568832 -315.742022) (xy 44.526958 -315.773941) (xy 44.480702 -315.799094) (xy 44.431149 -315.816892)
			(xy 44.379459 -315.826916) (xy 44.326845 -315.828933) (xy 44.27454 -315.822895) (xy 44.223769 -315.808943)
			(xy 44.175724 -315.787404) (xy 44.131529 -315.758784) (xy 44.092221 -315.723753) (xy 44.058721 -315.683132)
			(xy 44.031815 -315.637873) (xy 44.012132 -315.589038) (xy 44.000135 -315.53777) (xy 43.996105 -315.485272)
			(xy 37.139372 -315.485272) (xy 37.138868 -315.511598) (xy 37.130831 -315.563634) (xy 37.114945 -315.613833)
			(xy 37.091582 -315.661018) (xy 37.06129 -315.704084) (xy 37.024778 -315.742022) (xy 36.982904 -315.773941)
			(xy 36.936648 -315.799094) (xy 36.887095 -315.816892) (xy 36.835405 -315.826916) (xy 36.782791 -315.828933)
			(xy 36.730486 -315.822895) (xy 36.679715 -315.808943) (xy 36.63167 -315.787404) (xy 36.587475 -315.758784)
			(xy 36.548167 -315.723753) (xy 36.514667 -315.683132) (xy 36.487761 -315.637873) (xy 36.468078 -315.589038)
			(xy 36.456081 -315.53777) (xy 36.452051 -315.485272) (xy 29.595572 -315.485272) (xy 29.595068 -315.511598)
			(xy 29.587031 -315.563634) (xy 29.571145 -315.613833) (xy 29.547782 -315.661018) (xy 29.51749 -315.704084)
			(xy 29.480978 -315.742022) (xy 29.439104 -315.773941) (xy 29.392848 -315.799094) (xy 29.343295 -315.816892)
			(xy 29.291605 -315.826916) (xy 29.238991 -315.828933) (xy 29.186686 -315.822895) (xy 29.135915 -315.808943)
			(xy 29.08787 -315.787404) (xy 29.043675 -315.758784) (xy 29.004367 -315.723753) (xy 28.970867 -315.683132)
			(xy 28.943961 -315.637873) (xy 28.924278 -315.589038) (xy 28.912281 -315.53777) (xy 28.908251 -315.485272)
			(xy 22.051518 -315.485272) (xy 22.051014 -315.511598) (xy 22.042977 -315.563634) (xy 22.027091 -315.613833)
			(xy 22.003728 -315.661018) (xy 21.973436 -315.704084) (xy 21.936924 -315.742022) (xy 21.89505 -315.773941)
			(xy 21.848794 -315.799094) (xy 21.799241 -315.816892) (xy 21.747551 -315.826916) (xy 21.694937 -315.828933)
			(xy 21.642632 -315.822895) (xy 21.591861 -315.808943) (xy 21.543816 -315.787404) (xy 21.499621 -315.758784)
			(xy 21.460313 -315.723753) (xy 21.426813 -315.683132) (xy 21.399907 -315.637873) (xy 21.380224 -315.589038)
			(xy 21.368227 -315.53777) (xy 21.364197 -315.485272) (xy 16.346262 -315.485272) (xy 16.515389 -316.33541)
			(xy 17.264129 -316.33541) (xy 17.268159 -316.282912) (xy 17.280156 -316.231644) (xy 17.299839 -316.182809)
			(xy 17.326745 -316.13755) (xy 17.360245 -316.096929) (xy 17.399553 -316.061898) (xy 17.443748 -316.033278)
			(xy 17.491793 -316.011739) (xy 17.542564 -315.997787) (xy 17.594869 -315.991749) (xy 17.647483 -315.993766)
			(xy 17.699173 -316.00379) (xy 17.748726 -316.021588) (xy 17.794982 -316.046741) (xy 17.836856 -316.07866)
			(xy 17.873368 -316.116598) (xy 17.90366 -316.159664) (xy 17.927023 -316.206849) (xy 17.942909 -316.257048)
			(xy 17.950946 -316.309084) (xy 17.95145 -316.33541) (xy 24.808183 -316.33541) (xy 24.812213 -316.282912)
			(xy 24.82421 -316.231644) (xy 24.843893 -316.182809) (xy 24.870799 -316.13755) (xy 24.904299 -316.096929)
			(xy 24.943607 -316.061898) (xy 24.987802 -316.033278) (xy 25.035847 -316.011739) (xy 25.086618 -315.997787)
			(xy 25.138923 -315.991749) (xy 25.191537 -315.993766) (xy 25.243227 -316.00379) (xy 25.29278 -316.021588)
			(xy 25.339036 -316.046741) (xy 25.38091 -316.07866) (xy 25.417422 -316.116598) (xy 25.447714 -316.159664)
			(xy 25.471077 -316.206849) (xy 25.486963 -316.257048) (xy 25.495 -316.309084) (xy 25.495504 -316.33541)
			(xy 32.351983 -316.33541) (xy 32.356013 -316.282912) (xy 32.36801 -316.231644) (xy 32.387693 -316.182809)
			(xy 32.414599 -316.13755) (xy 32.448099 -316.096929) (xy 32.487407 -316.061898) (xy 32.531602 -316.033278)
			(xy 32.579647 -316.011739) (xy 32.630418 -315.997787) (xy 32.682723 -315.991749) (xy 32.735337 -315.993766)
			(xy 32.787027 -316.00379) (xy 32.83658 -316.021588) (xy 32.882836 -316.046741) (xy 32.92471 -316.07866)
			(xy 32.961222 -316.116598) (xy 32.991514 -316.159664) (xy 33.014877 -316.206849) (xy 33.030763 -316.257048)
			(xy 33.0388 -316.309084) (xy 33.039304 -316.33541) (xy 39.896037 -316.33541) (xy 39.900067 -316.282912)
			(xy 39.912064 -316.231644) (xy 39.931747 -316.182809) (xy 39.958653 -316.13755) (xy 39.992153 -316.096929)
			(xy 40.031461 -316.061898) (xy 40.075656 -316.033278) (xy 40.123701 -316.011739) (xy 40.174472 -315.997787)
			(xy 40.226777 -315.991749) (xy 40.279391 -315.993766) (xy 40.331081 -316.00379) (xy 40.380634 -316.021588)
			(xy 40.42689 -316.046741) (xy 40.468764 -316.07866) (xy 40.505276 -316.116598) (xy 40.535568 -316.159664)
			(xy 40.558931 -316.206849) (xy 40.574817 -316.257048) (xy 40.582854 -316.309084) (xy 40.583358 -316.33541)
			(xy 47.440091 -316.33541) (xy 47.444121 -316.282912) (xy 47.456118 -316.231644) (xy 47.475801 -316.182809)
			(xy 47.502707 -316.13755) (xy 47.536207 -316.096929) (xy 47.575515 -316.061898) (xy 47.61971 -316.033278)
			(xy 47.667755 -316.011739) (xy 47.718526 -315.997787) (xy 47.770831 -315.991749) (xy 47.823445 -315.993766)
			(xy 47.875135 -316.00379) (xy 47.924688 -316.021588) (xy 47.970944 -316.046741) (xy 48.012818 -316.07866)
			(xy 48.04933 -316.116598) (xy 48.079622 -316.159664) (xy 48.102985 -316.206849) (xy 48.118871 -316.257048)
			(xy 48.126908 -316.309084) (xy 48.127412 -316.33541) (xy 48.126908 -316.361736) (xy 48.118871 -316.413772)
			(xy 48.102985 -316.463971) (xy 48.079622 -316.511156) (xy 48.04933 -316.554222) (xy 48.012818 -316.59216)
			(xy 47.970944 -316.624079) (xy 47.924688 -316.649232) (xy 47.875135 -316.66703) (xy 47.823445 -316.677054)
			(xy 47.770831 -316.679071) (xy 47.718526 -316.673033) (xy 47.667755 -316.659081) (xy 47.61971 -316.637542)
			(xy 47.575515 -316.608922) (xy 47.536207 -316.573891) (xy 47.502707 -316.53327) (xy 47.475801 -316.488011)
			(xy 47.456118 -316.439176) (xy 47.444121 -316.387908) (xy 47.440091 -316.33541) (xy 40.583358 -316.33541)
			(xy 40.582854 -316.361736) (xy 40.574817 -316.413772) (xy 40.558931 -316.463971) (xy 40.535568 -316.511156)
			(xy 40.505276 -316.554222) (xy 40.468764 -316.59216) (xy 40.42689 -316.624079) (xy 40.380634 -316.649232)
			(xy 40.331081 -316.66703) (xy 40.279391 -316.677054) (xy 40.226777 -316.679071) (xy 40.174472 -316.673033)
			(xy 40.123701 -316.659081) (xy 40.075656 -316.637542) (xy 40.031461 -316.608922) (xy 39.992153 -316.573891)
			(xy 39.958653 -316.53327) (xy 39.931747 -316.488011) (xy 39.912064 -316.439176) (xy 39.900067 -316.387908)
			(xy 39.896037 -316.33541) (xy 33.039304 -316.33541) (xy 33.0388 -316.361736) (xy 33.030763 -316.413772)
			(xy 33.014877 -316.463971) (xy 32.991514 -316.511156) (xy 32.961222 -316.554222) (xy 32.92471 -316.59216)
			(xy 32.882836 -316.624079) (xy 32.83658 -316.649232) (xy 32.787027 -316.66703) (xy 32.735337 -316.677054)
			(xy 32.682723 -316.679071) (xy 32.630418 -316.673033) (xy 32.579647 -316.659081) (xy 32.531602 -316.637542)
			(xy 32.487407 -316.608922) (xy 32.448099 -316.573891) (xy 32.414599 -316.53327) (xy 32.387693 -316.488011)
			(xy 32.36801 -316.439176) (xy 32.356013 -316.387908) (xy 32.351983 -316.33541) (xy 25.495504 -316.33541)
			(xy 25.495 -316.361736) (xy 25.486963 -316.413772) (xy 25.471077 -316.463971) (xy 25.447714 -316.511156)
			(xy 25.417422 -316.554222) (xy 25.38091 -316.59216) (xy 25.339036 -316.624079) (xy 25.29278 -316.649232)
			(xy 25.243227 -316.66703) (xy 25.191537 -316.677054) (xy 25.138923 -316.679071) (xy 25.086618 -316.673033)
			(xy 25.035847 -316.659081) (xy 24.987802 -316.637542) (xy 24.943607 -316.608922) (xy 24.904299 -316.573891)
			(xy 24.870799 -316.53327) (xy 24.843893 -316.488011) (xy 24.82421 -316.439176) (xy 24.812213 -316.387908)
			(xy 24.808183 -316.33541) (xy 17.95145 -316.33541) (xy 17.950946 -316.361736) (xy 17.942909 -316.413772)
			(xy 17.927023 -316.463971) (xy 17.90366 -316.511156) (xy 17.873368 -316.554222) (xy 17.836856 -316.59216)
			(xy 17.794982 -316.624079) (xy 17.748726 -316.649232) (xy 17.699173 -316.66703) (xy 17.647483 -316.677054)
			(xy 17.594869 -316.679071) (xy 17.542564 -316.673033) (xy 17.491793 -316.659081) (xy 17.443748 -316.637542)
			(xy 17.399553 -316.608922) (xy 17.360245 -316.573891) (xy 17.326745 -316.53327) (xy 17.299839 -316.488011)
			(xy 17.280156 -316.439176) (xy 17.268159 -316.387908) (xy 17.264129 -316.33541) (xy 16.515389 -316.33541)
			(xy 16.678402 -317.154814) (xy 16.681196 -317.164466) (xy 16.68986 -317.185294) (xy 21.364197 -317.185294)
			(xy 21.368227 -317.132796) (xy 21.380224 -317.081528) (xy 21.399907 -317.032693) (xy 21.426813 -316.987434)
			(xy 21.460313 -316.946813) (xy 21.499621 -316.911782) (xy 21.543816 -316.883162) (xy 21.591861 -316.861623)
			(xy 21.642632 -316.847671) (xy 21.694937 -316.841633) (xy 21.747551 -316.84365) (xy 21.799241 -316.853674)
			(xy 21.848794 -316.871472) (xy 21.89505 -316.896625) (xy 21.936924 -316.928544) (xy 21.973436 -316.966482)
			(xy 22.003728 -317.009548) (xy 22.027091 -317.056733) (xy 22.042977 -317.106932) (xy 22.051014 -317.158968)
			(xy 22.051518 -317.185294) (xy 28.908251 -317.185294) (xy 28.912281 -317.132796) (xy 28.924278 -317.081528)
			(xy 28.943961 -317.032693) (xy 28.970867 -316.987434) (xy 29.004367 -316.946813) (xy 29.043675 -316.911782)
			(xy 29.08787 -316.883162) (xy 29.135915 -316.861623) (xy 29.186686 -316.847671) (xy 29.238991 -316.841633)
			(xy 29.291605 -316.84365) (xy 29.343295 -316.853674) (xy 29.392848 -316.871472) (xy 29.439104 -316.896625)
			(xy 29.480978 -316.928544) (xy 29.51749 -316.966482) (xy 29.547782 -317.009548) (xy 29.571145 -317.056733)
			(xy 29.587031 -317.106932) (xy 29.595068 -317.158968) (xy 29.595572 -317.185294) (xy 36.452051 -317.185294)
			(xy 36.456081 -317.132796) (xy 36.468078 -317.081528) (xy 36.487761 -317.032693) (xy 36.514667 -316.987434)
			(xy 36.548167 -316.946813) (xy 36.587475 -316.911782) (xy 36.63167 -316.883162) (xy 36.679715 -316.861623)
			(xy 36.730486 -316.847671) (xy 36.782791 -316.841633) (xy 36.835405 -316.84365) (xy 36.887095 -316.853674)
			(xy 36.936648 -316.871472) (xy 36.982904 -316.896625) (xy 37.024778 -316.928544) (xy 37.06129 -316.966482)
			(xy 37.091582 -317.009548) (xy 37.114945 -317.056733) (xy 37.130831 -317.106932) (xy 37.138868 -317.158968)
			(xy 37.139372 -317.185294) (xy 43.996105 -317.185294) (xy 44.000135 -317.132796) (xy 44.012132 -317.081528)
			(xy 44.031815 -317.032693) (xy 44.058721 -316.987434) (xy 44.092221 -316.946813) (xy 44.131529 -316.911782)
			(xy 44.175724 -316.883162) (xy 44.223769 -316.861623) (xy 44.27454 -316.847671) (xy 44.326845 -316.841633)
			(xy 44.379459 -316.84365) (xy 44.431149 -316.853674) (xy 44.480702 -316.871472) (xy 44.526958 -316.896625)
			(xy 44.568832 -316.928544) (xy 44.605344 -316.966482) (xy 44.635636 -317.009548) (xy 44.658999 -317.056733)
			(xy 44.674885 -317.106932) (xy 44.682922 -317.158968) (xy 44.683426 -317.185294) (xy 51.540159 -317.185294)
			(xy 51.544189 -317.132796) (xy 51.556186 -317.081528) (xy 51.575869 -317.032693) (xy 51.602775 -316.987434)
			(xy 51.636275 -316.946813) (xy 51.675583 -316.911782) (xy 51.719778 -316.883162) (xy 51.767823 -316.861623)
			(xy 51.818594 -316.847671) (xy 51.870899 -316.841633) (xy 51.923513 -316.84365) (xy 51.975203 -316.853674)
			(xy 52.024756 -316.871472) (xy 52.071012 -316.896625) (xy 52.112886 -316.928544) (xy 52.149398 -316.966482)
			(xy 52.17969 -317.009548) (xy 52.203053 -317.056733) (xy 52.218939 -317.106932) (xy 52.226976 -317.158968)
			(xy 52.22748 -317.185294) (xy 52.226976 -317.21162) (xy 52.218939 -317.263656) (xy 52.203053 -317.313855)
			(xy 52.17969 -317.36104) (xy 52.149398 -317.404106) (xy 52.112886 -317.442044) (xy 52.071012 -317.473963)
			(xy 52.024756 -317.499116) (xy 51.975203 -317.516914) (xy 51.923513 -317.526938) (xy 51.870899 -317.528955)
			(xy 51.818594 -317.522917) (xy 51.767823 -317.508965) (xy 51.719778 -317.487426) (xy 51.675583 -317.458806)
			(xy 51.636275 -317.423775) (xy 51.602775 -317.383154) (xy 51.575869 -317.337895) (xy 51.556186 -317.28906)
			(xy 51.544189 -317.237792) (xy 51.540159 -317.185294) (xy 44.683426 -317.185294) (xy 44.682922 -317.21162)
			(xy 44.674885 -317.263656) (xy 44.658999 -317.313855) (xy 44.635636 -317.36104) (xy 44.605344 -317.404106)
			(xy 44.568832 -317.442044) (xy 44.526958 -317.473963) (xy 44.480702 -317.499116) (xy 44.431149 -317.516914)
			(xy 44.379459 -317.526938) (xy 44.326845 -317.528955) (xy 44.27454 -317.522917) (xy 44.223769 -317.508965)
			(xy 44.175724 -317.487426) (xy 44.131529 -317.458806) (xy 44.092221 -317.423775) (xy 44.058721 -317.383154)
			(xy 44.031815 -317.337895) (xy 44.012132 -317.28906) (xy 44.000135 -317.237792) (xy 43.996105 -317.185294)
			(xy 37.139372 -317.185294) (xy 37.138868 -317.21162) (xy 37.130831 -317.263656) (xy 37.114945 -317.313855)
			(xy 37.091582 -317.36104) (xy 37.06129 -317.404106) (xy 37.024778 -317.442044) (xy 36.982904 -317.473963)
			(xy 36.936648 -317.499116) (xy 36.887095 -317.516914) (xy 36.835405 -317.526938) (xy 36.782791 -317.528955)
			(xy 36.730486 -317.522917) (xy 36.679715 -317.508965) (xy 36.63167 -317.487426) (xy 36.587475 -317.458806)
			(xy 36.548167 -317.423775) (xy 36.514667 -317.383154) (xy 36.487761 -317.337895) (xy 36.468078 -317.28906)
			(xy 36.456081 -317.237792) (xy 36.452051 -317.185294) (xy 29.595572 -317.185294) (xy 29.595068 -317.21162)
			(xy 29.587031 -317.263656) (xy 29.571145 -317.313855) (xy 29.547782 -317.36104) (xy 29.51749 -317.404106)
			(xy 29.480978 -317.442044) (xy 29.439104 -317.473963) (xy 29.392848 -317.499116) (xy 29.343295 -317.516914)
			(xy 29.291605 -317.526938) (xy 29.238991 -317.528955) (xy 29.186686 -317.522917) (xy 29.135915 -317.508965)
			(xy 29.08787 -317.487426) (xy 29.043675 -317.458806) (xy 29.004367 -317.423775) (xy 28.970867 -317.383154)
			(xy 28.943961 -317.337895) (xy 28.924278 -317.28906) (xy 28.912281 -317.237792) (xy 28.908251 -317.185294)
			(xy 22.051518 -317.185294) (xy 22.051014 -317.21162) (xy 22.042977 -317.263656) (xy 22.027091 -317.313855)
			(xy 22.003728 -317.36104) (xy 21.973436 -317.404106) (xy 21.936924 -317.442044) (xy 21.89505 -317.473963)
			(xy 21.848794 -317.499116) (xy 21.799241 -317.516914) (xy 21.747551 -317.526938) (xy 21.694937 -317.528955)
			(xy 21.642632 -317.522917) (xy 21.591861 -317.508965) (xy 21.543816 -317.487426) (xy 21.499621 -317.458806)
			(xy 21.460313 -317.423775) (xy 21.426813 -317.383154) (xy 21.399907 -317.337895) (xy 21.380224 -317.28906)
			(xy 21.368227 -317.237792) (xy 21.364197 -317.185294) (xy 16.68986 -317.185294) (xy 16.734028 -317.291466)
			(xy 16.736036 -317.296029) (xy 16.741535 -317.304343) (xy 16.74495 -317.307976) (xy 17.225518 -317.788544)
			(xy 17.232847 -317.795264) (xy 17.25115 -317.802986) (xy 17.261078 -317.80353) (xy 17.342612 -317.804038)
			(xy 17.361154 -317.796672) (xy 17.368266 -317.78956) (xy 17.387622 -317.77137) (xy 17.430901 -317.740578)
			(xy 17.478405 -317.716818) (xy 17.529002 -317.700659) (xy 17.581484 -317.692485) (xy 17.608042 -317.692024)
			(xy 17.635024 -317.692556) (xy 17.688323 -317.701005) (xy 17.739644 -317.717687) (xy 17.787724 -317.742191)
			(xy 17.831378 -317.773915) (xy 17.869533 -317.812078) (xy 17.901247 -317.855739) (xy 17.925742 -317.903824)
			(xy 17.942413 -317.955149) (xy 17.950849 -318.00845) (xy 17.95145 -318.035432) (xy 24.808183 -318.035432)
			(xy 24.812213 -317.982934) (xy 24.82421 -317.931666) (xy 24.843893 -317.882831) (xy 24.870799 -317.837572)
			(xy 24.904299 -317.796951) (xy 24.943607 -317.76192) (xy 24.987802 -317.7333) (xy 25.035847 -317.711761)
			(xy 25.086618 -317.697809) (xy 25.138923 -317.691771) (xy 25.191537 -317.693788) (xy 25.243227 -317.703812)
			(xy 25.29278 -317.72161) (xy 25.339036 -317.746763) (xy 25.38091 -317.778682) (xy 25.417422 -317.81662)
			(xy 25.447714 -317.859686) (xy 25.471077 -317.906871) (xy 25.486963 -317.95707) (xy 25.495 -318.009106)
			(xy 25.495504 -318.035432) (xy 32.351983 -318.035432) (xy 32.356013 -317.982934) (xy 32.36801 -317.931666)
			(xy 32.387693 -317.882831) (xy 32.414599 -317.837572) (xy 32.448099 -317.796951) (xy 32.487407 -317.76192)
			(xy 32.531602 -317.7333) (xy 32.579647 -317.711761) (xy 32.630418 -317.697809) (xy 32.682723 -317.691771)
			(xy 32.735337 -317.693788) (xy 32.787027 -317.703812) (xy 32.83658 -317.72161) (xy 32.882836 -317.746763)
			(xy 32.92471 -317.778682) (xy 32.961222 -317.81662) (xy 32.991514 -317.859686) (xy 33.014877 -317.906871)
			(xy 33.030763 -317.95707) (xy 33.0388 -318.009106) (xy 33.039304 -318.035432) (xy 39.896037 -318.035432)
			(xy 39.900067 -317.982934) (xy 39.912064 -317.931666) (xy 39.931747 -317.882831) (xy 39.958653 -317.837572)
			(xy 39.992153 -317.796951) (xy 40.031461 -317.76192) (xy 40.075656 -317.7333) (xy 40.123701 -317.711761)
			(xy 40.174472 -317.697809) (xy 40.226777 -317.691771) (xy 40.279391 -317.693788) (xy 40.331081 -317.703812)
			(xy 40.380634 -317.72161) (xy 40.42689 -317.746763) (xy 40.468764 -317.778682) (xy 40.505276 -317.81662)
			(xy 40.535568 -317.859686) (xy 40.558931 -317.906871) (xy 40.574817 -317.95707) (xy 40.582854 -318.009106)
			(xy 40.583358 -318.035432) (xy 47.440091 -318.035432) (xy 47.444121 -317.982934) (xy 47.456118 -317.931666)
			(xy 47.475801 -317.882831) (xy 47.502707 -317.837572) (xy 47.536207 -317.796951) (xy 47.575515 -317.76192)
			(xy 47.61971 -317.7333) (xy 47.667755 -317.711761) (xy 47.718526 -317.697809) (xy 47.770831 -317.691771)
			(xy 47.823445 -317.693788) (xy 47.875135 -317.703812) (xy 47.924688 -317.72161) (xy 47.970944 -317.746763)
			(xy 48.012818 -317.778682) (xy 48.04933 -317.81662) (xy 48.079622 -317.859686) (xy 48.102985 -317.906871)
			(xy 48.118871 -317.95707) (xy 48.126908 -318.009106) (xy 48.127412 -318.035432) (xy 48.126908 -318.061758)
			(xy 48.118871 -318.113794) (xy 48.102985 -318.163993) (xy 48.079622 -318.211178) (xy 48.04933 -318.254244)
			(xy 48.012818 -318.292182) (xy 47.970944 -318.324101) (xy 47.924688 -318.349254) (xy 47.875135 -318.367052)
			(xy 47.823445 -318.377076) (xy 47.770831 -318.379093) (xy 47.718526 -318.373055) (xy 47.667755 -318.359103)
			(xy 47.61971 -318.337564) (xy 47.575515 -318.308944) (xy 47.536207 -318.273913) (xy 47.502707 -318.233292)
			(xy 47.475801 -318.188033) (xy 47.456118 -318.139198) (xy 47.444121 -318.08793) (xy 47.440091 -318.035432)
			(xy 40.583358 -318.035432) (xy 40.582854 -318.061758) (xy 40.574817 -318.113794) (xy 40.558931 -318.163993)
			(xy 40.535568 -318.211178) (xy 40.505276 -318.254244) (xy 40.468764 -318.292182) (xy 40.42689 -318.324101)
			(xy 40.380634 -318.349254) (xy 40.331081 -318.367052) (xy 40.279391 -318.377076) (xy 40.226777 -318.379093)
			(xy 40.174472 -318.373055) (xy 40.123701 -318.359103) (xy 40.075656 -318.337564) (xy 40.031461 -318.308944)
			(xy 39.992153 -318.273913) (xy 39.958653 -318.233292) (xy 39.931747 -318.188033) (xy 39.912064 -318.139198)
			(xy 39.900067 -318.08793) (xy 39.896037 -318.035432) (xy 33.039304 -318.035432) (xy 33.0388 -318.061758)
			(xy 33.030763 -318.113794) (xy 33.014877 -318.163993) (xy 32.991514 -318.211178) (xy 32.961222 -318.254244)
			(xy 32.92471 -318.292182) (xy 32.882836 -318.324101) (xy 32.83658 -318.349254) (xy 32.787027 -318.367052)
			(xy 32.735337 -318.377076) (xy 32.682723 -318.379093) (xy 32.630418 -318.373055) (xy 32.579647 -318.359103)
			(xy 32.531602 -318.337564) (xy 32.487407 -318.308944) (xy 32.448099 -318.273913) (xy 32.414599 -318.233292)
			(xy 32.387693 -318.188033) (xy 32.36801 -318.139198) (xy 32.356013 -318.08793) (xy 32.351983 -318.035432)
			(xy 25.495504 -318.035432) (xy 25.495 -318.061758) (xy 25.486963 -318.113794) (xy 25.471077 -318.163993)
			(xy 25.447714 -318.211178) (xy 25.417422 -318.254244) (xy 25.38091 -318.292182) (xy 25.339036 -318.324101)
			(xy 25.29278 -318.349254) (xy 25.243227 -318.367052) (xy 25.191537 -318.377076) (xy 25.138923 -318.379093)
			(xy 25.086618 -318.373055) (xy 25.035847 -318.359103) (xy 24.987802 -318.337564) (xy 24.943607 -318.308944)
			(xy 24.904299 -318.273913) (xy 24.870799 -318.233292) (xy 24.843893 -318.188033) (xy 24.82421 -318.139198)
			(xy 24.812213 -318.08793) (xy 24.808183 -318.035432) (xy 17.95145 -318.035432) (xy 17.950952 -318.061987)
			(xy 17.942774 -318.114463) (xy 17.926618 -318.165056) (xy 17.902868 -318.21256) (xy 17.872091 -318.255843)
			(xy 17.853914 -318.275208) (xy 17.846802 -318.28232) (xy 17.839436 -318.300862) (xy 17.839944 -318.382396)
			(xy 17.840509 -318.392322) (xy 17.84821 -318.41063) (xy 17.85493 -318.417956) (xy 18.427954 -318.99098)
			(xy 18.433656 -318.996322) (xy 18.447492 -319.003566) (xy 18.455132 -319.005204) (xy 19.353276 -319.163446)
			(xy 19.361912 -319.164462) (xy 57.096406 -319.34404) (xy 57.118276 -319.344313) (xy 57.161884 -319.347749)
			(xy 57.183528 -319.350898) (xy 57.187338 -319.35166)
		)
		(stroke
			(width 0)
			(type solid)
		)
		(fill yes)
		(layer "In15.Cu")
		(net "GND")
	)
	(gr_poly
		(pts
			(xy 121.549668 -262.94588) (xy 121.561291 -262.945309) (xy 121.582187 -262.935123) (xy 121.5898 -262.926322)
			(xy 121.646188 -262.853932) (xy 121.651014 -262.831072) (xy 121.64822 -262.819896) (xy 121.644033 -262.801771)
			(xy 121.639579 -262.764837) (xy 121.63933 -262.746236) (xy 121.639852 -262.720981) (xy 121.648165 -262.671159)
			(xy 121.664566 -262.623385) (xy 121.688607 -262.578962) (xy 121.719631 -262.539102) (xy 121.756793 -262.504892)
			(xy 121.799079 -262.477266) (xy 121.845335 -262.456976) (xy 121.8943 -262.444576) (xy 121.944638 -262.440405)
			(xy 121.994976 -262.444576) (xy 122.043941 -262.456976) (xy 122.090197 -262.477266) (xy 122.132483 -262.504892)
			(xy 122.169645 -262.539102) (xy 122.200669 -262.578962) (xy 122.22471 -262.623385) (xy 122.241111 -262.671159)
			(xy 122.249424 -262.720981) (xy 122.249946 -262.746236) (xy 122.249698 -262.764837) (xy 122.245236 -262.801769)
			(xy 122.241056 -262.819896) (xy 122.238262 -262.831072) (xy 122.243088 -262.853932) (xy 122.299476 -262.926322)
			(xy 122.307067 -262.935149) (xy 122.327977 -262.945329) (xy 122.339608 -262.94588) (xy 122.489722 -262.94588)
			(xy 122.50135 -262.945319) (xy 122.522261 -262.935144) (xy 122.529854 -262.926322) (xy 122.586242 -262.853932)
			(xy 122.591068 -262.831072) (xy 122.588274 -262.819896) (xy 122.584087 -262.801771) (xy 122.579632 -262.764837)
			(xy 122.579384 -262.746236) (xy 122.579906 -262.720981) (xy 122.588219 -262.671159) (xy 122.60462 -262.623385)
			(xy 122.628661 -262.578962) (xy 122.659685 -262.539102) (xy 122.696847 -262.504892) (xy 122.739133 -262.477266)
			(xy 122.785389 -262.456976) (xy 122.834354 -262.444576) (xy 122.884692 -262.440405) (xy 122.93503 -262.444576)
			(xy 122.983995 -262.456976) (xy 123.030251 -262.477266) (xy 123.072537 -262.504892) (xy 123.109699 -262.539102)
			(xy 123.140723 -262.578962) (xy 123.164764 -262.623385) (xy 123.181165 -262.671159) (xy 123.189478 -262.720981)
			(xy 123.19 -262.746236) (xy 123.189752 -262.764837) (xy 123.185289 -262.801769) (xy 123.18111 -262.819896)
			(xy 123.178316 -262.831072) (xy 123.183142 -262.853932) (xy 123.23953 -262.926322) (xy 123.247118 -262.935157)
			(xy 123.268028 -262.945355) (xy 123.279662 -262.94588) (xy 123.429776 -262.94588) (xy 123.441398 -262.945308)
			(xy 123.462291 -262.935119) (xy 123.469908 -262.926322) (xy 123.526296 -262.853932) (xy 123.531122 -262.831072)
			(xy 123.528328 -262.819896) (xy 123.524141 -262.801771) (xy 123.519687 -262.764837) (xy 123.519438 -262.746236)
			(xy 123.51996 -262.720981) (xy 123.528273 -262.671159) (xy 123.544674 -262.623385) (xy 123.568715 -262.578962)
			(xy 123.599739 -262.539102) (xy 123.636901 -262.504892) (xy 123.679187 -262.477266) (xy 123.725443 -262.456976)
			(xy 123.774408 -262.444576) (xy 123.824746 -262.440405) (xy 123.875084 -262.444576) (xy 123.924049 -262.456976)
			(xy 123.970305 -262.477266) (xy 124.012591 -262.504892) (xy 124.049753 -262.539102) (xy 124.080777 -262.578962)
			(xy 124.104818 -262.623385) (xy 124.121219 -262.671159) (xy 124.129532 -262.720981) (xy 124.130054 -262.746236)
			(xy 124.129806 -262.764837) (xy 124.125344 -262.801769) (xy 124.121164 -262.819896) (xy 124.11837 -262.831072)
			(xy 124.123196 -262.853932) (xy 124.179584 -262.926322) (xy 124.187176 -262.935148) (xy 124.208086 -262.945324)
			(xy 124.219716 -262.94588) (xy 125.309884 -262.94588) (xy 125.321505 -262.945306) (xy 125.342396 -262.935116)
			(xy 125.350016 -262.926322) (xy 125.406404 -262.853932) (xy 125.41123 -262.831072) (xy 125.408436 -262.819896)
			(xy 125.404249 -262.801771) (xy 125.399795 -262.764837) (xy 125.399546 -262.746236) (xy 125.400068 -262.720981)
			(xy 125.408381 -262.671159) (xy 125.424782 -262.623385) (xy 125.448823 -262.578962) (xy 125.479847 -262.539102)
			(xy 125.517009 -262.504892) (xy 125.559295 -262.477266) (xy 125.605551 -262.456976) (xy 125.654516 -262.444576)
			(xy 125.704854 -262.440405) (xy 125.755192 -262.444576) (xy 125.804157 -262.456976) (xy 125.850413 -262.477266)
			(xy 125.892699 -262.504892) (xy 125.929861 -262.539102) (xy 125.960885 -262.578962) (xy 125.984926 -262.623385)
			(xy 126.001327 -262.671159) (xy 126.00964 -262.720981) (xy 126.010162 -262.746236) (xy 126.009914 -262.764837)
			(xy 126.005452 -262.801769) (xy 126.001272 -262.819896) (xy 125.998478 -262.831072) (xy 126.003304 -262.853932)
			(xy 126.059692 -262.926322) (xy 126.067284 -262.935147) (xy 126.088195 -262.94532) (xy 126.099824 -262.94588)
			(xy 127.189738 -262.94588) (xy 127.201364 -262.945315) (xy 127.22227 -262.935137) (xy 127.22987 -262.926322)
			(xy 127.286258 -262.853932) (xy 127.291084 -262.831072) (xy 127.28829 -262.819896) (xy 127.284104 -262.801771)
			(xy 127.27965 -262.764837) (xy 127.2794 -262.746236) (xy 127.279922 -262.720981) (xy 127.288235 -262.671159)
			(xy 127.304636 -262.623385) (xy 127.328677 -262.578962) (xy 127.359701 -262.539102) (xy 127.396863 -262.504892)
			(xy 127.439149 -262.477266) (xy 127.485405 -262.456976) (xy 127.53437 -262.444576) (xy 127.584708 -262.440405)
			(xy 127.635046 -262.444576) (xy 127.684011 -262.456976) (xy 127.730267 -262.477266) (xy 127.772553 -262.504892)
			(xy 127.809715 -262.539102) (xy 127.840739 -262.578962) (xy 127.86478 -262.623385) (xy 127.881181 -262.671159)
			(xy 127.889494 -262.720981) (xy 127.890016 -262.746236) (xy 127.889768 -262.764837) (xy 127.885305 -262.801769)
			(xy 127.881126 -262.819896) (xy 127.878332 -262.831072) (xy 127.883158 -262.853932) (xy 127.939546 -262.926322)
			(xy 127.947135 -262.935154) (xy 127.968045 -262.945346) (xy 127.979678 -262.94588) (xy 128.125728 -262.94588)
			(xy 128.136454 -262.945464) (xy 128.156062 -262.936782) (xy 128.163574 -262.929116) (xy 128.164844 -262.927846)
			(xy 128.222248 -262.854186) (xy 128.224534 -262.843772) (xy 128.217291 -262.820042) (xy 128.209512 -262.771043)
			(xy 128.20904 -262.746236) (xy 128.209527 -262.721426) (xy 128.217289 -262.672418) (xy 128.232622 -262.625228)
			(xy 128.255149 -262.581017) (xy 128.284314 -262.540874) (xy 128.3194 -262.505788) (xy 128.359543 -262.476623)
			(xy 128.403754 -262.454096) (xy 128.450944 -262.438763) (xy 128.499952 -262.431001) (xy 128.549572 -262.431001)
			(xy 128.59858 -262.438763) (xy 128.64577 -262.454096) (xy 128.689981 -262.476623) (xy 128.730124 -262.505788)
			(xy 128.76521 -262.540874) (xy 128.794375 -262.581017) (xy 128.816902 -262.625228) (xy 128.832235 -262.672418)
			(xy 128.839997 -262.721426) (xy 128.840484 -262.746236) (xy 128.839977 -262.771039) (xy 128.832197 -262.820034)
			(xy 128.82499 -262.843772) (xy 128.827276 -262.854186) (xy 128.883664 -262.926322) (xy 128.88595 -262.929116)
			(xy 128.893547 -262.936664) (xy 128.913102 -262.945335) (xy 128.923796 -262.94588) (xy 129.065782 -262.94588)
			(xy 129.076503 -262.945454) (xy 129.096094 -262.936758) (xy 129.103628 -262.929116) (xy 129.104898 -262.927846)
			(xy 129.162302 -262.854186) (xy 129.164588 -262.843772) (xy 129.157445 -262.820024) (xy 129.149787 -262.771031)
			(xy 129.149348 -262.746236) (xy 129.149834 -262.721446) (xy 129.15759 -262.672478) (xy 129.172911 -262.625325)
			(xy 129.19542 -262.58115) (xy 129.224562 -262.541039) (xy 129.259619 -262.505982) (xy 129.29973 -262.47684)
			(xy 129.343905 -262.454331) (xy 129.391058 -262.43901) (xy 129.440026 -262.431254) (xy 129.489606 -262.431254)
			(xy 129.538574 -262.43901) (xy 129.585727 -262.454331) (xy 129.629902 -262.47684) (xy 129.670013 -262.505982)
			(xy 129.70507 -262.541039) (xy 129.734212 -262.58115) (xy 129.756721 -262.625325) (xy 129.772042 -262.672478)
			(xy 129.779798 -262.721446) (xy 129.780284 -262.746236) (xy 129.779885 -262.771034) (xy 129.772231 -262.820035)
			(xy 129.765044 -262.843772) (xy 129.76733 -262.854186) (xy 129.823718 -262.926322) (xy 129.826004 -262.929116)
			(xy 129.833604 -262.936655) (xy 129.853159 -262.945306) (xy 129.86385 -262.94588) (xy 130.0099 -262.94588)
			(xy 130.021519 -262.945303) (xy 130.042405 -262.935109) (xy 130.050032 -262.926322) (xy 130.10642 -262.853932)
			(xy 130.111246 -262.831072) (xy 130.108452 -262.819896) (xy 130.104265 -262.801771) (xy 130.09981 -262.764837)
			(xy 130.099562 -262.746236) (xy 130.100084 -262.720981) (xy 130.108397 -262.671159) (xy 130.124798 -262.623385)
			(xy 130.148839 -262.578962) (xy 130.179863 -262.539102) (xy 130.217025 -262.504892) (xy 130.259311 -262.477266)
			(xy 130.305567 -262.456976) (xy 130.354532 -262.444576) (xy 130.40487 -262.440405) (xy 130.455208 -262.444576)
			(xy 130.504173 -262.456976) (xy 130.550429 -262.477266) (xy 130.592715 -262.504892) (xy 130.629877 -262.539102)
			(xy 130.660901 -262.578962) (xy 130.684942 -262.623385) (xy 130.701343 -262.671159) (xy 130.709656 -262.720981)
			(xy 130.710178 -262.746236) (xy 130.70993 -262.764837) (xy 130.705467 -262.801769) (xy 130.701288 -262.819896)
			(xy 130.698494 -262.831072) (xy 130.70332 -262.853932) (xy 130.759708 -262.926322) (xy 130.767295 -262.935161)
			(xy 130.788204 -262.945368) (xy 130.79984 -262.94588) (xy 130.945636 -262.94588) (xy 130.956361 -262.945463)
			(xy 130.975966 -262.936778) (xy 130.983482 -262.929116) (xy 130.984752 -262.927846) (xy 131.042156 -262.854186)
			(xy 131.044442 -262.843772) (xy 131.037198 -262.820042) (xy 131.02942 -262.771043) (xy 131.028948 -262.746236)
			(xy 131.029435 -262.721426) (xy 131.037197 -262.672418) (xy 131.05253 -262.625228) (xy 131.075057 -262.581017)
			(xy 131.104222 -262.540874) (xy 131.139308 -262.505788) (xy 131.179451 -262.476623) (xy 131.223662 -262.454096)
			(xy 131.270852 -262.438763) (xy 131.31986 -262.431001) (xy 131.36948 -262.431001) (xy 131.418488 -262.438763)
			(xy 131.465678 -262.454096) (xy 131.509889 -262.476623) (xy 131.550032 -262.505788) (xy 131.585118 -262.540874)
			(xy 131.614283 -262.581017) (xy 131.63681 -262.625228) (xy 131.652143 -262.672418) (xy 131.659905 -262.721426)
			(xy 131.660392 -262.746236) (xy 131.659885 -262.771039) (xy 131.652106 -262.820034) (xy 131.644898 -262.843772)
			(xy 131.647184 -262.854186) (xy 131.703572 -262.926322) (xy 131.705858 -262.929116) (xy 131.713455 -262.936663)
			(xy 131.73301 -262.945331) (xy 131.743704 -262.94588) (xy 131.889754 -262.94588) (xy 131.901378 -262.945312)
			(xy 131.922279 -262.935129) (xy 131.929886 -262.926322) (xy 131.986274 -262.853932) (xy 131.9911 -262.831072)
			(xy 131.988306 -262.819896) (xy 131.98412 -262.801771) (xy 131.979666 -262.764837) (xy 131.979416 -262.746236)
			(xy 131.979938 -262.720981) (xy 131.988251 -262.671159) (xy 132.004652 -262.623385) (xy 132.028693 -262.578962)
			(xy 132.059717 -262.539102) (xy 132.096879 -262.504892) (xy 132.139165 -262.477266) (xy 132.185421 -262.456976)
			(xy 132.234386 -262.444576) (xy 132.284724 -262.440405) (xy 132.335062 -262.444576) (xy 132.384027 -262.456976)
			(xy 132.430283 -262.477266) (xy 132.472569 -262.504892) (xy 132.509731 -262.539102) (xy 132.540755 -262.578962)
			(xy 132.564796 -262.623385) (xy 132.581197 -262.671159) (xy 132.58951 -262.720981) (xy 132.590032 -262.746236)
			(xy 132.589784 -262.764837) (xy 132.585322 -262.801769) (xy 132.581142 -262.819896) (xy 132.578348 -262.831072)
			(xy 132.583174 -262.853932) (xy 132.639562 -262.926322) (xy 132.647153 -262.935151) (xy 132.668062 -262.945337)
			(xy 132.679694 -262.94588) (xy 132.825744 -262.94588) (xy 132.836468 -262.945461) (xy 132.856071 -262.936775)
			(xy 132.86359 -262.929116) (xy 132.86486 -262.927846) (xy 132.922264 -262.854186) (xy 132.92455 -262.843772)
			(xy 132.917306 -262.820042) (xy 132.909528 -262.771043) (xy 132.909056 -262.746236) (xy 132.909543 -262.721426)
			(xy 132.917305 -262.672418) (xy 132.932638 -262.625228) (xy 132.955165 -262.581017) (xy 132.98433 -262.540874)
			(xy 133.019416 -262.505788) (xy 133.059559 -262.476623) (xy 133.10377 -262.454096) (xy 133.15096 -262.438763)
			(xy 133.199968 -262.431001) (xy 133.249588 -262.431001) (xy 133.298596 -262.438763) (xy 133.345786 -262.454096)
			(xy 133.389997 -262.476623) (xy 133.43014 -262.505788) (xy 133.465226 -262.540874) (xy 133.494391 -262.581017)
			(xy 133.516918 -262.625228) (xy 133.532251 -262.672418) (xy 133.540013 -262.721426) (xy 133.5405 -262.746236)
			(xy 133.539993 -262.771039) (xy 133.532214 -262.820034) (xy 133.525006 -262.843772) (xy 133.527292 -262.854186)
			(xy 133.58368 -262.926322) (xy 133.585966 -262.929116) (xy 133.593564 -262.936661) (xy 133.613119 -262.945327)
			(xy 133.623812 -262.94588) (xy 133.769862 -262.94588) (xy 133.781485 -262.94531) (xy 133.802384 -262.935126)
			(xy 133.809994 -262.926322) (xy 133.866382 -262.853932) (xy 133.871208 -262.831072) (xy 133.868414 -262.819896)
			(xy 133.864227 -262.801771) (xy 133.859774 -262.764837) (xy 133.859524 -262.746236) (xy 133.860046 -262.720981)
			(xy 133.868359 -262.671159) (xy 133.88476 -262.623385) (xy 133.908801 -262.578962) (xy 133.939825 -262.539102)
			(xy 133.976987 -262.504892) (xy 134.019273 -262.477266) (xy 134.065529 -262.456976) (xy 134.114494 -262.444576)
			(xy 134.164832 -262.440405) (xy 134.21517 -262.444576) (xy 134.264135 -262.456976) (xy 134.310391 -262.477266)
			(xy 134.352677 -262.504892) (xy 134.389839 -262.539102) (xy 134.420863 -262.578962) (xy 134.444904 -262.623385)
			(xy 134.461305 -262.671159) (xy 134.469618 -262.720981) (xy 134.47014 -262.746236) (xy 134.469892 -262.764837)
			(xy 134.46543 -262.801769) (xy 134.46125 -262.819896) (xy 134.458456 -262.831072) (xy 134.463282 -262.853932)
			(xy 134.51967 -262.926322) (xy 134.527261 -262.93515) (xy 134.548171 -262.945332) (xy 134.559802 -262.94588)
			(xy 134.705598 -262.94588) (xy 134.716326 -262.94547) (xy 134.735943 -262.936796) (xy 134.743444 -262.929116)
			(xy 134.744714 -262.927846) (xy 134.802118 -262.854186) (xy 134.804404 -262.843772) (xy 134.797261 -262.820024)
			(xy 134.789603 -262.771031) (xy 134.789164 -262.746236) (xy 134.78965 -262.721446) (xy 134.797406 -262.672478)
			(xy 134.812727 -262.625325) (xy 134.835236 -262.58115) (xy 134.864378 -262.541039) (xy 134.899435 -262.505982)
			(xy 134.939546 -262.47684) (xy 134.983721 -262.454331) (xy 135.030874 -262.43901) (xy 135.079842 -262.431254)
			(xy 135.129422 -262.431254) (xy 135.17839 -262.43901) (xy 135.225543 -262.454331) (xy 135.269718 -262.47684)
			(xy 135.309829 -262.505982) (xy 135.344886 -262.541039) (xy 135.374028 -262.58115) (xy 135.396537 -262.625325)
			(xy 135.411858 -262.672478) (xy 135.419614 -262.721446) (xy 135.4201 -262.746236) (xy 135.419701 -262.771034)
			(xy 135.412047 -262.820035) (xy 135.40486 -262.843772) (xy 135.407146 -262.854186) (xy 135.463534 -262.926322)
			(xy 135.46582 -262.929116) (xy 135.473421 -262.936653) (xy 135.492976 -262.945298) (xy 135.503666 -262.94588)
			(xy 135.645652 -262.94588) (xy 135.656375 -262.94546) (xy 135.675976 -262.936771) (xy 135.683498 -262.929116)
			(xy 135.684768 -262.927846) (xy 135.742172 -262.854186) (xy 135.744458 -262.843772) (xy 135.737214 -262.820042)
			(xy 135.729435 -262.771043) (xy 135.728964 -262.746236) (xy 135.729451 -262.721426) (xy 135.737213 -262.672418)
			(xy 135.752546 -262.625228) (xy 135.775073 -262.581017) (xy 135.804238 -262.540874) (xy 135.839324 -262.505788)
			(xy 135.879467 -262.476623) (xy 135.923678 -262.454096) (xy 135.970868 -262.438763) (xy 136.019876 -262.431001)
			(xy 136.069496 -262.431001) (xy 136.118504 -262.438763) (xy 136.165694 -262.454096) (xy 136.209905 -262.476623)
			(xy 136.250048 -262.505788) (xy 136.285134 -262.540874) (xy 136.314299 -262.581017) (xy 136.336826 -262.625228)
			(xy 136.352159 -262.672418) (xy 136.359921 -262.721426) (xy 136.360408 -262.746236) (xy 136.359901 -262.771039)
			(xy 136.352122 -262.820034) (xy 136.344914 -262.843772) (xy 136.3472 -262.854186) (xy 136.403588 -262.926322)
			(xy 136.405874 -262.929116) (xy 136.413472 -262.93666) (xy 136.433027 -262.945323) (xy 136.44372 -262.94588)
			(xy 136.58977 -262.94588) (xy 136.601392 -262.945309) (xy 136.622288 -262.935122) (xy 136.629902 -262.926322)
			(xy 136.68629 -262.853932) (xy 136.691116 -262.831072) (xy 136.688322 -262.819896) (xy 136.684135 -262.801771)
			(xy 136.679681 -262.764837) (xy 136.679432 -262.746236) (xy 136.679954 -262.720981) (xy 136.688267 -262.671159)
			(xy 136.704668 -262.623385) (xy 136.728709 -262.578962) (xy 136.759733 -262.539102) (xy 136.796895 -262.504892)
			(xy 136.839181 -262.477266) (xy 136.885437 -262.456976) (xy 136.934402 -262.444576) (xy 136.98474 -262.440405)
			(xy 137.035078 -262.444576) (xy 137.084043 -262.456976) (xy 137.130299 -262.477266) (xy 137.172585 -262.504892)
			(xy 137.209747 -262.539102) (xy 137.240771 -262.578962) (xy 137.264812 -262.623385) (xy 137.281213 -262.671159)
			(xy 137.289526 -262.720981) (xy 137.290048 -262.746236) (xy 137.2898 -262.764837) (xy 137.285338 -262.801769)
			(xy 137.281158 -262.819896) (xy 137.278364 -262.831072) (xy 137.28319 -262.853932) (xy 137.339578 -262.926322)
			(xy 137.347169 -262.935149) (xy 137.36808 -262.945328) (xy 137.37971 -262.94588) (xy 137.52576 -262.94588)
			(xy 137.536483 -262.945458) (xy 137.556081 -262.936767) (xy 137.563606 -262.929116) (xy 137.564876 -262.927846)
			(xy 137.62228 -262.854186) (xy 137.624566 -262.843772) (xy 137.617322 -262.820042) (xy 137.609543 -262.771043)
			(xy 137.609072 -262.746236) (xy 137.609559 -262.721426) (xy 137.617321 -262.672418) (xy 137.632654 -262.625228)
			(xy 137.655181 -262.581017) (xy 137.684346 -262.540874) (xy 137.719432 -262.505788) (xy 137.759575 -262.476623)
			(xy 137.803786 -262.454096) (xy 137.850976 -262.438763) (xy 137.899984 -262.431001) (xy 137.949604 -262.431001)
			(xy 137.998612 -262.438763) (xy 138.045802 -262.454096) (xy 138.090013 -262.476623) (xy 138.130156 -262.505788)
			(xy 138.165242 -262.540874) (xy 138.194407 -262.581017) (xy 138.216934 -262.625228) (xy 138.232267 -262.672418)
			(xy 138.240029 -262.721426) (xy 138.240516 -262.746236) (xy 138.240009 -262.771039) (xy 138.23223 -262.820034)
			(xy 138.225022 -262.843772) (xy 138.227308 -262.854186) (xy 138.283696 -262.926322) (xy 138.285982 -262.929116)
			(xy 138.293581 -262.936659) (xy 138.313136 -262.945318) (xy 138.323828 -262.94588) (xy 138.469878 -262.94588)
			(xy 138.4815 -262.945307) (xy 138.502393 -262.935119) (xy 138.51001 -262.926322) (xy 138.566398 -262.853932)
			(xy 138.571224 -262.831072) (xy 138.56843 -262.819896) (xy 138.564243 -262.801771) (xy 138.559789 -262.764837)
			(xy 138.55954 -262.746236) (xy 138.560062 -262.720981) (xy 138.568375 -262.671159) (xy 138.584776 -262.623385)
			(xy 138.608817 -262.578962) (xy 138.639841 -262.539102) (xy 138.677003 -262.504892) (xy 138.719289 -262.477266)
			(xy 138.765545 -262.456976) (xy 138.81451 -262.444576) (xy 138.864848 -262.440405) (xy 138.915186 -262.444576)
			(xy 138.964151 -262.456976) (xy 139.010407 -262.477266) (xy 139.052693 -262.504892) (xy 139.089855 -262.539102)
			(xy 139.120879 -262.578962) (xy 139.14492 -262.623385) (xy 139.161321 -262.671159) (xy 139.169634 -262.720981)
			(xy 139.170156 -262.746236) (xy 139.169908 -262.764837) (xy 139.165446 -262.801769) (xy 139.161266 -262.819896)
			(xy 139.158472 -262.831072) (xy 139.163298 -262.853932) (xy 139.219686 -262.926322) (xy 139.227278 -262.935148)
			(xy 139.248188 -262.945323) (xy 139.259818 -262.94588) (xy 139.405614 -262.94588) (xy 139.416341 -262.945467)
			(xy 139.435953 -262.936788) (xy 139.44346 -262.929116) (xy 139.44473 -262.927846) (xy 139.502134 -262.854186)
			(xy 139.50442 -262.843772) (xy 139.497277 -262.820024) (xy 139.489618 -262.771031) (xy 139.48918 -262.746236)
			(xy 139.489666 -262.721446) (xy 139.497422 -262.672478) (xy 139.512743 -262.625325) (xy 139.535252 -262.58115)
			(xy 139.564394 -262.541039) (xy 139.599451 -262.505982) (xy 139.639562 -262.47684) (xy 139.683737 -262.454331)
			(xy 139.73089 -262.43901) (xy 139.779858 -262.431254) (xy 139.829438 -262.431254) (xy 139.878406 -262.43901)
			(xy 139.925559 -262.454331) (xy 139.969734 -262.47684) (xy 140.009845 -262.505982) (xy 140.044902 -262.541039)
			(xy 140.074044 -262.58115) (xy 140.096553 -262.625325) (xy 140.111874 -262.672478) (xy 140.11963 -262.721446)
			(xy 140.120116 -262.746236) (xy 140.119718 -262.771034) (xy 140.112064 -262.820035) (xy 140.104876 -262.843772)
			(xy 140.107162 -262.854186) (xy 140.16355 -262.926322) (xy 140.165836 -262.929116) (xy 140.173438 -262.93665)
			(xy 140.192993 -262.945289) (xy 140.203682 -262.94588) (xy 140.349732 -262.94588) (xy 140.361358 -262.945317)
			(xy 140.382267 -262.935139) (xy 140.389864 -262.926322) (xy 140.446252 -262.853932) (xy 140.451078 -262.831072)
			(xy 140.448284 -262.819896) (xy 140.444098 -262.801771) (xy 140.439644 -262.764837) (xy 140.439394 -262.746236)
			(xy 140.439916 -262.720981) (xy 140.448229 -262.671159) (xy 140.46463 -262.623385) (xy 140.488671 -262.578962)
			(xy 140.519695 -262.539102) (xy 140.556857 -262.504892) (xy 140.599143 -262.477266) (xy 140.645399 -262.456976)
			(xy 140.694364 -262.444576) (xy 140.744702 -262.440405) (xy 140.79504 -262.444576) (xy 140.844005 -262.456976)
			(xy 140.890261 -262.477266) (xy 140.932547 -262.504892) (xy 140.969709 -262.539102) (xy 141.000733 -262.578962)
			(xy 141.024774 -262.623385) (xy 141.041175 -262.671159) (xy 141.049488 -262.720981) (xy 141.05001 -262.746236)
			(xy 141.049762 -262.764837) (xy 141.045299 -262.801769) (xy 141.04112 -262.819896) (xy 141.038326 -262.831072)
			(xy 141.043152 -262.853932) (xy 141.09954 -262.926322) (xy 141.107129 -262.935155) (xy 141.128039 -262.94535)
			(xy 141.139672 -262.94588) (xy 141.285722 -262.94588) (xy 141.296448 -262.945466) (xy 141.316058 -262.936785)
			(xy 141.323568 -262.929116) (xy 141.324838 -262.927846) (xy 141.382242 -262.854186) (xy 141.384528 -262.843772)
			(xy 141.377384 -262.820024) (xy 141.369726 -262.771031) (xy 141.369288 -262.746236) (xy 141.369774 -262.721446)
			(xy 141.37753 -262.672478) (xy 141.392851 -262.625325) (xy 141.41536 -262.58115) (xy 141.444502 -262.541039)
			(xy 141.479559 -262.505982) (xy 141.51967 -262.47684) (xy 141.563845 -262.454331) (xy 141.610998 -262.43901)
			(xy 141.659966 -262.431254) (xy 141.709546 -262.431254) (xy 141.758514 -262.43901) (xy 141.805667 -262.454331)
			(xy 141.849842 -262.47684) (xy 141.889953 -262.505982) (xy 141.92501 -262.541039) (xy 141.954152 -262.58115)
			(xy 141.976661 -262.625325) (xy 141.991982 -262.672478) (xy 141.999738 -262.721446) (xy 142.000224 -262.746236)
			(xy 141.999826 -262.771034) (xy 141.992172 -262.820035) (xy 141.984984 -262.843772) (xy 141.98727 -262.854186)
			(xy 142.043658 -262.926322) (xy 142.045944 -262.929116) (xy 142.053546 -262.936649) (xy 142.073102 -262.945284)
			(xy 142.08379 -262.94588) (xy 142.225776 -262.94588) (xy 142.236497 -262.945455) (xy 142.256091 -262.93676)
			(xy 142.263622 -262.929116) (xy 142.264892 -262.927846) (xy 142.322296 -262.854186) (xy 142.324582 -262.843772)
			(xy 142.317338 -262.820042) (xy 142.309558 -262.771043) (xy 142.309088 -262.746236) (xy 142.309575 -262.721426)
			(xy 142.317337 -262.672418) (xy 142.33267 -262.625228) (xy 142.355197 -262.581017) (xy 142.384362 -262.540874)
			(xy 142.419448 -262.505788) (xy 142.459591 -262.476623) (xy 142.503802 -262.454096) (xy 142.550992 -262.438763)
			(xy 142.6 -262.431001) (xy 142.64962 -262.431001) (xy 142.698628 -262.438763) (xy 142.745818 -262.454096)
			(xy 142.790029 -262.476623) (xy 142.830172 -262.505788) (xy 142.865258 -262.540874) (xy 142.894423 -262.581017)
			(xy 142.91695 -262.625228) (xy 142.932283 -262.672418) (xy 142.940045 -262.721426) (xy 142.940532 -262.746236)
			(xy 142.940025 -262.77104) (xy 142.932247 -262.820034) (xy 142.925038 -262.843772) (xy 142.927324 -262.854186)
			(xy 142.983712 -262.926322) (xy 142.985998 -262.929116) (xy 142.993598 -262.936656) (xy 143.013153 -262.945309)
			(xy 143.023844 -262.94588) (xy 143.16964 -262.94588) (xy 143.181266 -262.945315) (xy 143.202171 -262.935136)
			(xy 143.209772 -262.926322) (xy 143.26616 -262.853932) (xy 143.270986 -262.831072) (xy 143.268192 -262.819896)
			(xy 143.264006 -262.801771) (xy 143.259552 -262.764837) (xy 143.259302 -262.746236) (xy 143.259824 -262.720981)
			(xy 143.268137 -262.671159) (xy 143.284538 -262.623385) (xy 143.308579 -262.578962) (xy 143.339603 -262.539102)
			(xy 143.376765 -262.504892) (xy 143.419051 -262.477266) (xy 143.465307 -262.456976) (xy 143.514272 -262.444576)
			(xy 143.56461 -262.440405) (xy 143.614948 -262.444576) (xy 143.663913 -262.456976) (xy 143.710169 -262.477266)
			(xy 143.752455 -262.504892) (xy 143.789617 -262.539102) (xy 143.820641 -262.578962) (xy 143.844682 -262.623385)
			(xy 143.861083 -262.671159) (xy 143.869396 -262.720981) (xy 143.869918 -262.746236) (xy 143.86967 -262.764837)
			(xy 143.865208 -262.801769) (xy 143.861028 -262.819896) (xy 143.858234 -262.831072) (xy 143.86306 -262.853932)
			(xy 143.919448 -262.926322) (xy 143.927037 -262.935154) (xy 143.947947 -262.945345) (xy 143.95958 -262.94588)
			(xy 144.758918 -262.94588) (xy 144.768795 -262.94542) (xy 144.787091 -262.937974) (xy 144.794478 -262.931402)
			(xy 144.794732 -262.931148) (xy 145.605754 -262.120126) (xy 145.606262 -262.119618) (xy 145.612839 -262.112235)
			(xy 145.620278 -262.093936) (xy 145.62074 -262.084058) (xy 145.62074 -261.526274) (xy 145.620166 -261.515071)
			(xy 145.610693 -261.494766) (xy 145.602452 -261.487158) (xy 145.542508 -261.437374) (xy 145.533552 -261.430676)
			(xy 145.511943 -261.425014) (xy 145.500852 -261.426452) (xy 145.500598 -261.426452) (xy 145.486752 -261.428839)
			(xy 145.458768 -261.431379) (xy 145.444718 -261.431532) (xy 145.419457 -261.431041) (xy 145.369625 -261.422728)
			(xy 145.32184 -261.406326) (xy 145.277407 -261.382282) (xy 145.237537 -261.351253) (xy 145.203319 -261.314084)
			(xy 145.175686 -261.27179) (xy 145.155391 -261.225524) (xy 145.142988 -261.176549) (xy 145.138816 -261.1262)
			(xy 145.142988 -261.075851) (xy 145.155391 -261.026876) (xy 145.175686 -260.98061) (xy 145.203319 -260.938316)
			(xy 145.237537 -260.901147) (xy 145.277407 -260.870118) (xy 145.32184 -260.846074) (xy 145.369625 -260.829672)
			(xy 145.419457 -260.821359) (xy 145.444718 -260.820916) (xy 145.458769 -260.821047) (xy 145.486754 -260.823593)
			(xy 145.500598 -260.825996) (xy 145.500852 -260.825996) (xy 145.511943 -260.827443) (xy 145.533553 -260.821776)
			(xy 145.542508 -260.815074) (xy 145.602452 -260.76529) (xy 145.610698 -260.757682) (xy 145.620181 -260.73738)
			(xy 145.62074 -260.726174) (xy 145.62074 -223.758506) (xy 145.595594 -223.729804) (xy 145.57629 -223.727264)
			(xy 145.552023 -223.723717) (xy 145.504972 -223.709889) (xy 145.460738 -223.688715) (xy 145.420459 -223.660739)
			(xy 145.385174 -223.626681) (xy 145.35579 -223.587418) (xy 145.333063 -223.543962) (xy 145.317579 -223.497429)
			(xy 145.309736 -223.44902) (xy 145.309736 -223.399979) (xy 145.317579 -223.35157) (xy 145.333063 -223.305038)
			(xy 145.35579 -223.261581) (xy 145.385175 -223.222318) (xy 145.42046 -223.188261) (xy 145.460739 -223.160285)
			(xy 145.504973 -223.13911) (xy 145.552024 -223.125283) (xy 145.57629 -223.121728) (xy 145.595594 -223.119188)
			(xy 145.62074 -223.090486) (xy 145.62074 -222.177102) (xy 145.620316 -222.167033) (xy 145.612595 -222.148434)
			(xy 145.605754 -222.141034) (xy 145.277586 -221.812866) (xy 145.270474 -221.8055) (xy 145.251678 -221.79788)
			(xy 145.008854 -221.79788) (xy 144.980152 -221.823026) (xy 144.977866 -221.84233) (xy 144.974336 -221.866634)
			(xy 144.96053 -221.913763) (xy 144.939359 -221.958074) (xy 144.91137 -221.998427) (xy 144.877283 -222.03378)
			(xy 144.837978 -222.063222) (xy 144.794468 -222.085994) (xy 144.747875 -222.10151) (xy 144.699399 -222.10937)
			(xy 144.650289 -222.10937) (xy 144.601813 -222.10151) (xy 144.55522 -222.085994) (xy 144.51171 -222.063222)
			(xy 144.472405 -222.03378) (xy 144.438318 -221.998427) (xy 144.410329 -221.958074) (xy 144.389158 -221.913763)
			(xy 144.375352 -221.866634) (xy 144.371822 -221.84233) (xy 144.369536 -221.823026) (xy 144.340834 -221.79788)
			(xy 143.128746 -221.79788) (xy 143.100044 -221.823026) (xy 143.097758 -221.84233) (xy 143.094228 -221.866634)
			(xy 143.080422 -221.913763) (xy 143.059251 -221.958074) (xy 143.031262 -221.998427) (xy 142.997175 -222.03378)
			(xy 142.95787 -222.063222) (xy 142.91436 -222.085994) (xy 142.867767 -222.10151) (xy 142.819291 -222.10937)
			(xy 142.770181 -222.10937) (xy 142.721705 -222.10151) (xy 142.675112 -222.085994) (xy 142.631602 -222.063222)
			(xy 142.592297 -222.03378) (xy 142.55821 -221.998427) (xy 142.530221 -221.958074) (xy 142.50905 -221.913763)
			(xy 142.495244 -221.866634) (xy 142.491714 -221.84233) (xy 142.489428 -221.823026) (xy 142.460726 -221.79788)
			(xy 138.66876 -221.79788) (xy 138.66114 -221.80042) (xy 138.649784 -221.803943) (xy 138.626644 -221.809411)
			(xy 138.614912 -221.811342) (xy 138.603238 -221.813025) (xy 138.579716 -221.814803) (xy 138.567922 -221.814898)
			(xy 138.544294 -221.814454) (xy 138.497602 -221.807179) (xy 138.474958 -221.80042) (xy 138.467084 -221.79788)
			(xy 135.608822 -221.79788) (xy 135.58012 -221.823026) (xy 135.577834 -221.84233) (xy 135.574304 -221.866634)
			(xy 135.560498 -221.913763) (xy 135.539327 -221.958074) (xy 135.511338 -221.998427) (xy 135.477251 -222.03378)
			(xy 135.437946 -222.063222) (xy 135.394436 -222.085994) (xy 135.347843 -222.10151) (xy 135.299367 -222.10937)
			(xy 135.250257 -222.10937) (xy 135.201781 -222.10151) (xy 135.155188 -222.085994) (xy 135.111678 -222.063222)
			(xy 135.072373 -222.03378) (xy 135.038286 -221.998427) (xy 135.010297 -221.958074) (xy 134.989126 -221.913763)
			(xy 134.97532 -221.866634) (xy 134.97179 -221.84233) (xy 134.969504 -221.823026) (xy 134.940802 -221.79788)
			(xy 133.728714 -221.79788) (xy 133.700012 -221.823026) (xy 133.697726 -221.84233) (xy 133.694196 -221.866634)
			(xy 133.68039 -221.913763) (xy 133.659219 -221.958074) (xy 133.63123 -221.998427) (xy 133.597143 -222.03378)
			(xy 133.557838 -222.063222) (xy 133.514328 -222.085994) (xy 133.467735 -222.10151) (xy 133.419259 -222.10937)
			(xy 133.370149 -222.10937) (xy 133.321673 -222.10151) (xy 133.27508 -222.085994) (xy 133.23157 -222.063222)
			(xy 133.192265 -222.03378) (xy 133.158178 -221.998427) (xy 133.130189 -221.958074) (xy 133.109018 -221.913763)
			(xy 133.095212 -221.866634) (xy 133.091682 -221.84233) (xy 133.089396 -221.823026) (xy 133.060694 -221.79788)
			(xy 132.807964 -221.79788) (xy 132.798753 -221.79833) (xy 132.781549 -221.804936) (xy 132.767776 -221.817179)
			(xy 132.759199 -221.833489) (xy 132.757672 -221.842584) (xy 132.757418 -221.8436) (xy 132.753801 -221.867812)
			(xy 132.739863 -221.914736) (xy 132.718615 -221.958836) (xy 132.690602 -221.998979) (xy 132.656543 -222.034138)
			(xy 132.61731 -222.063412) (xy 132.573908 -222.08605) (xy 132.527449 -222.101472) (xy 132.479126 -222.109284)
			(xy 132.430174 -222.109284) (xy 132.381851 -222.101472) (xy 132.335392 -222.08605) (xy 132.29199 -222.063412)
			(xy 132.252757 -222.034138) (xy 132.218698 -221.998979) (xy 132.190685 -221.958836) (xy 132.169437 -221.914736)
			(xy 132.155499 -221.867812) (xy 132.151882 -221.8436) (xy 132.151628 -221.842584) (xy 132.150136 -221.833474)
			(xy 132.14159 -221.817128) (xy 132.127799 -221.804878) (xy 132.110559 -221.79832) (xy 132.101336 -221.79788)
			(xy 131.868164 -221.79788) (xy 131.858953 -221.79833) (xy 131.841749 -221.804936) (xy 131.827976 -221.817179)
			(xy 131.819399 -221.833489) (xy 131.817872 -221.842584) (xy 131.817618 -221.8436) (xy 131.814001 -221.867812)
			(xy 131.800063 -221.914736) (xy 131.778815 -221.958836) (xy 131.750802 -221.998979) (xy 131.716743 -222.034138)
			(xy 131.67751 -222.063412) (xy 131.634108 -222.08605) (xy 131.587649 -222.101472) (xy 131.539326 -222.109284)
			(xy 131.490374 -222.109284) (xy 131.442051 -222.101472) (xy 131.395592 -222.08605) (xy 131.35219 -222.063412)
			(xy 131.312957 -222.034138) (xy 131.278898 -221.998979) (xy 131.250885 -221.958836) (xy 131.229637 -221.914736)
			(xy 131.215699 -221.867812) (xy 131.212082 -221.8436) (xy 131.211828 -221.842584) (xy 131.210336 -221.833474)
			(xy 131.20179 -221.817128) (xy 131.187999 -221.804878) (xy 131.170759 -221.79832) (xy 131.161536 -221.79788)
			(xy 128.453642 -221.79788) (xy 128.443576 -221.798313) (xy 128.424985 -221.80604) (xy 128.417574 -221.812866)
			(xy 127.685546 -222.544894) (xy 127.677926 -222.564198) (xy 127.67818 -222.574866) (xy 127.678688 -222.614236)
			(xy 127.678688 -222.61449) (xy 128.859038 -222.61449) (xy 128.862998 -222.565436) (xy 128.874775 -222.517652)
			(xy 128.894066 -222.472376) (xy 128.920369 -222.43078) (xy 128.953004 -222.393943) (xy 128.991125 -222.362818)
			(xy 129.033746 -222.338211) (xy 129.079762 -222.320759) (xy 129.127981 -222.310915) (xy 129.177156 -222.308934)
			(xy 129.226011 -222.314866) (xy 129.273282 -222.328558) (xy 129.317744 -222.349656) (xy 129.358247 -222.377612)
			(xy 129.39374 -222.411704) (xy 129.423305 -222.451048) (xy 129.446176 -222.494625) (xy 129.46176 -222.541306)
			(xy 129.469655 -222.589883) (xy 129.47015 -222.61449) (xy 129.798838 -222.61449) (xy 129.802798 -222.565436)
			(xy 129.814575 -222.517652) (xy 129.833866 -222.472376) (xy 129.860169 -222.43078) (xy 129.892804 -222.393943)
			(xy 129.930925 -222.362818) (xy 129.973546 -222.338211) (xy 130.019562 -222.320759) (xy 130.067781 -222.310915)
			(xy 130.116956 -222.308934) (xy 130.165811 -222.314866) (xy 130.213082 -222.328558) (xy 130.257544 -222.349656)
			(xy 130.298047 -222.377612) (xy 130.33354 -222.411704) (xy 130.363105 -222.451048) (xy 130.385976 -222.494625)
			(xy 130.40156 -222.541306) (xy 130.409455 -222.589883) (xy 130.40995 -222.61449) (xy 130.738892 -222.61449)
			(xy 130.742852 -222.565436) (xy 130.754629 -222.517652) (xy 130.77392 -222.472376) (xy 130.800223 -222.43078)
			(xy 130.832858 -222.393943) (xy 130.870979 -222.362818) (xy 130.9136 -222.338211) (xy 130.959616 -222.320759)
			(xy 131.007835 -222.310915) (xy 131.05701 -222.308934) (xy 131.105865 -222.314866) (xy 131.153136 -222.328558)
			(xy 131.197598 -222.349656) (xy 131.238101 -222.377612) (xy 131.273594 -222.411704) (xy 131.303159 -222.451048)
			(xy 131.32603 -222.494625) (xy 131.341614 -222.541306) (xy 131.349509 -222.589883) (xy 131.350004 -222.61449)
			(xy 131.678946 -222.61449) (xy 131.682906 -222.565436) (xy 131.694683 -222.517652) (xy 131.713974 -222.472376)
			(xy 131.740277 -222.43078) (xy 131.772912 -222.393943) (xy 131.811033 -222.362818) (xy 131.853654 -222.338211)
			(xy 131.89967 -222.320759) (xy 131.947889 -222.310915) (xy 131.997064 -222.308934) (xy 132.045919 -222.314866)
			(xy 132.09319 -222.328558) (xy 132.137652 -222.349656) (xy 132.178155 -222.377612) (xy 132.213648 -222.411704)
			(xy 132.243213 -222.451048) (xy 132.266084 -222.494625) (xy 132.281668 -222.541306) (xy 132.289563 -222.589883)
			(xy 132.290058 -222.61449) (xy 133.559054 -222.61449) (xy 133.563014 -222.565436) (xy 133.574791 -222.517652)
			(xy 133.594082 -222.472376) (xy 133.620385 -222.43078) (xy 133.65302 -222.393943) (xy 133.691141 -222.362818)
			(xy 133.733762 -222.338211) (xy 133.779778 -222.320759) (xy 133.827997 -222.310915) (xy 133.877172 -222.308934)
			(xy 133.926027 -222.314866) (xy 133.973298 -222.328558) (xy 134.01776 -222.349656) (xy 134.058263 -222.377612)
			(xy 134.093756 -222.411704) (xy 134.123321 -222.451048) (xy 134.146192 -222.494625) (xy 134.161776 -222.541306)
			(xy 134.169671 -222.589883) (xy 134.170166 -222.61449) (xy 134.498854 -222.61449) (xy 134.502814 -222.565436)
			(xy 134.514591 -222.517652) (xy 134.533882 -222.472376) (xy 134.560185 -222.43078) (xy 134.59282 -222.393943)
			(xy 134.630941 -222.362818) (xy 134.673562 -222.338211) (xy 134.719578 -222.320759) (xy 134.767797 -222.310915)
			(xy 134.816972 -222.308934) (xy 134.865827 -222.314866) (xy 134.913098 -222.328558) (xy 134.95756 -222.349656)
			(xy 134.998063 -222.377612) (xy 135.033556 -222.411704) (xy 135.063121 -222.451048) (xy 135.085992 -222.494625)
			(xy 135.101576 -222.541306) (xy 135.109471 -222.589883) (xy 135.109966 -222.61449) (xy 135.438908 -222.61449)
			(xy 135.442868 -222.565436) (xy 135.454645 -222.517652) (xy 135.473936 -222.472376) (xy 135.500239 -222.43078)
			(xy 135.532874 -222.393943) (xy 135.570995 -222.362818) (xy 135.613616 -222.338211) (xy 135.659632 -222.320759)
			(xy 135.707851 -222.310915) (xy 135.757026 -222.308934) (xy 135.805881 -222.314866) (xy 135.853152 -222.328558)
			(xy 135.897614 -222.349656) (xy 135.938117 -222.377612) (xy 135.97361 -222.411704) (xy 136.003175 -222.451048)
			(xy 136.026046 -222.494625) (xy 136.04163 -222.541306) (xy 136.049525 -222.589883) (xy 136.05002 -222.61449)
			(xy 137.319016 -222.61449) (xy 137.322976 -222.565436) (xy 137.334753 -222.517652) (xy 137.354044 -222.472376)
			(xy 137.380347 -222.43078) (xy 137.412982 -222.393943) (xy 137.451103 -222.362818) (xy 137.493724 -222.338211)
			(xy 137.53974 -222.320759) (xy 137.587959 -222.310915) (xy 137.637134 -222.308934) (xy 137.685989 -222.314866)
			(xy 137.73326 -222.328558) (xy 137.777722 -222.349656) (xy 137.818225 -222.377612) (xy 137.853718 -222.411704)
			(xy 137.883283 -222.451048) (xy 137.906154 -222.494625) (xy 137.921738 -222.541306) (xy 137.929633 -222.589883)
			(xy 137.930128 -222.61449) (xy 138.25907 -222.61449) (xy 138.26303 -222.565436) (xy 138.274807 -222.517652)
			(xy 138.294098 -222.472376) (xy 138.320401 -222.43078) (xy 138.353036 -222.393943) (xy 138.391157 -222.362818)
			(xy 138.433778 -222.338211) (xy 138.479794 -222.320759) (xy 138.528013 -222.310915) (xy 138.577188 -222.308934)
			(xy 138.626043 -222.314866) (xy 138.673314 -222.328558) (xy 138.717776 -222.349656) (xy 138.758279 -222.377612)
			(xy 138.793772 -222.411704) (xy 138.823337 -222.451048) (xy 138.846208 -222.494625) (xy 138.861792 -222.541306)
			(xy 138.869687 -222.589883) (xy 138.870182 -222.61449) (xy 140.138924 -222.61449) (xy 140.142884 -222.565436)
			(xy 140.154661 -222.517652) (xy 140.173952 -222.472376) (xy 140.200255 -222.43078) (xy 140.23289 -222.393943)
			(xy 140.271011 -222.362818) (xy 140.313632 -222.338211) (xy 140.359648 -222.320759) (xy 140.407867 -222.310915)
			(xy 140.457042 -222.308934) (xy 140.505897 -222.314866) (xy 140.553168 -222.328558) (xy 140.59763 -222.349656)
			(xy 140.638133 -222.377612) (xy 140.673626 -222.411704) (xy 140.703191 -222.451048) (xy 140.726062 -222.494625)
			(xy 140.741646 -222.541306) (xy 140.749541 -222.589883) (xy 140.750036 -222.61449) (xy 141.078978 -222.61449)
			(xy 141.082938 -222.565436) (xy 141.094715 -222.517652) (xy 141.114006 -222.472376) (xy 141.140309 -222.43078)
			(xy 141.172944 -222.393943) (xy 141.211065 -222.362818) (xy 141.253686 -222.338211) (xy 141.299702 -222.320759)
			(xy 141.347921 -222.310915) (xy 141.397096 -222.308934) (xy 141.445951 -222.314866) (xy 141.493222 -222.328558)
			(xy 141.537684 -222.349656) (xy 141.578187 -222.377612) (xy 141.61368 -222.411704) (xy 141.643245 -222.451048)
			(xy 141.666116 -222.494625) (xy 141.6817 -222.541306) (xy 141.689595 -222.589883) (xy 141.69009 -222.61449)
			(xy 144.83894 -222.61449) (xy 144.8429 -222.565436) (xy 144.854677 -222.517652) (xy 144.873968 -222.472376)
			(xy 144.900271 -222.43078) (xy 144.932906 -222.393943) (xy 144.971027 -222.362818) (xy 145.013648 -222.338211)
			(xy 145.059664 -222.320759) (xy 145.107883 -222.310915) (xy 145.157058 -222.308934) (xy 145.205913 -222.314866)
			(xy 145.253184 -222.328558) (xy 145.297646 -222.349656) (xy 145.338149 -222.377612) (xy 145.373642 -222.411704)
			(xy 145.403207 -222.451048) (xy 145.426078 -222.494625) (xy 145.441662 -222.541306) (xy 145.449557 -222.589883)
			(xy 145.450052 -222.61449) (xy 145.449557 -222.639097) (xy 145.441662 -222.687674) (xy 145.426078 -222.734355)
			(xy 145.403207 -222.777932) (xy 145.373642 -222.817276) (xy 145.338149 -222.851368) (xy 145.297646 -222.879324)
			(xy 145.253184 -222.900422) (xy 145.205913 -222.914114) (xy 145.157058 -222.920046) (xy 145.107883 -222.918065)
			(xy 145.059664 -222.908221) (xy 145.013648 -222.890769) (xy 144.971027 -222.866162) (xy 144.932906 -222.835037)
			(xy 144.900271 -222.7982) (xy 144.873968 -222.756604) (xy 144.854677 -222.711328) (xy 144.8429 -222.663544)
			(xy 144.83894 -222.61449) (xy 141.69009 -222.61449) (xy 141.689595 -222.639097) (xy 141.6817 -222.687674)
			(xy 141.666116 -222.734355) (xy 141.643245 -222.777932) (xy 141.61368 -222.817276) (xy 141.578187 -222.851368)
			(xy 141.537684 -222.879324) (xy 141.493222 -222.900422) (xy 141.445951 -222.914114) (xy 141.397096 -222.920046)
			(xy 141.347921 -222.918065) (xy 141.299702 -222.908221) (xy 141.253686 -222.890769) (xy 141.211065 -222.866162)
			(xy 141.172944 -222.835037) (xy 141.140309 -222.7982) (xy 141.114006 -222.756604) (xy 141.094715 -222.711328)
			(xy 141.082938 -222.663544) (xy 141.078978 -222.61449) (xy 140.750036 -222.61449) (xy 140.749541 -222.639097)
			(xy 140.741646 -222.687674) (xy 140.726062 -222.734355) (xy 140.703191 -222.777932) (xy 140.673626 -222.817276)
			(xy 140.638133 -222.851368) (xy 140.59763 -222.879324) (xy 140.553168 -222.900422) (xy 140.505897 -222.914114)
			(xy 140.457042 -222.920046) (xy 140.407867 -222.918065) (xy 140.359648 -222.908221) (xy 140.313632 -222.890769)
			(xy 140.271011 -222.866162) (xy 140.23289 -222.835037) (xy 140.200255 -222.7982) (xy 140.173952 -222.756604)
			(xy 140.154661 -222.711328) (xy 140.142884 -222.663544) (xy 140.138924 -222.61449) (xy 138.870182 -222.61449)
			(xy 138.869687 -222.639097) (xy 138.861792 -222.687674) (xy 138.846208 -222.734355) (xy 138.823337 -222.777932)
			(xy 138.793772 -222.817276) (xy 138.758279 -222.851368) (xy 138.717776 -222.879324) (xy 138.673314 -222.900422)
			(xy 138.626043 -222.914114) (xy 138.577188 -222.920046) (xy 138.528013 -222.918065) (xy 138.479794 -222.908221)
			(xy 138.433778 -222.890769) (xy 138.391157 -222.866162) (xy 138.353036 -222.835037) (xy 138.320401 -222.7982)
			(xy 138.294098 -222.756604) (xy 138.274807 -222.711328) (xy 138.26303 -222.663544) (xy 138.25907 -222.61449)
			(xy 137.930128 -222.61449) (xy 137.929633 -222.639097) (xy 137.921738 -222.687674) (xy 137.906154 -222.734355)
			(xy 137.883283 -222.777932) (xy 137.853718 -222.817276) (xy 137.818225 -222.851368) (xy 137.777722 -222.879324)
			(xy 137.73326 -222.900422) (xy 137.685989 -222.914114) (xy 137.637134 -222.920046) (xy 137.587959 -222.918065)
			(xy 137.53974 -222.908221) (xy 137.493724 -222.890769) (xy 137.451103 -222.866162) (xy 137.412982 -222.835037)
			(xy 137.380347 -222.7982) (xy 137.354044 -222.756604) (xy 137.334753 -222.711328) (xy 137.322976 -222.663544)
			(xy 137.319016 -222.61449) (xy 136.05002 -222.61449) (xy 136.049525 -222.639097) (xy 136.04163 -222.687674)
			(xy 136.026046 -222.734355) (xy 136.003175 -222.777932) (xy 135.97361 -222.817276) (xy 135.938117 -222.851368)
			(xy 135.897614 -222.879324) (xy 135.853152 -222.900422) (xy 135.805881 -222.914114) (xy 135.757026 -222.920046)
			(xy 135.707851 -222.918065) (xy 135.659632 -222.908221) (xy 135.613616 -222.890769) (xy 135.570995 -222.866162)
			(xy 135.532874 -222.835037) (xy 135.500239 -222.7982) (xy 135.473936 -222.756604) (xy 135.454645 -222.711328)
			(xy 135.442868 -222.663544) (xy 135.438908 -222.61449) (xy 135.109966 -222.61449) (xy 135.109471 -222.639097)
			(xy 135.101576 -222.687674) (xy 135.085992 -222.734355) (xy 135.063121 -222.777932) (xy 135.033556 -222.817276)
			(xy 134.998063 -222.851368) (xy 134.95756 -222.879324) (xy 134.913098 -222.900422) (xy 134.865827 -222.914114)
			(xy 134.816972 -222.920046) (xy 134.767797 -222.918065) (xy 134.719578 -222.908221) (xy 134.673562 -222.890769)
			(xy 134.630941 -222.866162) (xy 134.59282 -222.835037) (xy 134.560185 -222.7982) (xy 134.533882 -222.756604)
			(xy 134.514591 -222.711328) (xy 134.502814 -222.663544) (xy 134.498854 -222.61449) (xy 134.170166 -222.61449)
			(xy 134.169671 -222.639097) (xy 134.161776 -222.687674) (xy 134.146192 -222.734355) (xy 134.123321 -222.777932)
			(xy 134.093756 -222.817276) (xy 134.058263 -222.851368) (xy 134.01776 -222.879324) (xy 133.973298 -222.900422)
			(xy 133.926027 -222.914114) (xy 133.877172 -222.920046) (xy 133.827997 -222.918065) (xy 133.779778 -222.908221)
			(xy 133.733762 -222.890769) (xy 133.691141 -222.866162) (xy 133.65302 -222.835037) (xy 133.620385 -222.7982)
			(xy 133.594082 -222.756604) (xy 133.574791 -222.711328) (xy 133.563014 -222.663544) (xy 133.559054 -222.61449)
			(xy 132.290058 -222.61449) (xy 132.289563 -222.639097) (xy 132.281668 -222.687674) (xy 132.266084 -222.734355)
			(xy 132.243213 -222.777932) (xy 132.213648 -222.817276) (xy 132.178155 -222.851368) (xy 132.137652 -222.879324)
			(xy 132.09319 -222.900422) (xy 132.045919 -222.914114) (xy 131.997064 -222.920046) (xy 131.947889 -222.918065)
			(xy 131.89967 -222.908221) (xy 131.853654 -222.890769) (xy 131.811033 -222.866162) (xy 131.772912 -222.835037)
			(xy 131.740277 -222.7982) (xy 131.713974 -222.756604) (xy 131.694683 -222.711328) (xy 131.682906 -222.663544)
			(xy 131.678946 -222.61449) (xy 131.350004 -222.61449) (xy 131.349509 -222.639097) (xy 131.341614 -222.687674)
			(xy 131.32603 -222.734355) (xy 131.303159 -222.777932) (xy 131.273594 -222.817276) (xy 131.238101 -222.851368)
			(xy 131.197598 -222.879324) (xy 131.153136 -222.900422) (xy 131.105865 -222.914114) (xy 131.05701 -222.920046)
			(xy 131.007835 -222.918065) (xy 130.959616 -222.908221) (xy 130.9136 -222.890769) (xy 130.870979 -222.866162)
			(xy 130.832858 -222.835037) (xy 130.800223 -222.7982) (xy 130.77392 -222.756604) (xy 130.754629 -222.711328)
			(xy 130.742852 -222.663544) (xy 130.738892 -222.61449) (xy 130.40995 -222.61449) (xy 130.409455 -222.639097)
			(xy 130.40156 -222.687674) (xy 130.385976 -222.734355) (xy 130.363105 -222.777932) (xy 130.33354 -222.817276)
			(xy 130.298047 -222.851368) (xy 130.257544 -222.879324) (xy 130.213082 -222.900422) (xy 130.165811 -222.914114)
			(xy 130.116956 -222.920046) (xy 130.067781 -222.918065) (xy 130.019562 -222.908221) (xy 129.973546 -222.890769)
			(xy 129.930925 -222.866162) (xy 129.892804 -222.835037) (xy 129.860169 -222.7982) (xy 129.833866 -222.756604)
			(xy 129.814575 -222.711328) (xy 129.802798 -222.663544) (xy 129.798838 -222.61449) (xy 129.47015 -222.61449)
			(xy 129.469655 -222.639097) (xy 129.46176 -222.687674) (xy 129.446176 -222.734355) (xy 129.423305 -222.777932)
			(xy 129.39374 -222.817276) (xy 129.358247 -222.851368) (xy 129.317744 -222.879324) (xy 129.273282 -222.900422)
			(xy 129.226011 -222.914114) (xy 129.177156 -222.920046) (xy 129.127981 -222.918065) (xy 129.079762 -222.908221)
			(xy 129.033746 -222.890769) (xy 128.991125 -222.866162) (xy 128.953004 -222.835037) (xy 128.920369 -222.7982)
			(xy 128.894066 -222.756604) (xy 128.874775 -222.711328) (xy 128.862998 -222.663544) (xy 128.859038 -222.61449)
			(xy 127.678688 -222.61449) (xy 127.678688 -222.614744) (xy 127.678235 -222.664309) (xy 127.670874 -222.763165)
			(xy 127.65619 -222.861201) (xy 127.645668 -222.909638) (xy 127.637666 -222.944102) (xy 127.61848 -223.01221)
			(xy 127.607314 -223.045782) (xy 127.60452 -223.053656) (xy 127.60452 -223.082612) (xy 127.604942 -223.09263)
			(xy 127.612615 -223.111139) (xy 127.626787 -223.125303) (xy 127.645302 -223.132964) (xy 127.65532 -223.133412)
			(xy 127.662432 -223.133412) (xy 127.669544 -223.13138) (xy 127.690359 -223.125707) (xy 127.733064 -223.119587)
			(xy 127.754634 -223.119188) (xy 127.779888 -223.119712) (xy 127.829706 -223.128031) (xy 127.877476 -223.144435)
			(xy 127.921894 -223.168477) (xy 127.96175 -223.199502) (xy 127.995956 -223.236664) (xy 128.023579 -223.278948)
			(xy 128.043866 -223.325202) (xy 128.056264 -223.374165) (xy 128.060435 -223.424496) (xy 128.388884 -223.424496)
			(xy 128.392844 -223.375442) (xy 128.404621 -223.327658) (xy 128.423912 -223.282382) (xy 128.450215 -223.240786)
			(xy 128.48285 -223.203949) (xy 128.520971 -223.172824) (xy 128.563592 -223.148217) (xy 128.609608 -223.130765)
			(xy 128.657827 -223.120921) (xy 128.707002 -223.11894) (xy 128.755857 -223.124872) (xy 128.803128 -223.138564)
			(xy 128.84759 -223.159662) (xy 128.888093 -223.187618) (xy 128.923586 -223.22171) (xy 128.953151 -223.261054)
			(xy 128.976022 -223.304631) (xy 128.991606 -223.351312) (xy 128.999501 -223.399889) (xy 128.999996 -223.424496)
			(xy 129.328938 -223.424496) (xy 129.332898 -223.375442) (xy 129.344675 -223.327658) (xy 129.363966 -223.282382)
			(xy 129.390269 -223.240786) (xy 129.422904 -223.203949) (xy 129.461025 -223.172824) (xy 129.503646 -223.148217)
			(xy 129.549662 -223.130765) (xy 129.597881 -223.120921) (xy 129.647056 -223.11894) (xy 129.695911 -223.124872)
			(xy 129.743182 -223.138564) (xy 129.787644 -223.159662) (xy 129.828147 -223.187618) (xy 129.86364 -223.22171)
			(xy 129.893205 -223.261054) (xy 129.916076 -223.304631) (xy 129.93166 -223.351312) (xy 129.939555 -223.399889)
			(xy 129.94005 -223.424496) (xy 130.268992 -223.424496) (xy 130.272952 -223.375442) (xy 130.284729 -223.327658)
			(xy 130.30402 -223.282382) (xy 130.330323 -223.240786) (xy 130.362958 -223.203949) (xy 130.401079 -223.172824)
			(xy 130.4437 -223.148217) (xy 130.489716 -223.130765) (xy 130.537935 -223.120921) (xy 130.58711 -223.11894)
			(xy 130.635965 -223.124872) (xy 130.683236 -223.138564) (xy 130.727698 -223.159662) (xy 130.768201 -223.187618)
			(xy 130.803694 -223.22171) (xy 130.833259 -223.261054) (xy 130.85613 -223.304631) (xy 130.871714 -223.351312)
			(xy 130.879609 -223.399889) (xy 130.880104 -223.424496) (xy 131.209046 -223.424496) (xy 131.213006 -223.375442)
			(xy 131.224783 -223.327658) (xy 131.244074 -223.282382) (xy 131.270377 -223.240786) (xy 131.303012 -223.203949)
			(xy 131.341133 -223.172824) (xy 131.383754 -223.148217) (xy 131.42977 -223.130765) (xy 131.477989 -223.120921)
			(xy 131.527164 -223.11894) (xy 131.576019 -223.124872) (xy 131.62329 -223.138564) (xy 131.667752 -223.159662)
			(xy 131.708255 -223.187618) (xy 131.743748 -223.22171) (xy 131.773313 -223.261054) (xy 131.796184 -223.304631)
			(xy 131.811768 -223.351312) (xy 131.819663 -223.399889) (xy 131.820158 -223.424496) (xy 132.148846 -223.424496)
			(xy 132.152806 -223.375442) (xy 132.164583 -223.327658) (xy 132.183874 -223.282382) (xy 132.210177 -223.240786)
			(xy 132.242812 -223.203949) (xy 132.280933 -223.172824) (xy 132.323554 -223.148217) (xy 132.36957 -223.130765)
			(xy 132.417789 -223.120921) (xy 132.466964 -223.11894) (xy 132.515819 -223.124872) (xy 132.56309 -223.138564)
			(xy 132.607552 -223.159662) (xy 132.648055 -223.187618) (xy 132.683548 -223.22171) (xy 132.713113 -223.261054)
			(xy 132.735984 -223.304631) (xy 132.751568 -223.351312) (xy 132.759463 -223.399889) (xy 132.759958 -223.424496)
			(xy 133.0889 -223.424496) (xy 133.09286 -223.375442) (xy 133.104637 -223.327658) (xy 133.123928 -223.282382)
			(xy 133.150231 -223.240786) (xy 133.182866 -223.203949) (xy 133.220987 -223.172824) (xy 133.263608 -223.148217)
			(xy 133.309624 -223.130765) (xy 133.357843 -223.120921) (xy 133.407018 -223.11894) (xy 133.455873 -223.124872)
			(xy 133.503144 -223.138564) (xy 133.547606 -223.159662) (xy 133.588109 -223.187618) (xy 133.623602 -223.22171)
			(xy 133.653167 -223.261054) (xy 133.676038 -223.304631) (xy 133.691622 -223.351312) (xy 133.699517 -223.399889)
			(xy 133.700012 -223.424496) (xy 134.028954 -223.424496) (xy 134.032914 -223.375442) (xy 134.044691 -223.327658)
			(xy 134.063982 -223.282382) (xy 134.090285 -223.240786) (xy 134.12292 -223.203949) (xy 134.161041 -223.172824)
			(xy 134.203662 -223.148217) (xy 134.249678 -223.130765) (xy 134.297897 -223.120921) (xy 134.347072 -223.11894)
			(xy 134.395927 -223.124872) (xy 134.443198 -223.138564) (xy 134.48766 -223.159662) (xy 134.528163 -223.187618)
			(xy 134.563656 -223.22171) (xy 134.593221 -223.261054) (xy 134.616092 -223.304631) (xy 134.631676 -223.351312)
			(xy 134.639571 -223.399889) (xy 134.640066 -223.424496) (xy 134.969008 -223.424496) (xy 134.972968 -223.375442)
			(xy 134.984745 -223.327658) (xy 135.004036 -223.282382) (xy 135.030339 -223.240786) (xy 135.062974 -223.203949)
			(xy 135.101095 -223.172824) (xy 135.143716 -223.148217) (xy 135.189732 -223.130765) (xy 135.237951 -223.120921)
			(xy 135.287126 -223.11894) (xy 135.335981 -223.124872) (xy 135.383252 -223.138564) (xy 135.427714 -223.159662)
			(xy 135.468217 -223.187618) (xy 135.50371 -223.22171) (xy 135.533275 -223.261054) (xy 135.556146 -223.304631)
			(xy 135.57173 -223.351312) (xy 135.579625 -223.399889) (xy 135.58012 -223.424496) (xy 136.848862 -223.424496)
			(xy 136.852822 -223.375442) (xy 136.864599 -223.327658) (xy 136.88389 -223.282382) (xy 136.910193 -223.240786)
			(xy 136.942828 -223.203949) (xy 136.980949 -223.172824) (xy 137.02357 -223.148217) (xy 137.069586 -223.130765)
			(xy 137.117805 -223.120921) (xy 137.16698 -223.11894) (xy 137.215835 -223.124872) (xy 137.263106 -223.138564)
			(xy 137.307568 -223.159662) (xy 137.348071 -223.187618) (xy 137.383564 -223.22171) (xy 137.413129 -223.261054)
			(xy 137.436 -223.304631) (xy 137.451584 -223.351312) (xy 137.459479 -223.399889) (xy 137.459974 -223.424496)
			(xy 137.788916 -223.424496) (xy 137.792876 -223.375442) (xy 137.804653 -223.327658) (xy 137.823944 -223.282382)
			(xy 137.850247 -223.240786) (xy 137.882882 -223.203949) (xy 137.921003 -223.172824) (xy 137.963624 -223.148217)
			(xy 138.00964 -223.130765) (xy 138.057859 -223.120921) (xy 138.107034 -223.11894) (xy 138.155889 -223.124872)
			(xy 138.20316 -223.138564) (xy 138.247622 -223.159662) (xy 138.288125 -223.187618) (xy 138.323618 -223.22171)
			(xy 138.353183 -223.261054) (xy 138.376054 -223.304631) (xy 138.391638 -223.351312) (xy 138.399533 -223.399889)
			(xy 138.400028 -223.424496) (xy 139.669024 -223.424496) (xy 139.672984 -223.375442) (xy 139.684761 -223.327658)
			(xy 139.704052 -223.282382) (xy 139.730355 -223.240786) (xy 139.76299 -223.203949) (xy 139.801111 -223.172824)
			(xy 139.843732 -223.148217) (xy 139.889748 -223.130765) (xy 139.937967 -223.120921) (xy 139.987142 -223.11894)
			(xy 140.035997 -223.124872) (xy 140.083268 -223.138564) (xy 140.12773 -223.159662) (xy 140.168233 -223.187618)
			(xy 140.203726 -223.22171) (xy 140.233291 -223.261054) (xy 140.256162 -223.304631) (xy 140.271746 -223.351312)
			(xy 140.279641 -223.399889) (xy 140.280136 -223.424496) (xy 140.609078 -223.424496) (xy 140.613038 -223.375442)
			(xy 140.624815 -223.327658) (xy 140.644106 -223.282382) (xy 140.670409 -223.240786) (xy 140.703044 -223.203949)
			(xy 140.741165 -223.172824) (xy 140.783786 -223.148217) (xy 140.829802 -223.130765) (xy 140.878021 -223.120921)
			(xy 140.927196 -223.11894) (xy 140.976051 -223.124872) (xy 141.023322 -223.138564) (xy 141.067784 -223.159662)
			(xy 141.108287 -223.187618) (xy 141.14378 -223.22171) (xy 141.173345 -223.261054) (xy 141.196216 -223.304631)
			(xy 141.2118 -223.351312) (xy 141.219695 -223.399889) (xy 141.22019 -223.424496) (xy 142.488932 -223.424496)
			(xy 142.492892 -223.375442) (xy 142.504669 -223.327658) (xy 142.52396 -223.282382) (xy 142.550263 -223.240786)
			(xy 142.582898 -223.203949) (xy 142.621019 -223.172824) (xy 142.66364 -223.148217) (xy 142.709656 -223.130765)
			(xy 142.757875 -223.120921) (xy 142.80705 -223.11894) (xy 142.855905 -223.124872) (xy 142.903176 -223.138564)
			(xy 142.947638 -223.159662) (xy 142.988141 -223.187618) (xy 143.023634 -223.22171) (xy 143.053199 -223.261054)
			(xy 143.07607 -223.304631) (xy 143.091654 -223.351312) (xy 143.099549 -223.399889) (xy 143.100044 -223.424496)
			(xy 144.36904 -223.424496) (xy 144.373 -223.375442) (xy 144.384777 -223.327658) (xy 144.404068 -223.282382)
			(xy 144.430371 -223.240786) (xy 144.463006 -223.203949) (xy 144.501127 -223.172824) (xy 144.543748 -223.148217)
			(xy 144.589764 -223.130765) (xy 144.637983 -223.120921) (xy 144.687158 -223.11894) (xy 144.736013 -223.124872)
			(xy 144.783284 -223.138564) (xy 144.827746 -223.159662) (xy 144.868249 -223.187618) (xy 144.903742 -223.22171)
			(xy 144.933307 -223.261054) (xy 144.956178 -223.304631) (xy 144.971762 -223.351312) (xy 144.979657 -223.399889)
			(xy 144.980152 -223.424496) (xy 144.979657 -223.449103) (xy 144.971762 -223.49768) (xy 144.956178 -223.544361)
			(xy 144.933307 -223.587938) (xy 144.903742 -223.627282) (xy 144.868249 -223.661374) (xy 144.827746 -223.68933)
			(xy 144.783284 -223.710428) (xy 144.736013 -223.72412) (xy 144.687158 -223.730052) (xy 144.637983 -223.728071)
			(xy 144.589764 -223.718227) (xy 144.543748 -223.700775) (xy 144.501127 -223.676168) (xy 144.463006 -223.645043)
			(xy 144.430371 -223.608206) (xy 144.404068 -223.56661) (xy 144.384777 -223.521334) (xy 144.373 -223.47355)
			(xy 144.36904 -223.424496) (xy 143.100044 -223.424496) (xy 143.099549 -223.449103) (xy 143.091654 -223.49768)
			(xy 143.07607 -223.544361) (xy 143.053199 -223.587938) (xy 143.023634 -223.627282) (xy 142.988141 -223.661374)
			(xy 142.947638 -223.68933) (xy 142.903176 -223.710428) (xy 142.855905 -223.72412) (xy 142.80705 -223.730052)
			(xy 142.757875 -223.728071) (xy 142.709656 -223.718227) (xy 142.66364 -223.700775) (xy 142.621019 -223.676168)
			(xy 142.582898 -223.645043) (xy 142.550263 -223.608206) (xy 142.52396 -223.56661) (xy 142.504669 -223.521334)
			(xy 142.492892 -223.47355) (xy 142.488932 -223.424496) (xy 141.22019 -223.424496) (xy 141.219695 -223.449103)
			(xy 141.2118 -223.49768) (xy 141.196216 -223.544361) (xy 141.173345 -223.587938) (xy 141.14378 -223.627282)
			(xy 141.108287 -223.661374) (xy 141.067784 -223.68933) (xy 141.023322 -223.710428) (xy 140.976051 -223.72412)
			(xy 140.927196 -223.730052) (xy 140.878021 -223.728071) (xy 140.829802 -223.718227) (xy 140.783786 -223.700775)
			(xy 140.741165 -223.676168) (xy 140.703044 -223.645043) (xy 140.670409 -223.608206) (xy 140.644106 -223.56661)
			(xy 140.624815 -223.521334) (xy 140.613038 -223.47355) (xy 140.609078 -223.424496) (xy 140.280136 -223.424496)
			(xy 140.279641 -223.449103) (xy 140.271746 -223.49768) (xy 140.256162 -223.544361) (xy 140.233291 -223.587938)
			(xy 140.203726 -223.627282) (xy 140.168233 -223.661374) (xy 140.12773 -223.68933) (xy 140.083268 -223.710428)
			(xy 140.035997 -223.72412) (xy 139.987142 -223.730052) (xy 139.937967 -223.728071) (xy 139.889748 -223.718227)
			(xy 139.843732 -223.700775) (xy 139.801111 -223.676168) (xy 139.76299 -223.645043) (xy 139.730355 -223.608206)
			(xy 139.704052 -223.56661) (xy 139.684761 -223.521334) (xy 139.672984 -223.47355) (xy 139.669024 -223.424496)
			(xy 138.400028 -223.424496) (xy 138.399533 -223.449103) (xy 138.391638 -223.49768) (xy 138.376054 -223.544361)
			(xy 138.353183 -223.587938) (xy 138.323618 -223.627282) (xy 138.288125 -223.661374) (xy 138.247622 -223.68933)
			(xy 138.20316 -223.710428) (xy 138.155889 -223.72412) (xy 138.107034 -223.730052) (xy 138.057859 -223.728071)
			(xy 138.00964 -223.718227) (xy 137.963624 -223.700775) (xy 137.921003 -223.676168) (xy 137.882882 -223.645043)
			(xy 137.850247 -223.608206) (xy 137.823944 -223.56661) (xy 137.804653 -223.521334) (xy 137.792876 -223.47355)
			(xy 137.788916 -223.424496) (xy 137.459974 -223.424496) (xy 137.459479 -223.449103) (xy 137.451584 -223.49768)
			(xy 137.436 -223.544361) (xy 137.413129 -223.587938) (xy 137.383564 -223.627282) (xy 137.348071 -223.661374)
			(xy 137.307568 -223.68933) (xy 137.263106 -223.710428) (xy 137.215835 -223.72412) (xy 137.16698 -223.730052)
			(xy 137.117805 -223.728071) (xy 137.069586 -223.718227) (xy 137.02357 -223.700775) (xy 136.980949 -223.676168)
			(xy 136.942828 -223.645043) (xy 136.910193 -223.608206) (xy 136.88389 -223.56661) (xy 136.864599 -223.521334)
			(xy 136.852822 -223.47355) (xy 136.848862 -223.424496) (xy 135.58012 -223.424496) (xy 135.579625 -223.449103)
			(xy 135.57173 -223.49768) (xy 135.556146 -223.544361) (xy 135.533275 -223.587938) (xy 135.50371 -223.627282)
			(xy 135.468217 -223.661374) (xy 135.427714 -223.68933) (xy 135.383252 -223.710428) (xy 135.335981 -223.72412)
			(xy 135.287126 -223.730052) (xy 135.237951 -223.728071) (xy 135.189732 -223.718227) (xy 135.143716 -223.700775)
			(xy 135.101095 -223.676168) (xy 135.062974 -223.645043) (xy 135.030339 -223.608206) (xy 135.004036 -223.56661)
			(xy 134.984745 -223.521334) (xy 134.972968 -223.47355) (xy 134.969008 -223.424496) (xy 134.640066 -223.424496)
			(xy 134.639571 -223.449103) (xy 134.631676 -223.49768) (xy 134.616092 -223.544361) (xy 134.593221 -223.587938)
			(xy 134.563656 -223.627282) (xy 134.528163 -223.661374) (xy 134.48766 -223.68933) (xy 134.443198 -223.710428)
			(xy 134.395927 -223.72412) (xy 134.347072 -223.730052) (xy 134.297897 -223.728071) (xy 134.249678 -223.718227)
			(xy 134.203662 -223.700775) (xy 134.161041 -223.676168) (xy 134.12292 -223.645043) (xy 134.090285 -223.608206)
			(xy 134.063982 -223.56661) (xy 134.044691 -223.521334) (xy 134.032914 -223.47355) (xy 134.028954 -223.424496)
			(xy 133.700012 -223.424496) (xy 133.699517 -223.449103) (xy 133.691622 -223.49768) (xy 133.676038 -223.544361)
			(xy 133.653167 -223.587938) (xy 133.623602 -223.627282) (xy 133.588109 -223.661374) (xy 133.547606 -223.68933)
			(xy 133.503144 -223.710428) (xy 133.455873 -223.72412) (xy 133.407018 -223.730052) (xy 133.357843 -223.728071)
			(xy 133.309624 -223.718227) (xy 133.263608 -223.700775) (xy 133.220987 -223.676168) (xy 133.182866 -223.645043)
			(xy 133.150231 -223.608206) (xy 133.123928 -223.56661) (xy 133.104637 -223.521334) (xy 133.09286 -223.47355)
			(xy 133.0889 -223.424496) (xy 132.759958 -223.424496) (xy 132.759463 -223.449103) (xy 132.751568 -223.49768)
			(xy 132.735984 -223.544361) (xy 132.713113 -223.587938) (xy 132.683548 -223.627282) (xy 132.648055 -223.661374)
			(xy 132.607552 -223.68933) (xy 132.56309 -223.710428) (xy 132.515819 -223.72412) (xy 132.466964 -223.730052)
			(xy 132.417789 -223.728071) (xy 132.36957 -223.718227) (xy 132.323554 -223.700775) (xy 132.280933 -223.676168)
			(xy 132.242812 -223.645043) (xy 132.210177 -223.608206) (xy 132.183874 -223.56661) (xy 132.164583 -223.521334)
			(xy 132.152806 -223.47355) (xy 132.148846 -223.424496) (xy 131.820158 -223.424496) (xy 131.819663 -223.449103)
			(xy 131.811768 -223.49768) (xy 131.796184 -223.544361) (xy 131.773313 -223.587938) (xy 131.743748 -223.627282)
			(xy 131.708255 -223.661374) (xy 131.667752 -223.68933) (xy 131.62329 -223.710428) (xy 131.576019 -223.72412)
			(xy 131.527164 -223.730052) (xy 131.477989 -223.728071) (xy 131.42977 -223.718227) (xy 131.383754 -223.700775)
			(xy 131.341133 -223.676168) (xy 131.303012 -223.645043) (xy 131.270377 -223.608206) (xy 131.244074 -223.56661)
			(xy 131.224783 -223.521334) (xy 131.213006 -223.47355) (xy 131.209046 -223.424496) (xy 130.880104 -223.424496)
			(xy 130.879609 -223.449103) (xy 130.871714 -223.49768) (xy 130.85613 -223.544361) (xy 130.833259 -223.587938)
			(xy 130.803694 -223.627282) (xy 130.768201 -223.661374) (xy 130.727698 -223.68933) (xy 130.683236 -223.710428)
			(xy 130.635965 -223.72412) (xy 130.58711 -223.730052) (xy 130.537935 -223.728071) (xy 130.489716 -223.718227)
			(xy 130.4437 -223.700775) (xy 130.401079 -223.676168) (xy 130.362958 -223.645043) (xy 130.330323 -223.608206)
			(xy 130.30402 -223.56661) (xy 130.284729 -223.521334) (xy 130.272952 -223.47355) (xy 130.268992 -223.424496)
			(xy 129.94005 -223.424496) (xy 129.939555 -223.449103) (xy 129.93166 -223.49768) (xy 129.916076 -223.544361)
			(xy 129.893205 -223.587938) (xy 129.86364 -223.627282) (xy 129.828147 -223.661374) (xy 129.787644 -223.68933)
			(xy 129.743182 -223.710428) (xy 129.695911 -223.72412) (xy 129.647056 -223.730052) (xy 129.597881 -223.728071)
			(xy 129.549662 -223.718227) (xy 129.503646 -223.700775) (xy 129.461025 -223.676168) (xy 129.422904 -223.645043)
			(xy 129.390269 -223.608206) (xy 129.363966 -223.56661) (xy 129.344675 -223.521334) (xy 129.332898 -223.47355)
			(xy 129.328938 -223.424496) (xy 128.999996 -223.424496) (xy 128.999501 -223.449103) (xy 128.991606 -223.49768)
			(xy 128.976022 -223.544361) (xy 128.953151 -223.587938) (xy 128.923586 -223.627282) (xy 128.888093 -223.661374)
			(xy 128.84759 -223.68933) (xy 128.803128 -223.710428) (xy 128.755857 -223.72412) (xy 128.707002 -223.730052)
			(xy 128.657827 -223.728071) (xy 128.609608 -223.718227) (xy 128.563592 -223.700775) (xy 128.520971 -223.676168)
			(xy 128.48285 -223.645043) (xy 128.450215 -223.608206) (xy 128.423912 -223.56661) (xy 128.404621 -223.521334)
			(xy 128.392844 -223.47355) (xy 128.388884 -223.424496) (xy 128.060435 -223.424496) (xy 128.060435 -223.4245)
			(xy 128.056264 -223.474835) (xy 128.043866 -223.523798) (xy 128.023579 -223.570052) (xy 127.995956 -223.612336)
			(xy 127.96175 -223.649498) (xy 127.921894 -223.680523) (xy 127.877476 -223.704565) (xy 127.829706 -223.720969)
			(xy 127.779888 -223.729288) (xy 127.754634 -223.729804) (xy 127.733063 -223.729416) (xy 127.690356 -223.723299)
			(xy 127.669544 -223.717612) (xy 127.662432 -223.71558) (xy 127.65532 -223.71558) (xy 127.645308 -223.716064)
			(xy 127.626806 -223.723719) (xy 127.612642 -223.737872) (xy 127.604972 -223.756369) (xy 127.60452 -223.76638)
			(xy 127.60452 -223.795336) (xy 127.607314 -223.80321) (xy 127.622679 -223.849534) (xy 127.647399 -223.94396)
			(xy 127.665151 -224.039939) (xy 127.675841 -224.13696) (xy 127.67941 -224.234502) (xy 127.918984 -224.234502)
			(xy 127.922944 -224.185448) (xy 127.934721 -224.137664) (xy 127.954012 -224.092388) (xy 127.980315 -224.050792)
			(xy 128.01295 -224.013955) (xy 128.051071 -223.98283) (xy 128.093692 -223.958223) (xy 128.139708 -223.940771)
			(xy 128.187927 -223.930927) (xy 128.237102 -223.928946) (xy 128.285957 -223.934878) (xy 128.333228 -223.94857)
			(xy 128.37769 -223.969668) (xy 128.418193 -223.997624) (xy 128.453686 -224.031716) (xy 128.483251 -224.07106)
			(xy 128.506122 -224.114637) (xy 128.521706 -224.161318) (xy 128.529601 -224.209895) (xy 128.530096 -224.234502)
			(xy 128.859038 -224.234502) (xy 128.862998 -224.185448) (xy 128.874775 -224.137664) (xy 128.894066 -224.092388)
			(xy 128.920369 -224.050792) (xy 128.953004 -224.013955) (xy 128.991125 -223.98283) (xy 129.033746 -223.958223)
			(xy 129.079762 -223.940771) (xy 129.127981 -223.930927) (xy 129.177156 -223.928946) (xy 129.226011 -223.934878)
			(xy 129.273282 -223.94857) (xy 129.317744 -223.969668) (xy 129.358247 -223.997624) (xy 129.39374 -224.031716)
			(xy 129.423305 -224.07106) (xy 129.446176 -224.114637) (xy 129.46176 -224.161318) (xy 129.469655 -224.209895)
			(xy 129.47015 -224.234502) (xy 129.798838 -224.234502) (xy 129.802798 -224.185448) (xy 129.814575 -224.137664)
			(xy 129.833866 -224.092388) (xy 129.860169 -224.050792) (xy 129.892804 -224.013955) (xy 129.930925 -223.98283)
			(xy 129.973546 -223.958223) (xy 130.019562 -223.940771) (xy 130.067781 -223.930927) (xy 130.116956 -223.928946)
			(xy 130.165811 -223.934878) (xy 130.213082 -223.94857) (xy 130.257544 -223.969668) (xy 130.298047 -223.997624)
			(xy 130.33354 -224.031716) (xy 130.363105 -224.07106) (xy 130.385976 -224.114637) (xy 130.40156 -224.161318)
			(xy 130.409455 -224.209895) (xy 130.40995 -224.234502) (xy 130.738892 -224.234502) (xy 130.742852 -224.185448)
			(xy 130.754629 -224.137664) (xy 130.77392 -224.092388) (xy 130.800223 -224.050792) (xy 130.832858 -224.013955)
			(xy 130.870979 -223.98283) (xy 130.9136 -223.958223) (xy 130.959616 -223.940771) (xy 131.007835 -223.930927)
			(xy 131.05701 -223.928946) (xy 131.105865 -223.934878) (xy 131.153136 -223.94857) (xy 131.197598 -223.969668)
			(xy 131.238101 -223.997624) (xy 131.273594 -224.031716) (xy 131.303159 -224.07106) (xy 131.32603 -224.114637)
			(xy 131.341614 -224.161318) (xy 131.349509 -224.209895) (xy 131.350004 -224.234502) (xy 131.678946 -224.234502)
			(xy 131.682906 -224.185448) (xy 131.694683 -224.137664) (xy 131.713974 -224.092388) (xy 131.740277 -224.050792)
			(xy 131.772912 -224.013955) (xy 131.811033 -223.98283) (xy 131.853654 -223.958223) (xy 131.89967 -223.940771)
			(xy 131.947889 -223.930927) (xy 131.997064 -223.928946) (xy 132.045919 -223.934878) (xy 132.09319 -223.94857)
			(xy 132.137652 -223.969668) (xy 132.178155 -223.997624) (xy 132.213648 -224.031716) (xy 132.243213 -224.07106)
			(xy 132.266084 -224.114637) (xy 132.281668 -224.161318) (xy 132.289563 -224.209895) (xy 132.290058 -224.234502)
			(xy 132.619 -224.234502) (xy 132.62296 -224.185448) (xy 132.634737 -224.137664) (xy 132.654028 -224.092388)
			(xy 132.680331 -224.050792) (xy 132.712966 -224.013955) (xy 132.751087 -223.98283) (xy 132.793708 -223.958223)
			(xy 132.839724 -223.940771) (xy 132.887943 -223.930927) (xy 132.937118 -223.928946) (xy 132.985973 -223.934878)
			(xy 133.033244 -223.94857) (xy 133.077706 -223.969668) (xy 133.118209 -223.997624) (xy 133.153702 -224.031716)
			(xy 133.183267 -224.07106) (xy 133.206138 -224.114637) (xy 133.221722 -224.161318) (xy 133.229617 -224.209895)
			(xy 133.230112 -224.234502) (xy 133.559054 -224.234502) (xy 133.563014 -224.185448) (xy 133.574791 -224.137664)
			(xy 133.594082 -224.092388) (xy 133.620385 -224.050792) (xy 133.65302 -224.013955) (xy 133.691141 -223.98283)
			(xy 133.733762 -223.958223) (xy 133.779778 -223.940771) (xy 133.827997 -223.930927) (xy 133.877172 -223.928946)
			(xy 133.926027 -223.934878) (xy 133.973298 -223.94857) (xy 134.01776 -223.969668) (xy 134.058263 -223.997624)
			(xy 134.093756 -224.031716) (xy 134.123321 -224.07106) (xy 134.146192 -224.114637) (xy 134.161776 -224.161318)
			(xy 134.169671 -224.209895) (xy 134.170166 -224.234502) (xy 134.498854 -224.234502) (xy 134.502814 -224.185448)
			(xy 134.514591 -224.137664) (xy 134.533882 -224.092388) (xy 134.560185 -224.050792) (xy 134.59282 -224.013955)
			(xy 134.630941 -223.98283) (xy 134.673562 -223.958223) (xy 134.719578 -223.940771) (xy 134.767797 -223.930927)
			(xy 134.816972 -223.928946) (xy 134.865827 -223.934878) (xy 134.913098 -223.94857) (xy 134.95756 -223.969668)
			(xy 134.998063 -223.997624) (xy 135.033556 -224.031716) (xy 135.063121 -224.07106) (xy 135.085992 -224.114637)
			(xy 135.101576 -224.161318) (xy 135.109471 -224.209895) (xy 135.109966 -224.234502) (xy 135.438908 -224.234502)
			(xy 135.442868 -224.185448) (xy 135.454645 -224.137664) (xy 135.473936 -224.092388) (xy 135.500239 -224.050792)
			(xy 135.532874 -224.013955) (xy 135.570995 -223.98283) (xy 135.613616 -223.958223) (xy 135.659632 -223.940771)
			(xy 135.707851 -223.930927) (xy 135.757026 -223.928946) (xy 135.805881 -223.934878) (xy 135.853152 -223.94857)
			(xy 135.897614 -223.969668) (xy 135.938117 -223.997624) (xy 135.97361 -224.031716) (xy 136.003175 -224.07106)
			(xy 136.026046 -224.114637) (xy 136.04163 -224.161318) (xy 136.049525 -224.209895) (xy 136.05002 -224.234502)
			(xy 136.378962 -224.234502) (xy 136.382922 -224.185448) (xy 136.394699 -224.137664) (xy 136.41399 -224.092388)
			(xy 136.440293 -224.050792) (xy 136.472928 -224.013955) (xy 136.511049 -223.98283) (xy 136.55367 -223.958223)
			(xy 136.599686 -223.940771) (xy 136.647905 -223.930927) (xy 136.69708 -223.928946) (xy 136.745935 -223.934878)
			(xy 136.793206 -223.94857) (xy 136.837668 -223.969668) (xy 136.878171 -223.997624) (xy 136.913664 -224.031716)
			(xy 136.943229 -224.07106) (xy 136.9661 -224.114637) (xy 136.981684 -224.161318) (xy 136.989579 -224.209895)
			(xy 136.990074 -224.234502) (xy 137.319016 -224.234502) (xy 137.322976 -224.185448) (xy 137.334753 -224.137664)
			(xy 137.354044 -224.092388) (xy 137.380347 -224.050792) (xy 137.412982 -224.013955) (xy 137.451103 -223.98283)
			(xy 137.493724 -223.958223) (xy 137.53974 -223.940771) (xy 137.587959 -223.930927) (xy 137.637134 -223.928946)
			(xy 137.685989 -223.934878) (xy 137.73326 -223.94857) (xy 137.777722 -223.969668) (xy 137.818225 -223.997624)
			(xy 137.853718 -224.031716) (xy 137.883283 -224.07106) (xy 137.906154 -224.114637) (xy 137.921738 -224.161318)
			(xy 137.929633 -224.209895) (xy 137.930128 -224.234502) (xy 138.25907 -224.234502) (xy 138.26303 -224.185448)
			(xy 138.274807 -224.137664) (xy 138.294098 -224.092388) (xy 138.320401 -224.050792) (xy 138.353036 -224.013955)
			(xy 138.391157 -223.98283) (xy 138.433778 -223.958223) (xy 138.479794 -223.940771) (xy 138.528013 -223.930927)
			(xy 138.577188 -223.928946) (xy 138.626043 -223.934878) (xy 138.673314 -223.94857) (xy 138.717776 -223.969668)
			(xy 138.758279 -223.997624) (xy 138.793772 -224.031716) (xy 138.823337 -224.07106) (xy 138.846208 -224.114637)
			(xy 138.861792 -224.161318) (xy 138.869687 -224.209895) (xy 138.870182 -224.234502) (xy 139.19887 -224.234502)
			(xy 139.20283 -224.185448) (xy 139.214607 -224.137664) (xy 139.233898 -224.092388) (xy 139.260201 -224.050792)
			(xy 139.292836 -224.013955) (xy 139.330957 -223.98283) (xy 139.373578 -223.958223) (xy 139.419594 -223.940771)
			(xy 139.467813 -223.930927) (xy 139.516988 -223.928946) (xy 139.565843 -223.934878) (xy 139.613114 -223.94857)
			(xy 139.657576 -223.969668) (xy 139.698079 -223.997624) (xy 139.733572 -224.031716) (xy 139.763137 -224.07106)
			(xy 139.786008 -224.114637) (xy 139.801592 -224.161318) (xy 139.809487 -224.209895) (xy 139.809982 -224.234502)
			(xy 140.138924 -224.234502) (xy 140.142884 -224.185448) (xy 140.154661 -224.137664) (xy 140.173952 -224.092388)
			(xy 140.200255 -224.050792) (xy 140.23289 -224.013955) (xy 140.271011 -223.98283) (xy 140.313632 -223.958223)
			(xy 140.359648 -223.940771) (xy 140.407867 -223.930927) (xy 140.457042 -223.928946) (xy 140.505897 -223.934878)
			(xy 140.553168 -223.94857) (xy 140.59763 -223.969668) (xy 140.638133 -223.997624) (xy 140.673626 -224.031716)
			(xy 140.703191 -224.07106) (xy 140.726062 -224.114637) (xy 140.741646 -224.161318) (xy 140.749541 -224.209895)
			(xy 140.750036 -224.234502) (xy 141.078978 -224.234502) (xy 141.082938 -224.185448) (xy 141.094715 -224.137664)
			(xy 141.114006 -224.092388) (xy 141.140309 -224.050792) (xy 141.172944 -224.013955) (xy 141.211065 -223.98283)
			(xy 141.253686 -223.958223) (xy 141.299702 -223.940771) (xy 141.347921 -223.930927) (xy 141.397096 -223.928946)
			(xy 141.445951 -223.934878) (xy 141.493222 -223.94857) (xy 141.537684 -223.969668) (xy 141.578187 -223.997624)
			(xy 141.61368 -224.031716) (xy 141.643245 -224.07106) (xy 141.666116 -224.114637) (xy 141.6817 -224.161318)
			(xy 141.689595 -224.209895) (xy 141.69009 -224.234502) (xy 142.019032 -224.234502) (xy 142.022992 -224.185448)
			(xy 142.034769 -224.137664) (xy 142.05406 -224.092388) (xy 142.080363 -224.050792) (xy 142.112998 -224.013955)
			(xy 142.151119 -223.98283) (xy 142.19374 -223.958223) (xy 142.239756 -223.940771) (xy 142.287975 -223.930927)
			(xy 142.33715 -223.928946) (xy 142.386005 -223.934878) (xy 142.433276 -223.94857) (xy 142.477738 -223.969668)
			(xy 142.518241 -223.997624) (xy 142.553734 -224.031716) (xy 142.583299 -224.07106) (xy 142.60617 -224.114637)
			(xy 142.621754 -224.161318) (xy 142.629649 -224.209895) (xy 142.630144 -224.234502) (xy 142.958832 -224.234502)
			(xy 142.962792 -224.185448) (xy 142.974569 -224.137664) (xy 142.99386 -224.092388) (xy 143.020163 -224.050792)
			(xy 143.052798 -224.013955) (xy 143.090919 -223.98283) (xy 143.13354 -223.958223) (xy 143.179556 -223.940771)
			(xy 143.227775 -223.930927) (xy 143.27695 -223.928946) (xy 143.325805 -223.934878) (xy 143.373076 -223.94857)
			(xy 143.417538 -223.969668) (xy 143.458041 -223.997624) (xy 143.493534 -224.031716) (xy 143.523099 -224.07106)
			(xy 143.54597 -224.114637) (xy 143.561554 -224.161318) (xy 143.569449 -224.209895) (xy 143.569944 -224.234502)
			(xy 143.898886 -224.234502) (xy 143.902846 -224.185448) (xy 143.914623 -224.137664) (xy 143.933914 -224.092388)
			(xy 143.960217 -224.050792) (xy 143.992852 -224.013955) (xy 144.030973 -223.98283) (xy 144.073594 -223.958223)
			(xy 144.11961 -223.940771) (xy 144.167829 -223.930927) (xy 144.217004 -223.928946) (xy 144.265859 -223.934878)
			(xy 144.31313 -223.94857) (xy 144.357592 -223.969668) (xy 144.398095 -223.997624) (xy 144.433588 -224.031716)
			(xy 144.463153 -224.07106) (xy 144.486024 -224.114637) (xy 144.501608 -224.161318) (xy 144.509503 -224.209895)
			(xy 144.509998 -224.234502) (xy 144.83894 -224.234502) (xy 144.8429 -224.185448) (xy 144.854677 -224.137664)
			(xy 144.873968 -224.092388) (xy 144.900271 -224.050792) (xy 144.932906 -224.013955) (xy 144.971027 -223.98283)
			(xy 145.013648 -223.958223) (xy 145.059664 -223.940771) (xy 145.107883 -223.930927) (xy 145.157058 -223.928946)
			(xy 145.205913 -223.934878) (xy 145.253184 -223.94857) (xy 145.297646 -223.969668) (xy 145.338149 -223.997624)
			(xy 145.373642 -224.031716) (xy 145.403207 -224.07106) (xy 145.426078 -224.114637) (xy 145.441662 -224.161318)
			(xy 145.449557 -224.209895) (xy 145.450052 -224.234502) (xy 145.449557 -224.259109) (xy 145.441662 -224.307686)
			(xy 145.426078 -224.354367) (xy 145.403207 -224.397944) (xy 145.373642 -224.437288) (xy 145.338149 -224.47138)
			(xy 145.297646 -224.499336) (xy 145.253184 -224.520434) (xy 145.205913 -224.534126) (xy 145.157058 -224.540058)
			(xy 145.107883 -224.538077) (xy 145.059664 -224.528233) (xy 145.013648 -224.510781) (xy 144.971027 -224.486174)
			(xy 144.932906 -224.455049) (xy 144.900271 -224.418212) (xy 144.873968 -224.376616) (xy 144.854677 -224.33134)
			(xy 144.8429 -224.283556) (xy 144.83894 -224.234502) (xy 144.509998 -224.234502) (xy 144.509503 -224.259109)
			(xy 144.501608 -224.307686) (xy 144.486024 -224.354367) (xy 144.463153 -224.397944) (xy 144.433588 -224.437288)
			(xy 144.398095 -224.47138) (xy 144.357592 -224.499336) (xy 144.31313 -224.520434) (xy 144.265859 -224.534126)
			(xy 144.217004 -224.540058) (xy 144.167829 -224.538077) (xy 144.11961 -224.528233) (xy 144.073594 -224.510781)
			(xy 144.030973 -224.486174) (xy 143.992852 -224.455049) (xy 143.960217 -224.418212) (xy 143.933914 -224.376616)
			(xy 143.914623 -224.33134) (xy 143.902846 -224.283556) (xy 143.898886 -224.234502) (xy 143.569944 -224.234502)
			(xy 143.569449 -224.259109) (xy 143.561554 -224.307686) (xy 143.54597 -224.354367) (xy 143.523099 -224.397944)
			(xy 143.493534 -224.437288) (xy 143.458041 -224.47138) (xy 143.417538 -224.499336) (xy 143.373076 -224.520434)
			(xy 143.325805 -224.534126) (xy 143.27695 -224.540058) (xy 143.227775 -224.538077) (xy 143.179556 -224.528233)
			(xy 143.13354 -224.510781) (xy 143.090919 -224.486174) (xy 143.052798 -224.455049) (xy 143.020163 -224.418212)
			(xy 142.99386 -224.376616) (xy 142.974569 -224.33134) (xy 142.962792 -224.283556) (xy 142.958832 -224.234502)
			(xy 142.630144 -224.234502) (xy 142.629649 -224.259109) (xy 142.621754 -224.307686) (xy 142.60617 -224.354367)
			(xy 142.583299 -224.397944) (xy 142.553734 -224.437288) (xy 142.518241 -224.47138) (xy 142.477738 -224.499336)
			(xy 142.433276 -224.520434) (xy 142.386005 -224.534126) (xy 142.33715 -224.540058) (xy 142.287975 -224.538077)
			(xy 142.239756 -224.528233) (xy 142.19374 -224.510781) (xy 142.151119 -224.486174) (xy 142.112998 -224.455049)
			(xy 142.080363 -224.418212) (xy 142.05406 -224.376616) (xy 142.034769 -224.33134) (xy 142.022992 -224.283556)
			(xy 142.019032 -224.234502) (xy 141.69009 -224.234502) (xy 141.689595 -224.259109) (xy 141.6817 -224.307686)
			(xy 141.666116 -224.354367) (xy 141.643245 -224.397944) (xy 141.61368 -224.437288) (xy 141.578187 -224.47138)
			(xy 141.537684 -224.499336) (xy 141.493222 -224.520434) (xy 141.445951 -224.534126) (xy 141.397096 -224.540058)
			(xy 141.347921 -224.538077) (xy 141.299702 -224.528233) (xy 141.253686 -224.510781) (xy 141.211065 -224.486174)
			(xy 141.172944 -224.455049) (xy 141.140309 -224.418212) (xy 141.114006 -224.376616) (xy 141.094715 -224.33134)
			(xy 141.082938 -224.283556) (xy 141.078978 -224.234502) (xy 140.750036 -224.234502) (xy 140.749541 -224.259109)
			(xy 140.741646 -224.307686) (xy 140.726062 -224.354367) (xy 140.703191 -224.397944) (xy 140.673626 -224.437288)
			(xy 140.638133 -224.47138) (xy 140.59763 -224.499336) (xy 140.553168 -224.520434) (xy 140.505897 -224.534126)
			(xy 140.457042 -224.540058) (xy 140.407867 -224.538077) (xy 140.359648 -224.528233) (xy 140.313632 -224.510781)
			(xy 140.271011 -224.486174) (xy 140.23289 -224.455049) (xy 140.200255 -224.418212) (xy 140.173952 -224.376616)
			(xy 140.154661 -224.33134) (xy 140.142884 -224.283556) (xy 140.138924 -224.234502) (xy 139.809982 -224.234502)
			(xy 139.809487 -224.259109) (xy 139.801592 -224.307686) (xy 139.786008 -224.354367) (xy 139.763137 -224.397944)
			(xy 139.733572 -224.437288) (xy 139.698079 -224.47138) (xy 139.657576 -224.499336) (xy 139.613114 -224.520434)
			(xy 139.565843 -224.534126) (xy 139.516988 -224.540058) (xy 139.467813 -224.538077) (xy 139.419594 -224.528233)
			(xy 139.373578 -224.510781) (xy 139.330957 -224.486174) (xy 139.292836 -224.455049) (xy 139.260201 -224.418212)
			(xy 139.233898 -224.376616) (xy 139.214607 -224.33134) (xy 139.20283 -224.283556) (xy 139.19887 -224.234502)
			(xy 138.870182 -224.234502) (xy 138.869687 -224.259109) (xy 138.861792 -224.307686) (xy 138.846208 -224.354367)
			(xy 138.823337 -224.397944) (xy 138.793772 -224.437288) (xy 138.758279 -224.47138) (xy 138.717776 -224.499336)
			(xy 138.673314 -224.520434) (xy 138.626043 -224.534126) (xy 138.577188 -224.540058) (xy 138.528013 -224.538077)
			(xy 138.479794 -224.528233) (xy 138.433778 -224.510781) (xy 138.391157 -224.486174) (xy 138.353036 -224.455049)
			(xy 138.320401 -224.418212) (xy 138.294098 -224.376616) (xy 138.274807 -224.33134) (xy 138.26303 -224.283556)
			(xy 138.25907 -224.234502) (xy 137.930128 -224.234502) (xy 137.929633 -224.259109) (xy 137.921738 -224.307686)
			(xy 137.906154 -224.354367) (xy 137.883283 -224.397944) (xy 137.853718 -224.437288) (xy 137.818225 -224.47138)
			(xy 137.777722 -224.499336) (xy 137.73326 -224.520434) (xy 137.685989 -224.534126) (xy 137.637134 -224.540058)
			(xy 137.587959 -224.538077) (xy 137.53974 -224.528233) (xy 137.493724 -224.510781) (xy 137.451103 -224.486174)
			(xy 137.412982 -224.455049) (xy 137.380347 -224.418212) (xy 137.354044 -224.376616) (xy 137.334753 -224.33134)
			(xy 137.322976 -224.283556) (xy 137.319016 -224.234502) (xy 136.990074 -224.234502) (xy 136.989579 -224.259109)
			(xy 136.981684 -224.307686) (xy 136.9661 -224.354367) (xy 136.943229 -224.397944) (xy 136.913664 -224.437288)
			(xy 136.878171 -224.47138) (xy 136.837668 -224.499336) (xy 136.793206 -224.520434) (xy 136.745935 -224.534126)
			(xy 136.69708 -224.540058) (xy 136.647905 -224.538077) (xy 136.599686 -224.528233) (xy 136.55367 -224.510781)
			(xy 136.511049 -224.486174) (xy 136.472928 -224.455049) (xy 136.440293 -224.418212) (xy 136.41399 -224.376616)
			(xy 136.394699 -224.33134) (xy 136.382922 -224.283556) (xy 136.378962 -224.234502) (xy 136.05002 -224.234502)
			(xy 136.049525 -224.259109) (xy 136.04163 -224.307686) (xy 136.026046 -224.354367) (xy 136.003175 -224.397944)
			(xy 135.97361 -224.437288) (xy 135.938117 -224.47138) (xy 135.897614 -224.499336) (xy 135.853152 -224.520434)
			(xy 135.805881 -224.534126) (xy 135.757026 -224.540058) (xy 135.707851 -224.538077) (xy 135.659632 -224.528233)
			(xy 135.613616 -224.510781) (xy 135.570995 -224.486174) (xy 135.532874 -224.455049) (xy 135.500239 -224.418212)
			(xy 135.473936 -224.376616) (xy 135.454645 -224.33134) (xy 135.442868 -224.283556) (xy 135.438908 -224.234502)
			(xy 135.109966 -224.234502) (xy 135.109471 -224.259109) (xy 135.101576 -224.307686) (xy 135.085992 -224.354367)
			(xy 135.063121 -224.397944) (xy 135.033556 -224.437288) (xy 134.998063 -224.47138) (xy 134.95756 -224.499336)
			(xy 134.913098 -224.520434) (xy 134.865827 -224.534126) (xy 134.816972 -224.540058) (xy 134.767797 -224.538077)
			(xy 134.719578 -224.528233) (xy 134.673562 -224.510781) (xy 134.630941 -224.486174) (xy 134.59282 -224.455049)
			(xy 134.560185 -224.418212) (xy 134.533882 -224.376616) (xy 134.514591 -224.33134) (xy 134.502814 -224.283556)
			(xy 134.498854 -224.234502) (xy 134.170166 -224.234502) (xy 134.169671 -224.259109) (xy 134.161776 -224.307686)
			(xy 134.146192 -224.354367) (xy 134.123321 -224.397944) (xy 134.093756 -224.437288) (xy 134.058263 -224.47138)
			(xy 134.01776 -224.499336) (xy 133.973298 -224.520434) (xy 133.926027 -224.534126) (xy 133.877172 -224.540058)
			(xy 133.827997 -224.538077) (xy 133.779778 -224.528233) (xy 133.733762 -224.510781) (xy 133.691141 -224.486174)
			(xy 133.65302 -224.455049) (xy 133.620385 -224.418212) (xy 133.594082 -224.376616) (xy 133.574791 -224.33134)
			(xy 133.563014 -224.283556) (xy 133.559054 -224.234502) (xy 133.230112 -224.234502) (xy 133.229617 -224.259109)
			(xy 133.221722 -224.307686) (xy 133.206138 -224.354367) (xy 133.183267 -224.397944) (xy 133.153702 -224.437288)
			(xy 133.118209 -224.47138) (xy 133.077706 -224.499336) (xy 133.033244 -224.520434) (xy 132.985973 -224.534126)
			(xy 132.937118 -224.540058) (xy 132.887943 -224.538077) (xy 132.839724 -224.528233) (xy 132.793708 -224.510781)
			(xy 132.751087 -224.486174) (xy 132.712966 -224.455049) (xy 132.680331 -224.418212) (xy 132.654028 -224.376616)
			(xy 132.634737 -224.33134) (xy 132.62296 -224.283556) (xy 132.619 -224.234502) (xy 132.290058 -224.234502)
			(xy 132.289563 -224.259109) (xy 132.281668 -224.307686) (xy 132.266084 -224.354367) (xy 132.243213 -224.397944)
			(xy 132.213648 -224.437288) (xy 132.178155 -224.47138) (xy 132.137652 -224.499336) (xy 132.09319 -224.520434)
			(xy 132.045919 -224.534126) (xy 131.997064 -224.540058) (xy 131.947889 -224.538077) (xy 131.89967 -224.528233)
			(xy 131.853654 -224.510781) (xy 131.811033 -224.486174) (xy 131.772912 -224.455049) (xy 131.740277 -224.418212)
			(xy 131.713974 -224.376616) (xy 131.694683 -224.33134) (xy 131.682906 -224.283556) (xy 131.678946 -224.234502)
			(xy 131.350004 -224.234502) (xy 131.349509 -224.259109) (xy 131.341614 -224.307686) (xy 131.32603 -224.354367)
			(xy 131.303159 -224.397944) (xy 131.273594 -224.437288) (xy 131.238101 -224.47138) (xy 131.197598 -224.499336)
			(xy 131.153136 -224.520434) (xy 131.105865 -224.534126) (xy 131.05701 -224.540058) (xy 131.007835 -224.538077)
			(xy 130.959616 -224.528233) (xy 130.9136 -224.510781) (xy 130.870979 -224.486174) (xy 130.832858 -224.455049)
			(xy 130.800223 -224.418212) (xy 130.77392 -224.376616) (xy 130.754629 -224.33134) (xy 130.742852 -224.283556)
			(xy 130.738892 -224.234502) (xy 130.40995 -224.234502) (xy 130.409455 -224.259109) (xy 130.40156 -224.307686)
			(xy 130.385976 -224.354367) (xy 130.363105 -224.397944) (xy 130.33354 -224.437288) (xy 130.298047 -224.47138)
			(xy 130.257544 -224.499336) (xy 130.213082 -224.520434) (xy 130.165811 -224.534126) (xy 130.116956 -224.540058)
			(xy 130.067781 -224.538077) (xy 130.019562 -224.528233) (xy 129.973546 -224.510781) (xy 129.930925 -224.486174)
			(xy 129.892804 -224.455049) (xy 129.860169 -224.418212) (xy 129.833866 -224.376616) (xy 129.814575 -224.33134)
			(xy 129.802798 -224.283556) (xy 129.798838 -224.234502) (xy 129.47015 -224.234502) (xy 129.469655 -224.259109)
			(xy 129.46176 -224.307686) (xy 129.446176 -224.354367) (xy 129.423305 -224.397944) (xy 129.39374 -224.437288)
			(xy 129.358247 -224.47138) (xy 129.317744 -224.499336) (xy 129.273282 -224.520434) (xy 129.226011 -224.534126)
			(xy 129.177156 -224.540058) (xy 129.127981 -224.538077) (xy 129.079762 -224.528233) (xy 129.033746 -224.510781)
			(xy 128.991125 -224.486174) (xy 128.953004 -224.455049) (xy 128.920369 -224.418212) (xy 128.894066 -224.376616)
			(xy 128.874775 -224.33134) (xy 128.862998 -224.283556) (xy 128.859038 -224.234502) (xy 128.530096 -224.234502)
			(xy 128.529601 -224.259109) (xy 128.521706 -224.307686) (xy 128.506122 -224.354367) (xy 128.483251 -224.397944)
			(xy 128.453686 -224.437288) (xy 128.418193 -224.47138) (xy 128.37769 -224.499336) (xy 128.333228 -224.520434)
			(xy 128.285957 -224.534126) (xy 128.237102 -224.540058) (xy 128.187927 -224.538077) (xy 128.139708 -224.528233)
			(xy 128.093692 -224.510781) (xy 128.051071 -224.486174) (xy 128.01295 -224.455049) (xy 127.980315 -224.418212)
			(xy 127.954012 -224.376616) (xy 127.934721 -224.33134) (xy 127.922944 -224.283556) (xy 127.918984 -224.234502)
			(xy 127.67941 -224.234502) (xy 127.67584 -224.332044) (xy 127.665151 -224.429065) (xy 127.647398 -224.525044)
			(xy 127.622678 -224.619469) (xy 127.607314 -224.665794) (xy 127.60452 -224.673668) (xy 127.60452 -224.702624)
			(xy 127.605012 -224.712627) (xy 127.612677 -224.731107) (xy 127.62683 -224.745248) (xy 127.645317 -224.752896)
			(xy 127.65532 -224.753424) (xy 127.662432 -224.753424) (xy 127.669544 -224.751392) (xy 127.690359 -224.745721)
			(xy 127.733064 -224.739602) (xy 127.754634 -224.7392) (xy 127.779887 -224.739724) (xy 127.829703 -224.748042)
			(xy 127.877471 -224.764446) (xy 127.921887 -224.788487) (xy 127.961741 -224.819511) (xy 127.995946 -224.856671)
			(xy 128.023568 -224.898954) (xy 128.043855 -224.945206) (xy 128.056253 -224.994167) (xy 128.060423 -225.0445)
			(xy 128.060422 -225.044508) (xy 128.388884 -225.044508) (xy 128.392844 -224.995454) (xy 128.404621 -224.94767)
			(xy 128.423912 -224.902394) (xy 128.450215 -224.860798) (xy 128.48285 -224.823961) (xy 128.520971 -224.792836)
			(xy 128.563592 -224.768229) (xy 128.609608 -224.750777) (xy 128.657827 -224.740933) (xy 128.707002 -224.738952)
			(xy 128.755857 -224.744884) (xy 128.803128 -224.758576) (xy 128.84759 -224.779674) (xy 128.888093 -224.80763)
			(xy 128.923586 -224.841722) (xy 128.953151 -224.881066) (xy 128.976022 -224.924643) (xy 128.991606 -224.971324)
			(xy 128.999501 -225.019901) (xy 128.999996 -225.044508) (xy 129.318507 -225.044508) (xy 129.322602 -224.99378)
			(xy 129.334781 -224.944366) (xy 129.354729 -224.897546) (xy 129.38193 -224.854532) (xy 129.415678 -224.816438)
			(xy 129.4551 -224.784251) (xy 129.499174 -224.758805) (xy 129.54676 -224.740758) (xy 129.596624 -224.730578)
			(xy 129.647476 -224.728529) (xy 129.697997 -224.734663) (xy 129.746881 -224.748823) (xy 129.79286 -224.77064)
			(xy 129.834744 -224.79955) (xy 129.871448 -224.834805) (xy 129.902021 -224.875491) (xy 129.925672 -224.920554)
			(xy 129.941788 -224.968828) (xy 129.949952 -225.019062) (xy 129.950464 -225.044508) (xy 130.268992 -225.044508)
			(xy 130.272952 -224.995454) (xy 130.284729 -224.94767) (xy 130.30402 -224.902394) (xy 130.330323 -224.860798)
			(xy 130.362958 -224.823961) (xy 130.401079 -224.792836) (xy 130.4437 -224.768229) (xy 130.489716 -224.750777)
			(xy 130.537935 -224.740933) (xy 130.58711 -224.738952) (xy 130.635965 -224.744884) (xy 130.683236 -224.758576)
			(xy 130.727698 -224.779674) (xy 130.768201 -224.80763) (xy 130.803694 -224.841722) (xy 130.833259 -224.881066)
			(xy 130.85613 -224.924643) (xy 130.871714 -224.971324) (xy 130.879609 -225.019901) (xy 130.880104 -225.044508)
			(xy 131.209046 -225.044508) (xy 131.213006 -224.995454) (xy 131.224783 -224.94767) (xy 131.244074 -224.902394)
			(xy 131.270377 -224.860798) (xy 131.303012 -224.823961) (xy 131.341133 -224.792836) (xy 131.383754 -224.768229)
			(xy 131.42977 -224.750777) (xy 131.477989 -224.740933) (xy 131.527164 -224.738952) (xy 131.576019 -224.744884)
			(xy 131.62329 -224.758576) (xy 131.667752 -224.779674) (xy 131.708255 -224.80763) (xy 131.743748 -224.841722)
			(xy 131.773313 -224.881066) (xy 131.796184 -224.924643) (xy 131.811768 -224.971324) (xy 131.819663 -225.019901)
			(xy 131.820158 -225.044508) (xy 132.138415 -225.044508) (xy 132.14251 -224.99378) (xy 132.154689 -224.944366)
			(xy 132.174637 -224.897546) (xy 132.201838 -224.854532) (xy 132.235586 -224.816438) (xy 132.275008 -224.784251)
			(xy 132.319082 -224.758805) (xy 132.366668 -224.740758) (xy 132.416532 -224.730578) (xy 132.467384 -224.728529)
			(xy 132.517905 -224.734663) (xy 132.566789 -224.748823) (xy 132.612768 -224.77064) (xy 132.654652 -224.79955)
			(xy 132.691356 -224.834805) (xy 132.721929 -224.875491) (xy 132.74558 -224.920554) (xy 132.761696 -224.968828)
			(xy 132.76986 -225.019062) (xy 132.770372 -225.044508) (xy 133.0889 -225.044508) (xy 133.09286 -224.995454)
			(xy 133.104637 -224.94767) (xy 133.123928 -224.902394) (xy 133.150231 -224.860798) (xy 133.182866 -224.823961)
			(xy 133.220987 -224.792836) (xy 133.263608 -224.768229) (xy 133.309624 -224.750777) (xy 133.357843 -224.740933)
			(xy 133.407018 -224.738952) (xy 133.455873 -224.744884) (xy 133.503144 -224.758576) (xy 133.547606 -224.779674)
			(xy 133.588109 -224.80763) (xy 133.623602 -224.841722) (xy 133.653167 -224.881066) (xy 133.676038 -224.924643)
			(xy 133.691622 -224.971324) (xy 133.699517 -225.019901) (xy 133.700012 -225.044508) (xy 134.028954 -225.044508)
			(xy 134.032914 -224.995454) (xy 134.044691 -224.94767) (xy 134.063982 -224.902394) (xy 134.090285 -224.860798)
			(xy 134.12292 -224.823961) (xy 134.161041 -224.792836) (xy 134.203662 -224.768229) (xy 134.249678 -224.750777)
			(xy 134.297897 -224.740933) (xy 134.347072 -224.738952) (xy 134.395927 -224.744884) (xy 134.443198 -224.758576)
			(xy 134.48766 -224.779674) (xy 134.528163 -224.80763) (xy 134.563656 -224.841722) (xy 134.593221 -224.881066)
			(xy 134.616092 -224.924643) (xy 134.631676 -224.971324) (xy 134.639571 -225.019901) (xy 134.640066 -225.044508)
			(xy 134.969008 -225.044508) (xy 134.972968 -224.995454) (xy 134.984745 -224.94767) (xy 135.004036 -224.902394)
			(xy 135.030339 -224.860798) (xy 135.062974 -224.823961) (xy 135.101095 -224.792836) (xy 135.143716 -224.768229)
			(xy 135.189732 -224.750777) (xy 135.237951 -224.740933) (xy 135.287126 -224.738952) (xy 135.335981 -224.744884)
			(xy 135.383252 -224.758576) (xy 135.427714 -224.779674) (xy 135.468217 -224.80763) (xy 135.50371 -224.841722)
			(xy 135.533275 -224.881066) (xy 135.556146 -224.924643) (xy 135.57173 -224.971324) (xy 135.579625 -225.019901)
			(xy 135.58012 -225.044508) (xy 135.898631 -225.044508) (xy 135.902726 -224.99378) (xy 135.914905 -224.944366)
			(xy 135.934853 -224.897546) (xy 135.962054 -224.854532) (xy 135.995802 -224.816438) (xy 136.035224 -224.784251)
			(xy 136.079298 -224.758805) (xy 136.126884 -224.740758) (xy 136.176748 -224.730578) (xy 136.2276 -224.728529)
			(xy 136.278121 -224.734663) (xy 136.327005 -224.748823) (xy 136.372984 -224.77064) (xy 136.414868 -224.79955)
			(xy 136.451572 -224.834805) (xy 136.482145 -224.875491) (xy 136.505796 -224.920554) (xy 136.521912 -224.968828)
			(xy 136.530076 -225.019062) (xy 136.530588 -225.044508) (xy 137.788916 -225.044508) (xy 137.792876 -224.995454)
			(xy 137.804653 -224.94767) (xy 137.823944 -224.902394) (xy 137.850247 -224.860798) (xy 137.882882 -224.823961)
			(xy 137.921003 -224.792836) (xy 137.963624 -224.768229) (xy 138.00964 -224.750777) (xy 138.057859 -224.740933)
			(xy 138.107034 -224.738952) (xy 138.155889 -224.744884) (xy 138.20316 -224.758576) (xy 138.247622 -224.779674)
			(xy 138.288125 -224.80763) (xy 138.323618 -224.841722) (xy 138.353183 -224.881066) (xy 138.376054 -224.924643)
			(xy 138.391638 -224.971324) (xy 138.399533 -225.019901) (xy 138.400028 -225.044508) (xy 138.718539 -225.044508)
			(xy 138.722634 -224.99378) (xy 138.734813 -224.944366) (xy 138.754761 -224.897546) (xy 138.781962 -224.854532)
			(xy 138.81571 -224.816438) (xy 138.855132 -224.784251) (xy 138.899206 -224.758805) (xy 138.946792 -224.740758)
			(xy 138.996656 -224.730578) (xy 139.047508 -224.728529) (xy 139.098029 -224.734663) (xy 139.146913 -224.748823)
			(xy 139.192892 -224.77064) (xy 139.234776 -224.79955) (xy 139.27148 -224.834805) (xy 139.302053 -224.875491)
			(xy 139.325704 -224.920554) (xy 139.34182 -224.968828) (xy 139.349984 -225.019062) (xy 139.350496 -225.044508)
			(xy 139.669024 -225.044508) (xy 139.672984 -224.995454) (xy 139.684761 -224.94767) (xy 139.704052 -224.902394)
			(xy 139.730355 -224.860798) (xy 139.76299 -224.823961) (xy 139.801111 -224.792836) (xy 139.843732 -224.768229)
			(xy 139.889748 -224.750777) (xy 139.937967 -224.740933) (xy 139.987142 -224.738952) (xy 140.035997 -224.744884)
			(xy 140.083268 -224.758576) (xy 140.12773 -224.779674) (xy 140.168233 -224.80763) (xy 140.203726 -224.841722)
			(xy 140.233291 -224.881066) (xy 140.256162 -224.924643) (xy 140.271746 -224.971324) (xy 140.279641 -225.019901)
			(xy 140.280136 -225.044508) (xy 140.609078 -225.044508) (xy 140.613038 -224.995454) (xy 140.624815 -224.94767)
			(xy 140.644106 -224.902394) (xy 140.670409 -224.860798) (xy 140.703044 -224.823961) (xy 140.741165 -224.792836)
			(xy 140.783786 -224.768229) (xy 140.829802 -224.750777) (xy 140.878021 -224.740933) (xy 140.927196 -224.738952)
			(xy 140.976051 -224.744884) (xy 141.023322 -224.758576) (xy 141.067784 -224.779674) (xy 141.108287 -224.80763)
			(xy 141.14378 -224.841722) (xy 141.173345 -224.881066) (xy 141.196216 -224.924643) (xy 141.2118 -224.971324)
			(xy 141.219695 -225.019901) (xy 141.22019 -225.044508) (xy 141.548878 -225.044508) (xy 141.552838 -224.995454)
			(xy 141.564615 -224.94767) (xy 141.583906 -224.902394) (xy 141.610209 -224.860798) (xy 141.642844 -224.823961)
			(xy 141.680965 -224.792836) (xy 141.723586 -224.768229) (xy 141.769602 -224.750777) (xy 141.817821 -224.740933)
			(xy 141.866996 -224.738952) (xy 141.915851 -224.744884) (xy 141.963122 -224.758576) (xy 142.007584 -224.779674)
			(xy 142.048087 -224.80763) (xy 142.08358 -224.841722) (xy 142.113145 -224.881066) (xy 142.136016 -224.924643)
			(xy 142.1516 -224.971324) (xy 142.159495 -225.019901) (xy 142.15999 -225.044508) (xy 142.478501 -225.044508)
			(xy 142.482596 -224.99378) (xy 142.494775 -224.944366) (xy 142.514723 -224.897546) (xy 142.541924 -224.854532)
			(xy 142.575672 -224.816438) (xy 142.615094 -224.784251) (xy 142.659168 -224.758805) (xy 142.706754 -224.740758)
			(xy 142.756618 -224.730578) (xy 142.80747 -224.728529) (xy 142.857991 -224.734663) (xy 142.906875 -224.748823)
			(xy 142.952854 -224.77064) (xy 142.994738 -224.79955) (xy 143.031442 -224.834805) (xy 143.062015 -224.875491)
			(xy 143.085666 -224.920554) (xy 143.101782 -224.968828) (xy 143.109946 -225.019062) (xy 143.110458 -225.044508)
			(xy 144.36904 -225.044508) (xy 144.373 -224.995454) (xy 144.384777 -224.94767) (xy 144.404068 -224.902394)
			(xy 144.430371 -224.860798) (xy 144.463006 -224.823961) (xy 144.501127 -224.792836) (xy 144.543748 -224.768229)
			(xy 144.589764 -224.750777) (xy 144.637983 -224.740933) (xy 144.687158 -224.738952) (xy 144.736013 -224.744884)
			(xy 144.783284 -224.758576) (xy 144.827746 -224.779674) (xy 144.868249 -224.80763) (xy 144.903742 -224.841722)
			(xy 144.933307 -224.881066) (xy 144.956178 -224.924643) (xy 144.971762 -224.971324) (xy 144.979657 -225.019901)
			(xy 144.980152 -225.044508) (xy 144.979657 -225.069115) (xy 144.971762 -225.117692) (xy 144.956178 -225.164373)
			(xy 144.933307 -225.20795) (xy 144.903742 -225.247294) (xy 144.868249 -225.281386) (xy 144.827746 -225.309342)
			(xy 144.783284 -225.33044) (xy 144.736013 -225.344132) (xy 144.687158 -225.350064) (xy 144.637983 -225.348083)
			(xy 144.589764 -225.338239) (xy 144.543748 -225.320787) (xy 144.501127 -225.29618) (xy 144.463006 -225.265055)
			(xy 144.430371 -225.228218) (xy 144.404068 -225.186622) (xy 144.384777 -225.141346) (xy 144.373 -225.093562)
			(xy 144.36904 -225.044508) (xy 143.110458 -225.044508) (xy 143.109946 -225.069954) (xy 143.101782 -225.120188)
			(xy 143.085666 -225.168462) (xy 143.062015 -225.213525) (xy 143.031442 -225.254211) (xy 142.994738 -225.289466)
			(xy 142.952854 -225.318376) (xy 142.906875 -225.340193) (xy 142.857991 -225.354353) (xy 142.80747 -225.360487)
			(xy 142.756618 -225.358438) (xy 142.706754 -225.348258) (xy 142.659168 -225.330211) (xy 142.615094 -225.304765)
			(xy 142.575672 -225.272578) (xy 142.541924 -225.234484) (xy 142.514723 -225.19147) (xy 142.494775 -225.14465)
			(xy 142.482596 -225.095236) (xy 142.478501 -225.044508) (xy 142.15999 -225.044508) (xy 142.159495 -225.069115)
			(xy 142.1516 -225.117692) (xy 142.136016 -225.164373) (xy 142.113145 -225.20795) (xy 142.08358 -225.247294)
			(xy 142.048087 -225.281386) (xy 142.007584 -225.309342) (xy 141.963122 -225.33044) (xy 141.915851 -225.344132)
			(xy 141.866996 -225.350064) (xy 141.817821 -225.348083) (xy 141.769602 -225.338239) (xy 141.723586 -225.320787)
			(xy 141.680965 -225.29618) (xy 141.642844 -225.265055) (xy 141.610209 -225.228218) (xy 141.583906 -225.186622)
			(xy 141.564615 -225.141346) (xy 141.552838 -225.093562) (xy 141.548878 -225.044508) (xy 141.22019 -225.044508)
			(xy 141.219695 -225.069115) (xy 141.2118 -225.117692) (xy 141.196216 -225.164373) (xy 141.173345 -225.20795)
			(xy 141.14378 -225.247294) (xy 141.108287 -225.281386) (xy 141.067784 -225.309342) (xy 141.023322 -225.33044)
			(xy 140.976051 -225.344132) (xy 140.927196 -225.350064) (xy 140.878021 -225.348083) (xy 140.829802 -225.338239)
			(xy 140.783786 -225.320787) (xy 140.741165 -225.29618) (xy 140.703044 -225.265055) (xy 140.670409 -225.228218)
			(xy 140.644106 -225.186622) (xy 140.624815 -225.141346) (xy 140.613038 -225.093562) (xy 140.609078 -225.044508)
			(xy 140.280136 -225.044508) (xy 140.279641 -225.069115) (xy 140.271746 -225.117692) (xy 140.256162 -225.164373)
			(xy 140.233291 -225.20795) (xy 140.203726 -225.247294) (xy 140.168233 -225.281386) (xy 140.12773 -225.309342)
			(xy 140.083268 -225.33044) (xy 140.035997 -225.344132) (xy 139.987142 -225.350064) (xy 139.937967 -225.348083)
			(xy 139.889748 -225.338239) (xy 139.843732 -225.320787) (xy 139.801111 -225.29618) (xy 139.76299 -225.265055)
			(xy 139.730355 -225.228218) (xy 139.704052 -225.186622) (xy 139.684761 -225.141346) (xy 139.672984 -225.093562)
			(xy 139.669024 -225.044508) (xy 139.350496 -225.044508) (xy 139.349984 -225.069954) (xy 139.34182 -225.120188)
			(xy 139.325704 -225.168462) (xy 139.302053 -225.213525) (xy 139.27148 -225.254211) (xy 139.234776 -225.289466)
			(xy 139.192892 -225.318376) (xy 139.146913 -225.340193) (xy 139.098029 -225.354353) (xy 139.047508 -225.360487)
			(xy 138.996656 -225.358438) (xy 138.946792 -225.348258) (xy 138.899206 -225.330211) (xy 138.855132 -225.304765)
			(xy 138.81571 -225.272578) (xy 138.781962 -225.234484) (xy 138.754761 -225.19147) (xy 138.734813 -225.14465)
			(xy 138.722634 -225.095236) (xy 138.718539 -225.044508) (xy 138.400028 -225.044508) (xy 138.399533 -225.069115)
			(xy 138.391638 -225.117692) (xy 138.376054 -225.164373) (xy 138.353183 -225.20795) (xy 138.323618 -225.247294)
			(xy 138.288125 -225.281386) (xy 138.247622 -225.309342) (xy 138.20316 -225.33044) (xy 138.155889 -225.344132)
			(xy 138.107034 -225.350064) (xy 138.057859 -225.348083) (xy 138.00964 -225.338239) (xy 137.963624 -225.320787)
			(xy 137.921003 -225.29618) (xy 137.882882 -225.265055) (xy 137.850247 -225.228218) (xy 137.823944 -225.186622)
			(xy 137.804653 -225.141346) (xy 137.792876 -225.093562) (xy 137.788916 -225.044508) (xy 136.530588 -225.044508)
			(xy 136.530076 -225.069954) (xy 136.521912 -225.120188) (xy 136.505796 -225.168462) (xy 136.482145 -225.213525)
			(xy 136.451572 -225.254211) (xy 136.414868 -225.289466) (xy 136.372984 -225.318376) (xy 136.327005 -225.340193)
			(xy 136.278121 -225.354353) (xy 136.2276 -225.360487) (xy 136.176748 -225.358438) (xy 136.126884 -225.348258)
			(xy 136.079298 -225.330211) (xy 136.035224 -225.304765) (xy 135.995802 -225.272578) (xy 135.962054 -225.234484)
			(xy 135.934853 -225.19147) (xy 135.914905 -225.14465) (xy 135.902726 -225.095236) (xy 135.898631 -225.044508)
			(xy 135.58012 -225.044508) (xy 135.579625 -225.069115) (xy 135.57173 -225.117692) (xy 135.556146 -225.164373)
			(xy 135.533275 -225.20795) (xy 135.50371 -225.247294) (xy 135.468217 -225.281386) (xy 135.427714 -225.309342)
			(xy 135.383252 -225.33044) (xy 135.335981 -225.344132) (xy 135.287126 -225.350064) (xy 135.237951 -225.348083)
			(xy 135.189732 -225.338239) (xy 135.143716 -225.320787) (xy 135.101095 -225.29618) (xy 135.062974 -225.265055)
			(xy 135.030339 -225.228218) (xy 135.004036 -225.186622) (xy 134.984745 -225.141346) (xy 134.972968 -225.093562)
			(xy 134.969008 -225.044508) (xy 134.640066 -225.044508) (xy 134.639571 -225.069115) (xy 134.631676 -225.117692)
			(xy 134.616092 -225.164373) (xy 134.593221 -225.20795) (xy 134.563656 -225.247294) (xy 134.528163 -225.281386)
			(xy 134.48766 -225.309342) (xy 134.443198 -225.33044) (xy 134.395927 -225.344132) (xy 134.347072 -225.350064)
			(xy 134.297897 -225.348083) (xy 134.249678 -225.338239) (xy 134.203662 -225.320787) (xy 134.161041 -225.29618)
			(xy 134.12292 -225.265055) (xy 134.090285 -225.228218) (xy 134.063982 -225.186622) (xy 134.044691 -225.141346)
			(xy 134.032914 -225.093562) (xy 134.028954 -225.044508) (xy 133.700012 -225.044508) (xy 133.699517 -225.069115)
			(xy 133.691622 -225.117692) (xy 133.676038 -225.164373) (xy 133.653167 -225.20795) (xy 133.623602 -225.247294)
			(xy 133.588109 -225.281386) (xy 133.547606 -225.309342) (xy 133.503144 -225.33044) (xy 133.455873 -225.344132)
			(xy 133.407018 -225.350064) (xy 133.357843 -225.348083) (xy 133.309624 -225.338239) (xy 133.263608 -225.320787)
			(xy 133.220987 -225.29618) (xy 133.182866 -225.265055) (xy 133.150231 -225.228218) (xy 133.123928 -225.186622)
			(xy 133.104637 -225.141346) (xy 133.09286 -225.093562) (xy 133.0889 -225.044508) (xy 132.770372 -225.044508)
			(xy 132.76986 -225.069954) (xy 132.761696 -225.120188) (xy 132.74558 -225.168462) (xy 132.721929 -225.213525)
			(xy 132.691356 -225.254211) (xy 132.654652 -225.289466) (xy 132.612768 -225.318376) (xy 132.566789 -225.340193)
			(xy 132.517905 -225.354353) (xy 132.467384 -225.360487) (xy 132.416532 -225.358438) (xy 132.366668 -225.348258)
			(xy 132.319082 -225.330211) (xy 132.275008 -225.304765) (xy 132.235586 -225.272578) (xy 132.201838 -225.234484)
			(xy 132.174637 -225.19147) (xy 132.154689 -225.14465) (xy 132.14251 -225.095236) (xy 132.138415 -225.044508)
			(xy 131.820158 -225.044508) (xy 131.819663 -225.069115) (xy 131.811768 -225.117692) (xy 131.796184 -225.164373)
			(xy 131.773313 -225.20795) (xy 131.743748 -225.247294) (xy 131.708255 -225.281386) (xy 131.667752 -225.309342)
			(xy 131.62329 -225.33044) (xy 131.576019 -225.344132) (xy 131.527164 -225.350064) (xy 131.477989 -225.348083)
			(xy 131.42977 -225.338239) (xy 131.383754 -225.320787) (xy 131.341133 -225.29618) (xy 131.303012 -225.265055)
			(xy 131.270377 -225.228218) (xy 131.244074 -225.186622) (xy 131.224783 -225.141346) (xy 131.213006 -225.093562)
			(xy 131.209046 -225.044508) (xy 130.880104 -225.044508) (xy 130.879609 -225.069115) (xy 130.871714 -225.117692)
			(xy 130.85613 -225.164373) (xy 130.833259 -225.20795) (xy 130.803694 -225.247294) (xy 130.768201 -225.281386)
			(xy 130.727698 -225.309342) (xy 130.683236 -225.33044) (xy 130.635965 -225.344132) (xy 130.58711 -225.350064)
			(xy 130.537935 -225.348083) (xy 130.489716 -225.338239) (xy 130.4437 -225.320787) (xy 130.401079 -225.29618)
			(xy 130.362958 -225.265055) (xy 130.330323 -225.228218) (xy 130.30402 -225.186622) (xy 130.284729 -225.141346)
			(xy 130.272952 -225.093562) (xy 130.268992 -225.044508) (xy 129.950464 -225.044508) (xy 129.949952 -225.069954)
			(xy 129.941788 -225.120188) (xy 129.925672 -225.168462) (xy 129.902021 -225.213525) (xy 129.871448 -225.254211)
			(xy 129.834744 -225.289466) (xy 129.79286 -225.318376) (xy 129.746881 -225.340193) (xy 129.697997 -225.354353)
			(xy 129.647476 -225.360487) (xy 129.596624 -225.358438) (xy 129.54676 -225.348258) (xy 129.499174 -225.330211)
			(xy 129.4551 -225.304765) (xy 129.415678 -225.272578) (xy 129.38193 -225.234484) (xy 129.354729 -225.19147)
			(xy 129.334781 -225.14465) (xy 129.322602 -225.095236) (xy 129.318507 -225.044508) (xy 128.999996 -225.044508)
			(xy 128.999501 -225.069115) (xy 128.991606 -225.117692) (xy 128.976022 -225.164373) (xy 128.953151 -225.20795)
			(xy 128.923586 -225.247294) (xy 128.888093 -225.281386) (xy 128.84759 -225.309342) (xy 128.803128 -225.33044)
			(xy 128.755857 -225.344132) (xy 128.707002 -225.350064) (xy 128.657827 -225.348083) (xy 128.609608 -225.338239)
			(xy 128.563592 -225.320787) (xy 128.520971 -225.29618) (xy 128.48285 -225.265055) (xy 128.450215 -225.228218)
			(xy 128.423912 -225.186622) (xy 128.404621 -225.141346) (xy 128.392844 -225.093562) (xy 128.388884 -225.044508)
			(xy 128.060422 -225.044508) (xy 128.056253 -225.094833) (xy 128.043855 -225.143794) (xy 128.023568 -225.190046)
			(xy 127.995946 -225.232329) (xy 127.961741 -225.269489) (xy 127.921887 -225.300513) (xy 127.877471 -225.324554)
			(xy 127.829703 -225.340958) (xy 127.779887 -225.349276) (xy 127.754634 -225.349816) (xy 127.733063 -225.349428)
			(xy 127.690356 -225.343309) (xy 127.669544 -225.337624) (xy 127.662432 -225.335592) (xy 127.65532 -225.335592)
			(xy 127.645295 -225.336008) (xy 127.62677 -225.343674) (xy 127.61259 -225.357847) (xy 127.604914 -225.376368)
			(xy 127.60452 -225.386392) (xy 127.60452 -225.415348) (xy 127.607314 -225.423222) (xy 127.622678 -225.469546)
			(xy 127.647398 -225.563971) (xy 127.665149 -225.659951) (xy 127.675838 -225.756971) (xy 127.679406 -225.854513)
			(xy 127.679406 -225.854514) (xy 127.908553 -225.854514) (xy 127.912648 -225.803786) (xy 127.924827 -225.754372)
			(xy 127.944775 -225.707552) (xy 127.971976 -225.664538) (xy 128.005724 -225.626444) (xy 128.045146 -225.594257)
			(xy 128.08922 -225.568811) (xy 128.136806 -225.550764) (xy 128.18667 -225.540584) (xy 128.237522 -225.538535)
			(xy 128.288043 -225.544669) (xy 128.336927 -225.558829) (xy 128.382906 -225.580646) (xy 128.42479 -225.609556)
			(xy 128.461494 -225.644811) (xy 128.492067 -225.685497) (xy 128.515718 -225.73056) (xy 128.531834 -225.778834)
			(xy 128.539998 -225.829068) (xy 128.54051 -225.854514) (xy 128.848607 -225.854514) (xy 128.852702 -225.803786)
			(xy 128.864881 -225.754372) (xy 128.884829 -225.707552) (xy 128.91203 -225.664538) (xy 128.945778 -225.626444)
			(xy 128.9852 -225.594257) (xy 129.029274 -225.568811) (xy 129.07686 -225.550764) (xy 129.126724 -225.540584)
			(xy 129.177576 -225.538535) (xy 129.228097 -225.544669) (xy 129.276981 -225.558829) (xy 129.32296 -225.580646)
			(xy 129.364844 -225.609556) (xy 129.401548 -225.644811) (xy 129.432121 -225.685497) (xy 129.455772 -225.73056)
			(xy 129.471888 -225.778834) (xy 129.480052 -225.829068) (xy 129.480564 -225.854514) (xy 129.798838 -225.854514)
			(xy 129.802798 -225.80546) (xy 129.814575 -225.757676) (xy 129.833866 -225.7124) (xy 129.860169 -225.670804)
			(xy 129.892804 -225.633967) (xy 129.930925 -225.602842) (xy 129.973546 -225.578235) (xy 130.019562 -225.560783)
			(xy 130.067781 -225.550939) (xy 130.116956 -225.548958) (xy 130.165811 -225.55489) (xy 130.213082 -225.568582)
			(xy 130.257544 -225.58968) (xy 130.298047 -225.617636) (xy 130.33354 -225.651728) (xy 130.363105 -225.691072)
			(xy 130.385976 -225.734649) (xy 130.40156 -225.78133) (xy 130.409455 -225.829907) (xy 130.40995 -225.854514)
			(xy 130.728461 -225.854514) (xy 130.732556 -225.803786) (xy 130.744735 -225.754372) (xy 130.764683 -225.707552)
			(xy 130.791884 -225.664538) (xy 130.825632 -225.626444) (xy 130.865054 -225.594257) (xy 130.909128 -225.568811)
			(xy 130.956714 -225.550764) (xy 131.006578 -225.540584) (xy 131.05743 -225.538535) (xy 131.107951 -225.544669)
			(xy 131.156835 -225.558829) (xy 131.202814 -225.580646) (xy 131.244698 -225.609556) (xy 131.281402 -225.644811)
			(xy 131.311975 -225.685497) (xy 131.335626 -225.73056) (xy 131.351742 -225.778834) (xy 131.359906 -225.829068)
			(xy 131.360418 -225.854514) (xy 131.678946 -225.854514) (xy 131.682906 -225.80546) (xy 131.694683 -225.757676)
			(xy 131.713974 -225.7124) (xy 131.740277 -225.670804) (xy 131.772912 -225.633967) (xy 131.811033 -225.602842)
			(xy 131.853654 -225.578235) (xy 131.89967 -225.560783) (xy 131.947889 -225.550939) (xy 131.997064 -225.548958)
			(xy 132.045919 -225.55489) (xy 132.09319 -225.568582) (xy 132.137652 -225.58968) (xy 132.178155 -225.617636)
			(xy 132.213648 -225.651728) (xy 132.243213 -225.691072) (xy 132.266084 -225.734649) (xy 132.281668 -225.78133)
			(xy 132.289563 -225.829907) (xy 132.290058 -225.854514) (xy 132.608569 -225.854514) (xy 132.612664 -225.803786)
			(xy 132.624843 -225.754372) (xy 132.644791 -225.707552) (xy 132.671992 -225.664538) (xy 132.70574 -225.626444)
			(xy 132.745162 -225.594257) (xy 132.789236 -225.568811) (xy 132.836822 -225.550764) (xy 132.886686 -225.540584)
			(xy 132.937538 -225.538535) (xy 132.988059 -225.544669) (xy 133.036943 -225.558829) (xy 133.082922 -225.580646)
			(xy 133.124806 -225.609556) (xy 133.16151 -225.644811) (xy 133.192083 -225.685497) (xy 133.215734 -225.73056)
			(xy 133.23185 -225.778834) (xy 133.240014 -225.829068) (xy 133.240526 -225.854514) (xy 133.559054 -225.854514)
			(xy 133.563014 -225.80546) (xy 133.574791 -225.757676) (xy 133.594082 -225.7124) (xy 133.620385 -225.670804)
			(xy 133.65302 -225.633967) (xy 133.691141 -225.602842) (xy 133.733762 -225.578235) (xy 133.779778 -225.560783)
			(xy 133.827997 -225.550939) (xy 133.877172 -225.548958) (xy 133.926027 -225.55489) (xy 133.973298 -225.568582)
			(xy 134.01776 -225.58968) (xy 134.058263 -225.617636) (xy 134.093756 -225.651728) (xy 134.123321 -225.691072)
			(xy 134.146192 -225.734649) (xy 134.161776 -225.78133) (xy 134.169671 -225.829907) (xy 134.170166 -225.854514)
			(xy 134.488423 -225.854514) (xy 134.492518 -225.803786) (xy 134.504697 -225.754372) (xy 134.524645 -225.707552)
			(xy 134.551846 -225.664538) (xy 134.585594 -225.626444) (xy 134.625016 -225.594257) (xy 134.66909 -225.568811)
			(xy 134.716676 -225.550764) (xy 134.76654 -225.540584) (xy 134.817392 -225.538535) (xy 134.867913 -225.544669)
			(xy 134.916797 -225.558829) (xy 134.962776 -225.580646) (xy 135.00466 -225.609556) (xy 135.041364 -225.644811)
			(xy 135.071937 -225.685497) (xy 135.095588 -225.73056) (xy 135.111704 -225.778834) (xy 135.119868 -225.829068)
			(xy 135.12038 -225.854514) (xy 135.428477 -225.854514) (xy 135.432572 -225.803786) (xy 135.444751 -225.754372)
			(xy 135.464699 -225.707552) (xy 135.4919 -225.664538) (xy 135.525648 -225.626444) (xy 135.56507 -225.594257)
			(xy 135.609144 -225.568811) (xy 135.65673 -225.550764) (xy 135.706594 -225.540584) (xy 135.757446 -225.538535)
			(xy 135.807967 -225.544669) (xy 135.856851 -225.558829) (xy 135.90283 -225.580646) (xy 135.944714 -225.609556)
			(xy 135.981418 -225.644811) (xy 136.011991 -225.685497) (xy 136.035642 -225.73056) (xy 136.051758 -225.778834)
			(xy 136.059922 -225.829068) (xy 136.060434 -225.854514) (xy 136.378962 -225.854514) (xy 136.382922 -225.80546)
			(xy 136.394699 -225.757676) (xy 136.41399 -225.7124) (xy 136.440293 -225.670804) (xy 136.472928 -225.633967)
			(xy 136.511049 -225.602842) (xy 136.55367 -225.578235) (xy 136.599686 -225.560783) (xy 136.647905 -225.550939)
			(xy 136.69708 -225.548958) (xy 136.745935 -225.55489) (xy 136.793206 -225.568582) (xy 136.837668 -225.58968)
			(xy 136.878171 -225.617636) (xy 136.913664 -225.651728) (xy 136.943229 -225.691072) (xy 136.9661 -225.734649)
			(xy 136.981684 -225.78133) (xy 136.989579 -225.829907) (xy 136.990074 -225.854514) (xy 137.308585 -225.854514)
			(xy 137.31268 -225.803786) (xy 137.324859 -225.754372) (xy 137.344807 -225.707552) (xy 137.372008 -225.664538)
			(xy 137.405756 -225.626444) (xy 137.445178 -225.594257) (xy 137.489252 -225.568811) (xy 137.536838 -225.550764)
			(xy 137.586702 -225.540584) (xy 137.637554 -225.538535) (xy 137.688075 -225.544669) (xy 137.736959 -225.558829)
			(xy 137.782938 -225.580646) (xy 137.824822 -225.609556) (xy 137.861526 -225.644811) (xy 137.892099 -225.685497)
			(xy 137.91575 -225.73056) (xy 137.931866 -225.778834) (xy 137.94003 -225.829068) (xy 137.940542 -225.854514)
			(xy 138.25907 -225.854514) (xy 138.26303 -225.80546) (xy 138.274807 -225.757676) (xy 138.294098 -225.7124)
			(xy 138.320401 -225.670804) (xy 138.353036 -225.633967) (xy 138.391157 -225.602842) (xy 138.433778 -225.578235)
			(xy 138.479794 -225.560783) (xy 138.528013 -225.550939) (xy 138.577188 -225.548958) (xy 138.626043 -225.55489)
			(xy 138.673314 -225.568582) (xy 138.717776 -225.58968) (xy 138.758279 -225.617636) (xy 138.793772 -225.651728)
			(xy 138.823337 -225.691072) (xy 138.846208 -225.734649) (xy 138.861792 -225.78133) (xy 138.869687 -225.829907)
			(xy 138.870182 -225.854514) (xy 139.188439 -225.854514) (xy 139.192534 -225.803786) (xy 139.204713 -225.754372)
			(xy 139.224661 -225.707552) (xy 139.251862 -225.664538) (xy 139.28561 -225.626444) (xy 139.325032 -225.594257)
			(xy 139.369106 -225.568811) (xy 139.416692 -225.550764) (xy 139.466556 -225.540584) (xy 139.517408 -225.538535)
			(xy 139.567929 -225.544669) (xy 139.616813 -225.558829) (xy 139.662792 -225.580646) (xy 139.704676 -225.609556)
			(xy 139.74138 -225.644811) (xy 139.771953 -225.685497) (xy 139.795604 -225.73056) (xy 139.81172 -225.778834)
			(xy 139.819884 -225.829068) (xy 139.820396 -225.854514) (xy 140.138924 -225.854514) (xy 140.142884 -225.80546)
			(xy 140.154661 -225.757676) (xy 140.173952 -225.7124) (xy 140.200255 -225.670804) (xy 140.23289 -225.633967)
			(xy 140.271011 -225.602842) (xy 140.313632 -225.578235) (xy 140.359648 -225.560783) (xy 140.407867 -225.550939)
			(xy 140.457042 -225.548958) (xy 140.505897 -225.55489) (xy 140.553168 -225.568582) (xy 140.59763 -225.58968)
			(xy 140.638133 -225.617636) (xy 140.673626 -225.651728) (xy 140.703191 -225.691072) (xy 140.726062 -225.734649)
			(xy 140.741646 -225.78133) (xy 140.749541 -225.829907) (xy 140.750036 -225.854514) (xy 141.068547 -225.854514)
			(xy 141.072642 -225.803786) (xy 141.084821 -225.754372) (xy 141.104769 -225.707552) (xy 141.13197 -225.664538)
			(xy 141.165718 -225.626444) (xy 141.20514 -225.594257) (xy 141.249214 -225.568811) (xy 141.2968 -225.550764)
			(xy 141.346664 -225.540584) (xy 141.397516 -225.538535) (xy 141.448037 -225.544669) (xy 141.496921 -225.558829)
			(xy 141.5429 -225.580646) (xy 141.584784 -225.609556) (xy 141.621488 -225.644811) (xy 141.652061 -225.685497)
			(xy 141.675712 -225.73056) (xy 141.691828 -225.778834) (xy 141.699992 -225.829068) (xy 141.700504 -225.854514)
			(xy 142.008601 -225.854514) (xy 142.012696 -225.803786) (xy 142.024875 -225.754372) (xy 142.044823 -225.707552)
			(xy 142.072024 -225.664538) (xy 142.105772 -225.626444) (xy 142.145194 -225.594257) (xy 142.189268 -225.568811)
			(xy 142.236854 -225.550764) (xy 142.286718 -225.540584) (xy 142.33757 -225.538535) (xy 142.388091 -225.544669)
			(xy 142.436975 -225.558829) (xy 142.482954 -225.580646) (xy 142.524838 -225.609556) (xy 142.561542 -225.644811)
			(xy 142.592115 -225.685497) (xy 142.615766 -225.73056) (xy 142.631882 -225.778834) (xy 142.640046 -225.829068)
			(xy 142.640558 -225.854514) (xy 142.958832 -225.854514) (xy 142.962792 -225.80546) (xy 142.974569 -225.757676)
			(xy 142.99386 -225.7124) (xy 143.020163 -225.670804) (xy 143.052798 -225.633967) (xy 143.090919 -225.602842)
			(xy 143.13354 -225.578235) (xy 143.179556 -225.560783) (xy 143.227775 -225.550939) (xy 143.27695 -225.548958)
			(xy 143.325805 -225.55489) (xy 143.373076 -225.568582) (xy 143.417538 -225.58968) (xy 143.458041 -225.617636)
			(xy 143.493534 -225.651728) (xy 143.523099 -225.691072) (xy 143.54597 -225.734649) (xy 143.561554 -225.78133)
			(xy 143.569449 -225.829907) (xy 143.569944 -225.854514) (xy 144.83894 -225.854514) (xy 144.8429 -225.80546)
			(xy 144.854677 -225.757676) (xy 144.873968 -225.7124) (xy 144.900271 -225.670804) (xy 144.932906 -225.633967)
			(xy 144.971027 -225.602842) (xy 145.013648 -225.578235) (xy 145.059664 -225.560783) (xy 145.107883 -225.550939)
			(xy 145.157058 -225.548958) (xy 145.205913 -225.55489) (xy 145.253184 -225.568582) (xy 145.297646 -225.58968)
			(xy 145.338149 -225.617636) (xy 145.373642 -225.651728) (xy 145.403207 -225.691072) (xy 145.426078 -225.734649)
			(xy 145.441662 -225.78133) (xy 145.449557 -225.829907) (xy 145.450052 -225.854514) (xy 145.449557 -225.879121)
			(xy 145.441662 -225.927698) (xy 145.426078 -225.974379) (xy 145.403207 -226.017956) (xy 145.373642 -226.0573)
			(xy 145.338149 -226.091392) (xy 145.297646 -226.119348) (xy 145.253184 -226.140446) (xy 145.205913 -226.154138)
			(xy 145.157058 -226.16007) (xy 145.107883 -226.158089) (xy 145.059664 -226.148245) (xy 145.013648 -226.130793)
			(xy 144.971027 -226.106186) (xy 144.932906 -226.075061) (xy 144.900271 -226.038224) (xy 144.873968 -225.996628)
			(xy 144.854677 -225.951352) (xy 144.8429 -225.903568) (xy 144.83894 -225.854514) (xy 143.569944 -225.854514)
			(xy 143.569449 -225.879121) (xy 143.561554 -225.927698) (xy 143.54597 -225.974379) (xy 143.523099 -226.017956)
			(xy 143.493534 -226.0573) (xy 143.458041 -226.091392) (xy 143.417538 -226.119348) (xy 143.373076 -226.140446)
			(xy 143.325805 -226.154138) (xy 143.27695 -226.16007) (xy 143.227775 -226.158089) (xy 143.179556 -226.148245)
			(xy 143.13354 -226.130793) (xy 143.090919 -226.106186) (xy 143.052798 -226.075061) (xy 143.020163 -226.038224)
			(xy 142.99386 -225.996628) (xy 142.974569 -225.951352) (xy 142.962792 -225.903568) (xy 142.958832 -225.854514)
			(xy 142.640558 -225.854514) (xy 142.640046 -225.87996) (xy 142.631882 -225.930194) (xy 142.615766 -225.978468)
			(xy 142.592115 -226.023531) (xy 142.561542 -226.064217) (xy 142.524838 -226.099472) (xy 142.482954 -226.128382)
			(xy 142.436975 -226.150199) (xy 142.388091 -226.164359) (xy 142.33757 -226.170493) (xy 142.286718 -226.168444)
			(xy 142.236854 -226.158264) (xy 142.189268 -226.140217) (xy 142.145194 -226.114771) (xy 142.105772 -226.082584)
			(xy 142.072024 -226.04449) (xy 142.044823 -226.001476) (xy 142.024875 -225.954656) (xy 142.012696 -225.905242)
			(xy 142.008601 -225.854514) (xy 141.700504 -225.854514) (xy 141.699992 -225.87996) (xy 141.691828 -225.930194)
			(xy 141.675712 -225.978468) (xy 141.652061 -226.023531) (xy 141.621488 -226.064217) (xy 141.584784 -226.099472)
			(xy 141.5429 -226.128382) (xy 141.496921 -226.150199) (xy 141.448037 -226.164359) (xy 141.397516 -226.170493)
			(xy 141.346664 -226.168444) (xy 141.2968 -226.158264) (xy 141.249214 -226.140217) (xy 141.20514 -226.114771)
			(xy 141.165718 -226.082584) (xy 141.13197 -226.04449) (xy 141.104769 -226.001476) (xy 141.084821 -225.954656)
			(xy 141.072642 -225.905242) (xy 141.068547 -225.854514) (xy 140.750036 -225.854514) (xy 140.749541 -225.879121)
			(xy 140.741646 -225.927698) (xy 140.726062 -225.974379) (xy 140.703191 -226.017956) (xy 140.673626 -226.0573)
			(xy 140.638133 -226.091392) (xy 140.59763 -226.119348) (xy 140.553168 -226.140446) (xy 140.505897 -226.154138)
			(xy 140.457042 -226.16007) (xy 140.407867 -226.158089) (xy 140.359648 -226.148245) (xy 140.313632 -226.130793)
			(xy 140.271011 -226.106186) (xy 140.23289 -226.075061) (xy 140.200255 -226.038224) (xy 140.173952 -225.996628)
			(xy 140.154661 -225.951352) (xy 140.142884 -225.903568) (xy 140.138924 -225.854514) (xy 139.820396 -225.854514)
			(xy 139.819884 -225.87996) (xy 139.81172 -225.930194) (xy 139.795604 -225.978468) (xy 139.771953 -226.023531)
			(xy 139.74138 -226.064217) (xy 139.704676 -226.099472) (xy 139.662792 -226.128382) (xy 139.616813 -226.150199)
			(xy 139.567929 -226.164359) (xy 139.517408 -226.170493) (xy 139.466556 -226.168444) (xy 139.416692 -226.158264)
			(xy 139.369106 -226.140217) (xy 139.325032 -226.114771) (xy 139.28561 -226.082584) (xy 139.251862 -226.04449)
			(xy 139.224661 -226.001476) (xy 139.204713 -225.954656) (xy 139.192534 -225.905242) (xy 139.188439 -225.854514)
			(xy 138.870182 -225.854514) (xy 138.869687 -225.879121) (xy 138.861792 -225.927698) (xy 138.846208 -225.974379)
			(xy 138.823337 -226.017956) (xy 138.793772 -226.0573) (xy 138.758279 -226.091392) (xy 138.717776 -226.119348)
			(xy 138.673314 -226.140446) (xy 138.626043 -226.154138) (xy 138.577188 -226.16007) (xy 138.528013 -226.158089)
			(xy 138.479794 -226.148245) (xy 138.433778 -226.130793) (xy 138.391157 -226.106186) (xy 138.353036 -226.075061)
			(xy 138.320401 -226.038224) (xy 138.294098 -225.996628) (xy 138.274807 -225.951352) (xy 138.26303 -225.903568)
			(xy 138.25907 -225.854514) (xy 137.940542 -225.854514) (xy 137.94003 -225.87996) (xy 137.931866 -225.930194)
			(xy 137.91575 -225.978468) (xy 137.892099 -226.023531) (xy 137.861526 -226.064217) (xy 137.824822 -226.099472)
			(xy 137.782938 -226.128382) (xy 137.736959 -226.150199) (xy 137.688075 -226.164359) (xy 137.637554 -226.170493)
			(xy 137.586702 -226.168444) (xy 137.536838 -226.158264) (xy 137.489252 -226.140217) (xy 137.445178 -226.114771)
			(xy 137.405756 -226.082584) (xy 137.372008 -226.04449) (xy 137.344807 -226.001476) (xy 137.324859 -225.954656)
			(xy 137.31268 -225.905242) (xy 137.308585 -225.854514) (xy 136.990074 -225.854514) (xy 136.989579 -225.879121)
			(xy 136.981684 -225.927698) (xy 136.9661 -225.974379) (xy 136.943229 -226.017956) (xy 136.913664 -226.0573)
			(xy 136.878171 -226.091392) (xy 136.837668 -226.119348) (xy 136.793206 -226.140446) (xy 136.745935 -226.154138)
			(xy 136.69708 -226.16007) (xy 136.647905 -226.158089) (xy 136.599686 -226.148245) (xy 136.55367 -226.130793)
			(xy 136.511049 -226.106186) (xy 136.472928 -226.075061) (xy 136.440293 -226.038224) (xy 136.41399 -225.996628)
			(xy 136.394699 -225.951352) (xy 136.382922 -225.903568) (xy 136.378962 -225.854514) (xy 136.060434 -225.854514)
			(xy 136.059922 -225.87996) (xy 136.051758 -225.930194) (xy 136.035642 -225.978468) (xy 136.011991 -226.023531)
			(xy 135.981418 -226.064217) (xy 135.944714 -226.099472) (xy 135.90283 -226.128382) (xy 135.856851 -226.150199)
			(xy 135.807967 -226.164359) (xy 135.757446 -226.170493) (xy 135.706594 -226.168444) (xy 135.65673 -226.158264)
			(xy 135.609144 -226.140217) (xy 135.56507 -226.114771) (xy 135.525648 -226.082584) (xy 135.4919 -226.04449)
			(xy 135.464699 -226.001476) (xy 135.444751 -225.954656) (xy 135.432572 -225.905242) (xy 135.428477 -225.854514)
			(xy 135.12038 -225.854514) (xy 135.119868 -225.87996) (xy 135.111704 -225.930194) (xy 135.095588 -225.978468)
			(xy 135.071937 -226.023531) (xy 135.041364 -226.064217) (xy 135.00466 -226.099472) (xy 134.962776 -226.128382)
			(xy 134.916797 -226.150199) (xy 134.867913 -226.164359) (xy 134.817392 -226.170493) (xy 134.76654 -226.168444)
			(xy 134.716676 -226.158264) (xy 134.66909 -226.140217) (xy 134.625016 -226.114771) (xy 134.585594 -226.082584)
			(xy 134.551846 -226.04449) (xy 134.524645 -226.001476) (xy 134.504697 -225.954656) (xy 134.492518 -225.905242)
			(xy 134.488423 -225.854514) (xy 134.170166 -225.854514) (xy 134.169671 -225.879121) (xy 134.161776 -225.927698)
			(xy 134.146192 -225.974379) (xy 134.123321 -226.017956) (xy 134.093756 -226.0573) (xy 134.058263 -226.091392)
			(xy 134.01776 -226.119348) (xy 133.973298 -226.140446) (xy 133.926027 -226.154138) (xy 133.877172 -226.16007)
			(xy 133.827997 -226.158089) (xy 133.779778 -226.148245) (xy 133.733762 -226.130793) (xy 133.691141 -226.106186)
			(xy 133.65302 -226.075061) (xy 133.620385 -226.038224) (xy 133.594082 -225.996628) (xy 133.574791 -225.951352)
			(xy 133.563014 -225.903568) (xy 133.559054 -225.854514) (xy 133.240526 -225.854514) (xy 133.240014 -225.87996)
			(xy 133.23185 -225.930194) (xy 133.215734 -225.978468) (xy 133.192083 -226.023531) (xy 133.16151 -226.064217)
			(xy 133.124806 -226.099472) (xy 133.082922 -226.128382) (xy 133.036943 -226.150199) (xy 132.988059 -226.164359)
			(xy 132.937538 -226.170493) (xy 132.886686 -226.168444) (xy 132.836822 -226.158264) (xy 132.789236 -226.140217)
			(xy 132.745162 -226.114771) (xy 132.70574 -226.082584) (xy 132.671992 -226.04449) (xy 132.644791 -226.001476)
			(xy 132.624843 -225.954656) (xy 132.612664 -225.905242) (xy 132.608569 -225.854514) (xy 132.290058 -225.854514)
			(xy 132.289563 -225.879121) (xy 132.281668 -225.927698) (xy 132.266084 -225.974379) (xy 132.243213 -226.017956)
			(xy 132.213648 -226.0573) (xy 132.178155 -226.091392) (xy 132.137652 -226.119348) (xy 132.09319 -226.140446)
			(xy 132.045919 -226.154138) (xy 131.997064 -226.16007) (xy 131.947889 -226.158089) (xy 131.89967 -226.148245)
			(xy 131.853654 -226.130793) (xy 131.811033 -226.106186) (xy 131.772912 -226.075061) (xy 131.740277 -226.038224)
			(xy 131.713974 -225.996628) (xy 131.694683 -225.951352) (xy 131.682906 -225.903568) (xy 131.678946 -225.854514)
			(xy 131.360418 -225.854514) (xy 131.359906 -225.87996) (xy 131.351742 -225.930194) (xy 131.335626 -225.978468)
			(xy 131.311975 -226.023531) (xy 131.281402 -226.064217) (xy 131.244698 -226.099472) (xy 131.202814 -226.128382)
			(xy 131.156835 -226.150199) (xy 131.107951 -226.164359) (xy 131.05743 -226.170493) (xy 131.006578 -226.168444)
			(xy 130.956714 -226.158264) (xy 130.909128 -226.140217) (xy 130.865054 -226.114771) (xy 130.825632 -226.082584)
			(xy 130.791884 -226.04449) (xy 130.764683 -226.001476) (xy 130.744735 -225.954656) (xy 130.732556 -225.905242)
			(xy 130.728461 -225.854514) (xy 130.40995 -225.854514) (xy 130.409455 -225.879121) (xy 130.40156 -225.927698)
			(xy 130.385976 -225.974379) (xy 130.363105 -226.017956) (xy 130.33354 -226.0573) (xy 130.298047 -226.091392)
			(xy 130.257544 -226.119348) (xy 130.213082 -226.140446) (xy 130.165811 -226.154138) (xy 130.116956 -226.16007)
			(xy 130.067781 -226.158089) (xy 130.019562 -226.148245) (xy 129.973546 -226.130793) (xy 129.930925 -226.106186)
			(xy 129.892804 -226.075061) (xy 129.860169 -226.038224) (xy 129.833866 -225.996628) (xy 129.814575 -225.951352)
			(xy 129.802798 -225.903568) (xy 129.798838 -225.854514) (xy 129.480564 -225.854514) (xy 129.480052 -225.87996)
			(xy 129.471888 -225.930194) (xy 129.455772 -225.978468) (xy 129.432121 -226.023531) (xy 129.401548 -226.064217)
			(xy 129.364844 -226.099472) (xy 129.32296 -226.128382) (xy 129.276981 -226.150199) (xy 129.228097 -226.164359)
			(xy 129.177576 -226.170493) (xy 129.126724 -226.168444) (xy 129.07686 -226.158264) (xy 129.029274 -226.140217)
			(xy 128.9852 -226.114771) (xy 128.945778 -226.082584) (xy 128.91203 -226.04449) (xy 128.884829 -226.001476)
			(xy 128.864881 -225.954656) (xy 128.852702 -225.905242) (xy 128.848607 -225.854514) (xy 128.54051 -225.854514)
			(xy 128.539998 -225.87996) (xy 128.531834 -225.930194) (xy 128.515718 -225.978468) (xy 128.492067 -226.023531)
			(xy 128.461494 -226.064217) (xy 128.42479 -226.099472) (xy 128.382906 -226.128382) (xy 128.336927 -226.150199)
			(xy 128.288043 -226.164359) (xy 128.237522 -226.170493) (xy 128.18667 -226.168444) (xy 128.136806 -226.158264)
			(xy 128.08922 -226.140217) (xy 128.045146 -226.114771) (xy 128.005724 -226.082584) (xy 127.971976 -226.04449)
			(xy 127.944775 -226.001476) (xy 127.924827 -225.954656) (xy 127.912648 -225.905242) (xy 127.908553 -225.854514)
			(xy 127.679406 -225.854514) (xy 127.675836 -225.952055) (xy 127.665145 -226.049075) (xy 127.647392 -226.145054)
			(xy 127.622671 -226.239479) (xy 127.607314 -226.285806) (xy 127.60452 -226.29368) (xy 127.60452 -226.311968)
			(xy 127.604935 -226.321992) (xy 127.6126 -226.340516) (xy 127.626774 -226.354694) (xy 127.645296 -226.362363)
			(xy 127.65532 -226.362768) (xy 127.662432 -226.362768) (xy 127.669036 -226.360736) (xy 127.690005 -226.355238)
			(xy 127.732958 -226.349381) (xy 127.754634 -226.349052) (xy 127.77942 -226.349541) (xy 127.828382 -226.357301)
			(xy 127.875527 -226.372623) (xy 127.919695 -226.395132) (xy 127.959798 -226.424273) (xy 127.994849 -226.459328)
			(xy 128.023986 -226.499434) (xy 128.04649 -226.543605) (xy 128.061807 -226.590751) (xy 128.069562 -226.639714)
			(xy 128.069562 -226.66452) (xy 128.388884 -226.66452) (xy 128.392844 -226.615466) (xy 128.404621 -226.567682)
			(xy 128.423912 -226.522406) (xy 128.450215 -226.48081) (xy 128.48285 -226.443973) (xy 128.520971 -226.412848)
			(xy 128.563592 -226.388241) (xy 128.609608 -226.370789) (xy 128.657827 -226.360945) (xy 128.707002 -226.358964)
			(xy 128.755857 -226.364896) (xy 128.803128 -226.378588) (xy 128.84759 -226.399686) (xy 128.888093 -226.427642)
			(xy 128.923586 -226.461734) (xy 128.953151 -226.501078) (xy 128.976022 -226.544655) (xy 128.991606 -226.591336)
			(xy 128.999501 -226.639913) (xy 128.999996 -226.66452) (xy 129.318507 -226.66452) (xy 129.322602 -226.613792)
			(xy 129.334781 -226.564378) (xy 129.354729 -226.517558) (xy 129.38193 -226.474544) (xy 129.415678 -226.43645)
			(xy 129.4551 -226.404263) (xy 129.499174 -226.378817) (xy 129.54676 -226.36077) (xy 129.596624 -226.35059)
			(xy 129.647476 -226.348541) (xy 129.697997 -226.354675) (xy 129.746881 -226.368835) (xy 129.79286 -226.390652)
			(xy 129.834744 -226.419562) (xy 129.871448 -226.454817) (xy 129.902021 -226.495503) (xy 129.925672 -226.540566)
			(xy 129.941788 -226.58884) (xy 129.949952 -226.639074) (xy 129.950464 -226.66452) (xy 130.268992 -226.66452)
			(xy 130.272952 -226.615466) (xy 130.284729 -226.567682) (xy 130.30402 -226.522406) (xy 130.330323 -226.48081)
			(xy 130.362958 -226.443973) (xy 130.401079 -226.412848) (xy 130.4437 -226.388241) (xy 130.489716 -226.370789)
			(xy 130.537935 -226.360945) (xy 130.58711 -226.358964) (xy 130.635965 -226.364896) (xy 130.683236 -226.378588)
			(xy 130.727698 -226.399686) (xy 130.768201 -226.427642) (xy 130.803694 -226.461734) (xy 130.833259 -226.501078)
			(xy 130.85613 -226.544655) (xy 130.871714 -226.591336) (xy 130.879609 -226.639913) (xy 130.880104 -226.66452)
			(xy 131.198615 -226.66452) (xy 131.20271 -226.613792) (xy 131.214889 -226.564378) (xy 131.234837 -226.517558)
			(xy 131.262038 -226.474544) (xy 131.295786 -226.43645) (xy 131.335208 -226.404263) (xy 131.379282 -226.378817)
			(xy 131.426868 -226.36077) (xy 131.476732 -226.35059) (xy 131.527584 -226.348541) (xy 131.578105 -226.354675)
			(xy 131.626989 -226.368835) (xy 131.672968 -226.390652) (xy 131.714852 -226.419562) (xy 131.751556 -226.454817)
			(xy 131.782129 -226.495503) (xy 131.80578 -226.540566) (xy 131.821896 -226.58884) (xy 131.83006 -226.639074)
			(xy 131.830572 -226.66452) (xy 132.138415 -226.66452) (xy 132.14251 -226.613792) (xy 132.154689 -226.564378)
			(xy 132.174637 -226.517558) (xy 132.201838 -226.474544) (xy 132.235586 -226.43645) (xy 132.275008 -226.404263)
			(xy 132.319082 -226.378817) (xy 132.366668 -226.36077) (xy 132.416532 -226.35059) (xy 132.467384 -226.348541)
			(xy 132.517905 -226.354675) (xy 132.566789 -226.368835) (xy 132.612768 -226.390652) (xy 132.654652 -226.419562)
			(xy 132.691356 -226.454817) (xy 132.721929 -226.495503) (xy 132.74558 -226.540566) (xy 132.761696 -226.58884)
			(xy 132.76986 -226.639074) (xy 132.770372 -226.66452) (xy 133.0889 -226.66452) (xy 133.09286 -226.615466)
			(xy 133.104637 -226.567682) (xy 133.123928 -226.522406) (xy 133.150231 -226.48081) (xy 133.182866 -226.443973)
			(xy 133.220987 -226.412848) (xy 133.263608 -226.388241) (xy 133.309624 -226.370789) (xy 133.357843 -226.360945)
			(xy 133.407018 -226.358964) (xy 133.455873 -226.364896) (xy 133.503144 -226.378588) (xy 133.547606 -226.399686)
			(xy 133.588109 -226.427642) (xy 133.623602 -226.461734) (xy 133.653167 -226.501078) (xy 133.676038 -226.544655)
			(xy 133.691622 -226.591336) (xy 133.699517 -226.639913) (xy 133.700012 -226.66452) (xy 134.018523 -226.66452)
			(xy 134.022618 -226.613792) (xy 134.034797 -226.564378) (xy 134.054745 -226.517558) (xy 134.081946 -226.474544)
			(xy 134.115694 -226.43645) (xy 134.155116 -226.404263) (xy 134.19919 -226.378817) (xy 134.246776 -226.36077)
			(xy 134.29664 -226.35059) (xy 134.347492 -226.348541) (xy 134.398013 -226.354675) (xy 134.446897 -226.368835)
			(xy 134.492876 -226.390652) (xy 134.53476 -226.419562) (xy 134.571464 -226.454817) (xy 134.602037 -226.495503)
			(xy 134.625688 -226.540566) (xy 134.641804 -226.58884) (xy 134.649968 -226.639074) (xy 134.65048 -226.66452)
			(xy 134.969008 -226.66452) (xy 134.972968 -226.615466) (xy 134.984745 -226.567682) (xy 135.004036 -226.522406)
			(xy 135.030339 -226.48081) (xy 135.062974 -226.443973) (xy 135.101095 -226.412848) (xy 135.143716 -226.388241)
			(xy 135.189732 -226.370789) (xy 135.237951 -226.360945) (xy 135.287126 -226.358964) (xy 135.335981 -226.364896)
			(xy 135.383252 -226.378588) (xy 135.427714 -226.399686) (xy 135.468217 -226.427642) (xy 135.50371 -226.461734)
			(xy 135.533275 -226.501078) (xy 135.556146 -226.544655) (xy 135.57173 -226.591336) (xy 135.579625 -226.639913)
			(xy 135.58012 -226.66452) (xy 135.898631 -226.66452) (xy 135.902726 -226.613792) (xy 135.914905 -226.564378)
			(xy 135.934853 -226.517558) (xy 135.962054 -226.474544) (xy 135.995802 -226.43645) (xy 136.035224 -226.404263)
			(xy 136.079298 -226.378817) (xy 136.126884 -226.36077) (xy 136.176748 -226.35059) (xy 136.2276 -226.348541)
			(xy 136.278121 -226.354675) (xy 136.327005 -226.368835) (xy 136.372984 -226.390652) (xy 136.414868 -226.419562)
			(xy 136.451572 -226.454817) (xy 136.482145 -226.495503) (xy 136.505796 -226.540566) (xy 136.521912 -226.58884)
			(xy 136.530076 -226.639074) (xy 136.530588 -226.66452) (xy 136.848862 -226.66452) (xy 136.852822 -226.615466)
			(xy 136.864599 -226.567682) (xy 136.88389 -226.522406) (xy 136.910193 -226.48081) (xy 136.942828 -226.443973)
			(xy 136.980949 -226.412848) (xy 137.02357 -226.388241) (xy 137.069586 -226.370789) (xy 137.117805 -226.360945)
			(xy 137.16698 -226.358964) (xy 137.215835 -226.364896) (xy 137.263106 -226.378588) (xy 137.307568 -226.399686)
			(xy 137.348071 -226.427642) (xy 137.383564 -226.461734) (xy 137.413129 -226.501078) (xy 137.436 -226.544655)
			(xy 137.451584 -226.591336) (xy 137.459479 -226.639913) (xy 137.459974 -226.66452) (xy 137.778485 -226.66452)
			(xy 137.78258 -226.613792) (xy 137.794759 -226.564378) (xy 137.814707 -226.517558) (xy 137.841908 -226.474544)
			(xy 137.875656 -226.43645) (xy 137.915078 -226.404263) (xy 137.959152 -226.378817) (xy 138.006738 -226.36077)
			(xy 138.056602 -226.35059) (xy 138.107454 -226.348541) (xy 138.157975 -226.354675) (xy 138.206859 -226.368835)
			(xy 138.252838 -226.390652) (xy 138.294722 -226.419562) (xy 138.331426 -226.454817) (xy 138.361999 -226.495503)
			(xy 138.38565 -226.540566) (xy 138.401766 -226.58884) (xy 138.40993 -226.639074) (xy 138.410442 -226.66452)
			(xy 138.718539 -226.66452) (xy 138.722634 -226.613792) (xy 138.734813 -226.564378) (xy 138.754761 -226.517558)
			(xy 138.781962 -226.474544) (xy 138.81571 -226.43645) (xy 138.855132 -226.404263) (xy 138.899206 -226.378817)
			(xy 138.946792 -226.36077) (xy 138.996656 -226.35059) (xy 139.047508 -226.348541) (xy 139.098029 -226.354675)
			(xy 139.146913 -226.368835) (xy 139.192892 -226.390652) (xy 139.234776 -226.419562) (xy 139.27148 -226.454817)
			(xy 139.302053 -226.495503) (xy 139.325704 -226.540566) (xy 139.34182 -226.58884) (xy 139.349984 -226.639074)
			(xy 139.350496 -226.66452) (xy 139.669024 -226.66452) (xy 139.672984 -226.615466) (xy 139.684761 -226.567682)
			(xy 139.704052 -226.522406) (xy 139.730355 -226.48081) (xy 139.76299 -226.443973) (xy 139.801111 -226.412848)
			(xy 139.843732 -226.388241) (xy 139.889748 -226.370789) (xy 139.937967 -226.360945) (xy 139.987142 -226.358964)
			(xy 140.035997 -226.364896) (xy 140.083268 -226.378588) (xy 140.12773 -226.399686) (xy 140.168233 -226.427642)
			(xy 140.203726 -226.461734) (xy 140.233291 -226.501078) (xy 140.256162 -226.544655) (xy 140.271746 -226.591336)
			(xy 140.279641 -226.639913) (xy 140.280136 -226.66452) (xy 140.598647 -226.66452) (xy 140.602742 -226.613792)
			(xy 140.614921 -226.564378) (xy 140.634869 -226.517558) (xy 140.66207 -226.474544) (xy 140.695818 -226.43645)
			(xy 140.73524 -226.404263) (xy 140.779314 -226.378817) (xy 140.8269 -226.36077) (xy 140.876764 -226.35059)
			(xy 140.927616 -226.348541) (xy 140.978137 -226.354675) (xy 141.027021 -226.368835) (xy 141.073 -226.390652)
			(xy 141.114884 -226.419562) (xy 141.151588 -226.454817) (xy 141.182161 -226.495503) (xy 141.205812 -226.540566)
			(xy 141.221928 -226.58884) (xy 141.230092 -226.639074) (xy 141.230604 -226.66452) (xy 141.548878 -226.66452)
			(xy 141.552838 -226.615466) (xy 141.564615 -226.567682) (xy 141.583906 -226.522406) (xy 141.610209 -226.48081)
			(xy 141.642844 -226.443973) (xy 141.680965 -226.412848) (xy 141.723586 -226.388241) (xy 141.769602 -226.370789)
			(xy 141.817821 -226.360945) (xy 141.866996 -226.358964) (xy 141.915851 -226.364896) (xy 141.963122 -226.378588)
			(xy 142.007584 -226.399686) (xy 142.048087 -226.427642) (xy 142.08358 -226.461734) (xy 142.113145 -226.501078)
			(xy 142.136016 -226.544655) (xy 142.1516 -226.591336) (xy 142.159495 -226.639913) (xy 142.15999 -226.66452)
			(xy 142.478501 -226.66452) (xy 142.482596 -226.613792) (xy 142.494775 -226.564378) (xy 142.514723 -226.517558)
			(xy 142.541924 -226.474544) (xy 142.575672 -226.43645) (xy 142.615094 -226.404263) (xy 142.659168 -226.378817)
			(xy 142.706754 -226.36077) (xy 142.756618 -226.35059) (xy 142.80747 -226.348541) (xy 142.857991 -226.354675)
			(xy 142.906875 -226.368835) (xy 142.952854 -226.390652) (xy 142.994738 -226.419562) (xy 143.031442 -226.454817)
			(xy 143.062015 -226.495503) (xy 143.085666 -226.540566) (xy 143.101782 -226.58884) (xy 143.109946 -226.639074)
			(xy 143.110458 -226.66452) (xy 143.428986 -226.66452) (xy 143.432946 -226.615466) (xy 143.444723 -226.567682)
			(xy 143.464014 -226.522406) (xy 143.490317 -226.48081) (xy 143.522952 -226.443973) (xy 143.561073 -226.412848)
			(xy 143.603694 -226.388241) (xy 143.64971 -226.370789) (xy 143.697929 -226.360945) (xy 143.747104 -226.358964)
			(xy 143.795959 -226.364896) (xy 143.84323 -226.378588) (xy 143.887692 -226.399686) (xy 143.928195 -226.427642)
			(xy 143.963688 -226.461734) (xy 143.993253 -226.501078) (xy 144.016124 -226.544655) (xy 144.031708 -226.591336)
			(xy 144.039603 -226.639913) (xy 144.040098 -226.66452) (xy 144.039603 -226.689127) (xy 144.031708 -226.737704)
			(xy 144.016124 -226.784385) (xy 143.993253 -226.827962) (xy 143.963688 -226.867306) (xy 143.928195 -226.901398)
			(xy 143.887692 -226.929354) (xy 143.84323 -226.950452) (xy 143.795959 -226.964144) (xy 143.747104 -226.970076)
			(xy 143.697929 -226.968095) (xy 143.64971 -226.958251) (xy 143.603694 -226.940799) (xy 143.561073 -226.916192)
			(xy 143.522952 -226.885067) (xy 143.490317 -226.84823) (xy 143.464014 -226.806634) (xy 143.444723 -226.761358)
			(xy 143.432946 -226.713574) (xy 143.428986 -226.66452) (xy 143.110458 -226.66452) (xy 143.109946 -226.689966)
			(xy 143.101782 -226.7402) (xy 143.085666 -226.788474) (xy 143.062015 -226.833537) (xy 143.031442 -226.874223)
			(xy 142.994738 -226.909478) (xy 142.952854 -226.938388) (xy 142.906875 -226.960205) (xy 142.857991 -226.974365)
			(xy 142.80747 -226.980499) (xy 142.756618 -226.97845) (xy 142.706754 -226.96827) (xy 142.659168 -226.950223)
			(xy 142.615094 -226.924777) (xy 142.575672 -226.89259) (xy 142.541924 -226.854496) (xy 142.514723 -226.811482)
			(xy 142.494775 -226.764662) (xy 142.482596 -226.715248) (xy 142.478501 -226.66452) (xy 142.15999 -226.66452)
			(xy 142.159495 -226.689127) (xy 142.1516 -226.737704) (xy 142.136016 -226.784385) (xy 142.113145 -226.827962)
			(xy 142.08358 -226.867306) (xy 142.048087 -226.901398) (xy 142.007584 -226.929354) (xy 141.963122 -226.950452)
			(xy 141.915851 -226.964144) (xy 141.866996 -226.970076) (xy 141.817821 -226.968095) (xy 141.769602 -226.958251)
			(xy 141.723586 -226.940799) (xy 141.680965 -226.916192) (xy 141.642844 -226.885067) (xy 141.610209 -226.84823)
			(xy 141.583906 -226.806634) (xy 141.564615 -226.761358) (xy 141.552838 -226.713574) (xy 141.548878 -226.66452)
			(xy 141.230604 -226.66452) (xy 141.230092 -226.689966) (xy 141.221928 -226.7402) (xy 141.205812 -226.788474)
			(xy 141.182161 -226.833537) (xy 141.151588 -226.874223) (xy 141.114884 -226.909478) (xy 141.073 -226.938388)
			(xy 141.027021 -226.960205) (xy 140.978137 -226.974365) (xy 140.927616 -226.980499) (xy 140.876764 -226.97845)
			(xy 140.8269 -226.96827) (xy 140.779314 -226.950223) (xy 140.73524 -226.924777) (xy 140.695818 -226.89259)
			(xy 140.66207 -226.854496) (xy 140.634869 -226.811482) (xy 140.614921 -226.764662) (xy 140.602742 -226.715248)
			(xy 140.598647 -226.66452) (xy 140.280136 -226.66452) (xy 140.279641 -226.689127) (xy 140.271746 -226.737704)
			(xy 140.256162 -226.784385) (xy 140.233291 -226.827962) (xy 140.203726 -226.867306) (xy 140.168233 -226.901398)
			(xy 140.12773 -226.929354) (xy 140.083268 -226.950452) (xy 140.035997 -226.964144) (xy 139.987142 -226.970076)
			(xy 139.937967 -226.968095) (xy 139.889748 -226.958251) (xy 139.843732 -226.940799) (xy 139.801111 -226.916192)
			(xy 139.76299 -226.885067) (xy 139.730355 -226.84823) (xy 139.704052 -226.806634) (xy 139.684761 -226.761358)
			(xy 139.672984 -226.713574) (xy 139.669024 -226.66452) (xy 139.350496 -226.66452) (xy 139.349984 -226.689966)
			(xy 139.34182 -226.7402) (xy 139.325704 -226.788474) (xy 139.302053 -226.833537) (xy 139.27148 -226.874223)
			(xy 139.234776 -226.909478) (xy 139.192892 -226.938388) (xy 139.146913 -226.960205) (xy 139.098029 -226.974365)
			(xy 139.047508 -226.980499) (xy 138.996656 -226.97845) (xy 138.946792 -226.96827) (xy 138.899206 -226.950223)
			(xy 138.855132 -226.924777) (xy 138.81571 -226.89259) (xy 138.781962 -226.854496) (xy 138.754761 -226.811482)
			(xy 138.734813 -226.764662) (xy 138.722634 -226.715248) (xy 138.718539 -226.66452) (xy 138.410442 -226.66452)
			(xy 138.40993 -226.689966) (xy 138.401766 -226.7402) (xy 138.38565 -226.788474) (xy 138.361999 -226.833537)
			(xy 138.331426 -226.874223) (xy 138.294722 -226.909478) (xy 138.252838 -226.938388) (xy 138.206859 -226.960205)
			(xy 138.157975 -226.974365) (xy 138.107454 -226.980499) (xy 138.056602 -226.97845) (xy 138.006738 -226.96827)
			(xy 137.959152 -226.950223) (xy 137.915078 -226.924777) (xy 137.875656 -226.89259) (xy 137.841908 -226.854496)
			(xy 137.814707 -226.811482) (xy 137.794759 -226.764662) (xy 137.78258 -226.715248) (xy 137.778485 -226.66452)
			(xy 137.459974 -226.66452) (xy 137.459479 -226.689127) (xy 137.451584 -226.737704) (xy 137.436 -226.784385)
			(xy 137.413129 -226.827962) (xy 137.383564 -226.867306) (xy 137.348071 -226.901398) (xy 137.307568 -226.929354)
			(xy 137.263106 -226.950452) (xy 137.215835 -226.964144) (xy 137.16698 -226.970076) (xy 137.117805 -226.968095)
			(xy 137.069586 -226.958251) (xy 137.02357 -226.940799) (xy 136.980949 -226.916192) (xy 136.942828 -226.885067)
			(xy 136.910193 -226.84823) (xy 136.88389 -226.806634) (xy 136.864599 -226.761358) (xy 136.852822 -226.713574)
			(xy 136.848862 -226.66452) (xy 136.530588 -226.66452) (xy 136.530076 -226.689966) (xy 136.521912 -226.7402)
			(xy 136.505796 -226.788474) (xy 136.482145 -226.833537) (xy 136.451572 -226.874223) (xy 136.414868 -226.909478)
			(xy 136.372984 -226.938388) (xy 136.327005 -226.960205) (xy 136.278121 -226.974365) (xy 136.2276 -226.980499)
			(xy 136.176748 -226.97845) (xy 136.126884 -226.96827) (xy 136.079298 -226.950223) (xy 136.035224 -226.924777)
			(xy 135.995802 -226.89259) (xy 135.962054 -226.854496) (xy 135.934853 -226.811482) (xy 135.914905 -226.764662)
			(xy 135.902726 -226.715248) (xy 135.898631 -226.66452) (xy 135.58012 -226.66452) (xy 135.579625 -226.689127)
			(xy 135.57173 -226.737704) (xy 135.556146 -226.784385) (xy 135.533275 -226.827962) (xy 135.50371 -226.867306)
			(xy 135.468217 -226.901398) (xy 135.427714 -226.929354) (xy 135.383252 -226.950452) (xy 135.335981 -226.964144)
			(xy 135.287126 -226.970076) (xy 135.237951 -226.968095) (xy 135.189732 -226.958251) (xy 135.143716 -226.940799)
			(xy 135.101095 -226.916192) (xy 135.062974 -226.885067) (xy 135.030339 -226.84823) (xy 135.004036 -226.806634)
			(xy 134.984745 -226.761358) (xy 134.972968 -226.713574) (xy 134.969008 -226.66452) (xy 134.65048 -226.66452)
			(xy 134.649968 -226.689966) (xy 134.641804 -226.7402) (xy 134.625688 -226.788474) (xy 134.602037 -226.833537)
			(xy 134.571464 -226.874223) (xy 134.53476 -226.909478) (xy 134.492876 -226.938388) (xy 134.446897 -226.960205)
			(xy 134.398013 -226.974365) (xy 134.347492 -226.980499) (xy 134.29664 -226.97845) (xy 134.246776 -226.96827)
			(xy 134.19919 -226.950223) (xy 134.155116 -226.924777) (xy 134.115694 -226.89259) (xy 134.081946 -226.854496)
			(xy 134.054745 -226.811482) (xy 134.034797 -226.764662) (xy 134.022618 -226.715248) (xy 134.018523 -226.66452)
			(xy 133.700012 -226.66452) (xy 133.699517 -226.689127) (xy 133.691622 -226.737704) (xy 133.676038 -226.784385)
			(xy 133.653167 -226.827962) (xy 133.623602 -226.867306) (xy 133.588109 -226.901398) (xy 133.547606 -226.929354)
			(xy 133.503144 -226.950452) (xy 133.455873 -226.964144) (xy 133.407018 -226.970076) (xy 133.357843 -226.968095)
			(xy 133.309624 -226.958251) (xy 133.263608 -226.940799) (xy 133.220987 -226.916192) (xy 133.182866 -226.885067)
			(xy 133.150231 -226.84823) (xy 133.123928 -226.806634) (xy 133.104637 -226.761358) (xy 133.09286 -226.713574)
			(xy 133.0889 -226.66452) (xy 132.770372 -226.66452) (xy 132.76986 -226.689966) (xy 132.761696 -226.7402)
			(xy 132.74558 -226.788474) (xy 132.721929 -226.833537) (xy 132.691356 -226.874223) (xy 132.654652 -226.909478)
			(xy 132.612768 -226.938388) (xy 132.566789 -226.960205) (xy 132.517905 -226.974365) (xy 132.467384 -226.980499)
			(xy 132.416532 -226.97845) (xy 132.366668 -226.96827) (xy 132.319082 -226.950223) (xy 132.275008 -226.924777)
			(xy 132.235586 -226.89259) (xy 132.201838 -226.854496) (xy 132.174637 -226.811482) (xy 132.154689 -226.764662)
			(xy 132.14251 -226.715248) (xy 132.138415 -226.66452) (xy 131.830572 -226.66452) (xy 131.83006 -226.689966)
			(xy 131.821896 -226.7402) (xy 131.80578 -226.788474) (xy 131.782129 -226.833537) (xy 131.751556 -226.874223)
			(xy 131.714852 -226.909478) (xy 131.672968 -226.938388) (xy 131.626989 -226.960205) (xy 131.578105 -226.974365)
			(xy 131.527584 -226.980499) (xy 131.476732 -226.97845) (xy 131.426868 -226.96827) (xy 131.379282 -226.950223)
			(xy 131.335208 -226.924777) (xy 131.295786 -226.89259) (xy 131.262038 -226.854496) (xy 131.234837 -226.811482)
			(xy 131.214889 -226.764662) (xy 131.20271 -226.715248) (xy 131.198615 -226.66452) (xy 130.880104 -226.66452)
			(xy 130.879609 -226.689127) (xy 130.871714 -226.737704) (xy 130.85613 -226.784385) (xy 130.833259 -226.827962)
			(xy 130.803694 -226.867306) (xy 130.768201 -226.901398) (xy 130.727698 -226.929354) (xy 130.683236 -226.950452)
			(xy 130.635965 -226.964144) (xy 130.58711 -226.970076) (xy 130.537935 -226.968095) (xy 130.489716 -226.958251)
			(xy 130.4437 -226.940799) (xy 130.401079 -226.916192) (xy 130.362958 -226.885067) (xy 130.330323 -226.84823)
			(xy 130.30402 -226.806634) (xy 130.284729 -226.761358) (xy 130.272952 -226.713574) (xy 130.268992 -226.66452)
			(xy 129.950464 -226.66452) (xy 129.949952 -226.689966) (xy 129.941788 -226.7402) (xy 129.925672 -226.788474)
			(xy 129.902021 -226.833537) (xy 129.871448 -226.874223) (xy 129.834744 -226.909478) (xy 129.79286 -226.938388)
			(xy 129.746881 -226.960205) (xy 129.697997 -226.974365) (xy 129.647476 -226.980499) (xy 129.596624 -226.97845)
			(xy 129.54676 -226.96827) (xy 129.499174 -226.950223) (xy 129.4551 -226.924777) (xy 129.415678 -226.89259)
			(xy 129.38193 -226.854496) (xy 129.354729 -226.811482) (xy 129.334781 -226.764662) (xy 129.322602 -226.715248)
			(xy 129.318507 -226.66452) (xy 128.999996 -226.66452) (xy 128.999501 -226.689127) (xy 128.991606 -226.737704)
			(xy 128.976022 -226.784385) (xy 128.953151 -226.827962) (xy 128.923586 -226.867306) (xy 128.888093 -226.901398)
			(xy 128.84759 -226.929354) (xy 128.803128 -226.950452) (xy 128.755857 -226.964144) (xy 128.707002 -226.970076)
			(xy 128.657827 -226.968095) (xy 128.609608 -226.958251) (xy 128.563592 -226.940799) (xy 128.520971 -226.916192)
			(xy 128.48285 -226.885067) (xy 128.450215 -226.84823) (xy 128.423912 -226.806634) (xy 128.404621 -226.761358)
			(xy 128.392844 -226.713574) (xy 128.388884 -226.66452) (xy 128.069562 -226.66452) (xy 128.069562 -226.689286)
			(xy 128.061807 -226.738249) (xy 128.04649 -226.785395) (xy 128.023986 -226.829566) (xy 127.994849 -226.869672)
			(xy 127.959798 -226.904727) (xy 127.919695 -226.933868) (xy 127.875527 -226.956377) (xy 127.828382 -226.971699)
			(xy 127.77942 -226.979459) (xy 127.754634 -226.979988) (xy 127.732959 -226.97966) (xy 127.690008 -226.973791)
			(xy 127.669036 -226.968304) (xy 127.662432 -226.966272) (xy 127.65532 -226.966272) (xy 127.645308 -226.966756)
			(xy 127.626804 -226.974411) (xy 127.612638 -226.988564) (xy 127.604966 -227.00706) (xy 127.60452 -227.017072)
			(xy 127.60452 -227.03536) (xy 127.607314 -227.043234) (xy 127.622678 -227.089558) (xy 127.647396 -227.183983)
			(xy 127.665147 -227.279963) (xy 127.675835 -227.376983) (xy 127.679402 -227.474525) (xy 127.679402 -227.474526)
			(xy 127.908553 -227.474526) (xy 127.912648 -227.423798) (xy 127.924827 -227.374384) (xy 127.944775 -227.327564)
			(xy 127.971976 -227.28455) (xy 128.005724 -227.246456) (xy 128.045146 -227.214269) (xy 128.08922 -227.188823)
			(xy 128.136806 -227.170776) (xy 128.18667 -227.160596) (xy 128.237522 -227.158547) (xy 128.288043 -227.164681)
			(xy 128.336927 -227.178841) (xy 128.382906 -227.200658) (xy 128.42479 -227.229568) (xy 128.461494 -227.264823)
			(xy 128.492067 -227.305509) (xy 128.515718 -227.350572) (xy 128.531834 -227.398846) (xy 128.539998 -227.44908)
			(xy 128.54051 -227.474526) (xy 128.848607 -227.474526) (xy 128.852702 -227.423798) (xy 128.864881 -227.374384)
			(xy 128.884829 -227.327564) (xy 128.91203 -227.28455) (xy 128.945778 -227.246456) (xy 128.9852 -227.214269)
			(xy 129.029274 -227.188823) (xy 129.07686 -227.170776) (xy 129.126724 -227.160596) (xy 129.177576 -227.158547)
			(xy 129.228097 -227.164681) (xy 129.276981 -227.178841) (xy 129.32296 -227.200658) (xy 129.364844 -227.229568)
			(xy 129.401548 -227.264823) (xy 129.432121 -227.305509) (xy 129.455772 -227.350572) (xy 129.471888 -227.398846)
			(xy 129.480052 -227.44908) (xy 129.480564 -227.474526) (xy 130.728461 -227.474526) (xy 130.732556 -227.423798)
			(xy 130.744735 -227.374384) (xy 130.764683 -227.327564) (xy 130.791884 -227.28455) (xy 130.825632 -227.246456)
			(xy 130.865054 -227.214269) (xy 130.909128 -227.188823) (xy 130.956714 -227.170776) (xy 131.006578 -227.160596)
			(xy 131.05743 -227.158547) (xy 131.107951 -227.164681) (xy 131.156835 -227.178841) (xy 131.202814 -227.200658)
			(xy 131.244698 -227.229568) (xy 131.281402 -227.264823) (xy 131.311975 -227.305509) (xy 131.335626 -227.350572)
			(xy 131.351742 -227.398846) (xy 131.359906 -227.44908) (xy 131.360418 -227.474526) (xy 131.678946 -227.474526)
			(xy 131.682906 -227.425472) (xy 131.694683 -227.377688) (xy 131.713974 -227.332412) (xy 131.740277 -227.290816)
			(xy 131.772912 -227.253979) (xy 131.811033 -227.222854) (xy 131.853654 -227.198247) (xy 131.89967 -227.180795)
			(xy 131.947889 -227.170951) (xy 131.997064 -227.16897) (xy 132.045919 -227.174902) (xy 132.09319 -227.188594)
			(xy 132.137652 -227.209692) (xy 132.178155 -227.237648) (xy 132.213648 -227.27174) (xy 132.243213 -227.311084)
			(xy 132.266084 -227.354661) (xy 132.281668 -227.401342) (xy 132.289563 -227.449919) (xy 132.290058 -227.474526)
			(xy 132.608569 -227.474526) (xy 132.612664 -227.423798) (xy 132.624843 -227.374384) (xy 132.644791 -227.327564)
			(xy 132.671992 -227.28455) (xy 132.70574 -227.246456) (xy 132.745162 -227.214269) (xy 132.789236 -227.188823)
			(xy 132.836822 -227.170776) (xy 132.886686 -227.160596) (xy 132.937538 -227.158547) (xy 132.988059 -227.164681)
			(xy 133.036943 -227.178841) (xy 133.082922 -227.200658) (xy 133.124806 -227.229568) (xy 133.16151 -227.264823)
			(xy 133.192083 -227.305509) (xy 133.215734 -227.350572) (xy 133.23185 -227.398846) (xy 133.240014 -227.44908)
			(xy 133.240526 -227.474526) (xy 133.559054 -227.474526) (xy 133.563014 -227.425472) (xy 133.574791 -227.377688)
			(xy 133.594082 -227.332412) (xy 133.620385 -227.290816) (xy 133.65302 -227.253979) (xy 133.691141 -227.222854)
			(xy 133.733762 -227.198247) (xy 133.779778 -227.180795) (xy 133.827997 -227.170951) (xy 133.877172 -227.16897)
			(xy 133.926027 -227.174902) (xy 133.973298 -227.188594) (xy 134.01776 -227.209692) (xy 134.058263 -227.237648)
			(xy 134.093756 -227.27174) (xy 134.123321 -227.311084) (xy 134.146192 -227.354661) (xy 134.161776 -227.401342)
			(xy 134.169671 -227.449919) (xy 134.170166 -227.474526) (xy 134.488423 -227.474526) (xy 134.492518 -227.423798)
			(xy 134.504697 -227.374384) (xy 134.524645 -227.327564) (xy 134.551846 -227.28455) (xy 134.585594 -227.246456)
			(xy 134.625016 -227.214269) (xy 134.66909 -227.188823) (xy 134.716676 -227.170776) (xy 134.76654 -227.160596)
			(xy 134.817392 -227.158547) (xy 134.867913 -227.164681) (xy 134.916797 -227.178841) (xy 134.962776 -227.200658)
			(xy 135.00466 -227.229568) (xy 135.041364 -227.264823) (xy 135.071937 -227.305509) (xy 135.095588 -227.350572)
			(xy 135.111704 -227.398846) (xy 135.119868 -227.44908) (xy 135.12038 -227.474526) (xy 135.428477 -227.474526)
			(xy 135.432572 -227.423798) (xy 135.444751 -227.374384) (xy 135.464699 -227.327564) (xy 135.4919 -227.28455)
			(xy 135.525648 -227.246456) (xy 135.56507 -227.214269) (xy 135.609144 -227.188823) (xy 135.65673 -227.170776)
			(xy 135.706594 -227.160596) (xy 135.757446 -227.158547) (xy 135.807967 -227.164681) (xy 135.856851 -227.178841)
			(xy 135.90283 -227.200658) (xy 135.944714 -227.229568) (xy 135.981418 -227.264823) (xy 136.011991 -227.305509)
			(xy 136.035642 -227.350572) (xy 136.051758 -227.398846) (xy 136.059922 -227.44908) (xy 136.060434 -227.474526)
			(xy 137.308585 -227.474526) (xy 137.31268 -227.423798) (xy 137.324859 -227.374384) (xy 137.344807 -227.327564)
			(xy 137.372008 -227.28455) (xy 137.405756 -227.246456) (xy 137.445178 -227.214269) (xy 137.489252 -227.188823)
			(xy 137.536838 -227.170776) (xy 137.586702 -227.160596) (xy 137.637554 -227.158547) (xy 137.688075 -227.164681)
			(xy 137.736959 -227.178841) (xy 137.782938 -227.200658) (xy 137.824822 -227.229568) (xy 137.861526 -227.264823)
			(xy 137.892099 -227.305509) (xy 137.91575 -227.350572) (xy 137.931866 -227.398846) (xy 137.94003 -227.44908)
			(xy 137.940542 -227.474526) (xy 138.25907 -227.474526) (xy 138.26303 -227.425472) (xy 138.274807 -227.377688)
			(xy 138.294098 -227.332412) (xy 138.320401 -227.290816) (xy 138.353036 -227.253979) (xy 138.391157 -227.222854)
			(xy 138.433778 -227.198247) (xy 138.479794 -227.180795) (xy 138.528013 -227.170951) (xy 138.577188 -227.16897)
			(xy 138.626043 -227.174902) (xy 138.673314 -227.188594) (xy 138.717776 -227.209692) (xy 138.758279 -227.237648)
			(xy 138.793772 -227.27174) (xy 138.823337 -227.311084) (xy 138.846208 -227.354661) (xy 138.861792 -227.401342)
			(xy 138.869687 -227.449919) (xy 138.870182 -227.474526) (xy 139.188439 -227.474526) (xy 139.192534 -227.423798)
			(xy 139.204713 -227.374384) (xy 139.224661 -227.327564) (xy 139.251862 -227.28455) (xy 139.28561 -227.246456)
			(xy 139.325032 -227.214269) (xy 139.369106 -227.188823) (xy 139.416692 -227.170776) (xy 139.466556 -227.160596)
			(xy 139.517408 -227.158547) (xy 139.567929 -227.164681) (xy 139.616813 -227.178841) (xy 139.662792 -227.200658)
			(xy 139.704676 -227.229568) (xy 139.74138 -227.264823) (xy 139.771953 -227.305509) (xy 139.795604 -227.350572)
			(xy 139.81172 -227.398846) (xy 139.819884 -227.44908) (xy 139.820396 -227.474526) (xy 140.138924 -227.474526)
			(xy 140.142884 -227.425472) (xy 140.154661 -227.377688) (xy 140.173952 -227.332412) (xy 140.200255 -227.290816)
			(xy 140.23289 -227.253979) (xy 140.271011 -227.222854) (xy 140.313632 -227.198247) (xy 140.359648 -227.180795)
			(xy 140.407867 -227.170951) (xy 140.457042 -227.16897) (xy 140.505897 -227.174902) (xy 140.553168 -227.188594)
			(xy 140.59763 -227.209692) (xy 140.638133 -227.237648) (xy 140.673626 -227.27174) (xy 140.703191 -227.311084)
			(xy 140.726062 -227.354661) (xy 140.741646 -227.401342) (xy 140.749541 -227.449919) (xy 140.750036 -227.474526)
			(xy 141.068547 -227.474526) (xy 141.072642 -227.423798) (xy 141.084821 -227.374384) (xy 141.104769 -227.327564)
			(xy 141.13197 -227.28455) (xy 141.165718 -227.246456) (xy 141.20514 -227.214269) (xy 141.249214 -227.188823)
			(xy 141.2968 -227.170776) (xy 141.346664 -227.160596) (xy 141.397516 -227.158547) (xy 141.448037 -227.164681)
			(xy 141.496921 -227.178841) (xy 141.5429 -227.200658) (xy 141.584784 -227.229568) (xy 141.621488 -227.264823)
			(xy 141.652061 -227.305509) (xy 141.675712 -227.350572) (xy 141.691828 -227.398846) (xy 141.699992 -227.44908)
			(xy 141.700504 -227.474526) (xy 142.008601 -227.474526) (xy 142.012696 -227.423798) (xy 142.024875 -227.374384)
			(xy 142.044823 -227.327564) (xy 142.072024 -227.28455) (xy 142.105772 -227.246456) (xy 142.145194 -227.214269)
			(xy 142.189268 -227.188823) (xy 142.236854 -227.170776) (xy 142.286718 -227.160596) (xy 142.33757 -227.158547)
			(xy 142.388091 -227.164681) (xy 142.436975 -227.178841) (xy 142.482954 -227.200658) (xy 142.524838 -227.229568)
			(xy 142.561542 -227.264823) (xy 142.592115 -227.305509) (xy 142.615766 -227.350572) (xy 142.631882 -227.398846)
			(xy 142.640046 -227.44908) (xy 142.640558 -227.474526) (xy 144.83894 -227.474526) (xy 144.8429 -227.425472)
			(xy 144.854677 -227.377688) (xy 144.873968 -227.332412) (xy 144.900271 -227.290816) (xy 144.932906 -227.253979)
			(xy 144.971027 -227.222854) (xy 145.013648 -227.198247) (xy 145.059664 -227.180795) (xy 145.107883 -227.170951)
			(xy 145.157058 -227.16897) (xy 145.205913 -227.174902) (xy 145.253184 -227.188594) (xy 145.297646 -227.209692)
			(xy 145.338149 -227.237648) (xy 145.373642 -227.27174) (xy 145.403207 -227.311084) (xy 145.426078 -227.354661)
			(xy 145.441662 -227.401342) (xy 145.449557 -227.449919) (xy 145.450052 -227.474526) (xy 145.449557 -227.499133)
			(xy 145.441662 -227.54771) (xy 145.426078 -227.594391) (xy 145.403207 -227.637968) (xy 145.373642 -227.677312)
			(xy 145.338149 -227.711404) (xy 145.297646 -227.73936) (xy 145.253184 -227.760458) (xy 145.205913 -227.77415)
			(xy 145.157058 -227.780082) (xy 145.107883 -227.778101) (xy 145.059664 -227.768257) (xy 145.013648 -227.750805)
			(xy 144.971027 -227.726198) (xy 144.932906 -227.695073) (xy 144.900271 -227.658236) (xy 144.873968 -227.61664)
			(xy 144.854677 -227.571364) (xy 144.8429 -227.52358) (xy 144.83894 -227.474526) (xy 142.640558 -227.474526)
			(xy 142.640046 -227.499972) (xy 142.631882 -227.550206) (xy 142.615766 -227.59848) (xy 142.592115 -227.643543)
			(xy 142.561542 -227.684229) (xy 142.524838 -227.719484) (xy 142.482954 -227.748394) (xy 142.436975 -227.770211)
			(xy 142.388091 -227.784371) (xy 142.33757 -227.790505) (xy 142.286718 -227.788456) (xy 142.236854 -227.778276)
			(xy 142.189268 -227.760229) (xy 142.145194 -227.734783) (xy 142.105772 -227.702596) (xy 142.072024 -227.664502)
			(xy 142.044823 -227.621488) (xy 142.024875 -227.574668) (xy 142.012696 -227.525254) (xy 142.008601 -227.474526)
			(xy 141.700504 -227.474526) (xy 141.699992 -227.499972) (xy 141.691828 -227.550206) (xy 141.675712 -227.59848)
			(xy 141.652061 -227.643543) (xy 141.621488 -227.684229) (xy 141.584784 -227.719484) (xy 141.5429 -227.748394)
			(xy 141.496921 -227.770211) (xy 141.448037 -227.784371) (xy 141.397516 -227.790505) (xy 141.346664 -227.788456)
			(xy 141.2968 -227.778276) (xy 141.249214 -227.760229) (xy 141.20514 -227.734783) (xy 141.165718 -227.702596)
			(xy 141.13197 -227.664502) (xy 141.104769 -227.621488) (xy 141.084821 -227.574668) (xy 141.072642 -227.525254)
			(xy 141.068547 -227.474526) (xy 140.750036 -227.474526) (xy 140.749541 -227.499133) (xy 140.741646 -227.54771)
			(xy 140.726062 -227.594391) (xy 140.703191 -227.637968) (xy 140.673626 -227.677312) (xy 140.638133 -227.711404)
			(xy 140.59763 -227.73936) (xy 140.553168 -227.760458) (xy 140.505897 -227.77415) (xy 140.457042 -227.780082)
			(xy 140.407867 -227.778101) (xy 140.359648 -227.768257) (xy 140.313632 -227.750805) (xy 140.271011 -227.726198)
			(xy 140.23289 -227.695073) (xy 140.200255 -227.658236) (xy 140.173952 -227.61664) (xy 140.154661 -227.571364)
			(xy 140.142884 -227.52358) (xy 140.138924 -227.474526) (xy 139.820396 -227.474526) (xy 139.819884 -227.499972)
			(xy 139.81172 -227.550206) (xy 139.795604 -227.59848) (xy 139.771953 -227.643543) (xy 139.74138 -227.684229)
			(xy 139.704676 -227.719484) (xy 139.662792 -227.748394) (xy 139.616813 -227.770211) (xy 139.567929 -227.784371)
			(xy 139.517408 -227.790505) (xy 139.466556 -227.788456) (xy 139.416692 -227.778276) (xy 139.369106 -227.760229)
			(xy 139.325032 -227.734783) (xy 139.28561 -227.702596) (xy 139.251862 -227.664502) (xy 139.224661 -227.621488)
			(xy 139.204713 -227.574668) (xy 139.192534 -227.525254) (xy 139.188439 -227.474526) (xy 138.870182 -227.474526)
			(xy 138.869687 -227.499133) (xy 138.861792 -227.54771) (xy 138.846208 -227.594391) (xy 138.823337 -227.637968)
			(xy 138.793772 -227.677312) (xy 138.758279 -227.711404) (xy 138.717776 -227.73936) (xy 138.673314 -227.760458)
			(xy 138.626043 -227.77415) (xy 138.577188 -227.780082) (xy 138.528013 -227.778101) (xy 138.479794 -227.768257)
			(xy 138.433778 -227.750805) (xy 138.391157 -227.726198) (xy 138.353036 -227.695073) (xy 138.320401 -227.658236)
			(xy 138.294098 -227.61664) (xy 138.274807 -227.571364) (xy 138.26303 -227.52358) (xy 138.25907 -227.474526)
			(xy 137.940542 -227.474526) (xy 137.94003 -227.499972) (xy 137.931866 -227.550206) (xy 137.91575 -227.59848)
			(xy 137.892099 -227.643543) (xy 137.861526 -227.684229) (xy 137.824822 -227.719484) (xy 137.782938 -227.748394)
			(xy 137.736959 -227.770211) (xy 137.688075 -227.784371) (xy 137.637554 -227.790505) (xy 137.586702 -227.788456)
			(xy 137.536838 -227.778276) (xy 137.489252 -227.760229) (xy 137.445178 -227.734783) (xy 137.405756 -227.702596)
			(xy 137.372008 -227.664502) (xy 137.344807 -227.621488) (xy 137.324859 -227.574668) (xy 137.31268 -227.525254)
			(xy 137.308585 -227.474526) (xy 136.060434 -227.474526) (xy 136.059922 -227.499972) (xy 136.051758 -227.550206)
			(xy 136.035642 -227.59848) (xy 136.011991 -227.643543) (xy 135.981418 -227.684229) (xy 135.944714 -227.719484)
			(xy 135.90283 -227.748394) (xy 135.856851 -227.770211) (xy 135.807967 -227.784371) (xy 135.757446 -227.790505)
			(xy 135.706594 -227.788456) (xy 135.65673 -227.778276) (xy 135.609144 -227.760229) (xy 135.56507 -227.734783)
			(xy 135.525648 -227.702596) (xy 135.4919 -227.664502) (xy 135.464699 -227.621488) (xy 135.444751 -227.574668)
			(xy 135.432572 -227.525254) (xy 135.428477 -227.474526) (xy 135.12038 -227.474526) (xy 135.119868 -227.499972)
			(xy 135.111704 -227.550206) (xy 135.095588 -227.59848) (xy 135.071937 -227.643543) (xy 135.041364 -227.684229)
			(xy 135.00466 -227.719484) (xy 134.962776 -227.748394) (xy 134.916797 -227.770211) (xy 134.867913 -227.784371)
			(xy 134.817392 -227.790505) (xy 134.76654 -227.788456) (xy 134.716676 -227.778276) (xy 134.66909 -227.760229)
			(xy 134.625016 -227.734783) (xy 134.585594 -227.702596) (xy 134.551846 -227.664502) (xy 134.524645 -227.621488)
			(xy 134.504697 -227.574668) (xy 134.492518 -227.525254) (xy 134.488423 -227.474526) (xy 134.170166 -227.474526)
			(xy 134.169671 -227.499133) (xy 134.161776 -227.54771) (xy 134.146192 -227.594391) (xy 134.123321 -227.637968)
			(xy 134.093756 -227.677312) (xy 134.058263 -227.711404) (xy 134.01776 -227.73936) (xy 133.973298 -227.760458)
			(xy 133.926027 -227.77415) (xy 133.877172 -227.780082) (xy 133.827997 -227.778101) (xy 133.779778 -227.768257)
			(xy 133.733762 -227.750805) (xy 133.691141 -227.726198) (xy 133.65302 -227.695073) (xy 133.620385 -227.658236)
			(xy 133.594082 -227.61664) (xy 133.574791 -227.571364) (xy 133.563014 -227.52358) (xy 133.559054 -227.474526)
			(xy 133.240526 -227.474526) (xy 133.240014 -227.499972) (xy 133.23185 -227.550206) (xy 133.215734 -227.59848)
			(xy 133.192083 -227.643543) (xy 133.16151 -227.684229) (xy 133.124806 -227.719484) (xy 133.082922 -227.748394)
			(xy 133.036943 -227.770211) (xy 132.988059 -227.784371) (xy 132.937538 -227.790505) (xy 132.886686 -227.788456)
			(xy 132.836822 -227.778276) (xy 132.789236 -227.760229) (xy 132.745162 -227.734783) (xy 132.70574 -227.702596)
			(xy 132.671992 -227.664502) (xy 132.644791 -227.621488) (xy 132.624843 -227.574668) (xy 132.612664 -227.525254)
			(xy 132.608569 -227.474526) (xy 132.290058 -227.474526) (xy 132.289563 -227.499133) (xy 132.281668 -227.54771)
			(xy 132.266084 -227.594391) (xy 132.243213 -227.637968) (xy 132.213648 -227.677312) (xy 132.178155 -227.711404)
			(xy 132.137652 -227.73936) (xy 132.09319 -227.760458) (xy 132.045919 -227.77415) (xy 131.997064 -227.780082)
			(xy 131.947889 -227.778101) (xy 131.89967 -227.768257) (xy 131.853654 -227.750805) (xy 131.811033 -227.726198)
			(xy 131.772912 -227.695073) (xy 131.740277 -227.658236) (xy 131.713974 -227.61664) (xy 131.694683 -227.571364)
			(xy 131.682906 -227.52358) (xy 131.678946 -227.474526) (xy 131.360418 -227.474526) (xy 131.359906 -227.499972)
			(xy 131.351742 -227.550206) (xy 131.335626 -227.59848) (xy 131.311975 -227.643543) (xy 131.281402 -227.684229)
			(xy 131.244698 -227.719484) (xy 131.202814 -227.748394) (xy 131.156835 -227.770211) (xy 131.107951 -227.784371)
			(xy 131.05743 -227.790505) (xy 131.006578 -227.788456) (xy 130.956714 -227.778276) (xy 130.909128 -227.760229)
			(xy 130.865054 -227.734783) (xy 130.825632 -227.702596) (xy 130.791884 -227.664502) (xy 130.764683 -227.621488)
			(xy 130.744735 -227.574668) (xy 130.732556 -227.525254) (xy 130.728461 -227.474526) (xy 129.480564 -227.474526)
			(xy 129.480052 -227.499972) (xy 129.471888 -227.550206) (xy 129.455772 -227.59848) (xy 129.432121 -227.643543)
			(xy 129.401548 -227.684229) (xy 129.364844 -227.719484) (xy 129.32296 -227.748394) (xy 129.276981 -227.770211)
			(xy 129.228097 -227.784371) (xy 129.177576 -227.790505) (xy 129.126724 -227.788456) (xy 129.07686 -227.778276)
			(xy 129.029274 -227.760229) (xy 128.9852 -227.734783) (xy 128.945778 -227.702596) (xy 128.91203 -227.664502)
			(xy 128.884829 -227.621488) (xy 128.864881 -227.574668) (xy 128.852702 -227.525254) (xy 128.848607 -227.474526)
			(xy 128.54051 -227.474526) (xy 128.539998 -227.499972) (xy 128.531834 -227.550206) (xy 128.515718 -227.59848)
			(xy 128.492067 -227.643543) (xy 128.461494 -227.684229) (xy 128.42479 -227.719484) (xy 128.382906 -227.748394)
			(xy 128.336927 -227.770211) (xy 128.288043 -227.784371) (xy 128.237522 -227.790505) (xy 128.18667 -227.788456)
			(xy 128.136806 -227.778276) (xy 128.08922 -227.760229) (xy 128.045146 -227.734783) (xy 128.005724 -227.702596)
			(xy 127.971976 -227.664502) (xy 127.944775 -227.621488) (xy 127.924827 -227.574668) (xy 127.912648 -227.525254)
			(xy 127.908553 -227.474526) (xy 127.679402 -227.474526) (xy 127.675831 -227.572066) (xy 127.66514 -227.669086)
			(xy 127.647386 -227.765065) (xy 127.622664 -227.859489) (xy 127.607314 -227.905818) (xy 127.60452 -227.913692)
			(xy 127.60452 -227.93198) (xy 127.604937 -227.942002) (xy 127.612604 -227.960523) (xy 127.626777 -227.974696)
			(xy 127.645298 -227.982363) (xy 127.65532 -227.98278) (xy 127.662432 -227.98278) (xy 127.669036 -227.980748)
			(xy 127.690005 -227.97525) (xy 127.732958 -227.969392) (xy 127.754634 -227.969064) (xy 127.779419 -227.969553)
			(xy 127.828379 -227.977312) (xy 127.875522 -227.992635) (xy 127.919688 -228.015142) (xy 127.95979 -228.044282)
			(xy 127.99484 -228.079336) (xy 128.023975 -228.119441) (xy 128.046479 -228.163609) (xy 128.061796 -228.210754)
			(xy 128.06955 -228.259715) (xy 128.06955 -228.284532) (xy 128.388884 -228.284532) (xy 128.392844 -228.235478)
			(xy 128.404621 -228.187694) (xy 128.423912 -228.142418) (xy 128.450215 -228.100822) (xy 128.48285 -228.063985)
			(xy 128.520971 -228.03286) (xy 128.563592 -228.008253) (xy 128.609608 -227.990801) (xy 128.657827 -227.980957)
			(xy 128.707002 -227.978976) (xy 128.755857 -227.984908) (xy 128.803128 -227.9986) (xy 128.84759 -228.019698)
			(xy 128.888093 -228.047654) (xy 128.923586 -228.081746) (xy 128.953151 -228.12109) (xy 128.976022 -228.164667)
			(xy 128.991606 -228.211348) (xy 128.999501 -228.259925) (xy 128.999996 -228.284532) (xy 129.318507 -228.284532)
			(xy 129.322602 -228.233804) (xy 129.334781 -228.18439) (xy 129.354729 -228.13757) (xy 129.38193 -228.094556)
			(xy 129.415678 -228.056462) (xy 129.4551 -228.024275) (xy 129.499174 -227.998829) (xy 129.54676 -227.980782)
			(xy 129.596624 -227.970602) (xy 129.647476 -227.968553) (xy 129.697997 -227.974687) (xy 129.746881 -227.988847)
			(xy 129.79286 -228.010664) (xy 129.834744 -228.039574) (xy 129.871448 -228.074829) (xy 129.902021 -228.115515)
			(xy 129.925672 -228.160578) (xy 129.941788 -228.208852) (xy 129.949952 -228.259086) (xy 129.950464 -228.284532)
			(xy 130.268992 -228.284532) (xy 130.272952 -228.235478) (xy 130.284729 -228.187694) (xy 130.30402 -228.142418)
			(xy 130.330323 -228.100822) (xy 130.362958 -228.063985) (xy 130.401079 -228.03286) (xy 130.4437 -228.008253)
			(xy 130.489716 -227.990801) (xy 130.537935 -227.980957) (xy 130.58711 -227.978976) (xy 130.635965 -227.984908)
			(xy 130.683236 -227.9986) (xy 130.727698 -228.019698) (xy 130.768201 -228.047654) (xy 130.803694 -228.081746)
			(xy 130.833259 -228.12109) (xy 130.85613 -228.164667) (xy 130.871714 -228.211348) (xy 130.879609 -228.259925)
			(xy 130.880104 -228.284532) (xy 131.198615 -228.284532) (xy 131.20271 -228.233804) (xy 131.214889 -228.18439)
			(xy 131.234837 -228.13757) (xy 131.262038 -228.094556) (xy 131.295786 -228.056462) (xy 131.335208 -228.024275)
			(xy 131.379282 -227.998829) (xy 131.426868 -227.980782) (xy 131.476732 -227.970602) (xy 131.527584 -227.968553)
			(xy 131.578105 -227.974687) (xy 131.626989 -227.988847) (xy 131.672968 -228.010664) (xy 131.714852 -228.039574)
			(xy 131.751556 -228.074829) (xy 131.782129 -228.115515) (xy 131.80578 -228.160578) (xy 131.821896 -228.208852)
			(xy 131.83006 -228.259086) (xy 131.830572 -228.284532) (xy 132.138415 -228.284532) (xy 132.14251 -228.233804)
			(xy 132.154689 -228.18439) (xy 132.174637 -228.13757) (xy 132.201838 -228.094556) (xy 132.235586 -228.056462)
			(xy 132.275008 -228.024275) (xy 132.319082 -227.998829) (xy 132.366668 -227.980782) (xy 132.416532 -227.970602)
			(xy 132.467384 -227.968553) (xy 132.517905 -227.974687) (xy 132.566789 -227.988847) (xy 132.612768 -228.010664)
			(xy 132.654652 -228.039574) (xy 132.691356 -228.074829) (xy 132.721929 -228.115515) (xy 132.74558 -228.160578)
			(xy 132.761696 -228.208852) (xy 132.76986 -228.259086) (xy 132.770372 -228.284532) (xy 133.0889 -228.284532)
			(xy 133.09286 -228.235478) (xy 133.104637 -228.187694) (xy 133.123928 -228.142418) (xy 133.150231 -228.100822)
			(xy 133.182866 -228.063985) (xy 133.220987 -228.03286) (xy 133.263608 -228.008253) (xy 133.309624 -227.990801)
			(xy 133.357843 -227.980957) (xy 133.407018 -227.978976) (xy 133.455873 -227.984908) (xy 133.503144 -227.9986)
			(xy 133.547606 -228.019698) (xy 133.588109 -228.047654) (xy 133.623602 -228.081746) (xy 133.653167 -228.12109)
			(xy 133.676038 -228.164667) (xy 133.691622 -228.211348) (xy 133.699517 -228.259925) (xy 133.700012 -228.284532)
			(xy 134.018523 -228.284532) (xy 134.022618 -228.233804) (xy 134.034797 -228.18439) (xy 134.054745 -228.13757)
			(xy 134.081946 -228.094556) (xy 134.115694 -228.056462) (xy 134.155116 -228.024275) (xy 134.19919 -227.998829)
			(xy 134.246776 -227.980782) (xy 134.29664 -227.970602) (xy 134.347492 -227.968553) (xy 134.398013 -227.974687)
			(xy 134.446897 -227.988847) (xy 134.492876 -228.010664) (xy 134.53476 -228.039574) (xy 134.571464 -228.074829)
			(xy 134.602037 -228.115515) (xy 134.625688 -228.160578) (xy 134.641804 -228.208852) (xy 134.649968 -228.259086)
			(xy 134.65048 -228.284532) (xy 134.969008 -228.284532) (xy 134.972968 -228.235478) (xy 134.984745 -228.187694)
			(xy 135.004036 -228.142418) (xy 135.030339 -228.100822) (xy 135.062974 -228.063985) (xy 135.101095 -228.03286)
			(xy 135.143716 -228.008253) (xy 135.189732 -227.990801) (xy 135.237951 -227.980957) (xy 135.287126 -227.978976)
			(xy 135.335981 -227.984908) (xy 135.383252 -227.9986) (xy 135.427714 -228.019698) (xy 135.468217 -228.047654)
			(xy 135.50371 -228.081746) (xy 135.533275 -228.12109) (xy 135.556146 -228.164667) (xy 135.57173 -228.211348)
			(xy 135.579625 -228.259925) (xy 135.58012 -228.284532) (xy 135.898631 -228.284532) (xy 135.902726 -228.233804)
			(xy 135.914905 -228.18439) (xy 135.934853 -228.13757) (xy 135.962054 -228.094556) (xy 135.995802 -228.056462)
			(xy 136.035224 -228.024275) (xy 136.079298 -227.998829) (xy 136.126884 -227.980782) (xy 136.176748 -227.970602)
			(xy 136.2276 -227.968553) (xy 136.278121 -227.974687) (xy 136.327005 -227.988847) (xy 136.372984 -228.010664)
			(xy 136.414868 -228.039574) (xy 136.451572 -228.074829) (xy 136.482145 -228.115515) (xy 136.505796 -228.160578)
			(xy 136.521912 -228.208852) (xy 136.530076 -228.259086) (xy 136.530588 -228.284532) (xy 136.848862 -228.284532)
			(xy 136.852822 -228.235478) (xy 136.864599 -228.187694) (xy 136.88389 -228.142418) (xy 136.910193 -228.100822)
			(xy 136.942828 -228.063985) (xy 136.980949 -228.03286) (xy 137.02357 -228.008253) (xy 137.069586 -227.990801)
			(xy 137.117805 -227.980957) (xy 137.16698 -227.978976) (xy 137.215835 -227.984908) (xy 137.263106 -227.9986)
			(xy 137.307568 -228.019698) (xy 137.348071 -228.047654) (xy 137.383564 -228.081746) (xy 137.413129 -228.12109)
			(xy 137.436 -228.164667) (xy 137.451584 -228.211348) (xy 137.459479 -228.259925) (xy 137.459974 -228.284532)
			(xy 137.778485 -228.284532) (xy 137.78258 -228.233804) (xy 137.794759 -228.18439) (xy 137.814707 -228.13757)
			(xy 137.841908 -228.094556) (xy 137.875656 -228.056462) (xy 137.915078 -228.024275) (xy 137.959152 -227.998829)
			(xy 138.006738 -227.980782) (xy 138.056602 -227.970602) (xy 138.107454 -227.968553) (xy 138.157975 -227.974687)
			(xy 138.206859 -227.988847) (xy 138.252838 -228.010664) (xy 138.294722 -228.039574) (xy 138.331426 -228.074829)
			(xy 138.361999 -228.115515) (xy 138.38565 -228.160578) (xy 138.401766 -228.208852) (xy 138.40993 -228.259086)
			(xy 138.410442 -228.284532) (xy 138.718539 -228.284532) (xy 138.722634 -228.233804) (xy 138.734813 -228.18439)
			(xy 138.754761 -228.13757) (xy 138.781962 -228.094556) (xy 138.81571 -228.056462) (xy 138.855132 -228.024275)
			(xy 138.899206 -227.998829) (xy 138.946792 -227.980782) (xy 138.996656 -227.970602) (xy 139.047508 -227.968553)
			(xy 139.098029 -227.974687) (xy 139.146913 -227.988847) (xy 139.192892 -228.010664) (xy 139.234776 -228.039574)
			(xy 139.27148 -228.074829) (xy 139.302053 -228.115515) (xy 139.325704 -228.160578) (xy 139.34182 -228.208852)
			(xy 139.349984 -228.259086) (xy 139.350496 -228.284532) (xy 139.669024 -228.284532) (xy 139.672984 -228.235478)
			(xy 139.684761 -228.187694) (xy 139.704052 -228.142418) (xy 139.730355 -228.100822) (xy 139.76299 -228.063985)
			(xy 139.801111 -228.03286) (xy 139.843732 -228.008253) (xy 139.889748 -227.990801) (xy 139.937967 -227.980957)
			(xy 139.987142 -227.978976) (xy 140.035997 -227.984908) (xy 140.083268 -227.9986) (xy 140.12773 -228.019698)
			(xy 140.168233 -228.047654) (xy 140.203726 -228.081746) (xy 140.233291 -228.12109) (xy 140.256162 -228.164667)
			(xy 140.271746 -228.211348) (xy 140.279641 -228.259925) (xy 140.280136 -228.284532) (xy 140.598647 -228.284532)
			(xy 140.602742 -228.233804) (xy 140.614921 -228.18439) (xy 140.634869 -228.13757) (xy 140.66207 -228.094556)
			(xy 140.695818 -228.056462) (xy 140.73524 -228.024275) (xy 140.779314 -227.998829) (xy 140.8269 -227.980782)
			(xy 140.876764 -227.970602) (xy 140.927616 -227.968553) (xy 140.978137 -227.974687) (xy 141.027021 -227.988847)
			(xy 141.073 -228.010664) (xy 141.114884 -228.039574) (xy 141.151588 -228.074829) (xy 141.182161 -228.115515)
			(xy 141.205812 -228.160578) (xy 141.221928 -228.208852) (xy 141.230092 -228.259086) (xy 141.230604 -228.284532)
			(xy 141.548878 -228.284532) (xy 141.552838 -228.235478) (xy 141.564615 -228.187694) (xy 141.583906 -228.142418)
			(xy 141.610209 -228.100822) (xy 141.642844 -228.063985) (xy 141.680965 -228.03286) (xy 141.723586 -228.008253)
			(xy 141.769602 -227.990801) (xy 141.817821 -227.980957) (xy 141.866996 -227.978976) (xy 141.915851 -227.984908)
			(xy 141.963122 -227.9986) (xy 142.007584 -228.019698) (xy 142.048087 -228.047654) (xy 142.08358 -228.081746)
			(xy 142.113145 -228.12109) (xy 142.136016 -228.164667) (xy 142.1516 -228.211348) (xy 142.159495 -228.259925)
			(xy 142.15999 -228.284532) (xy 142.478501 -228.284532) (xy 142.482596 -228.233804) (xy 142.494775 -228.18439)
			(xy 142.514723 -228.13757) (xy 142.541924 -228.094556) (xy 142.575672 -228.056462) (xy 142.615094 -228.024275)
			(xy 142.659168 -227.998829) (xy 142.706754 -227.980782) (xy 142.756618 -227.970602) (xy 142.80747 -227.968553)
			(xy 142.857991 -227.974687) (xy 142.906875 -227.988847) (xy 142.952854 -228.010664) (xy 142.994738 -228.039574)
			(xy 143.031442 -228.074829) (xy 143.062015 -228.115515) (xy 143.085666 -228.160578) (xy 143.101782 -228.208852)
			(xy 143.109946 -228.259086) (xy 143.110458 -228.284532) (xy 143.428986 -228.284532) (xy 143.432946 -228.235478)
			(xy 143.444723 -228.187694) (xy 143.464014 -228.142418) (xy 143.490317 -228.100822) (xy 143.522952 -228.063985)
			(xy 143.561073 -228.03286) (xy 143.603694 -228.008253) (xy 143.64971 -227.990801) (xy 143.697929 -227.980957)
			(xy 143.747104 -227.978976) (xy 143.795959 -227.984908) (xy 143.84323 -227.9986) (xy 143.887692 -228.019698)
			(xy 143.928195 -228.047654) (xy 143.963688 -228.081746) (xy 143.993253 -228.12109) (xy 144.016124 -228.164667)
			(xy 144.031708 -228.211348) (xy 144.039603 -228.259925) (xy 144.040098 -228.284532) (xy 144.039603 -228.309139)
			(xy 144.031708 -228.357716) (xy 144.016124 -228.404397) (xy 143.993253 -228.447974) (xy 143.963688 -228.487318)
			(xy 143.928195 -228.52141) (xy 143.887692 -228.549366) (xy 143.84323 -228.570464) (xy 143.795959 -228.584156)
			(xy 143.747104 -228.590088) (xy 143.697929 -228.588107) (xy 143.64971 -228.578263) (xy 143.603694 -228.560811)
			(xy 143.561073 -228.536204) (xy 143.522952 -228.505079) (xy 143.490317 -228.468242) (xy 143.464014 -228.426646)
			(xy 143.444723 -228.38137) (xy 143.432946 -228.333586) (xy 143.428986 -228.284532) (xy 143.110458 -228.284532)
			(xy 143.109946 -228.309978) (xy 143.101782 -228.360212) (xy 143.085666 -228.408486) (xy 143.062015 -228.453549)
			(xy 143.031442 -228.494235) (xy 142.994738 -228.52949) (xy 142.952854 -228.5584) (xy 142.906875 -228.580217)
			(xy 142.857991 -228.594377) (xy 142.80747 -228.600511) (xy 142.756618 -228.598462) (xy 142.706754 -228.588282)
			(xy 142.659168 -228.570235) (xy 142.615094 -228.544789) (xy 142.575672 -228.512602) (xy 142.541924 -228.474508)
			(xy 142.514723 -228.431494) (xy 142.494775 -228.384674) (xy 142.482596 -228.33526) (xy 142.478501 -228.284532)
			(xy 142.15999 -228.284532) (xy 142.159495 -228.309139) (xy 142.1516 -228.357716) (xy 142.136016 -228.404397)
			(xy 142.113145 -228.447974) (xy 142.08358 -228.487318) (xy 142.048087 -228.52141) (xy 142.007584 -228.549366)
			(xy 141.963122 -228.570464) (xy 141.915851 -228.584156) (xy 141.866996 -228.590088) (xy 141.817821 -228.588107)
			(xy 141.769602 -228.578263) (xy 141.723586 -228.560811) (xy 141.680965 -228.536204) (xy 141.642844 -228.505079)
			(xy 141.610209 -228.468242) (xy 141.583906 -228.426646) (xy 141.564615 -228.38137) (xy 141.552838 -228.333586)
			(xy 141.548878 -228.284532) (xy 141.230604 -228.284532) (xy 141.230092 -228.309978) (xy 141.221928 -228.360212)
			(xy 141.205812 -228.408486) (xy 141.182161 -228.453549) (xy 141.151588 -228.494235) (xy 141.114884 -228.52949)
			(xy 141.073 -228.5584) (xy 141.027021 -228.580217) (xy 140.978137 -228.594377) (xy 140.927616 -228.600511)
			(xy 140.876764 -228.598462) (xy 140.8269 -228.588282) (xy 140.779314 -228.570235) (xy 140.73524 -228.544789)
			(xy 140.695818 -228.512602) (xy 140.66207 -228.474508) (xy 140.634869 -228.431494) (xy 140.614921 -228.384674)
			(xy 140.602742 -228.33526) (xy 140.598647 -228.284532) (xy 140.280136 -228.284532) (xy 140.279641 -228.309139)
			(xy 140.271746 -228.357716) (xy 140.256162 -228.404397) (xy 140.233291 -228.447974) (xy 140.203726 -228.487318)
			(xy 140.168233 -228.52141) (xy 140.12773 -228.549366) (xy 140.083268 -228.570464) (xy 140.035997 -228.584156)
			(xy 139.987142 -228.590088) (xy 139.937967 -228.588107) (xy 139.889748 -228.578263) (xy 139.843732 -228.560811)
			(xy 139.801111 -228.536204) (xy 139.76299 -228.505079) (xy 139.730355 -228.468242) (xy 139.704052 -228.426646)
			(xy 139.684761 -228.38137) (xy 139.672984 -228.333586) (xy 139.669024 -228.284532) (xy 139.350496 -228.284532)
			(xy 139.349984 -228.309978) (xy 139.34182 -228.360212) (xy 139.325704 -228.408486) (xy 139.302053 -228.453549)
			(xy 139.27148 -228.494235) (xy 139.234776 -228.52949) (xy 139.192892 -228.5584) (xy 139.146913 -228.580217)
			(xy 139.098029 -228.594377) (xy 139.047508 -228.600511) (xy 138.996656 -228.598462) (xy 138.946792 -228.588282)
			(xy 138.899206 -228.570235) (xy 138.855132 -228.544789) (xy 138.81571 -228.512602) (xy 138.781962 -228.474508)
			(xy 138.754761 -228.431494) (xy 138.734813 -228.384674) (xy 138.722634 -228.33526) (xy 138.718539 -228.284532)
			(xy 138.410442 -228.284532) (xy 138.40993 -228.309978) (xy 138.401766 -228.360212) (xy 138.38565 -228.408486)
			(xy 138.361999 -228.453549) (xy 138.331426 -228.494235) (xy 138.294722 -228.52949) (xy 138.252838 -228.5584)
			(xy 138.206859 -228.580217) (xy 138.157975 -228.594377) (xy 138.107454 -228.600511) (xy 138.056602 -228.598462)
			(xy 138.006738 -228.588282) (xy 137.959152 -228.570235) (xy 137.915078 -228.544789) (xy 137.875656 -228.512602)
			(xy 137.841908 -228.474508) (xy 137.814707 -228.431494) (xy 137.794759 -228.384674) (xy 137.78258 -228.33526)
			(xy 137.778485 -228.284532) (xy 137.459974 -228.284532) (xy 137.459479 -228.309139) (xy 137.451584 -228.357716)
			(xy 137.436 -228.404397) (xy 137.413129 -228.447974) (xy 137.383564 -228.487318) (xy 137.348071 -228.52141)
			(xy 137.307568 -228.549366) (xy 137.263106 -228.570464) (xy 137.215835 -228.584156) (xy 137.16698 -228.590088)
			(xy 137.117805 -228.588107) (xy 137.069586 -228.578263) (xy 137.02357 -228.560811) (xy 136.980949 -228.536204)
			(xy 136.942828 -228.505079) (xy 136.910193 -228.468242) (xy 136.88389 -228.426646) (xy 136.864599 -228.38137)
			(xy 136.852822 -228.333586) (xy 136.848862 -228.284532) (xy 136.530588 -228.284532) (xy 136.530076 -228.309978)
			(xy 136.521912 -228.360212) (xy 136.505796 -228.408486) (xy 136.482145 -228.453549) (xy 136.451572 -228.494235)
			(xy 136.414868 -228.52949) (xy 136.372984 -228.5584) (xy 136.327005 -228.580217) (xy 136.278121 -228.594377)
			(xy 136.2276 -228.600511) (xy 136.176748 -228.598462) (xy 136.126884 -228.588282) (xy 136.079298 -228.570235)
			(xy 136.035224 -228.544789) (xy 135.995802 -228.512602) (xy 135.962054 -228.474508) (xy 135.934853 -228.431494)
			(xy 135.914905 -228.384674) (xy 135.902726 -228.33526) (xy 135.898631 -228.284532) (xy 135.58012 -228.284532)
			(xy 135.579625 -228.309139) (xy 135.57173 -228.357716) (xy 135.556146 -228.404397) (xy 135.533275 -228.447974)
			(xy 135.50371 -228.487318) (xy 135.468217 -228.52141) (xy 135.427714 -228.549366) (xy 135.383252 -228.570464)
			(xy 135.335981 -228.584156) (xy 135.287126 -228.590088) (xy 135.237951 -228.588107) (xy 135.189732 -228.578263)
			(xy 135.143716 -228.560811) (xy 135.101095 -228.536204) (xy 135.062974 -228.505079) (xy 135.030339 -228.468242)
			(xy 135.004036 -228.426646) (xy 134.984745 -228.38137) (xy 134.972968 -228.333586) (xy 134.969008 -228.284532)
			(xy 134.65048 -228.284532) (xy 134.649968 -228.309978) (xy 134.641804 -228.360212) (xy 134.625688 -228.408486)
			(xy 134.602037 -228.453549) (xy 134.571464 -228.494235) (xy 134.53476 -228.52949) (xy 134.492876 -228.5584)
			(xy 134.446897 -228.580217) (xy 134.398013 -228.594377) (xy 134.347492 -228.600511) (xy 134.29664 -228.598462)
			(xy 134.246776 -228.588282) (xy 134.19919 -228.570235) (xy 134.155116 -228.544789) (xy 134.115694 -228.512602)
			(xy 134.081946 -228.474508) (xy 134.054745 -228.431494) (xy 134.034797 -228.384674) (xy 134.022618 -228.33526)
			(xy 134.018523 -228.284532) (xy 133.700012 -228.284532) (xy 133.699517 -228.309139) (xy 133.691622 -228.357716)
			(xy 133.676038 -228.404397) (xy 133.653167 -228.447974) (xy 133.623602 -228.487318) (xy 133.588109 -228.52141)
			(xy 133.547606 -228.549366) (xy 133.503144 -228.570464) (xy 133.455873 -228.584156) (xy 133.407018 -228.590088)
			(xy 133.357843 -228.588107) (xy 133.309624 -228.578263) (xy 133.263608 -228.560811) (xy 133.220987 -228.536204)
			(xy 133.182866 -228.505079) (xy 133.150231 -228.468242) (xy 133.123928 -228.426646) (xy 133.104637 -228.38137)
			(xy 133.09286 -228.333586) (xy 133.0889 -228.284532) (xy 132.770372 -228.284532) (xy 132.76986 -228.309978)
			(xy 132.761696 -228.360212) (xy 132.74558 -228.408486) (xy 132.721929 -228.453549) (xy 132.691356 -228.494235)
			(xy 132.654652 -228.52949) (xy 132.612768 -228.5584) (xy 132.566789 -228.580217) (xy 132.517905 -228.594377)
			(xy 132.467384 -228.600511) (xy 132.416532 -228.598462) (xy 132.366668 -228.588282) (xy 132.319082 -228.570235)
			(xy 132.275008 -228.544789) (xy 132.235586 -228.512602) (xy 132.201838 -228.474508) (xy 132.174637 -228.431494)
			(xy 132.154689 -228.384674) (xy 132.14251 -228.33526) (xy 132.138415 -228.284532) (xy 131.830572 -228.284532)
			(xy 131.83006 -228.309978) (xy 131.821896 -228.360212) (xy 131.80578 -228.408486) (xy 131.782129 -228.453549)
			(xy 131.751556 -228.494235) (xy 131.714852 -228.52949) (xy 131.672968 -228.5584) (xy 131.626989 -228.580217)
			(xy 131.578105 -228.594377) (xy 131.527584 -228.600511) (xy 131.476732 -228.598462) (xy 131.426868 -228.588282)
			(xy 131.379282 -228.570235) (xy 131.335208 -228.544789) (xy 131.295786 -228.512602) (xy 131.262038 -228.474508)
			(xy 131.234837 -228.431494) (xy 131.214889 -228.384674) (xy 131.20271 -228.33526) (xy 131.198615 -228.284532)
			(xy 130.880104 -228.284532) (xy 130.879609 -228.309139) (xy 130.871714 -228.357716) (xy 130.85613 -228.404397)
			(xy 130.833259 -228.447974) (xy 130.803694 -228.487318) (xy 130.768201 -228.52141) (xy 130.727698 -228.549366)
			(xy 130.683236 -228.570464) (xy 130.635965 -228.584156) (xy 130.58711 -228.590088) (xy 130.537935 -228.588107)
			(xy 130.489716 -228.578263) (xy 130.4437 -228.560811) (xy 130.401079 -228.536204) (xy 130.362958 -228.505079)
			(xy 130.330323 -228.468242) (xy 130.30402 -228.426646) (xy 130.284729 -228.38137) (xy 130.272952 -228.333586)
			(xy 130.268992 -228.284532) (xy 129.950464 -228.284532) (xy 129.949952 -228.309978) (xy 129.941788 -228.360212)
			(xy 129.925672 -228.408486) (xy 129.902021 -228.453549) (xy 129.871448 -228.494235) (xy 129.834744 -228.52949)
			(xy 129.79286 -228.5584) (xy 129.746881 -228.580217) (xy 129.697997 -228.594377) (xy 129.647476 -228.600511)
			(xy 129.596624 -228.598462) (xy 129.54676 -228.588282) (xy 129.499174 -228.570235) (xy 129.4551 -228.544789)
			(xy 129.415678 -228.512602) (xy 129.38193 -228.474508) (xy 129.354729 -228.431494) (xy 129.334781 -228.384674)
			(xy 129.322602 -228.33526) (xy 129.318507 -228.284532) (xy 128.999996 -228.284532) (xy 128.999501 -228.309139)
			(xy 128.991606 -228.357716) (xy 128.976022 -228.404397) (xy 128.953151 -228.447974) (xy 128.923586 -228.487318)
			(xy 128.888093 -228.52141) (xy 128.84759 -228.549366) (xy 128.803128 -228.570464) (xy 128.755857 -228.584156)
			(xy 128.707002 -228.590088) (xy 128.657827 -228.588107) (xy 128.609608 -228.578263) (xy 128.563592 -228.560811)
			(xy 128.520971 -228.536204) (xy 128.48285 -228.505079) (xy 128.450215 -228.468242) (xy 128.423912 -228.426646)
			(xy 128.404621 -228.38137) (xy 128.392844 -228.333586) (xy 128.388884 -228.284532) (xy 128.06955 -228.284532)
			(xy 128.06955 -228.309285) (xy 128.061796 -228.358246) (xy 128.046479 -228.405391) (xy 128.023975 -228.449559)
			(xy 127.99484 -228.489664) (xy 127.95979 -228.524718) (xy 127.919688 -228.553858) (xy 127.875522 -228.576365)
			(xy 127.828379 -228.591688) (xy 127.779419 -228.599447) (xy 127.754634 -228.6) (xy 127.732959 -228.599672)
			(xy 127.690008 -228.593803) (xy 127.669036 -228.588316) (xy 127.662432 -228.586284) (xy 127.65532 -228.586284)
			(xy 127.645295 -228.5867) (xy 127.626768 -228.594366) (xy 127.612586 -228.608538) (xy 127.604907 -228.627059)
			(xy 127.60452 -228.637084) (xy 127.60452 -228.655372) (xy 127.607314 -228.663246) (xy 127.622677 -228.70957)
			(xy 127.647395 -228.803995) (xy 127.665145 -228.899975) (xy 127.675831 -228.996994) (xy 127.679398 -229.094536)
			(xy 127.679398 -229.094538) (xy 127.908553 -229.094538) (xy 127.912648 -229.04381) (xy 127.924827 -228.994396)
			(xy 127.944775 -228.947576) (xy 127.971976 -228.904562) (xy 128.005724 -228.866468) (xy 128.045146 -228.834281)
			(xy 128.08922 -228.808835) (xy 128.136806 -228.790788) (xy 128.18667 -228.780608) (xy 128.237522 -228.778559)
			(xy 128.288043 -228.784693) (xy 128.336927 -228.798853) (xy 128.382906 -228.82067) (xy 128.42479 -228.84958)
			(xy 128.461494 -228.884835) (xy 128.492067 -228.925521) (xy 128.515718 -228.970584) (xy 128.531834 -229.018858)
			(xy 128.539998 -229.069092) (xy 128.54051 -229.094538) (xy 128.848607 -229.094538) (xy 128.852702 -229.04381)
			(xy 128.864881 -228.994396) (xy 128.884829 -228.947576) (xy 128.91203 -228.904562) (xy 128.945778 -228.866468)
			(xy 128.9852 -228.834281) (xy 129.029274 -228.808835) (xy 129.07686 -228.790788) (xy 129.126724 -228.780608)
			(xy 129.177576 -228.778559) (xy 129.228097 -228.784693) (xy 129.276981 -228.798853) (xy 129.32296 -228.82067)
			(xy 129.364844 -228.84958) (xy 129.401548 -228.884835) (xy 129.432121 -228.925521) (xy 129.455772 -228.970584)
			(xy 129.471888 -229.018858) (xy 129.480052 -229.069092) (xy 129.480564 -229.094538) (xy 129.798838 -229.094538)
			(xy 129.802798 -229.045484) (xy 129.814575 -228.9977) (xy 129.833866 -228.952424) (xy 129.860169 -228.910828)
			(xy 129.892804 -228.873991) (xy 129.930925 -228.842866) (xy 129.973546 -228.818259) (xy 130.019562 -228.800807)
			(xy 130.067781 -228.790963) (xy 130.116956 -228.788982) (xy 130.165811 -228.794914) (xy 130.213082 -228.808606)
			(xy 130.257544 -228.829704) (xy 130.298047 -228.85766) (xy 130.33354 -228.891752) (xy 130.363105 -228.931096)
			(xy 130.385976 -228.974673) (xy 130.40156 -229.021354) (xy 130.409455 -229.069931) (xy 130.40995 -229.094538)
			(xy 130.728461 -229.094538) (xy 130.732556 -229.04381) (xy 130.744735 -228.994396) (xy 130.764683 -228.947576)
			(xy 130.791884 -228.904562) (xy 130.825632 -228.866468) (xy 130.865054 -228.834281) (xy 130.909128 -228.808835)
			(xy 130.956714 -228.790788) (xy 131.006578 -228.780608) (xy 131.05743 -228.778559) (xy 131.107951 -228.784693)
			(xy 131.156835 -228.798853) (xy 131.202814 -228.82067) (xy 131.244698 -228.84958) (xy 131.281402 -228.884835)
			(xy 131.311975 -228.925521) (xy 131.335626 -228.970584) (xy 131.351742 -229.018858) (xy 131.359906 -229.069092)
			(xy 131.360418 -229.094538) (xy 131.678946 -229.094538) (xy 131.682906 -229.045484) (xy 131.694683 -228.9977)
			(xy 131.713974 -228.952424) (xy 131.740277 -228.910828) (xy 131.772912 -228.873991) (xy 131.811033 -228.842866)
			(xy 131.853654 -228.818259) (xy 131.89967 -228.800807) (xy 131.947889 -228.790963) (xy 131.997064 -228.788982)
			(xy 132.045919 -228.794914) (xy 132.09319 -228.808606) (xy 132.137652 -228.829704) (xy 132.178155 -228.85766)
			(xy 132.213648 -228.891752) (xy 132.243213 -228.931096) (xy 132.266084 -228.974673) (xy 132.281668 -229.021354)
			(xy 132.289563 -229.069931) (xy 132.290058 -229.094538) (xy 132.608569 -229.094538) (xy 132.612664 -229.04381)
			(xy 132.624843 -228.994396) (xy 132.644791 -228.947576) (xy 132.671992 -228.904562) (xy 132.70574 -228.866468)
			(xy 132.745162 -228.834281) (xy 132.789236 -228.808835) (xy 132.836822 -228.790788) (xy 132.886686 -228.780608)
			(xy 132.937538 -228.778559) (xy 132.988059 -228.784693) (xy 133.036943 -228.798853) (xy 133.082922 -228.82067)
			(xy 133.124806 -228.84958) (xy 133.16151 -228.884835) (xy 133.192083 -228.925521) (xy 133.215734 -228.970584)
			(xy 133.23185 -229.018858) (xy 133.240014 -229.069092) (xy 133.240526 -229.094538) (xy 133.559054 -229.094538)
			(xy 133.563014 -229.045484) (xy 133.574791 -228.9977) (xy 133.594082 -228.952424) (xy 133.620385 -228.910828)
			(xy 133.65302 -228.873991) (xy 133.691141 -228.842866) (xy 133.733762 -228.818259) (xy 133.779778 -228.800807)
			(xy 133.827997 -228.790963) (xy 133.877172 -228.788982) (xy 133.926027 -228.794914) (xy 133.973298 -228.808606)
			(xy 134.01776 -228.829704) (xy 134.058263 -228.85766) (xy 134.093756 -228.891752) (xy 134.123321 -228.931096)
			(xy 134.146192 -228.974673) (xy 134.161776 -229.021354) (xy 134.169671 -229.069931) (xy 134.170166 -229.094538)
			(xy 134.488423 -229.094538) (xy 134.492518 -229.04381) (xy 134.504697 -228.994396) (xy 134.524645 -228.947576)
			(xy 134.551846 -228.904562) (xy 134.585594 -228.866468) (xy 134.625016 -228.834281) (xy 134.66909 -228.808835)
			(xy 134.716676 -228.790788) (xy 134.76654 -228.780608) (xy 134.817392 -228.778559) (xy 134.867913 -228.784693)
			(xy 134.916797 -228.798853) (xy 134.962776 -228.82067) (xy 135.00466 -228.84958) (xy 135.041364 -228.884835)
			(xy 135.071937 -228.925521) (xy 135.095588 -228.970584) (xy 135.111704 -229.018858) (xy 135.119868 -229.069092)
			(xy 135.12038 -229.094538) (xy 135.428477 -229.094538) (xy 135.432572 -229.04381) (xy 135.444751 -228.994396)
			(xy 135.464699 -228.947576) (xy 135.4919 -228.904562) (xy 135.525648 -228.866468) (xy 135.56507 -228.834281)
			(xy 135.609144 -228.808835) (xy 135.65673 -228.790788) (xy 135.706594 -228.780608) (xy 135.757446 -228.778559)
			(xy 135.807967 -228.784693) (xy 135.856851 -228.798853) (xy 135.90283 -228.82067) (xy 135.944714 -228.84958)
			(xy 135.981418 -228.884835) (xy 136.011991 -228.925521) (xy 136.035642 -228.970584) (xy 136.051758 -229.018858)
			(xy 136.059922 -229.069092) (xy 136.060434 -229.094538) (xy 136.378962 -229.094538) (xy 136.382922 -229.045484)
			(xy 136.394699 -228.9977) (xy 136.41399 -228.952424) (xy 136.440293 -228.910828) (xy 136.472928 -228.873991)
			(xy 136.511049 -228.842866) (xy 136.55367 -228.818259) (xy 136.599686 -228.800807) (xy 136.647905 -228.790963)
			(xy 136.69708 -228.788982) (xy 136.745935 -228.794914) (xy 136.793206 -228.808606) (xy 136.837668 -228.829704)
			(xy 136.878171 -228.85766) (xy 136.913664 -228.891752) (xy 136.943229 -228.931096) (xy 136.9661 -228.974673)
			(xy 136.981684 -229.021354) (xy 136.989579 -229.069931) (xy 136.990074 -229.094538) (xy 137.308585 -229.094538)
			(xy 137.31268 -229.04381) (xy 137.324859 -228.994396) (xy 137.344807 -228.947576) (xy 137.372008 -228.904562)
			(xy 137.405756 -228.866468) (xy 137.445178 -228.834281) (xy 137.489252 -228.808835) (xy 137.536838 -228.790788)
			(xy 137.586702 -228.780608) (xy 137.637554 -228.778559) (xy 137.688075 -228.784693) (xy 137.736959 -228.798853)
			(xy 137.782938 -228.82067) (xy 137.824822 -228.84958) (xy 137.861526 -228.884835) (xy 137.892099 -228.925521)
			(xy 137.91575 -228.970584) (xy 137.931866 -229.018858) (xy 137.94003 -229.069092) (xy 137.940542 -229.094538)
			(xy 138.25907 -229.094538) (xy 138.26303 -229.045484) (xy 138.274807 -228.9977) (xy 138.294098 -228.952424)
			(xy 138.320401 -228.910828) (xy 138.353036 -228.873991) (xy 138.391157 -228.842866) (xy 138.433778 -228.818259)
			(xy 138.479794 -228.800807) (xy 138.528013 -228.790963) (xy 138.577188 -228.788982) (xy 138.626043 -228.794914)
			(xy 138.673314 -228.808606) (xy 138.717776 -228.829704) (xy 138.758279 -228.85766) (xy 138.793772 -228.891752)
			(xy 138.823337 -228.931096) (xy 138.846208 -228.974673) (xy 138.861792 -229.021354) (xy 138.869687 -229.069931)
			(xy 138.870182 -229.094538) (xy 139.188439 -229.094538) (xy 139.192534 -229.04381) (xy 139.204713 -228.994396)
			(xy 139.224661 -228.947576) (xy 139.251862 -228.904562) (xy 139.28561 -228.866468) (xy 139.325032 -228.834281)
			(xy 139.369106 -228.808835) (xy 139.416692 -228.790788) (xy 139.466556 -228.780608) (xy 139.517408 -228.778559)
			(xy 139.567929 -228.784693) (xy 139.616813 -228.798853) (xy 139.662792 -228.82067) (xy 139.704676 -228.84958)
			(xy 139.74138 -228.884835) (xy 139.771953 -228.925521) (xy 139.795604 -228.970584) (xy 139.81172 -229.018858)
			(xy 139.819884 -229.069092) (xy 139.820396 -229.094538) (xy 140.138924 -229.094538) (xy 140.142884 -229.045484)
			(xy 140.154661 -228.9977) (xy 140.173952 -228.952424) (xy 140.200255 -228.910828) (xy 140.23289 -228.873991)
			(xy 140.271011 -228.842866) (xy 140.313632 -228.818259) (xy 140.359648 -228.800807) (xy 140.407867 -228.790963)
			(xy 140.457042 -228.788982) (xy 140.505897 -228.794914) (xy 140.553168 -228.808606) (xy 140.59763 -228.829704)
			(xy 140.638133 -228.85766) (xy 140.673626 -228.891752) (xy 140.703191 -228.931096) (xy 140.726062 -228.974673)
			(xy 140.741646 -229.021354) (xy 140.749541 -229.069931) (xy 140.750036 -229.094538) (xy 141.068547 -229.094538)
			(xy 141.072642 -229.04381) (xy 141.084821 -228.994396) (xy 141.104769 -228.947576) (xy 141.13197 -228.904562)
			(xy 141.165718 -228.866468) (xy 141.20514 -228.834281) (xy 141.249214 -228.808835) (xy 141.2968 -228.790788)
			(xy 141.346664 -228.780608) (xy 141.397516 -228.778559) (xy 141.448037 -228.784693) (xy 141.496921 -228.798853)
			(xy 141.5429 -228.82067) (xy 141.584784 -228.84958) (xy 141.621488 -228.884835) (xy 141.652061 -228.925521)
			(xy 141.675712 -228.970584) (xy 141.691828 -229.018858) (xy 141.699992 -229.069092) (xy 141.700504 -229.094538)
			(xy 142.008601 -229.094538) (xy 142.012696 -229.04381) (xy 142.024875 -228.994396) (xy 142.044823 -228.947576)
			(xy 142.072024 -228.904562) (xy 142.105772 -228.866468) (xy 142.145194 -228.834281) (xy 142.189268 -228.808835)
			(xy 142.236854 -228.790788) (xy 142.286718 -228.780608) (xy 142.33757 -228.778559) (xy 142.388091 -228.784693)
			(xy 142.436975 -228.798853) (xy 142.482954 -228.82067) (xy 142.524838 -228.84958) (xy 142.561542 -228.884835)
			(xy 142.592115 -228.925521) (xy 142.615766 -228.970584) (xy 142.631882 -229.018858) (xy 142.640046 -229.069092)
			(xy 142.640558 -229.094538) (xy 142.958832 -229.094538) (xy 142.962792 -229.045484) (xy 142.974569 -228.9977)
			(xy 142.99386 -228.952424) (xy 143.020163 -228.910828) (xy 143.052798 -228.873991) (xy 143.090919 -228.842866)
			(xy 143.13354 -228.818259) (xy 143.179556 -228.800807) (xy 143.227775 -228.790963) (xy 143.27695 -228.788982)
			(xy 143.325805 -228.794914) (xy 143.373076 -228.808606) (xy 143.417538 -228.829704) (xy 143.458041 -228.85766)
			(xy 143.493534 -228.891752) (xy 143.523099 -228.931096) (xy 143.54597 -228.974673) (xy 143.561554 -229.021354)
			(xy 143.569449 -229.069931) (xy 143.569944 -229.094538) (xy 144.83894 -229.094538) (xy 144.8429 -229.045484)
			(xy 144.854677 -228.9977) (xy 144.873968 -228.952424) (xy 144.900271 -228.910828) (xy 144.932906 -228.873991)
			(xy 144.971027 -228.842866) (xy 145.013648 -228.818259) (xy 145.059664 -228.800807) (xy 145.107883 -228.790963)
			(xy 145.157058 -228.788982) (xy 145.205913 -228.794914) (xy 145.253184 -228.808606) (xy 145.297646 -228.829704)
			(xy 145.338149 -228.85766) (xy 145.373642 -228.891752) (xy 145.403207 -228.931096) (xy 145.426078 -228.974673)
			(xy 145.441662 -229.021354) (xy 145.449557 -229.069931) (xy 145.450052 -229.094538) (xy 145.449557 -229.119145)
			(xy 145.441662 -229.167722) (xy 145.426078 -229.214403) (xy 145.403207 -229.25798) (xy 145.373642 -229.297324)
			(xy 145.338149 -229.331416) (xy 145.297646 -229.359372) (xy 145.253184 -229.38047) (xy 145.205913 -229.394162)
			(xy 145.157058 -229.400094) (xy 145.107883 -229.398113) (xy 145.059664 -229.388269) (xy 145.013648 -229.370817)
			(xy 144.971027 -229.34621) (xy 144.932906 -229.315085) (xy 144.900271 -229.278248) (xy 144.873968 -229.236652)
			(xy 144.854677 -229.191376) (xy 144.8429 -229.143592) (xy 144.83894 -229.094538) (xy 143.569944 -229.094538)
			(xy 143.569449 -229.119145) (xy 143.561554 -229.167722) (xy 143.54597 -229.214403) (xy 143.523099 -229.25798)
			(xy 143.493534 -229.297324) (xy 143.458041 -229.331416) (xy 143.417538 -229.359372) (xy 143.373076 -229.38047)
			(xy 143.325805 -229.394162) (xy 143.27695 -229.400094) (xy 143.227775 -229.398113) (xy 143.179556 -229.388269)
			(xy 143.13354 -229.370817) (xy 143.090919 -229.34621) (xy 143.052798 -229.315085) (xy 143.020163 -229.278248)
			(xy 142.99386 -229.236652) (xy 142.974569 -229.191376) (xy 142.962792 -229.143592) (xy 142.958832 -229.094538)
			(xy 142.640558 -229.094538) (xy 142.640046 -229.119984) (xy 142.631882 -229.170218) (xy 142.615766 -229.218492)
			(xy 142.592115 -229.263555) (xy 142.561542 -229.304241) (xy 142.524838 -229.339496) (xy 142.482954 -229.368406)
			(xy 142.436975 -229.390223) (xy 142.388091 -229.404383) (xy 142.33757 -229.410517) (xy 142.286718 -229.408468)
			(xy 142.236854 -229.398288) (xy 142.189268 -229.380241) (xy 142.145194 -229.354795) (xy 142.105772 -229.322608)
			(xy 142.072024 -229.284514) (xy 142.044823 -229.2415) (xy 142.024875 -229.19468) (xy 142.012696 -229.145266)
			(xy 142.008601 -229.094538) (xy 141.700504 -229.094538) (xy 141.699992 -229.119984) (xy 141.691828 -229.170218)
			(xy 141.675712 -229.218492) (xy 141.652061 -229.263555) (xy 141.621488 -229.304241) (xy 141.584784 -229.339496)
			(xy 141.5429 -229.368406) (xy 141.496921 -229.390223) (xy 141.448037 -229.404383) (xy 141.397516 -229.410517)
			(xy 141.346664 -229.408468) (xy 141.2968 -229.398288) (xy 141.249214 -229.380241) (xy 141.20514 -229.354795)
			(xy 141.165718 -229.322608) (xy 141.13197 -229.284514) (xy 141.104769 -229.2415) (xy 141.084821 -229.19468)
			(xy 141.072642 -229.145266) (xy 141.068547 -229.094538) (xy 140.750036 -229.094538) (xy 140.749541 -229.119145)
			(xy 140.741646 -229.167722) (xy 140.726062 -229.214403) (xy 140.703191 -229.25798) (xy 140.673626 -229.297324)
			(xy 140.638133 -229.331416) (xy 140.59763 -229.359372) (xy 140.553168 -229.38047) (xy 140.505897 -229.394162)
			(xy 140.457042 -229.400094) (xy 140.407867 -229.398113) (xy 140.359648 -229.388269) (xy 140.313632 -229.370817)
			(xy 140.271011 -229.34621) (xy 140.23289 -229.315085) (xy 140.200255 -229.278248) (xy 140.173952 -229.236652)
			(xy 140.154661 -229.191376) (xy 140.142884 -229.143592) (xy 140.138924 -229.094538) (xy 139.820396 -229.094538)
			(xy 139.819884 -229.119984) (xy 139.81172 -229.170218) (xy 139.795604 -229.218492) (xy 139.771953 -229.263555)
			(xy 139.74138 -229.304241) (xy 139.704676 -229.339496) (xy 139.662792 -229.368406) (xy 139.616813 -229.390223)
			(xy 139.567929 -229.404383) (xy 139.517408 -229.410517) (xy 139.466556 -229.408468) (xy 139.416692 -229.398288)
			(xy 139.369106 -229.380241) (xy 139.325032 -229.354795) (xy 139.28561 -229.322608) (xy 139.251862 -229.284514)
			(xy 139.224661 -229.2415) (xy 139.204713 -229.19468) (xy 139.192534 -229.145266) (xy 139.188439 -229.094538)
			(xy 138.870182 -229.094538) (xy 138.869687 -229.119145) (xy 138.861792 -229.167722) (xy 138.846208 -229.214403)
			(xy 138.823337 -229.25798) (xy 138.793772 -229.297324) (xy 138.758279 -229.331416) (xy 138.717776 -229.359372)
			(xy 138.673314 -229.38047) (xy 138.626043 -229.394162) (xy 138.577188 -229.400094) (xy 138.528013 -229.398113)
			(xy 138.479794 -229.388269) (xy 138.433778 -229.370817) (xy 138.391157 -229.34621) (xy 138.353036 -229.315085)
			(xy 138.320401 -229.278248) (xy 138.294098 -229.236652) (xy 138.274807 -229.191376) (xy 138.26303 -229.143592)
			(xy 138.25907 -229.094538) (xy 137.940542 -229.094538) (xy 137.94003 -229.119984) (xy 137.931866 -229.170218)
			(xy 137.91575 -229.218492) (xy 137.892099 -229.263555) (xy 137.861526 -229.304241) (xy 137.824822 -229.339496)
			(xy 137.782938 -229.368406) (xy 137.736959 -229.390223) (xy 137.688075 -229.404383) (xy 137.637554 -229.410517)
			(xy 137.586702 -229.408468) (xy 137.536838 -229.398288) (xy 137.489252 -229.380241) (xy 137.445178 -229.354795)
			(xy 137.405756 -229.322608) (xy 137.372008 -229.284514) (xy 137.344807 -229.2415) (xy 137.324859 -229.19468)
			(xy 137.31268 -229.145266) (xy 137.308585 -229.094538) (xy 136.990074 -229.094538) (xy 136.989579 -229.119145)
			(xy 136.981684 -229.167722) (xy 136.9661 -229.214403) (xy 136.943229 -229.25798) (xy 136.913664 -229.297324)
			(xy 136.878171 -229.331416) (xy 136.837668 -229.359372) (xy 136.793206 -229.38047) (xy 136.745935 -229.394162)
			(xy 136.69708 -229.400094) (xy 136.647905 -229.398113) (xy 136.599686 -229.388269) (xy 136.55367 -229.370817)
			(xy 136.511049 -229.34621) (xy 136.472928 -229.315085) (xy 136.440293 -229.278248) (xy 136.41399 -229.236652)
			(xy 136.394699 -229.191376) (xy 136.382922 -229.143592) (xy 136.378962 -229.094538) (xy 136.060434 -229.094538)
			(xy 136.059922 -229.119984) (xy 136.051758 -229.170218) (xy 136.035642 -229.218492) (xy 136.011991 -229.263555)
			(xy 135.981418 -229.304241) (xy 135.944714 -229.339496) (xy 135.90283 -229.368406) (xy 135.856851 -229.390223)
			(xy 135.807967 -229.404383) (xy 135.757446 -229.410517) (xy 135.706594 -229.408468) (xy 135.65673 -229.398288)
			(xy 135.609144 -229.380241) (xy 135.56507 -229.354795) (xy 135.525648 -229.322608) (xy 135.4919 -229.284514)
			(xy 135.464699 -229.2415) (xy 135.444751 -229.19468) (xy 135.432572 -229.145266) (xy 135.428477 -229.094538)
			(xy 135.12038 -229.094538) (xy 135.119868 -229.119984) (xy 135.111704 -229.170218) (xy 135.095588 -229.218492)
			(xy 135.071937 -229.263555) (xy 135.041364 -229.304241) (xy 135.00466 -229.339496) (xy 134.962776 -229.368406)
			(xy 134.916797 -229.390223) (xy 134.867913 -229.404383) (xy 134.817392 -229.410517) (xy 134.76654 -229.408468)
			(xy 134.716676 -229.398288) (xy 134.66909 -229.380241) (xy 134.625016 -229.354795) (xy 134.585594 -229.322608)
			(xy 134.551846 -229.284514) (xy 134.524645 -229.2415) (xy 134.504697 -229.19468) (xy 134.492518 -229.145266)
			(xy 134.488423 -229.094538) (xy 134.170166 -229.094538) (xy 134.169671 -229.119145) (xy 134.161776 -229.167722)
			(xy 134.146192 -229.214403) (xy 134.123321 -229.25798) (xy 134.093756 -229.297324) (xy 134.058263 -229.331416)
			(xy 134.01776 -229.359372) (xy 133.973298 -229.38047) (xy 133.926027 -229.394162) (xy 133.877172 -229.400094)
			(xy 133.827997 -229.398113) (xy 133.779778 -229.388269) (xy 133.733762 -229.370817) (xy 133.691141 -229.34621)
			(xy 133.65302 -229.315085) (xy 133.620385 -229.278248) (xy 133.594082 -229.236652) (xy 133.574791 -229.191376)
			(xy 133.563014 -229.143592) (xy 133.559054 -229.094538) (xy 133.240526 -229.094538) (xy 133.240014 -229.119984)
			(xy 133.23185 -229.170218) (xy 133.215734 -229.218492) (xy 133.192083 -229.263555) (xy 133.16151 -229.304241)
			(xy 133.124806 -229.339496) (xy 133.082922 -229.368406) (xy 133.036943 -229.390223) (xy 132.988059 -229.404383)
			(xy 132.937538 -229.410517) (xy 132.886686 -229.408468) (xy 132.836822 -229.398288) (xy 132.789236 -229.380241)
			(xy 132.745162 -229.354795) (xy 132.70574 -229.322608) (xy 132.671992 -229.284514) (xy 132.644791 -229.2415)
			(xy 132.624843 -229.19468) (xy 132.612664 -229.145266) (xy 132.608569 -229.094538) (xy 132.290058 -229.094538)
			(xy 132.289563 -229.119145) (xy 132.281668 -229.167722) (xy 132.266084 -229.214403) (xy 132.243213 -229.25798)
			(xy 132.213648 -229.297324) (xy 132.178155 -229.331416) (xy 132.137652 -229.359372) (xy 132.09319 -229.38047)
			(xy 132.045919 -229.394162) (xy 131.997064 -229.400094) (xy 131.947889 -229.398113) (xy 131.89967 -229.388269)
			(xy 131.853654 -229.370817) (xy 131.811033 -229.34621) (xy 131.772912 -229.315085) (xy 131.740277 -229.278248)
			(xy 131.713974 -229.236652) (xy 131.694683 -229.191376) (xy 131.682906 -229.143592) (xy 131.678946 -229.094538)
			(xy 131.360418 -229.094538) (xy 131.359906 -229.119984) (xy 131.351742 -229.170218) (xy 131.335626 -229.218492)
			(xy 131.311975 -229.263555) (xy 131.281402 -229.304241) (xy 131.244698 -229.339496) (xy 131.202814 -229.368406)
			(xy 131.156835 -229.390223) (xy 131.107951 -229.404383) (xy 131.05743 -229.410517) (xy 131.006578 -229.408468)
			(xy 130.956714 -229.398288) (xy 130.909128 -229.380241) (xy 130.865054 -229.354795) (xy 130.825632 -229.322608)
			(xy 130.791884 -229.284514) (xy 130.764683 -229.2415) (xy 130.744735 -229.19468) (xy 130.732556 -229.145266)
			(xy 130.728461 -229.094538) (xy 130.40995 -229.094538) (xy 130.409455 -229.119145) (xy 130.40156 -229.167722)
			(xy 130.385976 -229.214403) (xy 130.363105 -229.25798) (xy 130.33354 -229.297324) (xy 130.298047 -229.331416)
			(xy 130.257544 -229.359372) (xy 130.213082 -229.38047) (xy 130.165811 -229.394162) (xy 130.116956 -229.400094)
			(xy 130.067781 -229.398113) (xy 130.019562 -229.388269) (xy 129.973546 -229.370817) (xy 129.930925 -229.34621)
			(xy 129.892804 -229.315085) (xy 129.860169 -229.278248) (xy 129.833866 -229.236652) (xy 129.814575 -229.191376)
			(xy 129.802798 -229.143592) (xy 129.798838 -229.094538) (xy 129.480564 -229.094538) (xy 129.480052 -229.119984)
			(xy 129.471888 -229.170218) (xy 129.455772 -229.218492) (xy 129.432121 -229.263555) (xy 129.401548 -229.304241)
			(xy 129.364844 -229.339496) (xy 129.32296 -229.368406) (xy 129.276981 -229.390223) (xy 129.228097 -229.404383)
			(xy 129.177576 -229.410517) (xy 129.126724 -229.408468) (xy 129.07686 -229.398288) (xy 129.029274 -229.380241)
			(xy 128.9852 -229.354795) (xy 128.945778 -229.322608) (xy 128.91203 -229.284514) (xy 128.884829 -229.2415)
			(xy 128.864881 -229.19468) (xy 128.852702 -229.145266) (xy 128.848607 -229.094538) (xy 128.54051 -229.094538)
			(xy 128.539998 -229.119984) (xy 128.531834 -229.170218) (xy 128.515718 -229.218492) (xy 128.492067 -229.263555)
			(xy 128.461494 -229.304241) (xy 128.42479 -229.339496) (xy 128.382906 -229.368406) (xy 128.336927 -229.390223)
			(xy 128.288043 -229.404383) (xy 128.237522 -229.410517) (xy 128.18667 -229.408468) (xy 128.136806 -229.398288)
			(xy 128.08922 -229.380241) (xy 128.045146 -229.354795) (xy 128.005724 -229.322608) (xy 127.971976 -229.284514)
			(xy 127.944775 -229.2415) (xy 127.924827 -229.19468) (xy 127.912648 -229.145266) (xy 127.908553 -229.094538)
			(xy 127.679398 -229.094538) (xy 127.675826 -229.192077) (xy 127.665134 -229.289097) (xy 127.647379 -229.385075)
			(xy 127.622657 -229.479499) (xy 127.607314 -229.52583) (xy 127.60452 -229.533704) (xy 127.60452 -229.551738)
			(xy 127.605015 -229.561739) (xy 127.612682 -229.580214) (xy 127.626834 -229.594351) (xy 127.645318 -229.601997)
			(xy 127.65532 -229.602538) (xy 127.662432 -229.602538) (xy 127.669036 -229.600506) (xy 127.689997 -229.594938)
			(xy 127.73295 -229.588952) (xy 127.754634 -229.588568) (xy 127.779443 -229.589057) (xy 127.828448 -229.596824)
			(xy 127.875636 -229.612161) (xy 127.919843 -229.63469) (xy 127.959983 -229.663857) (xy 127.995066 -229.698943)
			(xy 128.024228 -229.739086) (xy 128.046752 -229.783296) (xy 128.062084 -229.830485) (xy 128.069845 -229.879491)
			(xy 128.069845 -229.90429) (xy 128.388884 -229.90429) (xy 128.392844 -229.855236) (xy 128.404621 -229.807452)
			(xy 128.423912 -229.762176) (xy 128.450215 -229.72058) (xy 128.48285 -229.683743) (xy 128.520971 -229.652618)
			(xy 128.563592 -229.628011) (xy 128.609608 -229.610559) (xy 128.657827 -229.600715) (xy 128.707002 -229.598734)
			(xy 128.755857 -229.604666) (xy 128.803128 -229.618358) (xy 128.84759 -229.639456) (xy 128.888093 -229.667412)
			(xy 128.923586 -229.701504) (xy 128.953151 -229.740848) (xy 128.976022 -229.784425) (xy 128.991606 -229.831106)
			(xy 128.999501 -229.879683) (xy 128.999996 -229.90429) (xy 129.318507 -229.90429) (xy 129.322602 -229.853562)
			(xy 129.334781 -229.804148) (xy 129.354729 -229.757328) (xy 129.38193 -229.714314) (xy 129.415678 -229.67622)
			(xy 129.4551 -229.644033) (xy 129.499174 -229.618587) (xy 129.54676 -229.60054) (xy 129.596624 -229.59036)
			(xy 129.647476 -229.588311) (xy 129.697997 -229.594445) (xy 129.746881 -229.608605) (xy 129.79286 -229.630422)
			(xy 129.834744 -229.659332) (xy 129.871448 -229.694587) (xy 129.902021 -229.735273) (xy 129.925672 -229.780336)
			(xy 129.941788 -229.82861) (xy 129.949952 -229.878844) (xy 129.950464 -229.90429) (xy 131.198615 -229.90429)
			(xy 131.20271 -229.853562) (xy 131.214889 -229.804148) (xy 131.234837 -229.757328) (xy 131.262038 -229.714314)
			(xy 131.295786 -229.67622) (xy 131.335208 -229.644033) (xy 131.379282 -229.618587) (xy 131.426868 -229.60054)
			(xy 131.476732 -229.59036) (xy 131.527584 -229.588311) (xy 131.578105 -229.594445) (xy 131.626989 -229.608605)
			(xy 131.672968 -229.630422) (xy 131.714852 -229.659332) (xy 131.751556 -229.694587) (xy 131.782129 -229.735273)
			(xy 131.80578 -229.780336) (xy 131.821896 -229.82861) (xy 131.83006 -229.878844) (xy 131.830572 -229.90429)
			(xy 132.138415 -229.90429) (xy 132.14251 -229.853562) (xy 132.154689 -229.804148) (xy 132.174637 -229.757328)
			(xy 132.201838 -229.714314) (xy 132.235586 -229.67622) (xy 132.275008 -229.644033) (xy 132.319082 -229.618587)
			(xy 132.366668 -229.60054) (xy 132.416532 -229.59036) (xy 132.467384 -229.588311) (xy 132.517905 -229.594445)
			(xy 132.566789 -229.608605) (xy 132.612768 -229.630422) (xy 132.654652 -229.659332) (xy 132.691356 -229.694587)
			(xy 132.721929 -229.735273) (xy 132.74558 -229.780336) (xy 132.761696 -229.82861) (xy 132.76986 -229.878844)
			(xy 132.770372 -229.90429) (xy 133.0889 -229.90429) (xy 133.09286 -229.855236) (xy 133.104637 -229.807452)
			(xy 133.123928 -229.762176) (xy 133.150231 -229.72058) (xy 133.182866 -229.683743) (xy 133.220987 -229.652618)
			(xy 133.263608 -229.628011) (xy 133.309624 -229.610559) (xy 133.357843 -229.600715) (xy 133.407018 -229.598734)
			(xy 133.455873 -229.604666) (xy 133.503144 -229.618358) (xy 133.547606 -229.639456) (xy 133.588109 -229.667412)
			(xy 133.623602 -229.701504) (xy 133.653167 -229.740848) (xy 133.676038 -229.784425) (xy 133.691622 -229.831106)
			(xy 133.699517 -229.879683) (xy 133.700012 -229.90429) (xy 134.018523 -229.90429) (xy 134.022618 -229.853562)
			(xy 134.034797 -229.804148) (xy 134.054745 -229.757328) (xy 134.081946 -229.714314) (xy 134.115694 -229.67622)
			(xy 134.155116 -229.644033) (xy 134.19919 -229.618587) (xy 134.246776 -229.60054) (xy 134.29664 -229.59036)
			(xy 134.347492 -229.588311) (xy 134.398013 -229.594445) (xy 134.446897 -229.608605) (xy 134.492876 -229.630422)
			(xy 134.53476 -229.659332) (xy 134.571464 -229.694587) (xy 134.602037 -229.735273) (xy 134.625688 -229.780336)
			(xy 134.641804 -229.82861) (xy 134.649968 -229.878844) (xy 134.65048 -229.90429) (xy 134.969008 -229.90429)
			(xy 134.972968 -229.855236) (xy 134.984745 -229.807452) (xy 135.004036 -229.762176) (xy 135.030339 -229.72058)
			(xy 135.062974 -229.683743) (xy 135.101095 -229.652618) (xy 135.143716 -229.628011) (xy 135.189732 -229.610559)
			(xy 135.237951 -229.600715) (xy 135.287126 -229.598734) (xy 135.335981 -229.604666) (xy 135.383252 -229.618358)
			(xy 135.427714 -229.639456) (xy 135.468217 -229.667412) (xy 135.50371 -229.701504) (xy 135.533275 -229.740848)
			(xy 135.556146 -229.784425) (xy 135.57173 -229.831106) (xy 135.579625 -229.879683) (xy 135.58012 -229.90429)
			(xy 135.898631 -229.90429) (xy 135.902726 -229.853562) (xy 135.914905 -229.804148) (xy 135.934853 -229.757328)
			(xy 135.962054 -229.714314) (xy 135.995802 -229.67622) (xy 136.035224 -229.644033) (xy 136.079298 -229.618587)
			(xy 136.126884 -229.60054) (xy 136.176748 -229.59036) (xy 136.2276 -229.588311) (xy 136.278121 -229.594445)
			(xy 136.327005 -229.608605) (xy 136.372984 -229.630422) (xy 136.414868 -229.659332) (xy 136.451572 -229.694587)
			(xy 136.482145 -229.735273) (xy 136.505796 -229.780336) (xy 136.521912 -229.82861) (xy 136.530076 -229.878844)
			(xy 136.530588 -229.90429) (xy 137.778485 -229.90429) (xy 137.78258 -229.853562) (xy 137.794759 -229.804148)
			(xy 137.814707 -229.757328) (xy 137.841908 -229.714314) (xy 137.875656 -229.67622) (xy 137.915078 -229.644033)
			(xy 137.959152 -229.618587) (xy 138.006738 -229.60054) (xy 138.056602 -229.59036) (xy 138.107454 -229.588311)
			(xy 138.157975 -229.594445) (xy 138.206859 -229.608605) (xy 138.252838 -229.630422) (xy 138.294722 -229.659332)
			(xy 138.331426 -229.694587) (xy 138.361999 -229.735273) (xy 138.38565 -229.780336) (xy 138.401766 -229.82861)
			(xy 138.40993 -229.878844) (xy 138.410442 -229.90429) (xy 138.718539 -229.90429) (xy 138.722634 -229.853562)
			(xy 138.734813 -229.804148) (xy 138.754761 -229.757328) (xy 138.781962 -229.714314) (xy 138.81571 -229.67622)
			(xy 138.855132 -229.644033) (xy 138.899206 -229.618587) (xy 138.946792 -229.60054) (xy 138.996656 -229.59036)
			(xy 139.047508 -229.588311) (xy 139.098029 -229.594445) (xy 139.146913 -229.608605) (xy 139.192892 -229.630422)
			(xy 139.234776 -229.659332) (xy 139.27148 -229.694587) (xy 139.302053 -229.735273) (xy 139.325704 -229.780336)
			(xy 139.34182 -229.82861) (xy 139.349984 -229.878844) (xy 139.350496 -229.90429) (xy 139.669024 -229.90429)
			(xy 139.672984 -229.855236) (xy 139.684761 -229.807452) (xy 139.704052 -229.762176) (xy 139.730355 -229.72058)
			(xy 139.76299 -229.683743) (xy 139.801111 -229.652618) (xy 139.843732 -229.628011) (xy 139.889748 -229.610559)
			(xy 139.937967 -229.600715) (xy 139.987142 -229.598734) (xy 140.035997 -229.604666) (xy 140.083268 -229.618358)
			(xy 140.12773 -229.639456) (xy 140.168233 -229.667412) (xy 140.203726 -229.701504) (xy 140.233291 -229.740848)
			(xy 140.256162 -229.784425) (xy 140.271746 -229.831106) (xy 140.279641 -229.879683) (xy 140.280136 -229.90429)
			(xy 140.598647 -229.90429) (xy 140.602742 -229.853562) (xy 140.614921 -229.804148) (xy 140.634869 -229.757328)
			(xy 140.66207 -229.714314) (xy 140.695818 -229.67622) (xy 140.73524 -229.644033) (xy 140.779314 -229.618587)
			(xy 140.8269 -229.60054) (xy 140.876764 -229.59036) (xy 140.927616 -229.588311) (xy 140.978137 -229.594445)
			(xy 141.027021 -229.608605) (xy 141.073 -229.630422) (xy 141.114884 -229.659332) (xy 141.151588 -229.694587)
			(xy 141.182161 -229.735273) (xy 141.205812 -229.780336) (xy 141.221928 -229.82861) (xy 141.230092 -229.878844)
			(xy 141.230604 -229.90429) (xy 141.548878 -229.90429) (xy 141.552838 -229.855236) (xy 141.564615 -229.807452)
			(xy 141.583906 -229.762176) (xy 141.610209 -229.72058) (xy 141.642844 -229.683743) (xy 141.680965 -229.652618)
			(xy 141.723586 -229.628011) (xy 141.769602 -229.610559) (xy 141.817821 -229.600715) (xy 141.866996 -229.598734)
			(xy 141.915851 -229.604666) (xy 141.963122 -229.618358) (xy 142.007584 -229.639456) (xy 142.048087 -229.667412)
			(xy 142.08358 -229.701504) (xy 142.113145 -229.740848) (xy 142.136016 -229.784425) (xy 142.1516 -229.831106)
			(xy 142.159495 -229.879683) (xy 142.15999 -229.90429) (xy 142.478501 -229.90429) (xy 142.482596 -229.853562)
			(xy 142.494775 -229.804148) (xy 142.514723 -229.757328) (xy 142.541924 -229.714314) (xy 142.575672 -229.67622)
			(xy 142.615094 -229.644033) (xy 142.659168 -229.618587) (xy 142.706754 -229.60054) (xy 142.756618 -229.59036)
			(xy 142.80747 -229.588311) (xy 142.857991 -229.594445) (xy 142.906875 -229.608605) (xy 142.952854 -229.630422)
			(xy 142.994738 -229.659332) (xy 143.031442 -229.694587) (xy 143.062015 -229.735273) (xy 143.085666 -229.780336)
			(xy 143.101782 -229.82861) (xy 143.109946 -229.878844) (xy 143.110458 -229.90429) (xy 143.109946 -229.929736)
			(xy 143.101782 -229.97997) (xy 143.085666 -230.028244) (xy 143.062015 -230.073307) (xy 143.031442 -230.113993)
			(xy 142.994738 -230.149248) (xy 142.952854 -230.178158) (xy 142.906875 -230.199975) (xy 142.857991 -230.214135)
			(xy 142.80747 -230.220269) (xy 142.756618 -230.21822) (xy 142.706754 -230.20804) (xy 142.659168 -230.189993)
			(xy 142.615094 -230.164547) (xy 142.575672 -230.13236) (xy 142.541924 -230.094266) (xy 142.514723 -230.051252)
			(xy 142.494775 -230.004432) (xy 142.482596 -229.955018) (xy 142.478501 -229.90429) (xy 142.15999 -229.90429)
			(xy 142.159495 -229.928897) (xy 142.1516 -229.977474) (xy 142.136016 -230.024155) (xy 142.113145 -230.067732)
			(xy 142.08358 -230.107076) (xy 142.048087 -230.141168) (xy 142.007584 -230.169124) (xy 141.963122 -230.190222)
			(xy 141.915851 -230.203914) (xy 141.866996 -230.209846) (xy 141.817821 -230.207865) (xy 141.769602 -230.198021)
			(xy 141.723586 -230.180569) (xy 141.680965 -230.155962) (xy 141.642844 -230.124837) (xy 141.610209 -230.088)
			(xy 141.583906 -230.046404) (xy 141.564615 -230.001128) (xy 141.552838 -229.953344) (xy 141.548878 -229.90429)
			(xy 141.230604 -229.90429) (xy 141.230092 -229.929736) (xy 141.221928 -229.97997) (xy 141.205812 -230.028244)
			(xy 141.182161 -230.073307) (xy 141.151588 -230.113993) (xy 141.114884 -230.149248) (xy 141.073 -230.178158)
			(xy 141.027021 -230.199975) (xy 140.978137 -230.214135) (xy 140.927616 -230.220269) (xy 140.876764 -230.21822)
			(xy 140.8269 -230.20804) (xy 140.779314 -230.189993) (xy 140.73524 -230.164547) (xy 140.695818 -230.13236)
			(xy 140.66207 -230.094266) (xy 140.634869 -230.051252) (xy 140.614921 -230.004432) (xy 140.602742 -229.955018)
			(xy 140.598647 -229.90429) (xy 140.280136 -229.90429) (xy 140.279641 -229.928897) (xy 140.271746 -229.977474)
			(xy 140.256162 -230.024155) (xy 140.233291 -230.067732) (xy 140.203726 -230.107076) (xy 140.168233 -230.141168)
			(xy 140.12773 -230.169124) (xy 140.083268 -230.190222) (xy 140.035997 -230.203914) (xy 139.987142 -230.209846)
			(xy 139.937967 -230.207865) (xy 139.889748 -230.198021) (xy 139.843732 -230.180569) (xy 139.801111 -230.155962)
			(xy 139.76299 -230.124837) (xy 139.730355 -230.088) (xy 139.704052 -230.046404) (xy 139.684761 -230.001128)
			(xy 139.672984 -229.953344) (xy 139.669024 -229.90429) (xy 139.350496 -229.90429) (xy 139.349984 -229.929736)
			(xy 139.34182 -229.97997) (xy 139.325704 -230.028244) (xy 139.302053 -230.073307) (xy 139.27148 -230.113993)
			(xy 139.234776 -230.149248) (xy 139.192892 -230.178158) (xy 139.146913 -230.199975) (xy 139.098029 -230.214135)
			(xy 139.047508 -230.220269) (xy 138.996656 -230.21822) (xy 138.946792 -230.20804) (xy 138.899206 -230.189993)
			(xy 138.855132 -230.164547) (xy 138.81571 -230.13236) (xy 138.781962 -230.094266) (xy 138.754761 -230.051252)
			(xy 138.734813 -230.004432) (xy 138.722634 -229.955018) (xy 138.718539 -229.90429) (xy 138.410442 -229.90429)
			(xy 138.40993 -229.929736) (xy 138.401766 -229.97997) (xy 138.38565 -230.028244) (xy 138.361999 -230.073307)
			(xy 138.331426 -230.113993) (xy 138.294722 -230.149248) (xy 138.252838 -230.178158) (xy 138.206859 -230.199975)
			(xy 138.157975 -230.214135) (xy 138.107454 -230.220269) (xy 138.056602 -230.21822) (xy 138.006738 -230.20804)
			(xy 137.959152 -230.189993) (xy 137.915078 -230.164547) (xy 137.875656 -230.13236) (xy 137.841908 -230.094266)
			(xy 137.814707 -230.051252) (xy 137.794759 -230.004432) (xy 137.78258 -229.955018) (xy 137.778485 -229.90429)
			(xy 136.530588 -229.90429) (xy 136.530076 -229.929736) (xy 136.521912 -229.97997) (xy 136.505796 -230.028244)
			(xy 136.482145 -230.073307) (xy 136.451572 -230.113993) (xy 136.414868 -230.149248) (xy 136.372984 -230.178158)
			(xy 136.327005 -230.199975) (xy 136.278121 -230.214135) (xy 136.2276 -230.220269) (xy 136.176748 -230.21822)
			(xy 136.126884 -230.20804) (xy 136.079298 -230.189993) (xy 136.035224 -230.164547) (xy 135.995802 -230.13236)
			(xy 135.962054 -230.094266) (xy 135.934853 -230.051252) (xy 135.914905 -230.004432) (xy 135.902726 -229.955018)
			(xy 135.898631 -229.90429) (xy 135.58012 -229.90429) (xy 135.579625 -229.928897) (xy 135.57173 -229.977474)
			(xy 135.556146 -230.024155) (xy 135.533275 -230.067732) (xy 135.50371 -230.107076) (xy 135.468217 -230.141168)
			(xy 135.427714 -230.169124) (xy 135.383252 -230.190222) (xy 135.335981 -230.203914) (xy 135.287126 -230.209846)
			(xy 135.237951 -230.207865) (xy 135.189732 -230.198021) (xy 135.143716 -230.180569) (xy 135.101095 -230.155962)
			(xy 135.062974 -230.124837) (xy 135.030339 -230.088) (xy 135.004036 -230.046404) (xy 134.984745 -230.001128)
			(xy 134.972968 -229.953344) (xy 134.969008 -229.90429) (xy 134.65048 -229.90429) (xy 134.649968 -229.929736)
			(xy 134.641804 -229.97997) (xy 134.625688 -230.028244) (xy 134.602037 -230.073307) (xy 134.571464 -230.113993)
			(xy 134.53476 -230.149248) (xy 134.492876 -230.178158) (xy 134.446897 -230.199975) (xy 134.398013 -230.214135)
			(xy 134.347492 -230.220269) (xy 134.29664 -230.21822) (xy 134.246776 -230.20804) (xy 134.19919 -230.189993)
			(xy 134.155116 -230.164547) (xy 134.115694 -230.13236) (xy 134.081946 -230.094266) (xy 134.054745 -230.051252)
			(xy 134.034797 -230.004432) (xy 134.022618 -229.955018) (xy 134.018523 -229.90429) (xy 133.700012 -229.90429)
			(xy 133.699517 -229.928897) (xy 133.691622 -229.977474) (xy 133.676038 -230.024155) (xy 133.653167 -230.067732)
			(xy 133.623602 -230.107076) (xy 133.588109 -230.141168) (xy 133.547606 -230.169124) (xy 133.503144 -230.190222)
			(xy 133.455873 -230.203914) (xy 133.407018 -230.209846) (xy 133.357843 -230.207865) (xy 133.309624 -230.198021)
			(xy 133.263608 -230.180569) (xy 133.220987 -230.155962) (xy 133.182866 -230.124837) (xy 133.150231 -230.088)
			(xy 133.123928 -230.046404) (xy 133.104637 -230.001128) (xy 133.09286 -229.953344) (xy 133.0889 -229.90429)
			(xy 132.770372 -229.90429) (xy 132.76986 -229.929736) (xy 132.761696 -229.97997) (xy 132.74558 -230.028244)
			(xy 132.721929 -230.073307) (xy 132.691356 -230.113993) (xy 132.654652 -230.149248) (xy 132.612768 -230.178158)
			(xy 132.566789 -230.199975) (xy 132.517905 -230.214135) (xy 132.467384 -230.220269) (xy 132.416532 -230.21822)
			(xy 132.366668 -230.20804) (xy 132.319082 -230.189993) (xy 132.275008 -230.164547) (xy 132.235586 -230.13236)
			(xy 132.201838 -230.094266) (xy 132.174637 -230.051252) (xy 132.154689 -230.004432) (xy 132.14251 -229.955018)
			(xy 132.138415 -229.90429) (xy 131.830572 -229.90429) (xy 131.83006 -229.929736) (xy 131.821896 -229.97997)
			(xy 131.80578 -230.028244) (xy 131.782129 -230.073307) (xy 131.751556 -230.113993) (xy 131.714852 -230.149248)
			(xy 131.672968 -230.178158) (xy 131.626989 -230.199975) (xy 131.578105 -230.214135) (xy 131.527584 -230.220269)
			(xy 131.476732 -230.21822) (xy 131.426868 -230.20804) (xy 131.379282 -230.189993) (xy 131.335208 -230.164547)
			(xy 131.295786 -230.13236) (xy 131.262038 -230.094266) (xy 131.234837 -230.051252) (xy 131.214889 -230.004432)
			(xy 131.20271 -229.955018) (xy 131.198615 -229.90429) (xy 129.950464 -229.90429) (xy 129.949952 -229.929736)
			(xy 129.941788 -229.97997) (xy 129.925672 -230.028244) (xy 129.902021 -230.073307) (xy 129.871448 -230.113993)
			(xy 129.834744 -230.149248) (xy 129.79286 -230.178158) (xy 129.746881 -230.199975) (xy 129.697997 -230.214135)
			(xy 129.647476 -230.220269) (xy 129.596624 -230.21822) (xy 129.54676 -230.20804) (xy 129.499174 -230.189993)
			(xy 129.4551 -230.164547) (xy 129.415678 -230.13236) (xy 129.38193 -230.094266) (xy 129.354729 -230.051252)
			(xy 129.334781 -230.004432) (xy 129.322602 -229.955018) (xy 129.318507 -229.90429) (xy 128.999996 -229.90429)
			(xy 128.999501 -229.928897) (xy 128.991606 -229.977474) (xy 128.976022 -230.024155) (xy 128.953151 -230.067732)
			(xy 128.923586 -230.107076) (xy 128.888093 -230.141168) (xy 128.84759 -230.169124) (xy 128.803128 -230.190222)
			(xy 128.755857 -230.203914) (xy 128.707002 -230.209846) (xy 128.657827 -230.207865) (xy 128.609608 -230.198021)
			(xy 128.563592 -230.180569) (xy 128.520971 -230.155962) (xy 128.48285 -230.124837) (xy 128.450215 -230.088)
			(xy 128.423912 -230.046404) (xy 128.404621 -230.001128) (xy 128.392844 -229.953344) (xy 128.388884 -229.90429)
			(xy 128.069845 -229.90429) (xy 128.069845 -229.929109) (xy 128.062084 -229.978115) (xy 128.046752 -230.025304)
			(xy 128.024228 -230.069514) (xy 127.995066 -230.109657) (xy 127.959983 -230.144743) (xy 127.919843 -230.17391)
			(xy 127.875636 -230.196439) (xy 127.828448 -230.211776) (xy 127.779443 -230.219543) (xy 127.754634 -230.220012)
			(xy 127.732952 -230.219613) (xy 127.690002 -230.213617) (xy 127.669036 -230.208074) (xy 127.662432 -230.206042)
			(xy 127.65532 -230.206042) (xy 127.645299 -230.206459) (xy 127.626783 -230.214127) (xy 127.612614 -230.228301)
			(xy 127.604954 -230.246821) (xy 127.60452 -230.256842) (xy 127.60452 -230.275384) (xy 127.607314 -230.283512)
			(xy 127.618119 -230.315906) (xy 127.636798 -230.381597) (xy 127.644652 -230.41483) (xy 127.655507 -230.464038)
			(xy 127.670658 -230.56367) (xy 127.678238 -230.664161) (xy 127.678688 -230.71455) (xy 127.908553 -230.71455)
			(xy 127.912648 -230.663822) (xy 127.924827 -230.614408) (xy 127.944775 -230.567588) (xy 127.971976 -230.524574)
			(xy 128.005724 -230.48648) (xy 128.045146 -230.454293) (xy 128.08922 -230.428847) (xy 128.136806 -230.4108)
			(xy 128.18667 -230.40062) (xy 128.237522 -230.398571) (xy 128.288043 -230.404705) (xy 128.336927 -230.418865)
			(xy 128.382906 -230.440682) (xy 128.42479 -230.469592) (xy 128.461494 -230.504847) (xy 128.492067 -230.545533)
			(xy 128.515718 -230.590596) (xy 128.531834 -230.63887) (xy 128.539998 -230.689104) (xy 128.54051 -230.71455)
			(xy 128.848607 -230.71455) (xy 128.852702 -230.663822) (xy 128.864881 -230.614408) (xy 128.884829 -230.567588)
			(xy 128.91203 -230.524574) (xy 128.945778 -230.48648) (xy 128.9852 -230.454293) (xy 129.029274 -230.428847)
			(xy 129.07686 -230.4108) (xy 129.126724 -230.40062) (xy 129.177576 -230.398571) (xy 129.228097 -230.404705)
			(xy 129.276981 -230.418865) (xy 129.32296 -230.440682) (xy 129.364844 -230.469592) (xy 129.401548 -230.504847)
			(xy 129.432121 -230.545533) (xy 129.455772 -230.590596) (xy 129.471888 -230.63887) (xy 129.480052 -230.689104)
			(xy 129.480564 -230.71455) (xy 129.798838 -230.71455) (xy 129.802798 -230.665496) (xy 129.814575 -230.617712)
			(xy 129.833866 -230.572436) (xy 129.860169 -230.53084) (xy 129.892804 -230.494003) (xy 129.930925 -230.462878)
			(xy 129.973546 -230.438271) (xy 130.019562 -230.420819) (xy 130.067781 -230.410975) (xy 130.116956 -230.408994)
			(xy 130.165811 -230.414926) (xy 130.213082 -230.428618) (xy 130.257544 -230.449716) (xy 130.298047 -230.477672)
			(xy 130.33354 -230.511764) (xy 130.363105 -230.551108) (xy 130.385976 -230.594685) (xy 130.40156 -230.641366)
			(xy 130.409455 -230.689943) (xy 130.40995 -230.71455) (xy 130.728461 -230.71455) (xy 130.732556 -230.663822)
			(xy 130.744735 -230.614408) (xy 130.764683 -230.567588) (xy 130.791884 -230.524574) (xy 130.825632 -230.48648)
			(xy 130.865054 -230.454293) (xy 130.909128 -230.428847) (xy 130.956714 -230.4108) (xy 131.006578 -230.40062)
			(xy 131.05743 -230.398571) (xy 131.107951 -230.404705) (xy 131.156835 -230.418865) (xy 131.202814 -230.440682)
			(xy 131.244698 -230.469592) (xy 131.281402 -230.504847) (xy 131.311975 -230.545533) (xy 131.335626 -230.590596)
			(xy 131.351742 -230.63887) (xy 131.359906 -230.689104) (xy 131.360418 -230.71455) (xy 131.678946 -230.71455)
			(xy 131.682906 -230.665496) (xy 131.694683 -230.617712) (xy 131.713974 -230.572436) (xy 131.740277 -230.53084)
			(xy 131.772912 -230.494003) (xy 131.811033 -230.462878) (xy 131.853654 -230.438271) (xy 131.89967 -230.420819)
			(xy 131.947889 -230.410975) (xy 131.997064 -230.408994) (xy 132.045919 -230.414926) (xy 132.09319 -230.428618)
			(xy 132.137652 -230.449716) (xy 132.178155 -230.477672) (xy 132.213648 -230.511764) (xy 132.243213 -230.551108)
			(xy 132.266084 -230.594685) (xy 132.281668 -230.641366) (xy 132.289563 -230.689943) (xy 132.290058 -230.71455)
			(xy 132.608569 -230.71455) (xy 132.612664 -230.663822) (xy 132.624843 -230.614408) (xy 132.644791 -230.567588)
			(xy 132.671992 -230.524574) (xy 132.70574 -230.48648) (xy 132.745162 -230.454293) (xy 132.789236 -230.428847)
			(xy 132.836822 -230.4108) (xy 132.886686 -230.40062) (xy 132.937538 -230.398571) (xy 132.988059 -230.404705)
			(xy 133.036943 -230.418865) (xy 133.082922 -230.440682) (xy 133.124806 -230.469592) (xy 133.16151 -230.504847)
			(xy 133.192083 -230.545533) (xy 133.215734 -230.590596) (xy 133.23185 -230.63887) (xy 133.240014 -230.689104)
			(xy 133.240521 -230.714296) (xy 133.559054 -230.714296) (xy 133.563014 -230.665242) (xy 133.574791 -230.617458)
			(xy 133.594082 -230.572182) (xy 133.620385 -230.530586) (xy 133.65302 -230.493749) (xy 133.691141 -230.462624)
			(xy 133.733762 -230.438017) (xy 133.779778 -230.420565) (xy 133.827997 -230.410721) (xy 133.877172 -230.40874)
			(xy 133.926027 -230.414672) (xy 133.973298 -230.428364) (xy 134.01776 -230.449462) (xy 134.058263 -230.477418)
			(xy 134.093756 -230.51151) (xy 134.123321 -230.550854) (xy 134.146192 -230.594431) (xy 134.161776 -230.641112)
			(xy 134.169671 -230.689689) (xy 134.170166 -230.714296) (xy 134.170161 -230.71455) (xy 134.488423 -230.71455)
			(xy 134.492518 -230.663822) (xy 134.504697 -230.614408) (xy 134.524645 -230.567588) (xy 134.551846 -230.524574)
			(xy 134.585594 -230.48648) (xy 134.625016 -230.454293) (xy 134.66909 -230.428847) (xy 134.716676 -230.4108)
			(xy 134.76654 -230.40062) (xy 134.817392 -230.398571) (xy 134.867913 -230.404705) (xy 134.916797 -230.418865)
			(xy 134.962776 -230.440682) (xy 135.00466 -230.469592) (xy 135.041364 -230.504847) (xy 135.071937 -230.545533)
			(xy 135.095588 -230.590596) (xy 135.111704 -230.63887) (xy 135.119868 -230.689104) (xy 135.12038 -230.71455)
			(xy 135.428477 -230.71455) (xy 135.432572 -230.663822) (xy 135.444751 -230.614408) (xy 135.464699 -230.567588)
			(xy 135.4919 -230.524574) (xy 135.525648 -230.48648) (xy 135.56507 -230.454293) (xy 135.609144 -230.428847)
			(xy 135.65673 -230.4108) (xy 135.706594 -230.40062) (xy 135.757446 -230.398571) (xy 135.807967 -230.404705)
			(xy 135.856851 -230.418865) (xy 135.90283 -230.440682) (xy 135.944714 -230.469592) (xy 135.981418 -230.504847)
			(xy 136.011991 -230.545533) (xy 136.035642 -230.590596) (xy 136.051758 -230.63887) (xy 136.059922 -230.689104)
			(xy 136.060434 -230.71455) (xy 136.378962 -230.71455) (xy 136.382922 -230.665496) (xy 136.394699 -230.617712)
			(xy 136.41399 -230.572436) (xy 136.440293 -230.53084) (xy 136.472928 -230.494003) (xy 136.511049 -230.462878)
			(xy 136.55367 -230.438271) (xy 136.599686 -230.420819) (xy 136.647905 -230.410975) (xy 136.69708 -230.408994)
			(xy 136.745935 -230.414926) (xy 136.793206 -230.428618) (xy 136.837668 -230.449716) (xy 136.878171 -230.477672)
			(xy 136.913664 -230.511764) (xy 136.943229 -230.551108) (xy 136.9661 -230.594685) (xy 136.981684 -230.641366)
			(xy 136.989579 -230.689943) (xy 136.990074 -230.71455) (xy 137.308585 -230.71455) (xy 137.31268 -230.663822)
			(xy 137.324859 -230.614408) (xy 137.344807 -230.567588) (xy 137.372008 -230.524574) (xy 137.405756 -230.48648)
			(xy 137.445178 -230.454293) (xy 137.489252 -230.428847) (xy 137.536838 -230.4108) (xy 137.586702 -230.40062)
			(xy 137.637554 -230.398571) (xy 137.688075 -230.404705) (xy 137.736959 -230.418865) (xy 137.782938 -230.440682)
			(xy 137.824822 -230.469592) (xy 137.861526 -230.504847) (xy 137.892099 -230.545533) (xy 137.91575 -230.590596)
			(xy 137.931866 -230.63887) (xy 137.94003 -230.689104) (xy 137.940537 -230.714296) (xy 138.25907 -230.714296)
			(xy 138.26303 -230.665242) (xy 138.274807 -230.617458) (xy 138.294098 -230.572182) (xy 138.320401 -230.530586)
			(xy 138.353036 -230.493749) (xy 138.391157 -230.462624) (xy 138.433778 -230.438017) (xy 138.479794 -230.420565)
			(xy 138.528013 -230.410721) (xy 138.577188 -230.40874) (xy 138.626043 -230.414672) (xy 138.673314 -230.428364)
			(xy 138.717776 -230.449462) (xy 138.758279 -230.477418) (xy 138.793772 -230.51151) (xy 138.823337 -230.550854)
			(xy 138.846208 -230.594431) (xy 138.861792 -230.641112) (xy 138.869687 -230.689689) (xy 138.870182 -230.714296)
			(xy 138.870177 -230.71455) (xy 139.188439 -230.71455) (xy 139.192534 -230.663822) (xy 139.204713 -230.614408)
			(xy 139.224661 -230.567588) (xy 139.251862 -230.524574) (xy 139.28561 -230.48648) (xy 139.325032 -230.454293)
			(xy 139.369106 -230.428847) (xy 139.416692 -230.4108) (xy 139.466556 -230.40062) (xy 139.517408 -230.398571)
			(xy 139.567929 -230.404705) (xy 139.616813 -230.418865) (xy 139.662792 -230.440682) (xy 139.704676 -230.469592)
			(xy 139.74138 -230.504847) (xy 139.771953 -230.545533) (xy 139.795604 -230.590596) (xy 139.81172 -230.63887)
			(xy 139.819884 -230.689104) (xy 139.820396 -230.71455) (xy 140.138924 -230.71455) (xy 140.142884 -230.665496)
			(xy 140.154661 -230.617712) (xy 140.173952 -230.572436) (xy 140.200255 -230.53084) (xy 140.23289 -230.494003)
			(xy 140.271011 -230.462878) (xy 140.313632 -230.438271) (xy 140.359648 -230.420819) (xy 140.407867 -230.410975)
			(xy 140.457042 -230.408994) (xy 140.505897 -230.414926) (xy 140.553168 -230.428618) (xy 140.59763 -230.449716)
			(xy 140.638133 -230.477672) (xy 140.673626 -230.511764) (xy 140.703191 -230.551108) (xy 140.726062 -230.594685)
			(xy 140.741646 -230.641366) (xy 140.749541 -230.689943) (xy 140.750036 -230.71455) (xy 141.068547 -230.71455)
			(xy 141.072642 -230.663822) (xy 141.084821 -230.614408) (xy 141.104769 -230.567588) (xy 141.13197 -230.524574)
			(xy 141.165718 -230.48648) (xy 141.20514 -230.454293) (xy 141.249214 -230.428847) (xy 141.2968 -230.4108)
			(xy 141.346664 -230.40062) (xy 141.397516 -230.398571) (xy 141.448037 -230.404705) (xy 141.496921 -230.418865)
			(xy 141.5429 -230.440682) (xy 141.584784 -230.469592) (xy 141.621488 -230.504847) (xy 141.652061 -230.545533)
			(xy 141.675712 -230.590596) (xy 141.691828 -230.63887) (xy 141.699992 -230.689104) (xy 141.700504 -230.71455)
			(xy 142.008601 -230.71455) (xy 142.012696 -230.663822) (xy 142.024875 -230.614408) (xy 142.044823 -230.567588)
			(xy 142.072024 -230.524574) (xy 142.105772 -230.48648) (xy 142.145194 -230.454293) (xy 142.189268 -230.428847)
			(xy 142.236854 -230.4108) (xy 142.286718 -230.40062) (xy 142.33757 -230.398571) (xy 142.388091 -230.404705)
			(xy 142.436975 -230.418865) (xy 142.482954 -230.440682) (xy 142.524838 -230.469592) (xy 142.561542 -230.504847)
			(xy 142.592115 -230.545533) (xy 142.615766 -230.590596) (xy 142.631882 -230.63887) (xy 142.640046 -230.689104)
			(xy 142.640558 -230.71455) (xy 142.958832 -230.71455) (xy 142.962792 -230.665496) (xy 142.974569 -230.617712)
			(xy 142.99386 -230.572436) (xy 143.020163 -230.53084) (xy 143.052798 -230.494003) (xy 143.090919 -230.462878)
			(xy 143.13354 -230.438271) (xy 143.179556 -230.420819) (xy 143.227775 -230.410975) (xy 143.27695 -230.408994)
			(xy 143.325805 -230.414926) (xy 143.373076 -230.428618) (xy 143.417538 -230.449716) (xy 143.458041 -230.477672)
			(xy 143.493534 -230.511764) (xy 143.523099 -230.551108) (xy 143.54597 -230.594685) (xy 143.561554 -230.641366)
			(xy 143.569449 -230.689943) (xy 143.569944 -230.71455) (xy 144.83894 -230.71455) (xy 144.8429 -230.665496)
			(xy 144.854677 -230.617712) (xy 144.873968 -230.572436) (xy 144.900271 -230.53084) (xy 144.932906 -230.494003)
			(xy 144.971027 -230.462878) (xy 145.013648 -230.438271) (xy 145.059664 -230.420819) (xy 145.107883 -230.410975)
			(xy 145.157058 -230.408994) (xy 145.205913 -230.414926) (xy 145.253184 -230.428618) (xy 145.297646 -230.449716)
			(xy 145.338149 -230.477672) (xy 145.373642 -230.511764) (xy 145.403207 -230.551108) (xy 145.426078 -230.594685)
			(xy 145.441662 -230.641366) (xy 145.449557 -230.689943) (xy 145.450052 -230.71455) (xy 145.449557 -230.739157)
			(xy 145.441662 -230.787734) (xy 145.426078 -230.834415) (xy 145.403207 -230.877992) (xy 145.373642 -230.917336)
			(xy 145.338149 -230.951428) (xy 145.297646 -230.979384) (xy 145.253184 -231.000482) (xy 145.205913 -231.014174)
			(xy 145.157058 -231.020106) (xy 145.107883 -231.018125) (xy 145.059664 -231.008281) (xy 145.013648 -230.990829)
			(xy 144.971027 -230.966222) (xy 144.932906 -230.935097) (xy 144.900271 -230.89826) (xy 144.873968 -230.856664)
			(xy 144.854677 -230.811388) (xy 144.8429 -230.763604) (xy 144.83894 -230.71455) (xy 143.569944 -230.71455)
			(xy 143.569449 -230.739157) (xy 143.561554 -230.787734) (xy 143.54597 -230.834415) (xy 143.523099 -230.877992)
			(xy 143.493534 -230.917336) (xy 143.458041 -230.951428) (xy 143.417538 -230.979384) (xy 143.373076 -231.000482)
			(xy 143.325805 -231.014174) (xy 143.27695 -231.020106) (xy 143.227775 -231.018125) (xy 143.179556 -231.008281)
			(xy 143.13354 -230.990829) (xy 143.090919 -230.966222) (xy 143.052798 -230.935097) (xy 143.020163 -230.89826)
			(xy 142.99386 -230.856664) (xy 142.974569 -230.811388) (xy 142.962792 -230.763604) (xy 142.958832 -230.71455)
			(xy 142.640558 -230.71455) (xy 142.640046 -230.739996) (xy 142.631882 -230.79023) (xy 142.615766 -230.838504)
			(xy 142.592115 -230.883567) (xy 142.561542 -230.924253) (xy 142.524838 -230.959508) (xy 142.482954 -230.988418)
			(xy 142.436975 -231.010235) (xy 142.388091 -231.024395) (xy 142.33757 -231.030529) (xy 142.286718 -231.02848)
			(xy 142.236854 -231.0183) (xy 142.189268 -231.000253) (xy 142.145194 -230.974807) (xy 142.105772 -230.94262)
			(xy 142.072024 -230.904526) (xy 142.044823 -230.861512) (xy 142.024875 -230.814692) (xy 142.012696 -230.765278)
			(xy 142.008601 -230.71455) (xy 141.700504 -230.71455) (xy 141.699992 -230.739996) (xy 141.691828 -230.79023)
			(xy 141.675712 -230.838504) (xy 141.652061 -230.883567) (xy 141.621488 -230.924253) (xy 141.584784 -230.959508)
			(xy 141.5429 -230.988418) (xy 141.496921 -231.010235) (xy 141.448037 -231.024395) (xy 141.397516 -231.030529)
			(xy 141.346664 -231.02848) (xy 141.2968 -231.0183) (xy 141.249214 -231.000253) (xy 141.20514 -230.974807)
			(xy 141.165718 -230.94262) (xy 141.13197 -230.904526) (xy 141.104769 -230.861512) (xy 141.084821 -230.814692)
			(xy 141.072642 -230.765278) (xy 141.068547 -230.71455) (xy 140.750036 -230.71455) (xy 140.749541 -230.739157)
			(xy 140.741646 -230.787734) (xy 140.726062 -230.834415) (xy 140.703191 -230.877992) (xy 140.673626 -230.917336)
			(xy 140.638133 -230.951428) (xy 140.59763 -230.979384) (xy 140.553168 -231.000482) (xy 140.505897 -231.014174)
			(xy 140.457042 -231.020106) (xy 140.407867 -231.018125) (xy 140.359648 -231.008281) (xy 140.313632 -230.990829)
			(xy 140.271011 -230.966222) (xy 140.23289 -230.935097) (xy 140.200255 -230.89826) (xy 140.173952 -230.856664)
			(xy 140.154661 -230.811388) (xy 140.142884 -230.763604) (xy 140.138924 -230.71455) (xy 139.820396 -230.71455)
			(xy 139.819884 -230.739996) (xy 139.81172 -230.79023) (xy 139.795604 -230.838504) (xy 139.771953 -230.883567)
			(xy 139.74138 -230.924253) (xy 139.704676 -230.959508) (xy 139.662792 -230.988418) (xy 139.616813 -231.010235)
			(xy 139.567929 -231.024395) (xy 139.517408 -231.030529) (xy 139.466556 -231.02848) (xy 139.416692 -231.0183)
			(xy 139.369106 -231.000253) (xy 139.325032 -230.974807) (xy 139.28561 -230.94262) (xy 139.251862 -230.904526)
			(xy 139.224661 -230.861512) (xy 139.204713 -230.814692) (xy 139.192534 -230.765278) (xy 139.188439 -230.71455)
			(xy 138.870177 -230.71455) (xy 138.869687 -230.738903) (xy 138.861792 -230.78748) (xy 138.846208 -230.834161)
			(xy 138.823337 -230.877738) (xy 138.793772 -230.917082) (xy 138.758279 -230.951174) (xy 138.717776 -230.97913)
			(xy 138.673314 -231.000228) (xy 138.626043 -231.01392) (xy 138.577188 -231.019852) (xy 138.528013 -231.017871)
			(xy 138.479794 -231.008027) (xy 138.433778 -230.990575) (xy 138.391157 -230.965968) (xy 138.353036 -230.934843)
			(xy 138.320401 -230.898006) (xy 138.294098 -230.85641) (xy 138.274807 -230.811134) (xy 138.26303 -230.76335)
			(xy 138.25907 -230.714296) (xy 137.940537 -230.714296) (xy 137.940542 -230.71455) (xy 137.94003 -230.739996)
			(xy 137.931866 -230.79023) (xy 137.91575 -230.838504) (xy 137.892099 -230.883567) (xy 137.861526 -230.924253)
			(xy 137.824822 -230.959508) (xy 137.782938 -230.988418) (xy 137.736959 -231.010235) (xy 137.688075 -231.024395)
			(xy 137.637554 -231.030529) (xy 137.586702 -231.02848) (xy 137.536838 -231.0183) (xy 137.489252 -231.000253)
			(xy 137.445178 -230.974807) (xy 137.405756 -230.94262) (xy 137.372008 -230.904526) (xy 137.344807 -230.861512)
			(xy 137.324859 -230.814692) (xy 137.31268 -230.765278) (xy 137.308585 -230.71455) (xy 136.990074 -230.71455)
			(xy 136.989579 -230.739157) (xy 136.981684 -230.787734) (xy 136.9661 -230.834415) (xy 136.943229 -230.877992)
			(xy 136.913664 -230.917336) (xy 136.878171 -230.951428) (xy 136.837668 -230.979384) (xy 136.793206 -231.000482)
			(xy 136.745935 -231.014174) (xy 136.69708 -231.020106) (xy 136.647905 -231.018125) (xy 136.599686 -231.008281)
			(xy 136.55367 -230.990829) (xy 136.511049 -230.966222) (xy 136.472928 -230.935097) (xy 136.440293 -230.89826)
			(xy 136.41399 -230.856664) (xy 136.394699 -230.811388) (xy 136.382922 -230.763604) (xy 136.378962 -230.71455)
			(xy 136.060434 -230.71455) (xy 136.059922 -230.739996) (xy 136.051758 -230.79023) (xy 136.035642 -230.838504)
			(xy 136.011991 -230.883567) (xy 135.981418 -230.924253) (xy 135.944714 -230.959508) (xy 135.90283 -230.988418)
			(xy 135.856851 -231.010235) (xy 135.807967 -231.024395) (xy 135.757446 -231.030529) (xy 135.706594 -231.02848)
			(xy 135.65673 -231.0183) (xy 135.609144 -231.000253) (xy 135.56507 -230.974807) (xy 135.525648 -230.94262)
			(xy 135.4919 -230.904526) (xy 135.464699 -230.861512) (xy 135.444751 -230.814692) (xy 135.432572 -230.765278)
			(xy 135.428477 -230.71455) (xy 135.12038 -230.71455) (xy 135.119868 -230.739996) (xy 135.111704 -230.79023)
			(xy 135.095588 -230.838504) (xy 135.071937 -230.883567) (xy 135.041364 -230.924253) (xy 135.00466 -230.959508)
			(xy 134.962776 -230.988418) (xy 134.916797 -231.010235) (xy 134.867913 -231.024395) (xy 134.817392 -231.030529)
			(xy 134.76654 -231.02848) (xy 134.716676 -231.0183) (xy 134.66909 -231.000253) (xy 134.625016 -230.974807)
			(xy 134.585594 -230.94262) (xy 134.551846 -230.904526) (xy 134.524645 -230.861512) (xy 134.504697 -230.814692)
			(xy 134.492518 -230.765278) (xy 134.488423 -230.71455) (xy 134.170161 -230.71455) (xy 134.169671 -230.738903)
			(xy 134.161776 -230.78748) (xy 134.146192 -230.834161) (xy 134.123321 -230.877738) (xy 134.093756 -230.917082)
			(xy 134.058263 -230.951174) (xy 134.01776 -230.97913) (xy 133.973298 -231.000228) (xy 133.926027 -231.01392)
			(xy 133.877172 -231.019852) (xy 133.827997 -231.017871) (xy 133.779778 -231.008027) (xy 133.733762 -230.990575)
			(xy 133.691141 -230.965968) (xy 133.65302 -230.934843) (xy 133.620385 -230.898006) (xy 133.594082 -230.85641)
			(xy 133.574791 -230.811134) (xy 133.563014 -230.76335) (xy 133.559054 -230.714296) (xy 133.240521 -230.714296)
			(xy 133.240526 -230.71455) (xy 133.240014 -230.739996) (xy 133.23185 -230.79023) (xy 133.215734 -230.838504)
			(xy 133.192083 -230.883567) (xy 133.16151 -230.924253) (xy 133.124806 -230.959508) (xy 133.082922 -230.988418)
			(xy 133.036943 -231.010235) (xy 132.988059 -231.024395) (xy 132.937538 -231.030529) (xy 132.886686 -231.02848)
			(xy 132.836822 -231.0183) (xy 132.789236 -231.000253) (xy 132.745162 -230.974807) (xy 132.70574 -230.94262)
			(xy 132.671992 -230.904526) (xy 132.644791 -230.861512) (xy 132.624843 -230.814692) (xy 132.612664 -230.765278)
			(xy 132.608569 -230.71455) (xy 132.290058 -230.71455) (xy 132.289563 -230.739157) (xy 132.281668 -230.787734)
			(xy 132.266084 -230.834415) (xy 132.243213 -230.877992) (xy 132.213648 -230.917336) (xy 132.178155 -230.951428)
			(xy 132.137652 -230.979384) (xy 132.09319 -231.000482) (xy 132.045919 -231.014174) (xy 131.997064 -231.020106)
			(xy 131.947889 -231.018125) (xy 131.89967 -231.008281) (xy 131.853654 -230.990829) (xy 131.811033 -230.966222)
			(xy 131.772912 -230.935097) (xy 131.740277 -230.89826) (xy 131.713974 -230.856664) (xy 131.694683 -230.811388)
			(xy 131.682906 -230.763604) (xy 131.678946 -230.71455) (xy 131.360418 -230.71455) (xy 131.359906 -230.739996)
			(xy 131.351742 -230.79023) (xy 131.335626 -230.838504) (xy 131.311975 -230.883567) (xy 131.281402 -230.924253)
			(xy 131.244698 -230.959508) (xy 131.202814 -230.988418) (xy 131.156835 -231.010235) (xy 131.107951 -231.024395)
			(xy 131.05743 -231.030529) (xy 131.006578 -231.02848) (xy 130.956714 -231.0183) (xy 130.909128 -231.000253)
			(xy 130.865054 -230.974807) (xy 130.825632 -230.94262) (xy 130.791884 -230.904526) (xy 130.764683 -230.861512)
			(xy 130.744735 -230.814692) (xy 130.732556 -230.765278) (xy 130.728461 -230.71455) (xy 130.40995 -230.71455)
			(xy 130.409455 -230.739157) (xy 130.40156 -230.787734) (xy 130.385976 -230.834415) (xy 130.363105 -230.877992)
			(xy 130.33354 -230.917336) (xy 130.298047 -230.951428) (xy 130.257544 -230.979384) (xy 130.213082 -231.000482)
			(xy 130.165811 -231.014174) (xy 130.116956 -231.020106) (xy 130.067781 -231.018125) (xy 130.019562 -231.008281)
			(xy 129.973546 -230.990829) (xy 129.930925 -230.966222) (xy 129.892804 -230.935097) (xy 129.860169 -230.89826)
			(xy 129.833866 -230.856664) (xy 129.814575 -230.811388) (xy 129.802798 -230.763604) (xy 129.798838 -230.71455)
			(xy 129.480564 -230.71455) (xy 129.480052 -230.739996) (xy 129.471888 -230.79023) (xy 129.455772 -230.838504)
			(xy 129.432121 -230.883567) (xy 129.401548 -230.924253) (xy 129.364844 -230.959508) (xy 129.32296 -230.988418)
			(xy 129.276981 -231.010235) (xy 129.228097 -231.024395) (xy 129.177576 -231.030529) (xy 129.126724 -231.02848)
			(xy 129.07686 -231.0183) (xy 129.029274 -231.000253) (xy 128.9852 -230.974807) (xy 128.945778 -230.94262)
			(xy 128.91203 -230.904526) (xy 128.884829 -230.861512) (xy 128.864881 -230.814692) (xy 128.852702 -230.765278)
			(xy 128.848607 -230.71455) (xy 128.54051 -230.71455) (xy 128.539998 -230.739996) (xy 128.531834 -230.79023)
			(xy 128.515718 -230.838504) (xy 128.492067 -230.883567) (xy 128.461494 -230.924253) (xy 128.42479 -230.959508)
			(xy 128.382906 -230.988418) (xy 128.336927 -231.010235) (xy 128.288043 -231.024395) (xy 128.237522 -231.030529)
			(xy 128.18667 -231.02848) (xy 128.136806 -231.0183) (xy 128.08922 -231.000253) (xy 128.045146 -230.974807)
			(xy 128.005724 -230.94262) (xy 127.971976 -230.904526) (xy 127.944775 -230.861512) (xy 127.924827 -230.814692)
			(xy 127.912648 -230.765278) (xy 127.908553 -230.71455) (xy 127.678688 -230.71455) (xy 127.678244 -230.764157)
			(xy 127.670893 -230.863099) (xy 127.656205 -230.961221) (xy 127.645668 -231.009698) (xy 127.637665 -231.044161)
			(xy 127.618476 -231.112268) (xy 127.607314 -231.145842) (xy 127.60452 -231.153716) (xy 127.60452 -231.17175)
			(xy 127.605017 -231.18175) (xy 127.612686 -231.200221) (xy 127.626838 -231.214353) (xy 127.64532 -231.221997)
			(xy 127.65532 -231.22255) (xy 127.662432 -231.22255) (xy 127.669036 -231.220518) (xy 127.689996 -231.21495)
			(xy 127.73295 -231.208963) (xy 127.754634 -231.20858) (xy 127.779442 -231.209069) (xy 127.828445 -231.216836)
			(xy 127.875631 -231.232172) (xy 127.919837 -231.2547) (xy 127.959975 -231.283866) (xy 127.995056 -231.318951)
			(xy 128.024218 -231.359092) (xy 128.046741 -231.4033) (xy 128.062072 -231.450488) (xy 128.069833 -231.499492)
			(xy 128.069833 -231.524302) (xy 128.388884 -231.524302) (xy 128.392844 -231.475248) (xy 128.404621 -231.427464)
			(xy 128.423912 -231.382188) (xy 128.450215 -231.340592) (xy 128.48285 -231.303755) (xy 128.520971 -231.27263)
			(xy 128.563592 -231.248023) (xy 128.609608 -231.230571) (xy 128.657827 -231.220727) (xy 128.707002 -231.218746)
			(xy 128.755857 -231.224678) (xy 128.803128 -231.23837) (xy 128.84759 -231.259468) (xy 128.888093 -231.287424)
			(xy 128.923586 -231.321516) (xy 128.953151 -231.36086) (xy 128.976022 -231.404437) (xy 128.991606 -231.451118)
			(xy 128.999501 -231.499695) (xy 128.999996 -231.524302) (xy 129.318507 -231.524302) (xy 129.322602 -231.473574)
			(xy 129.334781 -231.42416) (xy 129.354729 -231.37734) (xy 129.38193 -231.334326) (xy 129.415678 -231.296232)
			(xy 129.4551 -231.264045) (xy 129.499174 -231.238599) (xy 129.54676 -231.220552) (xy 129.596624 -231.210372)
			(xy 129.647476 -231.208323) (xy 129.697997 -231.214457) (xy 129.746881 -231.228617) (xy 129.79286 -231.250434)
			(xy 129.834744 -231.279344) (xy 129.871448 -231.314599) (xy 129.902021 -231.355285) (xy 129.925672 -231.400348)
			(xy 129.941788 -231.448622) (xy 129.949952 -231.498856) (xy 129.950464 -231.524302) (xy 130.268992 -231.524302)
			(xy 130.272952 -231.475248) (xy 130.284729 -231.427464) (xy 130.30402 -231.382188) (xy 130.330323 -231.340592)
			(xy 130.362958 -231.303755) (xy 130.401079 -231.27263) (xy 130.4437 -231.248023) (xy 130.489716 -231.230571)
			(xy 130.537935 -231.220727) (xy 130.58711 -231.218746) (xy 130.635965 -231.224678) (xy 130.683236 -231.23837)
			(xy 130.727698 -231.259468) (xy 130.768201 -231.287424) (xy 130.803694 -231.321516) (xy 130.833259 -231.36086)
			(xy 130.85613 -231.404437) (xy 130.871714 -231.451118) (xy 130.879609 -231.499695) (xy 130.880104 -231.524302)
			(xy 131.198615 -231.524302) (xy 131.20271 -231.473574) (xy 131.214889 -231.42416) (xy 131.234837 -231.37734)
			(xy 131.262038 -231.334326) (xy 131.295786 -231.296232) (xy 131.335208 -231.264045) (xy 131.379282 -231.238599)
			(xy 131.426868 -231.220552) (xy 131.476732 -231.210372) (xy 131.527584 -231.208323) (xy 131.578105 -231.214457)
			(xy 131.626989 -231.228617) (xy 131.672968 -231.250434) (xy 131.714852 -231.279344) (xy 131.751556 -231.314599)
			(xy 131.782129 -231.355285) (xy 131.80578 -231.400348) (xy 131.821896 -231.448622) (xy 131.83006 -231.498856)
			(xy 131.830572 -231.524302) (xy 132.138415 -231.524302) (xy 132.14251 -231.473574) (xy 132.154689 -231.42416)
			(xy 132.174637 -231.37734) (xy 132.201838 -231.334326) (xy 132.235586 -231.296232) (xy 132.275008 -231.264045)
			(xy 132.319082 -231.238599) (xy 132.366668 -231.220552) (xy 132.416532 -231.210372) (xy 132.467384 -231.208323)
			(xy 132.517905 -231.214457) (xy 132.566789 -231.228617) (xy 132.612768 -231.250434) (xy 132.654652 -231.279344)
			(xy 132.691356 -231.314599) (xy 132.721929 -231.355285) (xy 132.74558 -231.400348) (xy 132.761696 -231.448622)
			(xy 132.76986 -231.498856) (xy 132.770372 -231.524302) (xy 133.0889 -231.524302) (xy 133.09286 -231.475248)
			(xy 133.104637 -231.427464) (xy 133.123928 -231.382188) (xy 133.150231 -231.340592) (xy 133.182866 -231.303755)
			(xy 133.220987 -231.27263) (xy 133.263608 -231.248023) (xy 133.309624 -231.230571) (xy 133.357843 -231.220727)
			(xy 133.407018 -231.218746) (xy 133.455873 -231.224678) (xy 133.503144 -231.23837) (xy 133.547606 -231.259468)
			(xy 133.588109 -231.287424) (xy 133.623602 -231.321516) (xy 133.653167 -231.36086) (xy 133.676038 -231.404437)
			(xy 133.691622 -231.451118) (xy 133.699517 -231.499695) (xy 133.700012 -231.524302) (xy 134.018523 -231.524302)
			(xy 134.022618 -231.473574) (xy 134.034797 -231.42416) (xy 134.054745 -231.37734) (xy 134.081946 -231.334326)
			(xy 134.115694 -231.296232) (xy 134.155116 -231.264045) (xy 134.19919 -231.238599) (xy 134.246776 -231.220552)
			(xy 134.29664 -231.210372) (xy 134.347492 -231.208323) (xy 134.398013 -231.214457) (xy 134.446897 -231.228617)
			(xy 134.492876 -231.250434) (xy 134.53476 -231.279344) (xy 134.571464 -231.314599) (xy 134.602037 -231.355285)
			(xy 134.625688 -231.400348) (xy 134.641804 -231.448622) (xy 134.649968 -231.498856) (xy 134.65048 -231.524302)
			(xy 134.969008 -231.524302) (xy 134.972968 -231.475248) (xy 134.984745 -231.427464) (xy 135.004036 -231.382188)
			(xy 135.030339 -231.340592) (xy 135.062974 -231.303755) (xy 135.101095 -231.27263) (xy 135.143716 -231.248023)
			(xy 135.189732 -231.230571) (xy 135.237951 -231.220727) (xy 135.287126 -231.218746) (xy 135.335981 -231.224678)
			(xy 135.383252 -231.23837) (xy 135.427714 -231.259468) (xy 135.468217 -231.287424) (xy 135.50371 -231.321516)
			(xy 135.533275 -231.36086) (xy 135.556146 -231.404437) (xy 135.57173 -231.451118) (xy 135.579625 -231.499695)
			(xy 135.58012 -231.524302) (xy 135.898631 -231.524302) (xy 135.902726 -231.473574) (xy 135.914905 -231.42416)
			(xy 135.934853 -231.37734) (xy 135.962054 -231.334326) (xy 135.995802 -231.296232) (xy 136.035224 -231.264045)
			(xy 136.079298 -231.238599) (xy 136.126884 -231.220552) (xy 136.176748 -231.210372) (xy 136.2276 -231.208323)
			(xy 136.278121 -231.214457) (xy 136.327005 -231.228617) (xy 136.372984 -231.250434) (xy 136.414868 -231.279344)
			(xy 136.451572 -231.314599) (xy 136.482145 -231.355285) (xy 136.505796 -231.400348) (xy 136.521912 -231.448622)
			(xy 136.530076 -231.498856) (xy 136.530588 -231.524302) (xy 136.848862 -231.524302) (xy 136.852822 -231.475248)
			(xy 136.864599 -231.427464) (xy 136.88389 -231.382188) (xy 136.910193 -231.340592) (xy 136.942828 -231.303755)
			(xy 136.980949 -231.27263) (xy 137.02357 -231.248023) (xy 137.069586 -231.230571) (xy 137.117805 -231.220727)
			(xy 137.16698 -231.218746) (xy 137.215835 -231.224678) (xy 137.263106 -231.23837) (xy 137.307568 -231.259468)
			(xy 137.348071 -231.287424) (xy 137.383564 -231.321516) (xy 137.413129 -231.36086) (xy 137.436 -231.404437)
			(xy 137.451584 -231.451118) (xy 137.459479 -231.499695) (xy 137.459974 -231.524302) (xy 137.778485 -231.524302)
			(xy 137.78258 -231.473574) (xy 137.794759 -231.42416) (xy 137.814707 -231.37734) (xy 137.841908 -231.334326)
			(xy 137.875656 -231.296232) (xy 137.915078 -231.264045) (xy 137.959152 -231.238599) (xy 138.006738 -231.220552)
			(xy 138.056602 -231.210372) (xy 138.107454 -231.208323) (xy 138.157975 -231.214457) (xy 138.206859 -231.228617)
			(xy 138.252838 -231.250434) (xy 138.294722 -231.279344) (xy 138.331426 -231.314599) (xy 138.361999 -231.355285)
			(xy 138.38565 -231.400348) (xy 138.401766 -231.448622) (xy 138.40993 -231.498856) (xy 138.410442 -231.524302)
			(xy 138.718539 -231.524302) (xy 138.722634 -231.473574) (xy 138.734813 -231.42416) (xy 138.754761 -231.37734)
			(xy 138.781962 -231.334326) (xy 138.81571 -231.296232) (xy 138.855132 -231.264045) (xy 138.899206 -231.238599)
			(xy 138.946792 -231.220552) (xy 138.996656 -231.210372) (xy 139.047508 -231.208323) (xy 139.098029 -231.214457)
			(xy 139.146913 -231.228617) (xy 139.192892 -231.250434) (xy 139.234776 -231.279344) (xy 139.27148 -231.314599)
			(xy 139.302053 -231.355285) (xy 139.325704 -231.400348) (xy 139.34182 -231.448622) (xy 139.349984 -231.498856)
			(xy 139.350496 -231.524302) (xy 139.669024 -231.524302) (xy 139.672984 -231.475248) (xy 139.684761 -231.427464)
			(xy 139.704052 -231.382188) (xy 139.730355 -231.340592) (xy 139.76299 -231.303755) (xy 139.801111 -231.27263)
			(xy 139.843732 -231.248023) (xy 139.889748 -231.230571) (xy 139.937967 -231.220727) (xy 139.987142 -231.218746)
			(xy 140.035997 -231.224678) (xy 140.083268 -231.23837) (xy 140.12773 -231.259468) (xy 140.168233 -231.287424)
			(xy 140.203726 -231.321516) (xy 140.233291 -231.36086) (xy 140.256162 -231.404437) (xy 140.271746 -231.451118)
			(xy 140.279641 -231.499695) (xy 140.280136 -231.524302) (xy 140.598647 -231.524302) (xy 140.602742 -231.473574)
			(xy 140.614921 -231.42416) (xy 140.634869 -231.37734) (xy 140.66207 -231.334326) (xy 140.695818 -231.296232)
			(xy 140.73524 -231.264045) (xy 140.779314 -231.238599) (xy 140.8269 -231.220552) (xy 140.876764 -231.210372)
			(xy 140.927616 -231.208323) (xy 140.978137 -231.214457) (xy 141.027021 -231.228617) (xy 141.073 -231.250434)
			(xy 141.114884 -231.279344) (xy 141.151588 -231.314599) (xy 141.182161 -231.355285) (xy 141.205812 -231.400348)
			(xy 141.221928 -231.448622) (xy 141.230092 -231.498856) (xy 141.230604 -231.524302) (xy 141.548878 -231.524302)
			(xy 141.552838 -231.475248) (xy 141.564615 -231.427464) (xy 141.583906 -231.382188) (xy 141.610209 -231.340592)
			(xy 141.642844 -231.303755) (xy 141.680965 -231.27263) (xy 141.723586 -231.248023) (xy 141.769602 -231.230571)
			(xy 141.817821 -231.220727) (xy 141.866996 -231.218746) (xy 141.915851 -231.224678) (xy 141.963122 -231.23837)
			(xy 142.007584 -231.259468) (xy 142.048087 -231.287424) (xy 142.08358 -231.321516) (xy 142.113145 -231.36086)
			(xy 142.136016 -231.404437) (xy 142.1516 -231.451118) (xy 142.159495 -231.499695) (xy 142.15999 -231.524302)
			(xy 142.478501 -231.524302) (xy 142.482596 -231.473574) (xy 142.494775 -231.42416) (xy 142.514723 -231.37734)
			(xy 142.541924 -231.334326) (xy 142.575672 -231.296232) (xy 142.615094 -231.264045) (xy 142.659168 -231.238599)
			(xy 142.706754 -231.220552) (xy 142.756618 -231.210372) (xy 142.80747 -231.208323) (xy 142.857991 -231.214457)
			(xy 142.906875 -231.228617) (xy 142.952854 -231.250434) (xy 142.994738 -231.279344) (xy 143.031442 -231.314599)
			(xy 143.062015 -231.355285) (xy 143.085666 -231.400348) (xy 143.101782 -231.448622) (xy 143.109946 -231.498856)
			(xy 143.110458 -231.524302) (xy 143.428986 -231.524302) (xy 143.432946 -231.475248) (xy 143.444723 -231.427464)
			(xy 143.464014 -231.382188) (xy 143.490317 -231.340592) (xy 143.522952 -231.303755) (xy 143.561073 -231.27263)
			(xy 143.603694 -231.248023) (xy 143.64971 -231.230571) (xy 143.697929 -231.220727) (xy 143.747104 -231.218746)
			(xy 143.795959 -231.224678) (xy 143.84323 -231.23837) (xy 143.887692 -231.259468) (xy 143.928195 -231.287424)
			(xy 143.963688 -231.321516) (xy 143.993253 -231.36086) (xy 144.016124 -231.404437) (xy 144.031708 -231.451118)
			(xy 144.039603 -231.499695) (xy 144.040098 -231.524302) (xy 144.039603 -231.548909) (xy 144.031708 -231.597486)
			(xy 144.016124 -231.644167) (xy 143.993253 -231.687744) (xy 143.963688 -231.727088) (xy 143.928195 -231.76118)
			(xy 143.887692 -231.789136) (xy 143.84323 -231.810234) (xy 143.795959 -231.823926) (xy 143.747104 -231.829858)
			(xy 143.697929 -231.827877) (xy 143.64971 -231.818033) (xy 143.603694 -231.800581) (xy 143.561073 -231.775974)
			(xy 143.522952 -231.744849) (xy 143.490317 -231.708012) (xy 143.464014 -231.666416) (xy 143.444723 -231.62114)
			(xy 143.432946 -231.573356) (xy 143.428986 -231.524302) (xy 143.110458 -231.524302) (xy 143.109946 -231.549748)
			(xy 143.101782 -231.599982) (xy 143.085666 -231.648256) (xy 143.062015 -231.693319) (xy 143.031442 -231.734005)
			(xy 142.994738 -231.76926) (xy 142.952854 -231.79817) (xy 142.906875 -231.819987) (xy 142.857991 -231.834147)
			(xy 142.80747 -231.840281) (xy 142.756618 -231.838232) (xy 142.706754 -231.828052) (xy 142.659168 -231.810005)
			(xy 142.615094 -231.784559) (xy 142.575672 -231.752372) (xy 142.541924 -231.714278) (xy 142.514723 -231.671264)
			(xy 142.494775 -231.624444) (xy 142.482596 -231.57503) (xy 142.478501 -231.524302) (xy 142.15999 -231.524302)
			(xy 142.159495 -231.548909) (xy 142.1516 -231.597486) (xy 142.136016 -231.644167) (xy 142.113145 -231.687744)
			(xy 142.08358 -231.727088) (xy 142.048087 -231.76118) (xy 142.007584 -231.789136) (xy 141.963122 -231.810234)
			(xy 141.915851 -231.823926) (xy 141.866996 -231.829858) (xy 141.817821 -231.827877) (xy 141.769602 -231.818033)
			(xy 141.723586 -231.800581) (xy 141.680965 -231.775974) (xy 141.642844 -231.744849) (xy 141.610209 -231.708012)
			(xy 141.583906 -231.666416) (xy 141.564615 -231.62114) (xy 141.552838 -231.573356) (xy 141.548878 -231.524302)
			(xy 141.230604 -231.524302) (xy 141.230092 -231.549748) (xy 141.221928 -231.599982) (xy 141.205812 -231.648256)
			(xy 141.182161 -231.693319) (xy 141.151588 -231.734005) (xy 141.114884 -231.76926) (xy 141.073 -231.79817)
			(xy 141.027021 -231.819987) (xy 140.978137 -231.834147) (xy 140.927616 -231.840281) (xy 140.876764 -231.838232)
			(xy 140.8269 -231.828052) (xy 140.779314 -231.810005) (xy 140.73524 -231.784559) (xy 140.695818 -231.752372)
			(xy 140.66207 -231.714278) (xy 140.634869 -231.671264) (xy 140.614921 -231.624444) (xy 140.602742 -231.57503)
			(xy 140.598647 -231.524302) (xy 140.280136 -231.524302) (xy 140.279641 -231.548909) (xy 140.271746 -231.597486)
			(xy 140.256162 -231.644167) (xy 140.233291 -231.687744) (xy 140.203726 -231.727088) (xy 140.168233 -231.76118)
			(xy 140.12773 -231.789136) (xy 140.083268 -231.810234) (xy 140.035997 -231.823926) (xy 139.987142 -231.829858)
			(xy 139.937967 -231.827877) (xy 139.889748 -231.818033) (xy 139.843732 -231.800581) (xy 139.801111 -231.775974)
			(xy 139.76299 -231.744849) (xy 139.730355 -231.708012) (xy 139.704052 -231.666416) (xy 139.684761 -231.62114)
			(xy 139.672984 -231.573356) (xy 139.669024 -231.524302) (xy 139.350496 -231.524302) (xy 139.349984 -231.549748)
			(xy 139.34182 -231.599982) (xy 139.325704 -231.648256) (xy 139.302053 -231.693319) (xy 139.27148 -231.734005)
			(xy 139.234776 -231.76926) (xy 139.192892 -231.79817) (xy 139.146913 -231.819987) (xy 139.098029 -231.834147)
			(xy 139.047508 -231.840281) (xy 138.996656 -231.838232) (xy 138.946792 -231.828052) (xy 138.899206 -231.810005)
			(xy 138.855132 -231.784559) (xy 138.81571 -231.752372) (xy 138.781962 -231.714278) (xy 138.754761 -231.671264)
			(xy 138.734813 -231.624444) (xy 138.722634 -231.57503) (xy 138.718539 -231.524302) (xy 138.410442 -231.524302)
			(xy 138.40993 -231.549748) (xy 138.401766 -231.599982) (xy 138.38565 -231.648256) (xy 138.361999 -231.693319)
			(xy 138.331426 -231.734005) (xy 138.294722 -231.76926) (xy 138.252838 -231.79817) (xy 138.206859 -231.819987)
			(xy 138.157975 -231.834147) (xy 138.107454 -231.840281) (xy 138.056602 -231.838232) (xy 138.006738 -231.828052)
			(xy 137.959152 -231.810005) (xy 137.915078 -231.784559) (xy 137.875656 -231.752372) (xy 137.841908 -231.714278)
			(xy 137.814707 -231.671264) (xy 137.794759 -231.624444) (xy 137.78258 -231.57503) (xy 137.778485 -231.524302)
			(xy 137.459974 -231.524302) (xy 137.459479 -231.548909) (xy 137.451584 -231.597486) (xy 137.436 -231.644167)
			(xy 137.413129 -231.687744) (xy 137.383564 -231.727088) (xy 137.348071 -231.76118) (xy 137.307568 -231.789136)
			(xy 137.263106 -231.810234) (xy 137.215835 -231.823926) (xy 137.16698 -231.829858) (xy 137.117805 -231.827877)
			(xy 137.069586 -231.818033) (xy 137.02357 -231.800581) (xy 136.980949 -231.775974) (xy 136.942828 -231.744849)
			(xy 136.910193 -231.708012) (xy 136.88389 -231.666416) (xy 136.864599 -231.62114) (xy 136.852822 -231.573356)
			(xy 136.848862 -231.524302) (xy 136.530588 -231.524302) (xy 136.530076 -231.549748) (xy 136.521912 -231.599982)
			(xy 136.505796 -231.648256) (xy 136.482145 -231.693319) (xy 136.451572 -231.734005) (xy 136.414868 -231.76926)
			(xy 136.372984 -231.79817) (xy 136.327005 -231.819987) (xy 136.278121 -231.834147) (xy 136.2276 -231.840281)
			(xy 136.176748 -231.838232) (xy 136.126884 -231.828052) (xy 136.079298 -231.810005) (xy 136.035224 -231.784559)
			(xy 135.995802 -231.752372) (xy 135.962054 -231.714278) (xy 135.934853 -231.671264) (xy 135.914905 -231.624444)
			(xy 135.902726 -231.57503) (xy 135.898631 -231.524302) (xy 135.58012 -231.524302) (xy 135.579625 -231.548909)
			(xy 135.57173 -231.597486) (xy 135.556146 -231.644167) (xy 135.533275 -231.687744) (xy 135.50371 -231.727088)
			(xy 135.468217 -231.76118) (xy 135.427714 -231.789136) (xy 135.383252 -231.810234) (xy 135.335981 -231.823926)
			(xy 135.287126 -231.829858) (xy 135.237951 -231.827877) (xy 135.189732 -231.818033) (xy 135.143716 -231.800581)
			(xy 135.101095 -231.775974) (xy 135.062974 -231.744849) (xy 135.030339 -231.708012) (xy 135.004036 -231.666416)
			(xy 134.984745 -231.62114) (xy 134.972968 -231.573356) (xy 134.969008 -231.524302) (xy 134.65048 -231.524302)
			(xy 134.649968 -231.549748) (xy 134.641804 -231.599982) (xy 134.625688 -231.648256) (xy 134.602037 -231.693319)
			(xy 134.571464 -231.734005) (xy 134.53476 -231.76926) (xy 134.492876 -231.79817) (xy 134.446897 -231.819987)
			(xy 134.398013 -231.834147) (xy 134.347492 -231.840281) (xy 134.29664 -231.838232) (xy 134.246776 -231.828052)
			(xy 134.19919 -231.810005) (xy 134.155116 -231.784559) (xy 134.115694 -231.752372) (xy 134.081946 -231.714278)
			(xy 134.054745 -231.671264) (xy 134.034797 -231.624444) (xy 134.022618 -231.57503) (xy 134.018523 -231.524302)
			(xy 133.700012 -231.524302) (xy 133.699517 -231.548909) (xy 133.691622 -231.597486) (xy 133.676038 -231.644167)
			(xy 133.653167 -231.687744) (xy 133.623602 -231.727088) (xy 133.588109 -231.76118) (xy 133.547606 -231.789136)
			(xy 133.503144 -231.810234) (xy 133.455873 -231.823926) (xy 133.407018 -231.829858) (xy 133.357843 -231.827877)
			(xy 133.309624 -231.818033) (xy 133.263608 -231.800581) (xy 133.220987 -231.775974) (xy 133.182866 -231.744849)
			(xy 133.150231 -231.708012) (xy 133.123928 -231.666416) (xy 133.104637 -231.62114) (xy 133.09286 -231.573356)
			(xy 133.0889 -231.524302) (xy 132.770372 -231.524302) (xy 132.76986 -231.549748) (xy 132.761696 -231.599982)
			(xy 132.74558 -231.648256) (xy 132.721929 -231.693319) (xy 132.691356 -231.734005) (xy 132.654652 -231.76926)
			(xy 132.612768 -231.79817) (xy 132.566789 -231.819987) (xy 132.517905 -231.834147) (xy 132.467384 -231.840281)
			(xy 132.416532 -231.838232) (xy 132.366668 -231.828052) (xy 132.319082 -231.810005) (xy 132.275008 -231.784559)
			(xy 132.235586 -231.752372) (xy 132.201838 -231.714278) (xy 132.174637 -231.671264) (xy 132.154689 -231.624444)
			(xy 132.14251 -231.57503) (xy 132.138415 -231.524302) (xy 131.830572 -231.524302) (xy 131.83006 -231.549748)
			(xy 131.821896 -231.599982) (xy 131.80578 -231.648256) (xy 131.782129 -231.693319) (xy 131.751556 -231.734005)
			(xy 131.714852 -231.76926) (xy 131.672968 -231.79817) (xy 131.626989 -231.819987) (xy 131.578105 -231.834147)
			(xy 131.527584 -231.840281) (xy 131.476732 -231.838232) (xy 131.426868 -231.828052) (xy 131.379282 -231.810005)
			(xy 131.335208 -231.784559) (xy 131.295786 -231.752372) (xy 131.262038 -231.714278) (xy 131.234837 -231.671264)
			(xy 131.214889 -231.624444) (xy 131.20271 -231.57503) (xy 131.198615 -231.524302) (xy 130.880104 -231.524302)
			(xy 130.879609 -231.548909) (xy 130.871714 -231.597486) (xy 130.85613 -231.644167) (xy 130.833259 -231.687744)
			(xy 130.803694 -231.727088) (xy 130.768201 -231.76118) (xy 130.727698 -231.789136) (xy 130.683236 -231.810234)
			(xy 130.635965 -231.823926) (xy 130.58711 -231.829858) (xy 130.537935 -231.827877) (xy 130.489716 -231.818033)
			(xy 130.4437 -231.800581) (xy 130.401079 -231.775974) (xy 130.362958 -231.744849) (xy 130.330323 -231.708012)
			(xy 130.30402 -231.666416) (xy 130.284729 -231.62114) (xy 130.272952 -231.573356) (xy 130.268992 -231.524302)
			(xy 129.950464 -231.524302) (xy 129.949952 -231.549748) (xy 129.941788 -231.599982) (xy 129.925672 -231.648256)
			(xy 129.902021 -231.693319) (xy 129.871448 -231.734005) (xy 129.834744 -231.76926) (xy 129.79286 -231.79817)
			(xy 129.746881 -231.819987) (xy 129.697997 -231.834147) (xy 129.647476 -231.840281) (xy 129.596624 -231.838232)
			(xy 129.54676 -231.828052) (xy 129.499174 -231.810005) (xy 129.4551 -231.784559) (xy 129.415678 -231.752372)
			(xy 129.38193 -231.714278) (xy 129.354729 -231.671264) (xy 129.334781 -231.624444) (xy 129.322602 -231.57503)
			(xy 129.318507 -231.524302) (xy 128.999996 -231.524302) (xy 128.999501 -231.548909) (xy 128.991606 -231.597486)
			(xy 128.976022 -231.644167) (xy 128.953151 -231.687744) (xy 128.923586 -231.727088) (xy 128.888093 -231.76118)
			(xy 128.84759 -231.789136) (xy 128.803128 -231.810234) (xy 128.755857 -231.823926) (xy 128.707002 -231.829858)
			(xy 128.657827 -231.827877) (xy 128.609608 -231.818033) (xy 128.563592 -231.800581) (xy 128.520971 -231.775974)
			(xy 128.48285 -231.744849) (xy 128.450215 -231.708012) (xy 128.423912 -231.666416) (xy 128.404621 -231.62114)
			(xy 128.392844 -231.573356) (xy 128.388884 -231.524302) (xy 128.069833 -231.524302) (xy 128.069833 -231.549108)
			(xy 128.062072 -231.598112) (xy 128.046741 -231.6453) (xy 128.024218 -231.689508) (xy 127.995056 -231.729649)
			(xy 127.959975 -231.764734) (xy 127.919837 -231.7939) (xy 127.875631 -231.816428) (xy 127.828445 -231.831764)
			(xy 127.779442 -231.839531) (xy 127.754634 -231.840024) (xy 127.732952 -231.839625) (xy 127.690002 -231.83363)
			(xy 127.669036 -231.828086) (xy 127.662432 -231.826054) (xy 127.65532 -231.826054) (xy 127.645306 -231.826538)
			(xy 127.6268 -231.834192) (xy 127.612629 -231.848344) (xy 127.604951 -231.866841) (xy 127.60452 -231.876854)
			(xy 127.60452 -231.895142) (xy 127.607314 -231.903016) (xy 127.622678 -231.94934) (xy 127.647398 -232.043765)
			(xy 127.66515 -232.139745) (xy 127.675839 -232.236765) (xy 127.679408 -232.334308) (xy 127.908553 -232.334308)
			(xy 127.912648 -232.28358) (xy 127.924827 -232.234166) (xy 127.944775 -232.187346) (xy 127.971976 -232.144332)
			(xy 128.005724 -232.106238) (xy 128.045146 -232.074051) (xy 128.08922 -232.048605) (xy 128.136806 -232.030558)
			(xy 128.18667 -232.020378) (xy 128.237522 -232.018329) (xy 128.288043 -232.024463) (xy 128.336927 -232.038623)
			(xy 128.382906 -232.06044) (xy 128.42479 -232.08935) (xy 128.461494 -232.124605) (xy 128.492067 -232.165291)
			(xy 128.515718 -232.210354) (xy 128.531834 -232.258628) (xy 128.539998 -232.308862) (xy 128.54051 -232.334308)
			(xy 128.848607 -232.334308) (xy 128.852702 -232.28358) (xy 128.864881 -232.234166) (xy 128.884829 -232.187346)
			(xy 128.91203 -232.144332) (xy 128.945778 -232.106238) (xy 128.9852 -232.074051) (xy 129.029274 -232.048605)
			(xy 129.07686 -232.030558) (xy 129.126724 -232.020378) (xy 129.177576 -232.018329) (xy 129.228097 -232.024463)
			(xy 129.276981 -232.038623) (xy 129.32296 -232.06044) (xy 129.364844 -232.08935) (xy 129.401548 -232.124605)
			(xy 129.432121 -232.165291) (xy 129.455772 -232.210354) (xy 129.471888 -232.258628) (xy 129.480052 -232.308862)
			(xy 129.480564 -232.334308) (xy 130.728461 -232.334308) (xy 130.732556 -232.28358) (xy 130.744735 -232.234166)
			(xy 130.764683 -232.187346) (xy 130.791884 -232.144332) (xy 130.825632 -232.106238) (xy 130.865054 -232.074051)
			(xy 130.909128 -232.048605) (xy 130.956714 -232.030558) (xy 131.006578 -232.020378) (xy 131.05743 -232.018329)
			(xy 131.107951 -232.024463) (xy 131.156835 -232.038623) (xy 131.202814 -232.06044) (xy 131.244698 -232.08935)
			(xy 131.281402 -232.124605) (xy 131.311975 -232.165291) (xy 131.335626 -232.210354) (xy 131.351742 -232.258628)
			(xy 131.359906 -232.308862) (xy 131.360418 -232.334308) (xy 131.678946 -232.334308) (xy 131.682906 -232.285254)
			(xy 131.694683 -232.23747) (xy 131.713974 -232.192194) (xy 131.740277 -232.150598) (xy 131.772912 -232.113761)
			(xy 131.811033 -232.082636) (xy 131.853654 -232.058029) (xy 131.89967 -232.040577) (xy 131.947889 -232.030733)
			(xy 131.997064 -232.028752) (xy 132.045919 -232.034684) (xy 132.09319 -232.048376) (xy 132.137652 -232.069474)
			(xy 132.178155 -232.09743) (xy 132.213648 -232.131522) (xy 132.243213 -232.170866) (xy 132.266084 -232.214443)
			(xy 132.281668 -232.261124) (xy 132.289563 -232.309701) (xy 132.290058 -232.334308) (xy 132.608569 -232.334308)
			(xy 132.612664 -232.28358) (xy 132.624843 -232.234166) (xy 132.644791 -232.187346) (xy 132.671992 -232.144332)
			(xy 132.70574 -232.106238) (xy 132.745162 -232.074051) (xy 132.789236 -232.048605) (xy 132.836822 -232.030558)
			(xy 132.886686 -232.020378) (xy 132.937538 -232.018329) (xy 132.988059 -232.024463) (xy 133.036943 -232.038623)
			(xy 133.082922 -232.06044) (xy 133.124806 -232.08935) (xy 133.16151 -232.124605) (xy 133.192083 -232.165291)
			(xy 133.215734 -232.210354) (xy 133.23185 -232.258628) (xy 133.240014 -232.308862) (xy 133.240526 -232.334308)
			(xy 133.559054 -232.334308) (xy 133.563014 -232.285254) (xy 133.574791 -232.23747) (xy 133.594082 -232.192194)
			(xy 133.620385 -232.150598) (xy 133.65302 -232.113761) (xy 133.691141 -232.082636) (xy 133.733762 -232.058029)
			(xy 133.779778 -232.040577) (xy 133.827997 -232.030733) (xy 133.877172 -232.028752) (xy 133.926027 -232.034684)
			(xy 133.973298 -232.048376) (xy 134.01776 -232.069474) (xy 134.058263 -232.09743) (xy 134.093756 -232.131522)
			(xy 134.123321 -232.170866) (xy 134.146192 -232.214443) (xy 134.161776 -232.261124) (xy 134.169671 -232.309701)
			(xy 134.170166 -232.334308) (xy 134.488423 -232.334308) (xy 134.492518 -232.28358) (xy 134.504697 -232.234166)
			(xy 134.524645 -232.187346) (xy 134.551846 -232.144332) (xy 134.585594 -232.106238) (xy 134.625016 -232.074051)
			(xy 134.66909 -232.048605) (xy 134.716676 -232.030558) (xy 134.76654 -232.020378) (xy 134.817392 -232.018329)
			(xy 134.867913 -232.024463) (xy 134.916797 -232.038623) (xy 134.962776 -232.06044) (xy 135.00466 -232.08935)
			(xy 135.041364 -232.124605) (xy 135.071937 -232.165291) (xy 135.095588 -232.210354) (xy 135.111704 -232.258628)
			(xy 135.119868 -232.308862) (xy 135.12038 -232.334308) (xy 135.428477 -232.334308) (xy 135.432572 -232.28358)
			(xy 135.444751 -232.234166) (xy 135.464699 -232.187346) (xy 135.4919 -232.144332) (xy 135.525648 -232.106238)
			(xy 135.56507 -232.074051) (xy 135.609144 -232.048605) (xy 135.65673 -232.030558) (xy 135.706594 -232.020378)
			(xy 135.757446 -232.018329) (xy 135.807967 -232.024463) (xy 135.856851 -232.038623) (xy 135.90283 -232.06044)
			(xy 135.944714 -232.08935) (xy 135.981418 -232.124605) (xy 136.011991 -232.165291) (xy 136.035642 -232.210354)
			(xy 136.051758 -232.258628) (xy 136.059922 -232.308862) (xy 136.060434 -232.334308) (xy 137.308585 -232.334308)
			(xy 137.31268 -232.28358) (xy 137.324859 -232.234166) (xy 137.344807 -232.187346) (xy 137.372008 -232.144332)
			(xy 137.405756 -232.106238) (xy 137.445178 -232.074051) (xy 137.489252 -232.048605) (xy 137.536838 -232.030558)
			(xy 137.586702 -232.020378) (xy 137.637554 -232.018329) (xy 137.688075 -232.024463) (xy 137.736959 -232.038623)
			(xy 137.782938 -232.06044) (xy 137.824822 -232.08935) (xy 137.861526 -232.124605) (xy 137.892099 -232.165291)
			(xy 137.91575 -232.210354) (xy 137.931866 -232.258628) (xy 137.94003 -232.308862) (xy 137.940542 -232.334308)
			(xy 138.25907 -232.334308) (xy 138.26303 -232.285254) (xy 138.274807 -232.23747) (xy 138.294098 -232.192194)
			(xy 138.320401 -232.150598) (xy 138.353036 -232.113761) (xy 138.391157 -232.082636) (xy 138.433778 -232.058029)
			(xy 138.479794 -232.040577) (xy 138.528013 -232.030733) (xy 138.577188 -232.028752) (xy 138.626043 -232.034684)
			(xy 138.673314 -232.048376) (xy 138.717776 -232.069474) (xy 138.758279 -232.09743) (xy 138.793772 -232.131522)
			(xy 138.823337 -232.170866) (xy 138.846208 -232.214443) (xy 138.861792 -232.261124) (xy 138.869687 -232.309701)
			(xy 138.870182 -232.334308) (xy 139.188439 -232.334308) (xy 139.192534 -232.28358) (xy 139.204713 -232.234166)
			(xy 139.224661 -232.187346) (xy 139.251862 -232.144332) (xy 139.28561 -232.106238) (xy 139.325032 -232.074051)
			(xy 139.369106 -232.048605) (xy 139.416692 -232.030558) (xy 139.466556 -232.020378) (xy 139.517408 -232.018329)
			(xy 139.567929 -232.024463) (xy 139.616813 -232.038623) (xy 139.662792 -232.06044) (xy 139.704676 -232.08935)
			(xy 139.74138 -232.124605) (xy 139.771953 -232.165291) (xy 139.795604 -232.210354) (xy 139.81172 -232.258628)
			(xy 139.819884 -232.308862) (xy 139.820396 -232.334308) (xy 140.138924 -232.334308) (xy 140.142884 -232.285254)
			(xy 140.154661 -232.23747) (xy 140.173952 -232.192194) (xy 140.200255 -232.150598) (xy 140.23289 -232.113761)
			(xy 140.271011 -232.082636) (xy 140.313632 -232.058029) (xy 140.359648 -232.040577) (xy 140.407867 -232.030733)
			(xy 140.457042 -232.028752) (xy 140.505897 -232.034684) (xy 140.553168 -232.048376) (xy 140.59763 -232.069474)
			(xy 140.638133 -232.09743) (xy 140.673626 -232.131522) (xy 140.703191 -232.170866) (xy 140.726062 -232.214443)
			(xy 140.741646 -232.261124) (xy 140.749541 -232.309701) (xy 140.750036 -232.334308) (xy 141.068547 -232.334308)
			(xy 141.072642 -232.28358) (xy 141.084821 -232.234166) (xy 141.104769 -232.187346) (xy 141.13197 -232.144332)
			(xy 141.165718 -232.106238) (xy 141.20514 -232.074051) (xy 141.249214 -232.048605) (xy 141.2968 -232.030558)
			(xy 141.346664 -232.020378) (xy 141.397516 -232.018329) (xy 141.448037 -232.024463) (xy 141.496921 -232.038623)
			(xy 141.5429 -232.06044) (xy 141.584784 -232.08935) (xy 141.621488 -232.124605) (xy 141.652061 -232.165291)
			(xy 141.675712 -232.210354) (xy 141.691828 -232.258628) (xy 141.699992 -232.308862) (xy 141.700504 -232.334308)
			(xy 142.008601 -232.334308) (xy 142.012696 -232.28358) (xy 142.024875 -232.234166) (xy 142.044823 -232.187346)
			(xy 142.072024 -232.144332) (xy 142.105772 -232.106238) (xy 142.145194 -232.074051) (xy 142.189268 -232.048605)
			(xy 142.236854 -232.030558) (xy 142.286718 -232.020378) (xy 142.33757 -232.018329) (xy 142.388091 -232.024463)
			(xy 142.436975 -232.038623) (xy 142.482954 -232.06044) (xy 142.524838 -232.08935) (xy 142.561542 -232.124605)
			(xy 142.592115 -232.165291) (xy 142.615766 -232.210354) (xy 142.631882 -232.258628) (xy 142.640046 -232.308862)
			(xy 142.640558 -232.334308) (xy 144.83894 -232.334308) (xy 144.8429 -232.285254) (xy 144.854677 -232.23747)
			(xy 144.873968 -232.192194) (xy 144.900271 -232.150598) (xy 144.932906 -232.113761) (xy 144.971027 -232.082636)
			(xy 145.013648 -232.058029) (xy 145.059664 -232.040577) (xy 145.107883 -232.030733) (xy 145.157058 -232.028752)
			(xy 145.205913 -232.034684) (xy 145.253184 -232.048376) (xy 145.297646 -232.069474) (xy 145.338149 -232.09743)
			(xy 145.373642 -232.131522) (xy 145.403207 -232.170866) (xy 145.426078 -232.214443) (xy 145.441662 -232.261124)
			(xy 145.449557 -232.309701) (xy 145.450052 -232.334308) (xy 145.449557 -232.358915) (xy 145.441662 -232.407492)
			(xy 145.426078 -232.454173) (xy 145.403207 -232.49775) (xy 145.373642 -232.537094) (xy 145.338149 -232.571186)
			(xy 145.297646 -232.599142) (xy 145.253184 -232.62024) (xy 145.205913 -232.633932) (xy 145.157058 -232.639864)
			(xy 145.107883 -232.637883) (xy 145.059664 -232.628039) (xy 145.013648 -232.610587) (xy 144.971027 -232.58598)
			(xy 144.932906 -232.554855) (xy 144.900271 -232.518018) (xy 144.873968 -232.476422) (xy 144.854677 -232.431146)
			(xy 144.8429 -232.383362) (xy 144.83894 -232.334308) (xy 142.640558 -232.334308) (xy 142.640046 -232.359754)
			(xy 142.631882 -232.409988) (xy 142.615766 -232.458262) (xy 142.592115 -232.503325) (xy 142.561542 -232.544011)
			(xy 142.524838 -232.579266) (xy 142.482954 -232.608176) (xy 142.436975 -232.629993) (xy 142.388091 -232.644153)
			(xy 142.33757 -232.650287) (xy 142.286718 -232.648238) (xy 142.236854 -232.638058) (xy 142.189268 -232.620011)
			(xy 142.145194 -232.594565) (xy 142.105772 -232.562378) (xy 142.072024 -232.524284) (xy 142.044823 -232.48127)
			(xy 142.024875 -232.43445) (xy 142.012696 -232.385036) (xy 142.008601 -232.334308) (xy 141.700504 -232.334308)
			(xy 141.699992 -232.359754) (xy 141.691828 -232.409988) (xy 141.675712 -232.458262) (xy 141.652061 -232.503325)
			(xy 141.621488 -232.544011) (xy 141.584784 -232.579266) (xy 141.5429 -232.608176) (xy 141.496921 -232.629993)
			(xy 141.448037 -232.644153) (xy 141.397516 -232.650287) (xy 141.346664 -232.648238) (xy 141.2968 -232.638058)
			(xy 141.249214 -232.620011) (xy 141.20514 -232.594565) (xy 141.165718 -232.562378) (xy 141.13197 -232.524284)
			(xy 141.104769 -232.48127) (xy 141.084821 -232.43445) (xy 141.072642 -232.385036) (xy 141.068547 -232.334308)
			(xy 140.750036 -232.334308) (xy 140.749541 -232.358915) (xy 140.741646 -232.407492) (xy 140.726062 -232.454173)
			(xy 140.703191 -232.49775) (xy 140.673626 -232.537094) (xy 140.638133 -232.571186) (xy 140.59763 -232.599142)
			(xy 140.553168 -232.62024) (xy 140.505897 -232.633932) (xy 140.457042 -232.639864) (xy 140.407867 -232.637883)
			(xy 140.359648 -232.628039) (xy 140.313632 -232.610587) (xy 140.271011 -232.58598) (xy 140.23289 -232.554855)
			(xy 140.200255 -232.518018) (xy 140.173952 -232.476422) (xy 140.154661 -232.431146) (xy 140.142884 -232.383362)
			(xy 140.138924 -232.334308) (xy 139.820396 -232.334308) (xy 139.819884 -232.359754) (xy 139.81172 -232.409988)
			(xy 139.795604 -232.458262) (xy 139.771953 -232.503325) (xy 139.74138 -232.544011) (xy 139.704676 -232.579266)
			(xy 139.662792 -232.608176) (xy 139.616813 -232.629993) (xy 139.567929 -232.644153) (xy 139.517408 -232.650287)
			(xy 139.466556 -232.648238) (xy 139.416692 -232.638058) (xy 139.369106 -232.620011) (xy 139.325032 -232.594565)
			(xy 139.28561 -232.562378) (xy 139.251862 -232.524284) (xy 139.224661 -232.48127) (xy 139.204713 -232.43445)
			(xy 139.192534 -232.385036) (xy 139.188439 -232.334308) (xy 138.870182 -232.334308) (xy 138.869687 -232.358915)
			(xy 138.861792 -232.407492) (xy 138.846208 -232.454173) (xy 138.823337 -232.49775) (xy 138.793772 -232.537094)
			(xy 138.758279 -232.571186) (xy 138.717776 -232.599142) (xy 138.673314 -232.62024) (xy 138.626043 -232.633932)
			(xy 138.577188 -232.639864) (xy 138.528013 -232.637883) (xy 138.479794 -232.628039) (xy 138.433778 -232.610587)
			(xy 138.391157 -232.58598) (xy 138.353036 -232.554855) (xy 138.320401 -232.518018) (xy 138.294098 -232.476422)
			(xy 138.274807 -232.431146) (xy 138.26303 -232.383362) (xy 138.25907 -232.334308) (xy 137.940542 -232.334308)
			(xy 137.94003 -232.359754) (xy 137.931866 -232.409988) (xy 137.91575 -232.458262) (xy 137.892099 -232.503325)
			(xy 137.861526 -232.544011) (xy 137.824822 -232.579266) (xy 137.782938 -232.608176) (xy 137.736959 -232.629993)
			(xy 137.688075 -232.644153) (xy 137.637554 -232.650287) (xy 137.586702 -232.648238) (xy 137.536838 -232.638058)
			(xy 137.489252 -232.620011) (xy 137.445178 -232.594565) (xy 137.405756 -232.562378) (xy 137.372008 -232.524284)
			(xy 137.344807 -232.48127) (xy 137.324859 -232.43445) (xy 137.31268 -232.385036) (xy 137.308585 -232.334308)
			(xy 136.060434 -232.334308) (xy 136.059922 -232.359754) (xy 136.051758 -232.409988) (xy 136.035642 -232.458262)
			(xy 136.011991 -232.503325) (xy 135.981418 -232.544011) (xy 135.944714 -232.579266) (xy 135.90283 -232.608176)
			(xy 135.856851 -232.629993) (xy 135.807967 -232.644153) (xy 135.757446 -232.650287) (xy 135.706594 -232.648238)
			(xy 135.65673 -232.638058) (xy 135.609144 -232.620011) (xy 135.56507 -232.594565) (xy 135.525648 -232.562378)
			(xy 135.4919 -232.524284) (xy 135.464699 -232.48127) (xy 135.444751 -232.43445) (xy 135.432572 -232.385036)
			(xy 135.428477 -232.334308) (xy 135.12038 -232.334308) (xy 135.119868 -232.359754) (xy 135.111704 -232.409988)
			(xy 135.095588 -232.458262) (xy 135.071937 -232.503325) (xy 135.041364 -232.544011) (xy 135.00466 -232.579266)
			(xy 134.962776 -232.608176) (xy 134.916797 -232.629993) (xy 134.867913 -232.644153) (xy 134.817392 -232.650287)
			(xy 134.76654 -232.648238) (xy 134.716676 -232.638058) (xy 134.66909 -232.620011) (xy 134.625016 -232.594565)
			(xy 134.585594 -232.562378) (xy 134.551846 -232.524284) (xy 134.524645 -232.48127) (xy 134.504697 -232.43445)
			(xy 134.492518 -232.385036) (xy 134.488423 -232.334308) (xy 134.170166 -232.334308) (xy 134.169671 -232.358915)
			(xy 134.161776 -232.407492) (xy 134.146192 -232.454173) (xy 134.123321 -232.49775) (xy 134.093756 -232.537094)
			(xy 134.058263 -232.571186) (xy 134.01776 -232.599142) (xy 133.973298 -232.62024) (xy 133.926027 -232.633932)
			(xy 133.877172 -232.639864) (xy 133.827997 -232.637883) (xy 133.779778 -232.628039) (xy 133.733762 -232.610587)
			(xy 133.691141 -232.58598) (xy 133.65302 -232.554855) (xy 133.620385 -232.518018) (xy 133.594082 -232.476422)
			(xy 133.574791 -232.431146) (xy 133.563014 -232.383362) (xy 133.559054 -232.334308) (xy 133.240526 -232.334308)
			(xy 133.240014 -232.359754) (xy 133.23185 -232.409988) (xy 133.215734 -232.458262) (xy 133.192083 -232.503325)
			(xy 133.16151 -232.544011) (xy 133.124806 -232.579266) (xy 133.082922 -232.608176) (xy 133.036943 -232.629993)
			(xy 132.988059 -232.644153) (xy 132.937538 -232.650287) (xy 132.886686 -232.648238) (xy 132.836822 -232.638058)
			(xy 132.789236 -232.620011) (xy 132.745162 -232.594565) (xy 132.70574 -232.562378) (xy 132.671992 -232.524284)
			(xy 132.644791 -232.48127) (xy 132.624843 -232.43445) (xy 132.612664 -232.385036) (xy 132.608569 -232.334308)
			(xy 132.290058 -232.334308) (xy 132.289563 -232.358915) (xy 132.281668 -232.407492) (xy 132.266084 -232.454173)
			(xy 132.243213 -232.49775) (xy 132.213648 -232.537094) (xy 132.178155 -232.571186) (xy 132.137652 -232.599142)
			(xy 132.09319 -232.62024) (xy 132.045919 -232.633932) (xy 131.997064 -232.639864) (xy 131.947889 -232.637883)
			(xy 131.89967 -232.628039) (xy 131.853654 -232.610587) (xy 131.811033 -232.58598) (xy 131.772912 -232.554855)
			(xy 131.740277 -232.518018) (xy 131.713974 -232.476422) (xy 131.694683 -232.431146) (xy 131.682906 -232.383362)
			(xy 131.678946 -232.334308) (xy 131.360418 -232.334308) (xy 131.359906 -232.359754) (xy 131.351742 -232.409988)
			(xy 131.335626 -232.458262) (xy 131.311975 -232.503325) (xy 131.281402 -232.544011) (xy 131.244698 -232.579266)
			(xy 131.202814 -232.608176) (xy 131.156835 -232.629993) (xy 131.107951 -232.644153) (xy 131.05743 -232.650287)
			(xy 131.006578 -232.648238) (xy 130.956714 -232.638058) (xy 130.909128 -232.620011) (xy 130.865054 -232.594565)
			(xy 130.825632 -232.562378) (xy 130.791884 -232.524284) (xy 130.764683 -232.48127) (xy 130.744735 -232.43445)
			(xy 130.732556 -232.385036) (xy 130.728461 -232.334308) (xy 129.480564 -232.334308) (xy 129.480052 -232.359754)
			(xy 129.471888 -232.409988) (xy 129.455772 -232.458262) (xy 129.432121 -232.503325) (xy 129.401548 -232.544011)
			(xy 129.364844 -232.579266) (xy 129.32296 -232.608176) (xy 129.276981 -232.629993) (xy 129.228097 -232.644153)
			(xy 129.177576 -232.650287) (xy 129.126724 -232.648238) (xy 129.07686 -232.638058) (xy 129.029274 -232.620011)
			(xy 128.9852 -232.594565) (xy 128.945778 -232.562378) (xy 128.91203 -232.524284) (xy 128.884829 -232.48127)
			(xy 128.864881 -232.43445) (xy 128.852702 -232.385036) (xy 128.848607 -232.334308) (xy 128.54051 -232.334308)
			(xy 128.539998 -232.359754) (xy 128.531834 -232.409988) (xy 128.515718 -232.458262) (xy 128.492067 -232.503325)
			(xy 128.461494 -232.544011) (xy 128.42479 -232.579266) (xy 128.382906 -232.608176) (xy 128.336927 -232.629993)
			(xy 128.288043 -232.644153) (xy 128.237522 -232.650287) (xy 128.18667 -232.648238) (xy 128.136806 -232.638058)
			(xy 128.08922 -232.620011) (xy 128.045146 -232.594565) (xy 128.005724 -232.562378) (xy 127.971976 -232.524284)
			(xy 127.944775 -232.48127) (xy 127.924827 -232.43445) (xy 127.912648 -232.385036) (xy 127.908553 -232.334308)
			(xy 127.679408 -232.334308) (xy 127.675838 -232.43185) (xy 127.665148 -232.52887) (xy 127.647395 -232.624849)
			(xy 127.622674 -232.719274) (xy 127.607314 -232.7656) (xy 127.60452 -232.773474) (xy 127.60452 -232.791762)
			(xy 127.604934 -232.801787) (xy 127.612597 -232.820313) (xy 127.626772 -232.834493) (xy 127.645295 -232.842163)
			(xy 127.65532 -232.842562) (xy 127.662432 -232.842562) (xy 127.669036 -232.84053) (xy 127.689996 -232.834962)
			(xy 127.73295 -232.828975) (xy 127.754634 -232.828592) (xy 127.779441 -232.829081) (xy 127.828443 -232.836847)
			(xy 127.875627 -232.852183) (xy 127.919831 -232.87471) (xy 127.959967 -232.903875) (xy 127.995047 -232.938959)
			(xy 128.024208 -232.979098) (xy 128.04673 -233.023305) (xy 128.062061 -233.07049) (xy 128.069821 -233.119493)
			(xy 128.069821 -233.144314) (xy 128.388884 -233.144314) (xy 128.392844 -233.09526) (xy 128.404621 -233.047476)
			(xy 128.423912 -233.0022) (xy 128.450215 -232.960604) (xy 128.48285 -232.923767) (xy 128.520971 -232.892642)
			(xy 128.563592 -232.868035) (xy 128.609608 -232.850583) (xy 128.657827 -232.840739) (xy 128.707002 -232.838758)
			(xy 128.755857 -232.84469) (xy 128.803128 -232.858382) (xy 128.84759 -232.87948) (xy 128.888093 -232.907436)
			(xy 128.923586 -232.941528) (xy 128.953151 -232.980872) (xy 128.976022 -233.024449) (xy 128.991606 -233.07113)
			(xy 128.999501 -233.119707) (xy 128.999996 -233.144314) (xy 129.318507 -233.144314) (xy 129.322602 -233.093586)
			(xy 129.334781 -233.044172) (xy 129.354729 -232.997352) (xy 129.38193 -232.954338) (xy 129.415678 -232.916244)
			(xy 129.4551 -232.884057) (xy 129.499174 -232.858611) (xy 129.54676 -232.840564) (xy 129.596624 -232.830384)
			(xy 129.647476 -232.828335) (xy 129.697997 -232.834469) (xy 129.746881 -232.848629) (xy 129.79286 -232.870446)
			(xy 129.834744 -232.899356) (xy 129.871448 -232.934611) (xy 129.902021 -232.975297) (xy 129.925672 -233.02036)
			(xy 129.941788 -233.068634) (xy 129.949952 -233.118868) (xy 129.950464 -233.144314) (xy 130.268992 -233.144314)
			(xy 130.272952 -233.09526) (xy 130.284729 -233.047476) (xy 130.30402 -233.0022) (xy 130.330323 -232.960604)
			(xy 130.362958 -232.923767) (xy 130.401079 -232.892642) (xy 130.4437 -232.868035) (xy 130.489716 -232.850583)
			(xy 130.537935 -232.840739) (xy 130.58711 -232.838758) (xy 130.635965 -232.84469) (xy 130.683236 -232.858382)
			(xy 130.727698 -232.87948) (xy 130.768201 -232.907436) (xy 130.803694 -232.941528) (xy 130.833259 -232.980872)
			(xy 130.85613 -233.024449) (xy 130.871714 -233.07113) (xy 130.879609 -233.119707) (xy 130.880104 -233.144314)
			(xy 131.198615 -233.144314) (xy 131.20271 -233.093586) (xy 131.214889 -233.044172) (xy 131.234837 -232.997352)
			(xy 131.262038 -232.954338) (xy 131.295786 -232.916244) (xy 131.335208 -232.884057) (xy 131.379282 -232.858611)
			(xy 131.426868 -232.840564) (xy 131.476732 -232.830384) (xy 131.527584 -232.828335) (xy 131.578105 -232.834469)
			(xy 131.626989 -232.848629) (xy 131.672968 -232.870446) (xy 131.714852 -232.899356) (xy 131.751556 -232.934611)
			(xy 131.782129 -232.975297) (xy 131.80578 -233.02036) (xy 131.821896 -233.068634) (xy 131.83006 -233.118868)
			(xy 131.830572 -233.144314) (xy 132.138415 -233.144314) (xy 132.14251 -233.093586) (xy 132.154689 -233.044172)
			(xy 132.174637 -232.997352) (xy 132.201838 -232.954338) (xy 132.235586 -232.916244) (xy 132.275008 -232.884057)
			(xy 132.319082 -232.858611) (xy 132.366668 -232.840564) (xy 132.416532 -232.830384) (xy 132.467384 -232.828335)
			(xy 132.517905 -232.834469) (xy 132.566789 -232.848629) (xy 132.612768 -232.870446) (xy 132.654652 -232.899356)
			(xy 132.691356 -232.934611) (xy 132.721929 -232.975297) (xy 132.74558 -233.02036) (xy 132.761696 -233.068634)
			(xy 132.76986 -233.118868) (xy 132.770372 -233.144314) (xy 133.0889 -233.144314) (xy 133.09286 -233.09526)
			(xy 133.104637 -233.047476) (xy 133.123928 -233.0022) (xy 133.150231 -232.960604) (xy 133.182866 -232.923767)
			(xy 133.220987 -232.892642) (xy 133.263608 -232.868035) (xy 133.309624 -232.850583) (xy 133.357843 -232.840739)
			(xy 133.407018 -232.838758) (xy 133.455873 -232.84469) (xy 133.503144 -232.858382) (xy 133.547606 -232.87948)
			(xy 133.588109 -232.907436) (xy 133.623602 -232.941528) (xy 133.653167 -232.980872) (xy 133.676038 -233.024449)
			(xy 133.691622 -233.07113) (xy 133.699517 -233.119707) (xy 133.700012 -233.144314) (xy 134.018523 -233.144314)
			(xy 134.022618 -233.093586) (xy 134.034797 -233.044172) (xy 134.054745 -232.997352) (xy 134.081946 -232.954338)
			(xy 134.115694 -232.916244) (xy 134.155116 -232.884057) (xy 134.19919 -232.858611) (xy 134.246776 -232.840564)
			(xy 134.29664 -232.830384) (xy 134.347492 -232.828335) (xy 134.398013 -232.834469) (xy 134.446897 -232.848629)
			(xy 134.492876 -232.870446) (xy 134.53476 -232.899356) (xy 134.571464 -232.934611) (xy 134.602037 -232.975297)
			(xy 134.625688 -233.02036) (xy 134.641804 -233.068634) (xy 134.649968 -233.118868) (xy 134.65048 -233.144314)
			(xy 134.969008 -233.144314) (xy 134.972968 -233.09526) (xy 134.984745 -233.047476) (xy 135.004036 -233.0022)
			(xy 135.030339 -232.960604) (xy 135.062974 -232.923767) (xy 135.101095 -232.892642) (xy 135.143716 -232.868035)
			(xy 135.189732 -232.850583) (xy 135.237951 -232.840739) (xy 135.287126 -232.838758) (xy 135.335981 -232.84469)
			(xy 135.383252 -232.858382) (xy 135.427714 -232.87948) (xy 135.468217 -232.907436) (xy 135.50371 -232.941528)
			(xy 135.533275 -232.980872) (xy 135.556146 -233.024449) (xy 135.57173 -233.07113) (xy 135.579625 -233.119707)
			(xy 135.58012 -233.144314) (xy 135.898631 -233.144314) (xy 135.902726 -233.093586) (xy 135.914905 -233.044172)
			(xy 135.934853 -232.997352) (xy 135.962054 -232.954338) (xy 135.995802 -232.916244) (xy 136.035224 -232.884057)
			(xy 136.079298 -232.858611) (xy 136.126884 -232.840564) (xy 136.176748 -232.830384) (xy 136.2276 -232.828335)
			(xy 136.278121 -232.834469) (xy 136.327005 -232.848629) (xy 136.372984 -232.870446) (xy 136.414868 -232.899356)
			(xy 136.451572 -232.934611) (xy 136.482145 -232.975297) (xy 136.505796 -233.02036) (xy 136.521912 -233.068634)
			(xy 136.530076 -233.118868) (xy 136.530588 -233.144314) (xy 136.848862 -233.144314) (xy 136.852822 -233.09526)
			(xy 136.864599 -233.047476) (xy 136.88389 -233.0022) (xy 136.910193 -232.960604) (xy 136.942828 -232.923767)
			(xy 136.980949 -232.892642) (xy 137.02357 -232.868035) (xy 137.069586 -232.850583) (xy 137.117805 -232.840739)
			(xy 137.16698 -232.838758) (xy 137.215835 -232.84469) (xy 137.263106 -232.858382) (xy 137.307568 -232.87948)
			(xy 137.348071 -232.907436) (xy 137.383564 -232.941528) (xy 137.413129 -232.980872) (xy 137.436 -233.024449)
			(xy 137.451584 -233.07113) (xy 137.459479 -233.119707) (xy 137.459974 -233.144314) (xy 137.778485 -233.144314)
			(xy 137.78258 -233.093586) (xy 137.794759 -233.044172) (xy 137.814707 -232.997352) (xy 137.841908 -232.954338)
			(xy 137.875656 -232.916244) (xy 137.915078 -232.884057) (xy 137.959152 -232.858611) (xy 138.006738 -232.840564)
			(xy 138.056602 -232.830384) (xy 138.107454 -232.828335) (xy 138.157975 -232.834469) (xy 138.206859 -232.848629)
			(xy 138.252838 -232.870446) (xy 138.294722 -232.899356) (xy 138.331426 -232.934611) (xy 138.361999 -232.975297)
			(xy 138.38565 -233.02036) (xy 138.401766 -233.068634) (xy 138.40993 -233.118868) (xy 138.410442 -233.144314)
			(xy 138.718539 -233.144314) (xy 138.722634 -233.093586) (xy 138.734813 -233.044172) (xy 138.754761 -232.997352)
			(xy 138.781962 -232.954338) (xy 138.81571 -232.916244) (xy 138.855132 -232.884057) (xy 138.899206 -232.858611)
			(xy 138.946792 -232.840564) (xy 138.996656 -232.830384) (xy 139.047508 -232.828335) (xy 139.098029 -232.834469)
			(xy 139.146913 -232.848629) (xy 139.192892 -232.870446) (xy 139.234776 -232.899356) (xy 139.27148 -232.934611)
			(xy 139.302053 -232.975297) (xy 139.325704 -233.02036) (xy 139.34182 -233.068634) (xy 139.349984 -233.118868)
			(xy 139.350496 -233.144314) (xy 139.669024 -233.144314) (xy 139.672984 -233.09526) (xy 139.684761 -233.047476)
			(xy 139.704052 -233.0022) (xy 139.730355 -232.960604) (xy 139.76299 -232.923767) (xy 139.801111 -232.892642)
			(xy 139.843732 -232.868035) (xy 139.889748 -232.850583) (xy 139.937967 -232.840739) (xy 139.987142 -232.838758)
			(xy 140.035997 -232.84469) (xy 140.083268 -232.858382) (xy 140.12773 -232.87948) (xy 140.168233 -232.907436)
			(xy 140.203726 -232.941528) (xy 140.233291 -232.980872) (xy 140.256162 -233.024449) (xy 140.271746 -233.07113)
			(xy 140.279641 -233.119707) (xy 140.280136 -233.144314) (xy 140.598647 -233.144314) (xy 140.602742 -233.093586)
			(xy 140.614921 -233.044172) (xy 140.634869 -232.997352) (xy 140.66207 -232.954338) (xy 140.695818 -232.916244)
			(xy 140.73524 -232.884057) (xy 140.779314 -232.858611) (xy 140.8269 -232.840564) (xy 140.876764 -232.830384)
			(xy 140.927616 -232.828335) (xy 140.978137 -232.834469) (xy 141.027021 -232.848629) (xy 141.073 -232.870446)
			(xy 141.114884 -232.899356) (xy 141.151588 -232.934611) (xy 141.182161 -232.975297) (xy 141.205812 -233.02036)
			(xy 141.221928 -233.068634) (xy 141.230092 -233.118868) (xy 141.230604 -233.144314) (xy 141.548878 -233.144314)
			(xy 141.552838 -233.09526) (xy 141.564615 -233.047476) (xy 141.583906 -233.0022) (xy 141.610209 -232.960604)
			(xy 141.642844 -232.923767) (xy 141.680965 -232.892642) (xy 141.723586 -232.868035) (xy 141.769602 -232.850583)
			(xy 141.817821 -232.840739) (xy 141.866996 -232.838758) (xy 141.915851 -232.84469) (xy 141.963122 -232.858382)
			(xy 142.007584 -232.87948) (xy 142.048087 -232.907436) (xy 142.08358 -232.941528) (xy 142.113145 -232.980872)
			(xy 142.136016 -233.024449) (xy 142.1516 -233.07113) (xy 142.159495 -233.119707) (xy 142.15999 -233.144314)
			(xy 142.478501 -233.144314) (xy 142.482596 -233.093586) (xy 142.494775 -233.044172) (xy 142.514723 -232.997352)
			(xy 142.541924 -232.954338) (xy 142.575672 -232.916244) (xy 142.615094 -232.884057) (xy 142.659168 -232.858611)
			(xy 142.706754 -232.840564) (xy 142.756618 -232.830384) (xy 142.80747 -232.828335) (xy 142.857991 -232.834469)
			(xy 142.906875 -232.848629) (xy 142.952854 -232.870446) (xy 142.994738 -232.899356) (xy 143.031442 -232.934611)
			(xy 143.062015 -232.975297) (xy 143.085666 -233.02036) (xy 143.101782 -233.068634) (xy 143.109946 -233.118868)
			(xy 143.110458 -233.144314) (xy 143.428986 -233.144314) (xy 143.432946 -233.09526) (xy 143.444723 -233.047476)
			(xy 143.464014 -233.0022) (xy 143.490317 -232.960604) (xy 143.522952 -232.923767) (xy 143.561073 -232.892642)
			(xy 143.603694 -232.868035) (xy 143.64971 -232.850583) (xy 143.697929 -232.840739) (xy 143.747104 -232.838758)
			(xy 143.795959 -232.84469) (xy 143.84323 -232.858382) (xy 143.887692 -232.87948) (xy 143.928195 -232.907436)
			(xy 143.963688 -232.941528) (xy 143.993253 -232.980872) (xy 144.016124 -233.024449) (xy 144.031708 -233.07113)
			(xy 144.039603 -233.119707) (xy 144.040098 -233.144314) (xy 144.039603 -233.168921) (xy 144.031708 -233.217498)
			(xy 144.016124 -233.264179) (xy 143.993253 -233.307756) (xy 143.963688 -233.3471) (xy 143.928195 -233.381192)
			(xy 143.887692 -233.409148) (xy 143.84323 -233.430246) (xy 143.795959 -233.443938) (xy 143.747104 -233.44987)
			(xy 143.697929 -233.447889) (xy 143.64971 -233.438045) (xy 143.603694 -233.420593) (xy 143.561073 -233.395986)
			(xy 143.522952 -233.364861) (xy 143.490317 -233.328024) (xy 143.464014 -233.286428) (xy 143.444723 -233.241152)
			(xy 143.432946 -233.193368) (xy 143.428986 -233.144314) (xy 143.110458 -233.144314) (xy 143.109946 -233.16976)
			(xy 143.101782 -233.219994) (xy 143.085666 -233.268268) (xy 143.062015 -233.313331) (xy 143.031442 -233.354017)
			(xy 142.994738 -233.389272) (xy 142.952854 -233.418182) (xy 142.906875 -233.439999) (xy 142.857991 -233.454159)
			(xy 142.80747 -233.460293) (xy 142.756618 -233.458244) (xy 142.706754 -233.448064) (xy 142.659168 -233.430017)
			(xy 142.615094 -233.404571) (xy 142.575672 -233.372384) (xy 142.541924 -233.33429) (xy 142.514723 -233.291276)
			(xy 142.494775 -233.244456) (xy 142.482596 -233.195042) (xy 142.478501 -233.144314) (xy 142.15999 -233.144314)
			(xy 142.159495 -233.168921) (xy 142.1516 -233.217498) (xy 142.136016 -233.264179) (xy 142.113145 -233.307756)
			(xy 142.08358 -233.3471) (xy 142.048087 -233.381192) (xy 142.007584 -233.409148) (xy 141.963122 -233.430246)
			(xy 141.915851 -233.443938) (xy 141.866996 -233.44987) (xy 141.817821 -233.447889) (xy 141.769602 -233.438045)
			(xy 141.723586 -233.420593) (xy 141.680965 -233.395986) (xy 141.642844 -233.364861) (xy 141.610209 -233.328024)
			(xy 141.583906 -233.286428) (xy 141.564615 -233.241152) (xy 141.552838 -233.193368) (xy 141.548878 -233.144314)
			(xy 141.230604 -233.144314) (xy 141.230092 -233.16976) (xy 141.221928 -233.219994) (xy 141.205812 -233.268268)
			(xy 141.182161 -233.313331) (xy 141.151588 -233.354017) (xy 141.114884 -233.389272) (xy 141.073 -233.418182)
			(xy 141.027021 -233.439999) (xy 140.978137 -233.454159) (xy 140.927616 -233.460293) (xy 140.876764 -233.458244)
			(xy 140.8269 -233.448064) (xy 140.779314 -233.430017) (xy 140.73524 -233.404571) (xy 140.695818 -233.372384)
			(xy 140.66207 -233.33429) (xy 140.634869 -233.291276) (xy 140.614921 -233.244456) (xy 140.602742 -233.195042)
			(xy 140.598647 -233.144314) (xy 140.280136 -233.144314) (xy 140.279641 -233.168921) (xy 140.271746 -233.217498)
			(xy 140.256162 -233.264179) (xy 140.233291 -233.307756) (xy 140.203726 -233.3471) (xy 140.168233 -233.381192)
			(xy 140.12773 -233.409148) (xy 140.083268 -233.430246) (xy 140.035997 -233.443938) (xy 139.987142 -233.44987)
			(xy 139.937967 -233.447889) (xy 139.889748 -233.438045) (xy 139.843732 -233.420593) (xy 139.801111 -233.395986)
			(xy 139.76299 -233.364861) (xy 139.730355 -233.328024) (xy 139.704052 -233.286428) (xy 139.684761 -233.241152)
			(xy 139.672984 -233.193368) (xy 139.669024 -233.144314) (xy 139.350496 -233.144314) (xy 139.349984 -233.16976)
			(xy 139.34182 -233.219994) (xy 139.325704 -233.268268) (xy 139.302053 -233.313331) (xy 139.27148 -233.354017)
			(xy 139.234776 -233.389272) (xy 139.192892 -233.418182) (xy 139.146913 -233.439999) (xy 139.098029 -233.454159)
			(xy 139.047508 -233.460293) (xy 138.996656 -233.458244) (xy 138.946792 -233.448064) (xy 138.899206 -233.430017)
			(xy 138.855132 -233.404571) (xy 138.81571 -233.372384) (xy 138.781962 -233.33429) (xy 138.754761 -233.291276)
			(xy 138.734813 -233.244456) (xy 138.722634 -233.195042) (xy 138.718539 -233.144314) (xy 138.410442 -233.144314)
			(xy 138.40993 -233.16976) (xy 138.401766 -233.219994) (xy 138.38565 -233.268268) (xy 138.361999 -233.313331)
			(xy 138.331426 -233.354017) (xy 138.294722 -233.389272) (xy 138.252838 -233.418182) (xy 138.206859 -233.439999)
			(xy 138.157975 -233.454159) (xy 138.107454 -233.460293) (xy 138.056602 -233.458244) (xy 138.006738 -233.448064)
			(xy 137.959152 -233.430017) (xy 137.915078 -233.404571) (xy 137.875656 -233.372384) (xy 137.841908 -233.33429)
			(xy 137.814707 -233.291276) (xy 137.794759 -233.244456) (xy 137.78258 -233.195042) (xy 137.778485 -233.144314)
			(xy 137.459974 -233.144314) (xy 137.459479 -233.168921) (xy 137.451584 -233.217498) (xy 137.436 -233.264179)
			(xy 137.413129 -233.307756) (xy 137.383564 -233.3471) (xy 137.348071 -233.381192) (xy 137.307568 -233.409148)
			(xy 137.263106 -233.430246) (xy 137.215835 -233.443938) (xy 137.16698 -233.44987) (xy 137.117805 -233.447889)
			(xy 137.069586 -233.438045) (xy 137.02357 -233.420593) (xy 136.980949 -233.395986) (xy 136.942828 -233.364861)
			(xy 136.910193 -233.328024) (xy 136.88389 -233.286428) (xy 136.864599 -233.241152) (xy 136.852822 -233.193368)
			(xy 136.848862 -233.144314) (xy 136.530588 -233.144314) (xy 136.530076 -233.16976) (xy 136.521912 -233.219994)
			(xy 136.505796 -233.268268) (xy 136.482145 -233.313331) (xy 136.451572 -233.354017) (xy 136.414868 -233.389272)
			(xy 136.372984 -233.418182) (xy 136.327005 -233.439999) (xy 136.278121 -233.454159) (xy 136.2276 -233.460293)
			(xy 136.176748 -233.458244) (xy 136.126884 -233.448064) (xy 136.079298 -233.430017) (xy 136.035224 -233.404571)
			(xy 135.995802 -233.372384) (xy 135.962054 -233.33429) (xy 135.934853 -233.291276) (xy 135.914905 -233.244456)
			(xy 135.902726 -233.195042) (xy 135.898631 -233.144314) (xy 135.58012 -233.144314) (xy 135.579625 -233.168921)
			(xy 135.57173 -233.217498) (xy 135.556146 -233.264179) (xy 135.533275 -233.307756) (xy 135.50371 -233.3471)
			(xy 135.468217 -233.381192) (xy 135.427714 -233.409148) (xy 135.383252 -233.430246) (xy 135.335981 -233.443938)
			(xy 135.287126 -233.44987) (xy 135.237951 -233.447889) (xy 135.189732 -233.438045) (xy 135.143716 -233.420593)
			(xy 135.101095 -233.395986) (xy 135.062974 -233.364861) (xy 135.030339 -233.328024) (xy 135.004036 -233.286428)
			(xy 134.984745 -233.241152) (xy 134.972968 -233.193368) (xy 134.969008 -233.144314) (xy 134.65048 -233.144314)
			(xy 134.649968 -233.16976) (xy 134.641804 -233.219994) (xy 134.625688 -233.268268) (xy 134.602037 -233.313331)
			(xy 134.571464 -233.354017) (xy 134.53476 -233.389272) (xy 134.492876 -233.418182) (xy 134.446897 -233.439999)
			(xy 134.398013 -233.454159) (xy 134.347492 -233.460293) (xy 134.29664 -233.458244) (xy 134.246776 -233.448064)
			(xy 134.19919 -233.430017) (xy 134.155116 -233.404571) (xy 134.115694 -233.372384) (xy 134.081946 -233.33429)
			(xy 134.054745 -233.291276) (xy 134.034797 -233.244456) (xy 134.022618 -233.195042) (xy 134.018523 -233.144314)
			(xy 133.700012 -233.144314) (xy 133.699517 -233.168921) (xy 133.691622 -233.217498) (xy 133.676038 -233.264179)
			(xy 133.653167 -233.307756) (xy 133.623602 -233.3471) (xy 133.588109 -233.381192) (xy 133.547606 -233.409148)
			(xy 133.503144 -233.430246) (xy 133.455873 -233.443938) (xy 133.407018 -233.44987) (xy 133.357843 -233.447889)
			(xy 133.309624 -233.438045) (xy 133.263608 -233.420593) (xy 133.220987 -233.395986) (xy 133.182866 -233.364861)
			(xy 133.150231 -233.328024) (xy 133.123928 -233.286428) (xy 133.104637 -233.241152) (xy 133.09286 -233.193368)
			(xy 133.0889 -233.144314) (xy 132.770372 -233.144314) (xy 132.76986 -233.16976) (xy 132.761696 -233.219994)
			(xy 132.74558 -233.268268) (xy 132.721929 -233.313331) (xy 132.691356 -233.354017) (xy 132.654652 -233.389272)
			(xy 132.612768 -233.418182) (xy 132.566789 -233.439999) (xy 132.517905 -233.454159) (xy 132.467384 -233.460293)
			(xy 132.416532 -233.458244) (xy 132.366668 -233.448064) (xy 132.319082 -233.430017) (xy 132.275008 -233.404571)
			(xy 132.235586 -233.372384) (xy 132.201838 -233.33429) (xy 132.174637 -233.291276) (xy 132.154689 -233.244456)
			(xy 132.14251 -233.195042) (xy 132.138415 -233.144314) (xy 131.830572 -233.144314) (xy 131.83006 -233.16976)
			(xy 131.821896 -233.219994) (xy 131.80578 -233.268268) (xy 131.782129 -233.313331) (xy 131.751556 -233.354017)
			(xy 131.714852 -233.389272) (xy 131.672968 -233.418182) (xy 131.626989 -233.439999) (xy 131.578105 -233.454159)
			(xy 131.527584 -233.460293) (xy 131.476732 -233.458244) (xy 131.426868 -233.448064) (xy 131.379282 -233.430017)
			(xy 131.335208 -233.404571) (xy 131.295786 -233.372384) (xy 131.262038 -233.33429) (xy 131.234837 -233.291276)
			(xy 131.214889 -233.244456) (xy 131.20271 -233.195042) (xy 131.198615 -233.144314) (xy 130.880104 -233.144314)
			(xy 130.879609 -233.168921) (xy 130.871714 -233.217498) (xy 130.85613 -233.264179) (xy 130.833259 -233.307756)
			(xy 130.803694 -233.3471) (xy 130.768201 -233.381192) (xy 130.727698 -233.409148) (xy 130.683236 -233.430246)
			(xy 130.635965 -233.443938) (xy 130.58711 -233.44987) (xy 130.537935 -233.447889) (xy 130.489716 -233.438045)
			(xy 130.4437 -233.420593) (xy 130.401079 -233.395986) (xy 130.362958 -233.364861) (xy 130.330323 -233.328024)
			(xy 130.30402 -233.286428) (xy 130.284729 -233.241152) (xy 130.272952 -233.193368) (xy 130.268992 -233.144314)
			(xy 129.950464 -233.144314) (xy 129.949952 -233.16976) (xy 129.941788 -233.219994) (xy 129.925672 -233.268268)
			(xy 129.902021 -233.313331) (xy 129.871448 -233.354017) (xy 129.834744 -233.389272) (xy 129.79286 -233.418182)
			(xy 129.746881 -233.439999) (xy 129.697997 -233.454159) (xy 129.647476 -233.460293) (xy 129.596624 -233.458244)
			(xy 129.54676 -233.448064) (xy 129.499174 -233.430017) (xy 129.4551 -233.404571) (xy 129.415678 -233.372384)
			(xy 129.38193 -233.33429) (xy 129.354729 -233.291276) (xy 129.334781 -233.244456) (xy 129.322602 -233.195042)
			(xy 129.318507 -233.144314) (xy 128.999996 -233.144314) (xy 128.999501 -233.168921) (xy 128.991606 -233.217498)
			(xy 128.976022 -233.264179) (xy 128.953151 -233.307756) (xy 128.923586 -233.3471) (xy 128.888093 -233.381192)
			(xy 128.84759 -233.409148) (xy 128.803128 -233.430246) (xy 128.755857 -233.443938) (xy 128.707002 -233.44987)
			(xy 128.657827 -233.447889) (xy 128.609608 -233.438045) (xy 128.563592 -233.420593) (xy 128.520971 -233.395986)
			(xy 128.48285 -233.364861) (xy 128.450215 -233.328024) (xy 128.423912 -233.286428) (xy 128.404621 -233.241152)
			(xy 128.392844 -233.193368) (xy 128.388884 -233.144314) (xy 128.069821 -233.144314) (xy 128.069821 -233.169107)
			(xy 128.062061 -233.21811) (xy 128.04673 -233.265295) (xy 128.024208 -233.309502) (xy 127.995047 -233.349641)
			(xy 127.959967 -233.384725) (xy 127.919831 -233.41389) (xy 127.875627 -233.436417) (xy 127.828443 -233.451753)
			(xy 127.779441 -233.459519) (xy 127.754634 -233.460036) (xy 127.732952 -233.459637) (xy 127.690002 -233.453642)
			(xy 127.669036 -233.448098) (xy 127.662432 -233.446066) (xy 127.65532 -233.446066) (xy 127.645307 -233.44655)
			(xy 127.626803 -233.454205) (xy 127.612635 -233.468357) (xy 127.604961 -233.486854) (xy 127.60452 -233.496866)
			(xy 127.60452 -233.515154) (xy 127.607314 -233.523028) (xy 127.622678 -233.569352) (xy 127.647397 -233.663777)
			(xy 127.665148 -233.759757) (xy 127.675836 -233.856777) (xy 127.679404 -233.954319) (xy 127.679404 -233.95432)
			(xy 127.908553 -233.95432) (xy 127.912648 -233.903592) (xy 127.924827 -233.854178) (xy 127.944775 -233.807358)
			(xy 127.971976 -233.764344) (xy 128.005724 -233.72625) (xy 128.045146 -233.694063) (xy 128.08922 -233.668617)
			(xy 128.136806 -233.65057) (xy 128.18667 -233.64039) (xy 128.237522 -233.638341) (xy 128.288043 -233.644475)
			(xy 128.336927 -233.658635) (xy 128.382906 -233.680452) (xy 128.42479 -233.709362) (xy 128.461494 -233.744617)
			(xy 128.492067 -233.785303) (xy 128.515718 -233.830366) (xy 128.531834 -233.87864) (xy 128.539998 -233.928874)
			(xy 128.54051 -233.95432) (xy 128.848607 -233.95432) (xy 128.852702 -233.903592) (xy 128.864881 -233.854178)
			(xy 128.884829 -233.807358) (xy 128.91203 -233.764344) (xy 128.945778 -233.72625) (xy 128.9852 -233.694063)
			(xy 129.029274 -233.668617) (xy 129.07686 -233.65057) (xy 129.126724 -233.64039) (xy 129.177576 -233.638341)
			(xy 129.228097 -233.644475) (xy 129.276981 -233.658635) (xy 129.32296 -233.680452) (xy 129.364844 -233.709362)
			(xy 129.401548 -233.744617) (xy 129.432121 -233.785303) (xy 129.455772 -233.830366) (xy 129.471888 -233.87864)
			(xy 129.480052 -233.928874) (xy 129.480564 -233.95432) (xy 129.798838 -233.95432) (xy 129.802798 -233.905266)
			(xy 129.814575 -233.857482) (xy 129.833866 -233.812206) (xy 129.860169 -233.77061) (xy 129.892804 -233.733773)
			(xy 129.930925 -233.702648) (xy 129.973546 -233.678041) (xy 130.019562 -233.660589) (xy 130.067781 -233.650745)
			(xy 130.116956 -233.648764) (xy 130.165811 -233.654696) (xy 130.213082 -233.668388) (xy 130.257544 -233.689486)
			(xy 130.298047 -233.717442) (xy 130.33354 -233.751534) (xy 130.363105 -233.790878) (xy 130.385976 -233.834455)
			(xy 130.40156 -233.881136) (xy 130.409455 -233.929713) (xy 130.40995 -233.95432) (xy 130.728461 -233.95432)
			(xy 130.732556 -233.903592) (xy 130.744735 -233.854178) (xy 130.764683 -233.807358) (xy 130.791884 -233.764344)
			(xy 130.825632 -233.72625) (xy 130.865054 -233.694063) (xy 130.909128 -233.668617) (xy 130.956714 -233.65057)
			(xy 131.006578 -233.64039) (xy 131.05743 -233.638341) (xy 131.107951 -233.644475) (xy 131.156835 -233.658635)
			(xy 131.202814 -233.680452) (xy 131.244698 -233.709362) (xy 131.281402 -233.744617) (xy 131.311975 -233.785303)
			(xy 131.335626 -233.830366) (xy 131.351742 -233.87864) (xy 131.359906 -233.928874) (xy 131.360418 -233.95432)
			(xy 131.678946 -233.95432) (xy 131.682906 -233.905266) (xy 131.694683 -233.857482) (xy 131.713974 -233.812206)
			(xy 131.740277 -233.77061) (xy 131.772912 -233.733773) (xy 131.811033 -233.702648) (xy 131.853654 -233.678041)
			(xy 131.89967 -233.660589) (xy 131.947889 -233.650745) (xy 131.997064 -233.648764) (xy 132.045919 -233.654696)
			(xy 132.09319 -233.668388) (xy 132.137652 -233.689486) (xy 132.178155 -233.717442) (xy 132.213648 -233.751534)
			(xy 132.243213 -233.790878) (xy 132.266084 -233.834455) (xy 132.281668 -233.881136) (xy 132.289563 -233.929713)
			(xy 132.290058 -233.95432) (xy 132.608569 -233.95432) (xy 132.612664 -233.903592) (xy 132.624843 -233.854178)
			(xy 132.644791 -233.807358) (xy 132.671992 -233.764344) (xy 132.70574 -233.72625) (xy 132.745162 -233.694063)
			(xy 132.789236 -233.668617) (xy 132.836822 -233.65057) (xy 132.886686 -233.64039) (xy 132.937538 -233.638341)
			(xy 132.988059 -233.644475) (xy 133.036943 -233.658635) (xy 133.082922 -233.680452) (xy 133.124806 -233.709362)
			(xy 133.16151 -233.744617) (xy 133.192083 -233.785303) (xy 133.215734 -233.830366) (xy 133.23185 -233.87864)
			(xy 133.240014 -233.928874) (xy 133.240526 -233.95432) (xy 133.559054 -233.95432) (xy 133.563014 -233.905266)
			(xy 133.574791 -233.857482) (xy 133.594082 -233.812206) (xy 133.620385 -233.77061) (xy 133.65302 -233.733773)
			(xy 133.691141 -233.702648) (xy 133.733762 -233.678041) (xy 133.779778 -233.660589) (xy 133.827997 -233.650745)
			(xy 133.877172 -233.648764) (xy 133.926027 -233.654696) (xy 133.973298 -233.668388) (xy 134.01776 -233.689486)
			(xy 134.058263 -233.717442) (xy 134.093756 -233.751534) (xy 134.123321 -233.790878) (xy 134.146192 -233.834455)
			(xy 134.161776 -233.881136) (xy 134.169671 -233.929713) (xy 134.170166 -233.95432) (xy 134.488423 -233.95432)
			(xy 134.492518 -233.903592) (xy 134.504697 -233.854178) (xy 134.524645 -233.807358) (xy 134.551846 -233.764344)
			(xy 134.585594 -233.72625) (xy 134.625016 -233.694063) (xy 134.66909 -233.668617) (xy 134.716676 -233.65057)
			(xy 134.76654 -233.64039) (xy 134.817392 -233.638341) (xy 134.867913 -233.644475) (xy 134.916797 -233.658635)
			(xy 134.962776 -233.680452) (xy 135.00466 -233.709362) (xy 135.041364 -233.744617) (xy 135.071937 -233.785303)
			(xy 135.095588 -233.830366) (xy 135.111704 -233.87864) (xy 135.119868 -233.928874) (xy 135.12038 -233.95432)
			(xy 135.428477 -233.95432) (xy 135.432572 -233.903592) (xy 135.444751 -233.854178) (xy 135.464699 -233.807358)
			(xy 135.4919 -233.764344) (xy 135.525648 -233.72625) (xy 135.56507 -233.694063) (xy 135.609144 -233.668617)
			(xy 135.65673 -233.65057) (xy 135.706594 -233.64039) (xy 135.757446 -233.638341) (xy 135.807967 -233.644475)
			(xy 135.856851 -233.658635) (xy 135.90283 -233.680452) (xy 135.944714 -233.709362) (xy 135.981418 -233.744617)
			(xy 136.011991 -233.785303) (xy 136.035642 -233.830366) (xy 136.051758 -233.87864) (xy 136.059922 -233.928874)
			(xy 136.060434 -233.95432) (xy 136.378962 -233.95432) (xy 136.382922 -233.905266) (xy 136.394699 -233.857482)
			(xy 136.41399 -233.812206) (xy 136.440293 -233.77061) (xy 136.472928 -233.733773) (xy 136.511049 -233.702648)
			(xy 136.55367 -233.678041) (xy 136.599686 -233.660589) (xy 136.647905 -233.650745) (xy 136.69708 -233.648764)
			(xy 136.745935 -233.654696) (xy 136.793206 -233.668388) (xy 136.837668 -233.689486) (xy 136.878171 -233.717442)
			(xy 136.913664 -233.751534) (xy 136.943229 -233.790878) (xy 136.9661 -233.834455) (xy 136.981684 -233.881136)
			(xy 136.989579 -233.929713) (xy 136.990074 -233.95432) (xy 137.308585 -233.95432) (xy 137.31268 -233.903592)
			(xy 137.324859 -233.854178) (xy 137.344807 -233.807358) (xy 137.372008 -233.764344) (xy 137.405756 -233.72625)
			(xy 137.445178 -233.694063) (xy 137.489252 -233.668617) (xy 137.536838 -233.65057) (xy 137.586702 -233.64039)
			(xy 137.637554 -233.638341) (xy 137.688075 -233.644475) (xy 137.736959 -233.658635) (xy 137.782938 -233.680452)
			(xy 137.824822 -233.709362) (xy 137.861526 -233.744617) (xy 137.892099 -233.785303) (xy 137.91575 -233.830366)
			(xy 137.931866 -233.87864) (xy 137.94003 -233.928874) (xy 137.940542 -233.95432) (xy 138.25907 -233.95432)
			(xy 138.26303 -233.905266) (xy 138.274807 -233.857482) (xy 138.294098 -233.812206) (xy 138.320401 -233.77061)
			(xy 138.353036 -233.733773) (xy 138.391157 -233.702648) (xy 138.433778 -233.678041) (xy 138.479794 -233.660589)
			(xy 138.528013 -233.650745) (xy 138.577188 -233.648764) (xy 138.626043 -233.654696) (xy 138.673314 -233.668388)
			(xy 138.717776 -233.689486) (xy 138.758279 -233.717442) (xy 138.793772 -233.751534) (xy 138.823337 -233.790878)
			(xy 138.846208 -233.834455) (xy 138.861792 -233.881136) (xy 138.869687 -233.929713) (xy 138.870182 -233.95432)
			(xy 139.188439 -233.95432) (xy 139.192534 -233.903592) (xy 139.204713 -233.854178) (xy 139.224661 -233.807358)
			(xy 139.251862 -233.764344) (xy 139.28561 -233.72625) (xy 139.325032 -233.694063) (xy 139.369106 -233.668617)
			(xy 139.416692 -233.65057) (xy 139.466556 -233.64039) (xy 139.517408 -233.638341) (xy 139.567929 -233.644475)
			(xy 139.616813 -233.658635) (xy 139.662792 -233.680452) (xy 139.704676 -233.709362) (xy 139.74138 -233.744617)
			(xy 139.771953 -233.785303) (xy 139.795604 -233.830366) (xy 139.81172 -233.87864) (xy 139.819884 -233.928874)
			(xy 139.820396 -233.95432) (xy 140.138924 -233.95432) (xy 140.142884 -233.905266) (xy 140.154661 -233.857482)
			(xy 140.173952 -233.812206) (xy 140.200255 -233.77061) (xy 140.23289 -233.733773) (xy 140.271011 -233.702648)
			(xy 140.313632 -233.678041) (xy 140.359648 -233.660589) (xy 140.407867 -233.650745) (xy 140.457042 -233.648764)
			(xy 140.505897 -233.654696) (xy 140.553168 -233.668388) (xy 140.59763 -233.689486) (xy 140.638133 -233.717442)
			(xy 140.673626 -233.751534) (xy 140.703191 -233.790878) (xy 140.726062 -233.834455) (xy 140.741646 -233.881136)
			(xy 140.749541 -233.929713) (xy 140.750036 -233.95432) (xy 141.068547 -233.95432) (xy 141.072642 -233.903592)
			(xy 141.084821 -233.854178) (xy 141.104769 -233.807358) (xy 141.13197 -233.764344) (xy 141.165718 -233.72625)
			(xy 141.20514 -233.694063) (xy 141.249214 -233.668617) (xy 141.2968 -233.65057) (xy 141.346664 -233.64039)
			(xy 141.397516 -233.638341) (xy 141.448037 -233.644475) (xy 141.496921 -233.658635) (xy 141.5429 -233.680452)
			(xy 141.584784 -233.709362) (xy 141.621488 -233.744617) (xy 141.652061 -233.785303) (xy 141.675712 -233.830366)
			(xy 141.691828 -233.87864) (xy 141.699992 -233.928874) (xy 141.700504 -233.95432) (xy 142.008601 -233.95432)
			(xy 142.012696 -233.903592) (xy 142.024875 -233.854178) (xy 142.044823 -233.807358) (xy 142.072024 -233.764344)
			(xy 142.105772 -233.72625) (xy 142.145194 -233.694063) (xy 142.189268 -233.668617) (xy 142.236854 -233.65057)
			(xy 142.286718 -233.64039) (xy 142.33757 -233.638341) (xy 142.388091 -233.644475) (xy 142.436975 -233.658635)
			(xy 142.482954 -233.680452) (xy 142.524838 -233.709362) (xy 142.561542 -233.744617) (xy 142.592115 -233.785303)
			(xy 142.615766 -233.830366) (xy 142.631882 -233.87864) (xy 142.640046 -233.928874) (xy 142.640558 -233.95432)
			(xy 142.958832 -233.95432) (xy 142.962792 -233.905266) (xy 142.974569 -233.857482) (xy 142.99386 -233.812206)
			(xy 143.020163 -233.77061) (xy 143.052798 -233.733773) (xy 143.090919 -233.702648) (xy 143.13354 -233.678041)
			(xy 143.179556 -233.660589) (xy 143.227775 -233.650745) (xy 143.27695 -233.648764) (xy 143.325805 -233.654696)
			(xy 143.373076 -233.668388) (xy 143.417538 -233.689486) (xy 143.458041 -233.717442) (xy 143.493534 -233.751534)
			(xy 143.523099 -233.790878) (xy 143.54597 -233.834455) (xy 143.561554 -233.881136) (xy 143.569449 -233.929713)
			(xy 143.569944 -233.95432) (xy 144.83894 -233.95432) (xy 144.8429 -233.905266) (xy 144.854677 -233.857482)
			(xy 144.873968 -233.812206) (xy 144.900271 -233.77061) (xy 144.932906 -233.733773) (xy 144.971027 -233.702648)
			(xy 145.013648 -233.678041) (xy 145.059664 -233.660589) (xy 145.107883 -233.650745) (xy 145.157058 -233.648764)
			(xy 145.205913 -233.654696) (xy 145.253184 -233.668388) (xy 145.297646 -233.689486) (xy 145.338149 -233.717442)
			(xy 145.373642 -233.751534) (xy 145.403207 -233.790878) (xy 145.426078 -233.834455) (xy 145.441662 -233.881136)
			(xy 145.449557 -233.929713) (xy 145.450052 -233.95432) (xy 145.449557 -233.978927) (xy 145.441662 -234.027504)
			(xy 145.426078 -234.074185) (xy 145.403207 -234.117762) (xy 145.373642 -234.157106) (xy 145.338149 -234.191198)
			(xy 145.297646 -234.219154) (xy 145.253184 -234.240252) (xy 145.205913 -234.253944) (xy 145.157058 -234.259876)
			(xy 145.107883 -234.257895) (xy 145.059664 -234.248051) (xy 145.013648 -234.230599) (xy 144.971027 -234.205992)
			(xy 144.932906 -234.174867) (xy 144.900271 -234.13803) (xy 144.873968 -234.096434) (xy 144.854677 -234.051158)
			(xy 144.8429 -234.003374) (xy 144.83894 -233.95432) (xy 143.569944 -233.95432) (xy 143.569449 -233.978927)
			(xy 143.561554 -234.027504) (xy 143.54597 -234.074185) (xy 143.523099 -234.117762) (xy 143.493534 -234.157106)
			(xy 143.458041 -234.191198) (xy 143.417538 -234.219154) (xy 143.373076 -234.240252) (xy 143.325805 -234.253944)
			(xy 143.27695 -234.259876) (xy 143.227775 -234.257895) (xy 143.179556 -234.248051) (xy 143.13354 -234.230599)
			(xy 143.090919 -234.205992) (xy 143.052798 -234.174867) (xy 143.020163 -234.13803) (xy 142.99386 -234.096434)
			(xy 142.974569 -234.051158) (xy 142.962792 -234.003374) (xy 142.958832 -233.95432) (xy 142.640558 -233.95432)
			(xy 142.640046 -233.979766) (xy 142.631882 -234.03) (xy 142.615766 -234.078274) (xy 142.592115 -234.123337)
			(xy 142.561542 -234.164023) (xy 142.524838 -234.199278) (xy 142.482954 -234.228188) (xy 142.436975 -234.250005)
			(xy 142.388091 -234.264165) (xy 142.33757 -234.270299) (xy 142.286718 -234.26825) (xy 142.236854 -234.25807)
			(xy 142.189268 -234.240023) (xy 142.145194 -234.214577) (xy 142.105772 -234.18239) (xy 142.072024 -234.144296)
			(xy 142.044823 -234.101282) (xy 142.024875 -234.054462) (xy 142.012696 -234.005048) (xy 142.008601 -233.95432)
			(xy 141.700504 -233.95432) (xy 141.699992 -233.979766) (xy 141.691828 -234.03) (xy 141.675712 -234.078274)
			(xy 141.652061 -234.123337) (xy 141.621488 -234.164023) (xy 141.584784 -234.199278) (xy 141.5429 -234.228188)
			(xy 141.496921 -234.250005) (xy 141.448037 -234.264165) (xy 141.397516 -234.270299) (xy 141.346664 -234.26825)
			(xy 141.2968 -234.25807) (xy 141.249214 -234.240023) (xy 141.20514 -234.214577) (xy 141.165718 -234.18239)
			(xy 141.13197 -234.144296) (xy 141.104769 -234.101282) (xy 141.084821 -234.054462) (xy 141.072642 -234.005048)
			(xy 141.068547 -233.95432) (xy 140.750036 -233.95432) (xy 140.749541 -233.978927) (xy 140.741646 -234.027504)
			(xy 140.726062 -234.074185) (xy 140.703191 -234.117762) (xy 140.673626 -234.157106) (xy 140.638133 -234.191198)
			(xy 140.59763 -234.219154) (xy 140.553168 -234.240252) (xy 140.505897 -234.253944) (xy 140.457042 -234.259876)
			(xy 140.407867 -234.257895) (xy 140.359648 -234.248051) (xy 140.313632 -234.230599) (xy 140.271011 -234.205992)
			(xy 140.23289 -234.174867) (xy 140.200255 -234.13803) (xy 140.173952 -234.096434) (xy 140.154661 -234.051158)
			(xy 140.142884 -234.003374) (xy 140.138924 -233.95432) (xy 139.820396 -233.95432) (xy 139.819884 -233.979766)
			(xy 139.81172 -234.03) (xy 139.795604 -234.078274) (xy 139.771953 -234.123337) (xy 139.74138 -234.164023)
			(xy 139.704676 -234.199278) (xy 139.662792 -234.228188) (xy 139.616813 -234.250005) (xy 139.567929 -234.264165)
			(xy 139.517408 -234.270299) (xy 139.466556 -234.26825) (xy 139.416692 -234.25807) (xy 139.369106 -234.240023)
			(xy 139.325032 -234.214577) (xy 139.28561 -234.18239) (xy 139.251862 -234.144296) (xy 139.224661 -234.101282)
			(xy 139.204713 -234.054462) (xy 139.192534 -234.005048) (xy 139.188439 -233.95432) (xy 138.870182 -233.95432)
			(xy 138.869687 -233.978927) (xy 138.861792 -234.027504) (xy 138.846208 -234.074185) (xy 138.823337 -234.117762)
			(xy 138.793772 -234.157106) (xy 138.758279 -234.191198) (xy 138.717776 -234.219154) (xy 138.673314 -234.240252)
			(xy 138.626043 -234.253944) (xy 138.577188 -234.259876) (xy 138.528013 -234.257895) (xy 138.479794 -234.248051)
			(xy 138.433778 -234.230599) (xy 138.391157 -234.205992) (xy 138.353036 -234.174867) (xy 138.320401 -234.13803)
			(xy 138.294098 -234.096434) (xy 138.274807 -234.051158) (xy 138.26303 -234.003374) (xy 138.25907 -233.95432)
			(xy 137.940542 -233.95432) (xy 137.94003 -233.979766) (xy 137.931866 -234.03) (xy 137.91575 -234.078274)
			(xy 137.892099 -234.123337) (xy 137.861526 -234.164023) (xy 137.824822 -234.199278) (xy 137.782938 -234.228188)
			(xy 137.736959 -234.250005) (xy 137.688075 -234.264165) (xy 137.637554 -234.270299) (xy 137.586702 -234.26825)
			(xy 137.536838 -234.25807) (xy 137.489252 -234.240023) (xy 137.445178 -234.214577) (xy 137.405756 -234.18239)
			(xy 137.372008 -234.144296) (xy 137.344807 -234.101282) (xy 137.324859 -234.054462) (xy 137.31268 -234.005048)
			(xy 137.308585 -233.95432) (xy 136.990074 -233.95432) (xy 136.989579 -233.978927) (xy 136.981684 -234.027504)
			(xy 136.9661 -234.074185) (xy 136.943229 -234.117762) (xy 136.913664 -234.157106) (xy 136.878171 -234.191198)
			(xy 136.837668 -234.219154) (xy 136.793206 -234.240252) (xy 136.745935 -234.253944) (xy 136.69708 -234.259876)
			(xy 136.647905 -234.257895) (xy 136.599686 -234.248051) (xy 136.55367 -234.230599) (xy 136.511049 -234.205992)
			(xy 136.472928 -234.174867) (xy 136.440293 -234.13803) (xy 136.41399 -234.096434) (xy 136.394699 -234.051158)
			(xy 136.382922 -234.003374) (xy 136.378962 -233.95432) (xy 136.060434 -233.95432) (xy 136.059922 -233.979766)
			(xy 136.051758 -234.03) (xy 136.035642 -234.078274) (xy 136.011991 -234.123337) (xy 135.981418 -234.164023)
			(xy 135.944714 -234.199278) (xy 135.90283 -234.228188) (xy 135.856851 -234.250005) (xy 135.807967 -234.264165)
			(xy 135.757446 -234.270299) (xy 135.706594 -234.26825) (xy 135.65673 -234.25807) (xy 135.609144 -234.240023)
			(xy 135.56507 -234.214577) (xy 135.525648 -234.18239) (xy 135.4919 -234.144296) (xy 135.464699 -234.101282)
			(xy 135.444751 -234.054462) (xy 135.432572 -234.005048) (xy 135.428477 -233.95432) (xy 135.12038 -233.95432)
			(xy 135.119868 -233.979766) (xy 135.111704 -234.03) (xy 135.095588 -234.078274) (xy 135.071937 -234.123337)
			(xy 135.041364 -234.164023) (xy 135.00466 -234.199278) (xy 134.962776 -234.228188) (xy 134.916797 -234.250005)
			(xy 134.867913 -234.264165) (xy 134.817392 -234.270299) (xy 134.76654 -234.26825) (xy 134.716676 -234.25807)
			(xy 134.66909 -234.240023) (xy 134.625016 -234.214577) (xy 134.585594 -234.18239) (xy 134.551846 -234.144296)
			(xy 134.524645 -234.101282) (xy 134.504697 -234.054462) (xy 134.492518 -234.005048) (xy 134.488423 -233.95432)
			(xy 134.170166 -233.95432) (xy 134.169671 -233.978927) (xy 134.161776 -234.027504) (xy 134.146192 -234.074185)
			(xy 134.123321 -234.117762) (xy 134.093756 -234.157106) (xy 134.058263 -234.191198) (xy 134.01776 -234.219154)
			(xy 133.973298 -234.240252) (xy 133.926027 -234.253944) (xy 133.877172 -234.259876) (xy 133.827997 -234.257895)
			(xy 133.779778 -234.248051) (xy 133.733762 -234.230599) (xy 133.691141 -234.205992) (xy 133.65302 -234.174867)
			(xy 133.620385 -234.13803) (xy 133.594082 -234.096434) (xy 133.574791 -234.051158) (xy 133.563014 -234.003374)
			(xy 133.559054 -233.95432) (xy 133.240526 -233.95432) (xy 133.240014 -233.979766) (xy 133.23185 -234.03)
			(xy 133.215734 -234.078274) (xy 133.192083 -234.123337) (xy 133.16151 -234.164023) (xy 133.124806 -234.199278)
			(xy 133.082922 -234.228188) (xy 133.036943 -234.250005) (xy 132.988059 -234.264165) (xy 132.937538 -234.270299)
			(xy 132.886686 -234.26825) (xy 132.836822 -234.25807) (xy 132.789236 -234.240023) (xy 132.745162 -234.214577)
			(xy 132.70574 -234.18239) (xy 132.671992 -234.144296) (xy 132.644791 -234.101282) (xy 132.624843 -234.054462)
			(xy 132.612664 -234.005048) (xy 132.608569 -233.95432) (xy 132.290058 -233.95432) (xy 132.289563 -233.978927)
			(xy 132.281668 -234.027504) (xy 132.266084 -234.074185) (xy 132.243213 -234.117762) (xy 132.213648 -234.157106)
			(xy 132.178155 -234.191198) (xy 132.137652 -234.219154) (xy 132.09319 -234.240252) (xy 132.045919 -234.253944)
			(xy 131.997064 -234.259876) (xy 131.947889 -234.257895) (xy 131.89967 -234.248051) (xy 131.853654 -234.230599)
			(xy 131.811033 -234.205992) (xy 131.772912 -234.174867) (xy 131.740277 -234.13803) (xy 131.713974 -234.096434)
			(xy 131.694683 -234.051158) (xy 131.682906 -234.003374) (xy 131.678946 -233.95432) (xy 131.360418 -233.95432)
			(xy 131.359906 -233.979766) (xy 131.351742 -234.03) (xy 131.335626 -234.078274) (xy 131.311975 -234.123337)
			(xy 131.281402 -234.164023) (xy 131.244698 -234.199278) (xy 131.202814 -234.228188) (xy 131.156835 -234.250005)
			(xy 131.107951 -234.264165) (xy 131.05743 -234.270299) (xy 131.006578 -234.26825) (xy 130.956714 -234.25807)
			(xy 130.909128 -234.240023) (xy 130.865054 -234.214577) (xy 130.825632 -234.18239) (xy 130.791884 -234.144296)
			(xy 130.764683 -234.101282) (xy 130.744735 -234.054462) (xy 130.732556 -234.005048) (xy 130.728461 -233.95432)
			(xy 130.40995 -233.95432) (xy 130.409455 -233.978927) (xy 130.40156 -234.027504) (xy 130.385976 -234.074185)
			(xy 130.363105 -234.117762) (xy 130.33354 -234.157106) (xy 130.298047 -234.191198) (xy 130.257544 -234.219154)
			(xy 130.213082 -234.240252) (xy 130.165811 -234.253944) (xy 130.116956 -234.259876) (xy 130.067781 -234.257895)
			(xy 130.019562 -234.248051) (xy 129.973546 -234.230599) (xy 129.930925 -234.205992) (xy 129.892804 -234.174867)
			(xy 129.860169 -234.13803) (xy 129.833866 -234.096434) (xy 129.814575 -234.051158) (xy 129.802798 -234.003374)
			(xy 129.798838 -233.95432) (xy 129.480564 -233.95432) (xy 129.480052 -233.979766) (xy 129.471888 -234.03)
			(xy 129.455772 -234.078274) (xy 129.432121 -234.123337) (xy 129.401548 -234.164023) (xy 129.364844 -234.199278)
			(xy 129.32296 -234.228188) (xy 129.276981 -234.250005) (xy 129.228097 -234.264165) (xy 129.177576 -234.270299)
			(xy 129.126724 -234.26825) (xy 129.07686 -234.25807) (xy 129.029274 -234.240023) (xy 128.9852 -234.214577)
			(xy 128.945778 -234.18239) (xy 128.91203 -234.144296) (xy 128.884829 -234.101282) (xy 128.864881 -234.054462)
			(xy 128.852702 -234.005048) (xy 128.848607 -233.95432) (xy 128.54051 -233.95432) (xy 128.539998 -233.979766)
			(xy 128.531834 -234.03) (xy 128.515718 -234.078274) (xy 128.492067 -234.123337) (xy 128.461494 -234.164023)
			(xy 128.42479 -234.199278) (xy 128.382906 -234.228188) (xy 128.336927 -234.250005) (xy 128.288043 -234.264165)
			(xy 128.237522 -234.270299) (xy 128.18667 -234.26825) (xy 128.136806 -234.25807) (xy 128.08922 -234.240023)
			(xy 128.045146 -234.214577) (xy 128.005724 -234.18239) (xy 127.971976 -234.144296) (xy 127.944775 -234.101282)
			(xy 127.924827 -234.054462) (xy 127.912648 -234.005048) (xy 127.908553 -233.95432) (xy 127.679404 -233.95432)
			(xy 127.675833 -234.051861) (xy 127.665142 -234.148881) (xy 127.647389 -234.24486) (xy 127.622667 -234.339284)
			(xy 127.607314 -234.385612) (xy 127.60452 -234.393486) (xy 127.60452 -234.411774) (xy 127.604936 -234.421797)
			(xy 127.612602 -234.44032) (xy 127.626775 -234.454495) (xy 127.645297 -234.462163) (xy 127.65532 -234.462574)
			(xy 127.662432 -234.462574) (xy 127.669036 -234.460542) (xy 127.689996 -234.454974) (xy 127.73295 -234.448986)
			(xy 127.754634 -234.448604) (xy 127.77944 -234.449093) (xy 127.82844 -234.456859) (xy 127.875622 -234.472194)
			(xy 127.919825 -234.49472) (xy 127.959959 -234.523884) (xy 127.995038 -234.558967) (xy 128.024197 -234.599104)
			(xy 128.046719 -234.643309) (xy 128.062049 -234.690493) (xy 128.069809 -234.739494) (xy 128.069809 -234.764326)
			(xy 128.388884 -234.764326) (xy 128.392844 -234.715272) (xy 128.404621 -234.667488) (xy 128.423912 -234.622212)
			(xy 128.450215 -234.580616) (xy 128.48285 -234.543779) (xy 128.520971 -234.512654) (xy 128.563592 -234.488047)
			(xy 128.609608 -234.470595) (xy 128.657827 -234.460751) (xy 128.707002 -234.45877) (xy 128.755857 -234.464702)
			(xy 128.803128 -234.478394) (xy 128.84759 -234.499492) (xy 128.888093 -234.527448) (xy 128.923586 -234.56154)
			(xy 128.953151 -234.600884) (xy 128.976022 -234.644461) (xy 128.991606 -234.691142) (xy 128.999501 -234.739719)
			(xy 128.999996 -234.764326) (xy 129.318507 -234.764326) (xy 129.322602 -234.713598) (xy 129.334781 -234.664184)
			(xy 129.354729 -234.617364) (xy 129.38193 -234.57435) (xy 129.415678 -234.536256) (xy 129.4551 -234.504069)
			(xy 129.499174 -234.478623) (xy 129.54676 -234.460576) (xy 129.596624 -234.450396) (xy 129.647476 -234.448347)
			(xy 129.697997 -234.454481) (xy 129.746881 -234.468641) (xy 129.79286 -234.490458) (xy 129.834744 -234.519368)
			(xy 129.871448 -234.554623) (xy 129.902021 -234.595309) (xy 129.925672 -234.640372) (xy 129.941788 -234.688646)
			(xy 129.949952 -234.73888) (xy 129.950464 -234.764326) (xy 131.198615 -234.764326) (xy 131.20271 -234.713598)
			(xy 131.214889 -234.664184) (xy 131.234837 -234.617364) (xy 131.262038 -234.57435) (xy 131.295786 -234.536256)
			(xy 131.335208 -234.504069) (xy 131.379282 -234.478623) (xy 131.426868 -234.460576) (xy 131.476732 -234.450396)
			(xy 131.527584 -234.448347) (xy 131.578105 -234.454481) (xy 131.626989 -234.468641) (xy 131.672968 -234.490458)
			(xy 131.714852 -234.519368) (xy 131.751556 -234.554623) (xy 131.782129 -234.595309) (xy 131.80578 -234.640372)
			(xy 131.821896 -234.688646) (xy 131.83006 -234.73888) (xy 131.830572 -234.764326) (xy 132.138415 -234.764326)
			(xy 132.14251 -234.713598) (xy 132.154689 -234.664184) (xy 132.174637 -234.617364) (xy 132.201838 -234.57435)
			(xy 132.235586 -234.536256) (xy 132.275008 -234.504069) (xy 132.319082 -234.478623) (xy 132.366668 -234.460576)
			(xy 132.416532 -234.450396) (xy 132.467384 -234.448347) (xy 132.517905 -234.454481) (xy 132.566789 -234.468641)
			(xy 132.612768 -234.490458) (xy 132.654652 -234.519368) (xy 132.691356 -234.554623) (xy 132.721929 -234.595309)
			(xy 132.74558 -234.640372) (xy 132.761696 -234.688646) (xy 132.76986 -234.73888) (xy 132.770372 -234.764326)
			(xy 133.0889 -234.764326) (xy 133.09286 -234.715272) (xy 133.104637 -234.667488) (xy 133.123928 -234.622212)
			(xy 133.150231 -234.580616) (xy 133.182866 -234.543779) (xy 133.220987 -234.512654) (xy 133.263608 -234.488047)
			(xy 133.309624 -234.470595) (xy 133.357843 -234.460751) (xy 133.407018 -234.45877) (xy 133.455873 -234.464702)
			(xy 133.503144 -234.478394) (xy 133.547606 -234.499492) (xy 133.588109 -234.527448) (xy 133.623602 -234.56154)
			(xy 133.653167 -234.600884) (xy 133.676038 -234.644461) (xy 133.691622 -234.691142) (xy 133.699517 -234.739719)
			(xy 133.700012 -234.764326) (xy 134.018523 -234.764326) (xy 134.022618 -234.713598) (xy 134.034797 -234.664184)
			(xy 134.054745 -234.617364) (xy 134.081946 -234.57435) (xy 134.115694 -234.536256) (xy 134.155116 -234.504069)
			(xy 134.19919 -234.478623) (xy 134.246776 -234.460576) (xy 134.29664 -234.450396) (xy 134.347492 -234.448347)
			(xy 134.398013 -234.454481) (xy 134.446897 -234.468641) (xy 134.492876 -234.490458) (xy 134.53476 -234.519368)
			(xy 134.571464 -234.554623) (xy 134.602037 -234.595309) (xy 134.625688 -234.640372) (xy 134.641804 -234.688646)
			(xy 134.649968 -234.73888) (xy 134.65048 -234.764326) (xy 134.969008 -234.764326) (xy 134.972968 -234.715272)
			(xy 134.984745 -234.667488) (xy 135.004036 -234.622212) (xy 135.030339 -234.580616) (xy 135.062974 -234.543779)
			(xy 135.101095 -234.512654) (xy 135.143716 -234.488047) (xy 135.189732 -234.470595) (xy 135.237951 -234.460751)
			(xy 135.287126 -234.45877) (xy 135.335981 -234.464702) (xy 135.383252 -234.478394) (xy 135.427714 -234.499492)
			(xy 135.468217 -234.527448) (xy 135.50371 -234.56154) (xy 135.533275 -234.600884) (xy 135.556146 -234.644461)
			(xy 135.57173 -234.691142) (xy 135.579625 -234.739719) (xy 135.58012 -234.764326) (xy 135.898631 -234.764326)
			(xy 135.902726 -234.713598) (xy 135.914905 -234.664184) (xy 135.934853 -234.617364) (xy 135.962054 -234.57435)
			(xy 135.995802 -234.536256) (xy 136.035224 -234.504069) (xy 136.079298 -234.478623) (xy 136.126884 -234.460576)
			(xy 136.176748 -234.450396) (xy 136.2276 -234.448347) (xy 136.278121 -234.454481) (xy 136.327005 -234.468641)
			(xy 136.372984 -234.490458) (xy 136.414868 -234.519368) (xy 136.451572 -234.554623) (xy 136.482145 -234.595309)
			(xy 136.505796 -234.640372) (xy 136.521912 -234.688646) (xy 136.530076 -234.73888) (xy 136.530588 -234.764326)
			(xy 137.778485 -234.764326) (xy 137.78258 -234.713598) (xy 137.794759 -234.664184) (xy 137.814707 -234.617364)
			(xy 137.841908 -234.57435) (xy 137.875656 -234.536256) (xy 137.915078 -234.504069) (xy 137.959152 -234.478623)
			(xy 138.006738 -234.460576) (xy 138.056602 -234.450396) (xy 138.107454 -234.448347) (xy 138.157975 -234.454481)
			(xy 138.206859 -234.468641) (xy 138.252838 -234.490458) (xy 138.294722 -234.519368) (xy 138.331426 -234.554623)
			(xy 138.361999 -234.595309) (xy 138.38565 -234.640372) (xy 138.401766 -234.688646) (xy 138.40993 -234.73888)
			(xy 138.410442 -234.764326) (xy 138.718539 -234.764326) (xy 138.722634 -234.713598) (xy 138.734813 -234.664184)
			(xy 138.754761 -234.617364) (xy 138.781962 -234.57435) (xy 138.81571 -234.536256) (xy 138.855132 -234.504069)
			(xy 138.899206 -234.478623) (xy 138.946792 -234.460576) (xy 138.996656 -234.450396) (xy 139.047508 -234.448347)
			(xy 139.098029 -234.454481) (xy 139.146913 -234.468641) (xy 139.192892 -234.490458) (xy 139.234776 -234.519368)
			(xy 139.27148 -234.554623) (xy 139.302053 -234.595309) (xy 139.325704 -234.640372) (xy 139.34182 -234.688646)
			(xy 139.349984 -234.73888) (xy 139.350496 -234.764326) (xy 139.669024 -234.764326) (xy 139.672984 -234.715272)
			(xy 139.684761 -234.667488) (xy 139.704052 -234.622212) (xy 139.730355 -234.580616) (xy 139.76299 -234.543779)
			(xy 139.801111 -234.512654) (xy 139.843732 -234.488047) (xy 139.889748 -234.470595) (xy 139.937967 -234.460751)
			(xy 139.987142 -234.45877) (xy 140.035997 -234.464702) (xy 140.083268 -234.478394) (xy 140.12773 -234.499492)
			(xy 140.168233 -234.527448) (xy 140.203726 -234.56154) (xy 140.233291 -234.600884) (xy 140.256162 -234.644461)
			(xy 140.271746 -234.691142) (xy 140.279641 -234.739719) (xy 140.280136 -234.764326) (xy 140.598647 -234.764326)
			(xy 140.602742 -234.713598) (xy 140.614921 -234.664184) (xy 140.634869 -234.617364) (xy 140.66207 -234.57435)
			(xy 140.695818 -234.536256) (xy 140.73524 -234.504069) (xy 140.779314 -234.478623) (xy 140.8269 -234.460576)
			(xy 140.876764 -234.450396) (xy 140.927616 -234.448347) (xy 140.978137 -234.454481) (xy 141.027021 -234.468641)
			(xy 141.073 -234.490458) (xy 141.114884 -234.519368) (xy 141.151588 -234.554623) (xy 141.182161 -234.595309)
			(xy 141.205812 -234.640372) (xy 141.221928 -234.688646) (xy 141.230092 -234.73888) (xy 141.230604 -234.764326)
			(xy 141.548878 -234.764326) (xy 141.552838 -234.715272) (xy 141.564615 -234.667488) (xy 141.583906 -234.622212)
			(xy 141.610209 -234.580616) (xy 141.642844 -234.543779) (xy 141.680965 -234.512654) (xy 141.723586 -234.488047)
			(xy 141.769602 -234.470595) (xy 141.817821 -234.460751) (xy 141.866996 -234.45877) (xy 141.915851 -234.464702)
			(xy 141.963122 -234.478394) (xy 142.007584 -234.499492) (xy 142.048087 -234.527448) (xy 142.08358 -234.56154)
			(xy 142.113145 -234.600884) (xy 142.136016 -234.644461) (xy 142.1516 -234.691142) (xy 142.159495 -234.739719)
			(xy 142.15999 -234.764326) (xy 142.478501 -234.764326) (xy 142.482596 -234.713598) (xy 142.494775 -234.664184)
			(xy 142.514723 -234.617364) (xy 142.541924 -234.57435) (xy 142.575672 -234.536256) (xy 142.615094 -234.504069)
			(xy 142.659168 -234.478623) (xy 142.706754 -234.460576) (xy 142.756618 -234.450396) (xy 142.80747 -234.448347)
			(xy 142.857991 -234.454481) (xy 142.906875 -234.468641) (xy 142.952854 -234.490458) (xy 142.994738 -234.519368)
			(xy 143.031442 -234.554623) (xy 143.062015 -234.595309) (xy 143.085666 -234.640372) (xy 143.101782 -234.688646)
			(xy 143.109946 -234.73888) (xy 143.110458 -234.764326) (xy 143.109946 -234.789772) (xy 143.101782 -234.840006)
			(xy 143.085666 -234.88828) (xy 143.062015 -234.933343) (xy 143.031442 -234.974029) (xy 142.994738 -235.009284)
			(xy 142.952854 -235.038194) (xy 142.906875 -235.060011) (xy 142.857991 -235.074171) (xy 142.80747 -235.080305)
			(xy 142.756618 -235.078256) (xy 142.706754 -235.068076) (xy 142.659168 -235.050029) (xy 142.615094 -235.024583)
			(xy 142.575672 -234.992396) (xy 142.541924 -234.954302) (xy 142.514723 -234.911288) (xy 142.494775 -234.864468)
			(xy 142.482596 -234.815054) (xy 142.478501 -234.764326) (xy 142.15999 -234.764326) (xy 142.159495 -234.788933)
			(xy 142.1516 -234.83751) (xy 142.136016 -234.884191) (xy 142.113145 -234.927768) (xy 142.08358 -234.967112)
			(xy 142.048087 -235.001204) (xy 142.007584 -235.02916) (xy 141.963122 -235.050258) (xy 141.915851 -235.06395)
			(xy 141.866996 -235.069882) (xy 141.817821 -235.067901) (xy 141.769602 -235.058057) (xy 141.723586 -235.040605)
			(xy 141.680965 -235.015998) (xy 141.642844 -234.984873) (xy 141.610209 -234.948036) (xy 141.583906 -234.90644)
			(xy 141.564615 -234.861164) (xy 141.552838 -234.81338) (xy 141.548878 -234.764326) (xy 141.230604 -234.764326)
			(xy 141.230092 -234.789772) (xy 141.221928 -234.840006) (xy 141.205812 -234.88828) (xy 141.182161 -234.933343)
			(xy 141.151588 -234.974029) (xy 141.114884 -235.009284) (xy 141.073 -235.038194) (xy 141.027021 -235.060011)
			(xy 140.978137 -235.074171) (xy 140.927616 -235.080305) (xy 140.876764 -235.078256) (xy 140.8269 -235.068076)
			(xy 140.779314 -235.050029) (xy 140.73524 -235.024583) (xy 140.695818 -234.992396) (xy 140.66207 -234.954302)
			(xy 140.634869 -234.911288) (xy 140.614921 -234.864468) (xy 140.602742 -234.815054) (xy 140.598647 -234.764326)
			(xy 140.280136 -234.764326) (xy 140.279641 -234.788933) (xy 140.271746 -234.83751) (xy 140.256162 -234.884191)
			(xy 140.233291 -234.927768) (xy 140.203726 -234.967112) (xy 140.168233 -235.001204) (xy 140.12773 -235.02916)
			(xy 140.083268 -235.050258) (xy 140.035997 -235.06395) (xy 139.987142 -235.069882) (xy 139.937967 -235.067901)
			(xy 139.889748 -235.058057) (xy 139.843732 -235.040605) (xy 139.801111 -235.015998) (xy 139.76299 -234.984873)
			(xy 139.730355 -234.948036) (xy 139.704052 -234.90644) (xy 139.684761 -234.861164) (xy 139.672984 -234.81338)
			(xy 139.669024 -234.764326) (xy 139.350496 -234.764326) (xy 139.349984 -234.789772) (xy 139.34182 -234.840006)
			(xy 139.325704 -234.88828) (xy 139.302053 -234.933343) (xy 139.27148 -234.974029) (xy 139.234776 -235.009284)
			(xy 139.192892 -235.038194) (xy 139.146913 -235.060011) (xy 139.098029 -235.074171) (xy 139.047508 -235.080305)
			(xy 138.996656 -235.078256) (xy 138.946792 -235.068076) (xy 138.899206 -235.050029) (xy 138.855132 -235.024583)
			(xy 138.81571 -234.992396) (xy 138.781962 -234.954302) (xy 138.754761 -234.911288) (xy 138.734813 -234.864468)
			(xy 138.722634 -234.815054) (xy 138.718539 -234.764326) (xy 138.410442 -234.764326) (xy 138.40993 -234.789772)
			(xy 138.401766 -234.840006) (xy 138.38565 -234.88828) (xy 138.361999 -234.933343) (xy 138.331426 -234.974029)
			(xy 138.294722 -235.009284) (xy 138.252838 -235.038194) (xy 138.206859 -235.060011) (xy 138.157975 -235.074171)
			(xy 138.107454 -235.080305) (xy 138.056602 -235.078256) (xy 138.006738 -235.068076) (xy 137.959152 -235.050029)
			(xy 137.915078 -235.024583) (xy 137.875656 -234.992396) (xy 137.841908 -234.954302) (xy 137.814707 -234.911288)
			(xy 137.794759 -234.864468) (xy 137.78258 -234.815054) (xy 137.778485 -234.764326) (xy 136.530588 -234.764326)
			(xy 136.530076 -234.789772) (xy 136.521912 -234.840006) (xy 136.505796 -234.88828) (xy 136.482145 -234.933343)
			(xy 136.451572 -234.974029) (xy 136.414868 -235.009284) (xy 136.372984 -235.038194) (xy 136.327005 -235.060011)
			(xy 136.278121 -235.074171) (xy 136.2276 -235.080305) (xy 136.176748 -235.078256) (xy 136.126884 -235.068076)
			(xy 136.079298 -235.050029) (xy 136.035224 -235.024583) (xy 135.995802 -234.992396) (xy 135.962054 -234.954302)
			(xy 135.934853 -234.911288) (xy 135.914905 -234.864468) (xy 135.902726 -234.815054) (xy 135.898631 -234.764326)
			(xy 135.58012 -234.764326) (xy 135.579625 -234.788933) (xy 135.57173 -234.83751) (xy 135.556146 -234.884191)
			(xy 135.533275 -234.927768) (xy 135.50371 -234.967112) (xy 135.468217 -235.001204) (xy 135.427714 -235.02916)
			(xy 135.383252 -235.050258) (xy 135.335981 -235.06395) (xy 135.287126 -235.069882) (xy 135.237951 -235.067901)
			(xy 135.189732 -235.058057) (xy 135.143716 -235.040605) (xy 135.101095 -235.015998) (xy 135.062974 -234.984873)
			(xy 135.030339 -234.948036) (xy 135.004036 -234.90644) (xy 134.984745 -234.861164) (xy 134.972968 -234.81338)
			(xy 134.969008 -234.764326) (xy 134.65048 -234.764326) (xy 134.649968 -234.789772) (xy 134.641804 -234.840006)
			(xy 134.625688 -234.88828) (xy 134.602037 -234.933343) (xy 134.571464 -234.974029) (xy 134.53476 -235.009284)
			(xy 134.492876 -235.038194) (xy 134.446897 -235.060011) (xy 134.398013 -235.074171) (xy 134.347492 -235.080305)
			(xy 134.29664 -235.078256) (xy 134.246776 -235.068076) (xy 134.19919 -235.050029) (xy 134.155116 -235.024583)
			(xy 134.115694 -234.992396) (xy 134.081946 -234.954302) (xy 134.054745 -234.911288) (xy 134.034797 -234.864468)
			(xy 134.022618 -234.815054) (xy 134.018523 -234.764326) (xy 133.700012 -234.764326) (xy 133.699517 -234.788933)
			(xy 133.691622 -234.83751) (xy 133.676038 -234.884191) (xy 133.653167 -234.927768) (xy 133.623602 -234.967112)
			(xy 133.588109 -235.001204) (xy 133.547606 -235.02916) (xy 133.503144 -235.050258) (xy 133.455873 -235.06395)
			(xy 133.407018 -235.069882) (xy 133.357843 -235.067901) (xy 133.309624 -235.058057) (xy 133.263608 -235.040605)
			(xy 133.220987 -235.015998) (xy 133.182866 -234.984873) (xy 133.150231 -234.948036) (xy 133.123928 -234.90644)
			(xy 133.104637 -234.861164) (xy 133.09286 -234.81338) (xy 133.0889 -234.764326) (xy 132.770372 -234.764326)
			(xy 132.76986 -234.789772) (xy 132.761696 -234.840006) (xy 132.74558 -234.88828) (xy 132.721929 -234.933343)
			(xy 132.691356 -234.974029) (xy 132.654652 -235.009284) (xy 132.612768 -235.038194) (xy 132.566789 -235.060011)
			(xy 132.517905 -235.074171) (xy 132.467384 -235.080305) (xy 132.416532 -235.078256) (xy 132.366668 -235.068076)
			(xy 132.319082 -235.050029) (xy 132.275008 -235.024583) (xy 132.235586 -234.992396) (xy 132.201838 -234.954302)
			(xy 132.174637 -234.911288) (xy 132.154689 -234.864468) (xy 132.14251 -234.815054) (xy 132.138415 -234.764326)
			(xy 131.830572 -234.764326) (xy 131.83006 -234.789772) (xy 131.821896 -234.840006) (xy 131.80578 -234.88828)
			(xy 131.782129 -234.933343) (xy 131.751556 -234.974029) (xy 131.714852 -235.009284) (xy 131.672968 -235.038194)
			(xy 131.626989 -235.060011) (xy 131.578105 -235.074171) (xy 131.527584 -235.080305) (xy 131.476732 -235.078256)
			(xy 131.426868 -235.068076) (xy 131.379282 -235.050029) (xy 131.335208 -235.024583) (xy 131.295786 -234.992396)
			(xy 131.262038 -234.954302) (xy 131.234837 -234.911288) (xy 131.214889 -234.864468) (xy 131.20271 -234.815054)
			(xy 131.198615 -234.764326) (xy 129.950464 -234.764326) (xy 129.949952 -234.789772) (xy 129.941788 -234.840006)
			(xy 129.925672 -234.88828) (xy 129.902021 -234.933343) (xy 129.871448 -234.974029) (xy 129.834744 -235.009284)
			(xy 129.79286 -235.038194) (xy 129.746881 -235.060011) (xy 129.697997 -235.074171) (xy 129.647476 -235.080305)
			(xy 129.596624 -235.078256) (xy 129.54676 -235.068076) (xy 129.499174 -235.050029) (xy 129.4551 -235.024583)
			(xy 129.415678 -234.992396) (xy 129.38193 -234.954302) (xy 129.354729 -234.911288) (xy 129.334781 -234.864468)
			(xy 129.322602 -234.815054) (xy 129.318507 -234.764326) (xy 128.999996 -234.764326) (xy 128.999501 -234.788933)
			(xy 128.991606 -234.83751) (xy 128.976022 -234.884191) (xy 128.953151 -234.927768) (xy 128.923586 -234.967112)
			(xy 128.888093 -235.001204) (xy 128.84759 -235.02916) (xy 128.803128 -235.050258) (xy 128.755857 -235.06395)
			(xy 128.707002 -235.069882) (xy 128.657827 -235.067901) (xy 128.609608 -235.058057) (xy 128.563592 -235.040605)
			(xy 128.520971 -235.015998) (xy 128.48285 -234.984873) (xy 128.450215 -234.948036) (xy 128.423912 -234.90644)
			(xy 128.404621 -234.861164) (xy 128.392844 -234.81338) (xy 128.388884 -234.764326) (xy 128.069809 -234.764326)
			(xy 128.069809 -234.789106) (xy 128.062049 -234.838107) (xy 128.046719 -234.885291) (xy 128.024197 -234.929496)
			(xy 127.995038 -234.969633) (xy 127.959959 -235.004716) (xy 127.919825 -235.03388) (xy 127.875622 -235.056406)
			(xy 127.82844 -235.071741) (xy 127.77944 -235.079507) (xy 127.754634 -235.080048) (xy 127.732952 -235.079649)
			(xy 127.690002 -235.073654) (xy 127.669036 -235.06811) (xy 127.662432 -235.066078) (xy 127.65532 -235.066078)
			(xy 127.645308 -235.066562) (xy 127.626806 -235.074217) (xy 127.612641 -235.08837) (xy 127.60497 -235.106866)
			(xy 127.60452 -235.116878) (xy 127.60452 -235.135166) (xy 127.607314 -235.14304) (xy 127.622678 -235.189364)
			(xy 127.647396 -235.283789) (xy 127.665146 -235.379769) (xy 127.675833 -235.476789) (xy 127.6794 -235.57433)
			(xy 127.6794 -235.574332) (xy 127.908553 -235.574332) (xy 127.912648 -235.523604) (xy 127.924827 -235.47419)
			(xy 127.944775 -235.42737) (xy 127.971976 -235.384356) (xy 128.005724 -235.346262) (xy 128.045146 -235.314075)
			(xy 128.08922 -235.288629) (xy 128.136806 -235.270582) (xy 128.18667 -235.260402) (xy 128.237522 -235.258353)
			(xy 128.288043 -235.264487) (xy 128.336927 -235.278647) (xy 128.382906 -235.300464) (xy 128.42479 -235.329374)
			(xy 128.461494 -235.364629) (xy 128.492067 -235.405315) (xy 128.515718 -235.450378) (xy 128.531834 -235.498652)
			(xy 128.539998 -235.548886) (xy 128.54051 -235.574332) (xy 128.848607 -235.574332) (xy 128.852702 -235.523604)
			(xy 128.864881 -235.47419) (xy 128.884829 -235.42737) (xy 128.91203 -235.384356) (xy 128.945778 -235.346262)
			(xy 128.9852 -235.314075) (xy 129.029274 -235.288629) (xy 129.07686 -235.270582) (xy 129.126724 -235.260402)
			(xy 129.177576 -235.258353) (xy 129.228097 -235.264487) (xy 129.276981 -235.278647) (xy 129.32296 -235.300464)
			(xy 129.364844 -235.329374) (xy 129.401548 -235.364629) (xy 129.432121 -235.405315) (xy 129.455772 -235.450378)
			(xy 129.471888 -235.498652) (xy 129.480052 -235.548886) (xy 129.480564 -235.574332) (xy 129.798838 -235.574332)
			(xy 129.802798 -235.525278) (xy 129.814575 -235.477494) (xy 129.833866 -235.432218) (xy 129.860169 -235.390622)
			(xy 129.892804 -235.353785) (xy 129.930925 -235.32266) (xy 129.973546 -235.298053) (xy 130.019562 -235.280601)
			(xy 130.067781 -235.270757) (xy 130.116956 -235.268776) (xy 130.165811 -235.274708) (xy 130.213082 -235.2884)
			(xy 130.257544 -235.309498) (xy 130.298047 -235.337454) (xy 130.33354 -235.371546) (xy 130.363105 -235.41089)
			(xy 130.385976 -235.454467) (xy 130.40156 -235.501148) (xy 130.409455 -235.549725) (xy 130.40995 -235.574332)
			(xy 130.728461 -235.574332) (xy 130.732556 -235.523604) (xy 130.744735 -235.47419) (xy 130.764683 -235.42737)
			(xy 130.791884 -235.384356) (xy 130.825632 -235.346262) (xy 130.865054 -235.314075) (xy 130.909128 -235.288629)
			(xy 130.956714 -235.270582) (xy 131.006578 -235.260402) (xy 131.05743 -235.258353) (xy 131.107951 -235.264487)
			(xy 131.156835 -235.278647) (xy 131.202814 -235.300464) (xy 131.244698 -235.329374) (xy 131.281402 -235.364629)
			(xy 131.311975 -235.405315) (xy 131.335626 -235.450378) (xy 131.351742 -235.498652) (xy 131.359906 -235.548886)
			(xy 131.360418 -235.574332) (xy 131.678946 -235.574332) (xy 131.682906 -235.525278) (xy 131.694683 -235.477494)
			(xy 131.713974 -235.432218) (xy 131.740277 -235.390622) (xy 131.772912 -235.353785) (xy 131.811033 -235.32266)
			(xy 131.853654 -235.298053) (xy 131.89967 -235.280601) (xy 131.947889 -235.270757) (xy 131.997064 -235.268776)
			(xy 132.045919 -235.274708) (xy 132.09319 -235.2884) (xy 132.137652 -235.309498) (xy 132.178155 -235.337454)
			(xy 132.213648 -235.371546) (xy 132.243213 -235.41089) (xy 132.266084 -235.454467) (xy 132.281668 -235.501148)
			(xy 132.289563 -235.549725) (xy 132.290058 -235.574332) (xy 132.608569 -235.574332) (xy 132.612664 -235.523604)
			(xy 132.624843 -235.47419) (xy 132.644791 -235.42737) (xy 132.671992 -235.384356) (xy 132.70574 -235.346262)
			(xy 132.745162 -235.314075) (xy 132.789236 -235.288629) (xy 132.836822 -235.270582) (xy 132.886686 -235.260402)
			(xy 132.937538 -235.258353) (xy 132.988059 -235.264487) (xy 133.036943 -235.278647) (xy 133.082922 -235.300464)
			(xy 133.124806 -235.329374) (xy 133.16151 -235.364629) (xy 133.192083 -235.405315) (xy 133.215734 -235.450378)
			(xy 133.23185 -235.498652) (xy 133.240014 -235.548886) (xy 133.240526 -235.574332) (xy 133.559054 -235.574332)
			(xy 133.563014 -235.525278) (xy 133.574791 -235.477494) (xy 133.594082 -235.432218) (xy 133.620385 -235.390622)
			(xy 133.65302 -235.353785) (xy 133.691141 -235.32266) (xy 133.733762 -235.298053) (xy 133.779778 -235.280601)
			(xy 133.827997 -235.270757) (xy 133.877172 -235.268776) (xy 133.926027 -235.274708) (xy 133.973298 -235.2884)
			(xy 134.01776 -235.309498) (xy 134.058263 -235.337454) (xy 134.093756 -235.371546) (xy 134.123321 -235.41089)
			(xy 134.146192 -235.454467) (xy 134.161776 -235.501148) (xy 134.169671 -235.549725) (xy 134.170166 -235.574332)
			(xy 134.488423 -235.574332) (xy 134.492518 -235.523604) (xy 134.504697 -235.47419) (xy 134.524645 -235.42737)
			(xy 134.551846 -235.384356) (xy 134.585594 -235.346262) (xy 134.625016 -235.314075) (xy 134.66909 -235.288629)
			(xy 134.716676 -235.270582) (xy 134.76654 -235.260402) (xy 134.817392 -235.258353) (xy 134.867913 -235.264487)
			(xy 134.916797 -235.278647) (xy 134.962776 -235.300464) (xy 135.00466 -235.329374) (xy 135.041364 -235.364629)
			(xy 135.071937 -235.405315) (xy 135.095588 -235.450378) (xy 135.111704 -235.498652) (xy 135.119868 -235.548886)
			(xy 135.12038 -235.574332) (xy 135.428477 -235.574332) (xy 135.432572 -235.523604) (xy 135.444751 -235.47419)
			(xy 135.464699 -235.42737) (xy 135.4919 -235.384356) (xy 135.525648 -235.346262) (xy 135.56507 -235.314075)
			(xy 135.609144 -235.288629) (xy 135.65673 -235.270582) (xy 135.706594 -235.260402) (xy 135.757446 -235.258353)
			(xy 135.807967 -235.264487) (xy 135.856851 -235.278647) (xy 135.90283 -235.300464) (xy 135.944714 -235.329374)
			(xy 135.981418 -235.364629) (xy 136.011991 -235.405315) (xy 136.035642 -235.450378) (xy 136.051758 -235.498652)
			(xy 136.059922 -235.548886) (xy 136.060434 -235.574332) (xy 136.378962 -235.574332) (xy 136.382922 -235.525278)
			(xy 136.394699 -235.477494) (xy 136.41399 -235.432218) (xy 136.440293 -235.390622) (xy 136.472928 -235.353785)
			(xy 136.511049 -235.32266) (xy 136.55367 -235.298053) (xy 136.599686 -235.280601) (xy 136.647905 -235.270757)
			(xy 136.69708 -235.268776) (xy 136.745935 -235.274708) (xy 136.793206 -235.2884) (xy 136.837668 -235.309498)
			(xy 136.878171 -235.337454) (xy 136.913664 -235.371546) (xy 136.943229 -235.41089) (xy 136.9661 -235.454467)
			(xy 136.981684 -235.501148) (xy 136.989579 -235.549725) (xy 136.990074 -235.574332) (xy 137.308585 -235.574332)
			(xy 137.31268 -235.523604) (xy 137.324859 -235.47419) (xy 137.344807 -235.42737) (xy 137.372008 -235.384356)
			(xy 137.405756 -235.346262) (xy 137.445178 -235.314075) (xy 137.489252 -235.288629) (xy 137.536838 -235.270582)
			(xy 137.586702 -235.260402) (xy 137.637554 -235.258353) (xy 137.688075 -235.264487) (xy 137.736959 -235.278647)
			(xy 137.782938 -235.300464) (xy 137.824822 -235.329374) (xy 137.861526 -235.364629) (xy 137.892099 -235.405315)
			(xy 137.91575 -235.450378) (xy 137.931866 -235.498652) (xy 137.94003 -235.548886) (xy 137.940542 -235.574332)
			(xy 138.25907 -235.574332) (xy 138.26303 -235.525278) (xy 138.274807 -235.477494) (xy 138.294098 -235.432218)
			(xy 138.320401 -235.390622) (xy 138.353036 -235.353785) (xy 138.391157 -235.32266) (xy 138.433778 -235.298053)
			(xy 138.479794 -235.280601) (xy 138.528013 -235.270757) (xy 138.577188 -235.268776) (xy 138.626043 -235.274708)
			(xy 138.673314 -235.2884) (xy 138.717776 -235.309498) (xy 138.758279 -235.337454) (xy 138.793772 -235.371546)
			(xy 138.823337 -235.41089) (xy 138.846208 -235.454467) (xy 138.861792 -235.501148) (xy 138.869687 -235.549725)
			(xy 138.870182 -235.574332) (xy 139.188439 -235.574332) (xy 139.192534 -235.523604) (xy 139.204713 -235.47419)
			(xy 139.224661 -235.42737) (xy 139.251862 -235.384356) (xy 139.28561 -235.346262) (xy 139.325032 -235.314075)
			(xy 139.369106 -235.288629) (xy 139.416692 -235.270582) (xy 139.466556 -235.260402) (xy 139.517408 -235.258353)
			(xy 139.567929 -235.264487) (xy 139.616813 -235.278647) (xy 139.662792 -235.300464) (xy 139.704676 -235.329374)
			(xy 139.74138 -235.364629) (xy 139.771953 -235.405315) (xy 139.795604 -235.450378) (xy 139.81172 -235.498652)
			(xy 139.819884 -235.548886) (xy 139.820396 -235.574332) (xy 140.138924 -235.574332) (xy 140.142884 -235.525278)
			(xy 140.154661 -235.477494) (xy 140.173952 -235.432218) (xy 140.200255 -235.390622) (xy 140.23289 -235.353785)
			(xy 140.271011 -235.32266) (xy 140.313632 -235.298053) (xy 140.359648 -235.280601) (xy 140.407867 -235.270757)
			(xy 140.457042 -235.268776) (xy 140.505897 -235.274708) (xy 140.553168 -235.2884) (xy 140.59763 -235.309498)
			(xy 140.638133 -235.337454) (xy 140.673626 -235.371546) (xy 140.703191 -235.41089) (xy 140.726062 -235.454467)
			(xy 140.741646 -235.501148) (xy 140.749541 -235.549725) (xy 140.750036 -235.574332) (xy 141.068547 -235.574332)
			(xy 141.072642 -235.523604) (xy 141.084821 -235.47419) (xy 141.104769 -235.42737) (xy 141.13197 -235.384356)
			(xy 141.165718 -235.346262) (xy 141.20514 -235.314075) (xy 141.249214 -235.288629) (xy 141.2968 -235.270582)
			(xy 141.346664 -235.260402) (xy 141.397516 -235.258353) (xy 141.448037 -235.264487) (xy 141.496921 -235.278647)
			(xy 141.5429 -235.300464) (xy 141.584784 -235.329374) (xy 141.621488 -235.364629) (xy 141.652061 -235.405315)
			(xy 141.675712 -235.450378) (xy 141.691828 -235.498652) (xy 141.699992 -235.548886) (xy 141.700504 -235.574332)
			(xy 142.008601 -235.574332) (xy 142.012696 -235.523604) (xy 142.024875 -235.47419) (xy 142.044823 -235.42737)
			(xy 142.072024 -235.384356) (xy 142.105772 -235.346262) (xy 142.145194 -235.314075) (xy 142.189268 -235.288629)
			(xy 142.236854 -235.270582) (xy 142.286718 -235.260402) (xy 142.33757 -235.258353) (xy 142.388091 -235.264487)
			(xy 142.436975 -235.278647) (xy 142.482954 -235.300464) (xy 142.524838 -235.329374) (xy 142.561542 -235.364629)
			(xy 142.592115 -235.405315) (xy 142.615766 -235.450378) (xy 142.631882 -235.498652) (xy 142.640046 -235.548886)
			(xy 142.640558 -235.574332) (xy 142.958832 -235.574332) (xy 142.962792 -235.525278) (xy 142.974569 -235.477494)
			(xy 142.99386 -235.432218) (xy 143.020163 -235.390622) (xy 143.052798 -235.353785) (xy 143.090919 -235.32266)
			(xy 143.13354 -235.298053) (xy 143.179556 -235.280601) (xy 143.227775 -235.270757) (xy 143.27695 -235.268776)
			(xy 143.325805 -235.274708) (xy 143.373076 -235.2884) (xy 143.417538 -235.309498) (xy 143.458041 -235.337454)
			(xy 143.493534 -235.371546) (xy 143.523099 -235.41089) (xy 143.54597 -235.454467) (xy 143.561554 -235.501148)
			(xy 143.569449 -235.549725) (xy 143.569944 -235.574332) (xy 144.83894 -235.574332) (xy 144.8429 -235.525278)
			(xy 144.854677 -235.477494) (xy 144.873968 -235.432218) (xy 144.900271 -235.390622) (xy 144.932906 -235.353785)
			(xy 144.971027 -235.32266) (xy 145.013648 -235.298053) (xy 145.059664 -235.280601) (xy 145.107883 -235.270757)
			(xy 145.157058 -235.268776) (xy 145.205913 -235.274708) (xy 145.253184 -235.2884) (xy 145.297646 -235.309498)
			(xy 145.338149 -235.337454) (xy 145.373642 -235.371546) (xy 145.403207 -235.41089) (xy 145.426078 -235.454467)
			(xy 145.441662 -235.501148) (xy 145.449557 -235.549725) (xy 145.450052 -235.574332) (xy 145.449557 -235.598939)
			(xy 145.441662 -235.647516) (xy 145.426078 -235.694197) (xy 145.403207 -235.737774) (xy 145.373642 -235.777118)
			(xy 145.338149 -235.81121) (xy 145.297646 -235.839166) (xy 145.253184 -235.860264) (xy 145.205913 -235.873956)
			(xy 145.157058 -235.879888) (xy 145.107883 -235.877907) (xy 145.059664 -235.868063) (xy 145.013648 -235.850611)
			(xy 144.971027 -235.826004) (xy 144.932906 -235.794879) (xy 144.900271 -235.758042) (xy 144.873968 -235.716446)
			(xy 144.854677 -235.67117) (xy 144.8429 -235.623386) (xy 144.83894 -235.574332) (xy 143.569944 -235.574332)
			(xy 143.569449 -235.598939) (xy 143.561554 -235.647516) (xy 143.54597 -235.694197) (xy 143.523099 -235.737774)
			(xy 143.493534 -235.777118) (xy 143.458041 -235.81121) (xy 143.417538 -235.839166) (xy 143.373076 -235.860264)
			(xy 143.325805 -235.873956) (xy 143.27695 -235.879888) (xy 143.227775 -235.877907) (xy 143.179556 -235.868063)
			(xy 143.13354 -235.850611) (xy 143.090919 -235.826004) (xy 143.052798 -235.794879) (xy 143.020163 -235.758042)
			(xy 142.99386 -235.716446) (xy 142.974569 -235.67117) (xy 142.962792 -235.623386) (xy 142.958832 -235.574332)
			(xy 142.640558 -235.574332) (xy 142.640046 -235.599778) (xy 142.631882 -235.650012) (xy 142.615766 -235.698286)
			(xy 142.592115 -235.743349) (xy 142.561542 -235.784035) (xy 142.524838 -235.81929) (xy 142.482954 -235.8482)
			(xy 142.436975 -235.870017) (xy 142.388091 -235.884177) (xy 142.33757 -235.890311) (xy 142.286718 -235.888262)
			(xy 142.236854 -235.878082) (xy 142.189268 -235.860035) (xy 142.145194 -235.834589) (xy 142.105772 -235.802402)
			(xy 142.072024 -235.764308) (xy 142.044823 -235.721294) (xy 142.024875 -235.674474) (xy 142.012696 -235.62506)
			(xy 142.008601 -235.574332) (xy 141.700504 -235.574332) (xy 141.699992 -235.599778) (xy 141.691828 -235.650012)
			(xy 141.675712 -235.698286) (xy 141.652061 -235.743349) (xy 141.621488 -235.784035) (xy 141.584784 -235.81929)
			(xy 141.5429 -235.8482) (xy 141.496921 -235.870017) (xy 141.448037 -235.884177) (xy 141.397516 -235.890311)
			(xy 141.346664 -235.888262) (xy 141.2968 -235.878082) (xy 141.249214 -235.860035) (xy 141.20514 -235.834589)
			(xy 141.165718 -235.802402) (xy 141.13197 -235.764308) (xy 141.104769 -235.721294) (xy 141.084821 -235.674474)
			(xy 141.072642 -235.62506) (xy 141.068547 -235.574332) (xy 140.750036 -235.574332) (xy 140.749541 -235.598939)
			(xy 140.741646 -235.647516) (xy 140.726062 -235.694197) (xy 140.703191 -235.737774) (xy 140.673626 -235.777118)
			(xy 140.638133 -235.81121) (xy 140.59763 -235.839166) (xy 140.553168 -235.860264) (xy 140.505897 -235.873956)
			(xy 140.457042 -235.879888) (xy 140.407867 -235.877907) (xy 140.359648 -235.868063) (xy 140.313632 -235.850611)
			(xy 140.271011 -235.826004) (xy 140.23289 -235.794879) (xy 140.200255 -235.758042) (xy 140.173952 -235.716446)
			(xy 140.154661 -235.67117) (xy 140.142884 -235.623386) (xy 140.138924 -235.574332) (xy 139.820396 -235.574332)
			(xy 139.819884 -235.599778) (xy 139.81172 -235.650012) (xy 139.795604 -235.698286) (xy 139.771953 -235.743349)
			(xy 139.74138 -235.784035) (xy 139.704676 -235.81929) (xy 139.662792 -235.8482) (xy 139.616813 -235.870017)
			(xy 139.567929 -235.884177) (xy 139.517408 -235.890311) (xy 139.466556 -235.888262) (xy 139.416692 -235.878082)
			(xy 139.369106 -235.860035) (xy 139.325032 -235.834589) (xy 139.28561 -235.802402) (xy 139.251862 -235.764308)
			(xy 139.224661 -235.721294) (xy 139.204713 -235.674474) (xy 139.192534 -235.62506) (xy 139.188439 -235.574332)
			(xy 138.870182 -235.574332) (xy 138.869687 -235.598939) (xy 138.861792 -235.647516) (xy 138.846208 -235.694197)
			(xy 138.823337 -235.737774) (xy 138.793772 -235.777118) (xy 138.758279 -235.81121) (xy 138.717776 -235.839166)
			(xy 138.673314 -235.860264) (xy 138.626043 -235.873956) (xy 138.577188 -235.879888) (xy 138.528013 -235.877907)
			(xy 138.479794 -235.868063) (xy 138.433778 -235.850611) (xy 138.391157 -235.826004) (xy 138.353036 -235.794879)
			(xy 138.320401 -235.758042) (xy 138.294098 -235.716446) (xy 138.274807 -235.67117) (xy 138.26303 -235.623386)
			(xy 138.25907 -235.574332) (xy 137.940542 -235.574332) (xy 137.94003 -235.599778) (xy 137.931866 -235.650012)
			(xy 137.91575 -235.698286) (xy 137.892099 -235.743349) (xy 137.861526 -235.784035) (xy 137.824822 -235.81929)
			(xy 137.782938 -235.8482) (xy 137.736959 -235.870017) (xy 137.688075 -235.884177) (xy 137.637554 -235.890311)
			(xy 137.586702 -235.888262) (xy 137.536838 -235.878082) (xy 137.489252 -235.860035) (xy 137.445178 -235.834589)
			(xy 137.405756 -235.802402) (xy 137.372008 -235.764308) (xy 137.344807 -235.721294) (xy 137.324859 -235.674474)
			(xy 137.31268 -235.62506) (xy 137.308585 -235.574332) (xy 136.990074 -235.574332) (xy 136.989579 -235.598939)
			(xy 136.981684 -235.647516) (xy 136.9661 -235.694197) (xy 136.943229 -235.737774) (xy 136.913664 -235.777118)
			(xy 136.878171 -235.81121) (xy 136.837668 -235.839166) (xy 136.793206 -235.860264) (xy 136.745935 -235.873956)
			(xy 136.69708 -235.879888) (xy 136.647905 -235.877907) (xy 136.599686 -235.868063) (xy 136.55367 -235.850611)
			(xy 136.511049 -235.826004) (xy 136.472928 -235.794879) (xy 136.440293 -235.758042) (xy 136.41399 -235.716446)
			(xy 136.394699 -235.67117) (xy 136.382922 -235.623386) (xy 136.378962 -235.574332) (xy 136.060434 -235.574332)
			(xy 136.059922 -235.599778) (xy 136.051758 -235.650012) (xy 136.035642 -235.698286) (xy 136.011991 -235.743349)
			(xy 135.981418 -235.784035) (xy 135.944714 -235.81929) (xy 135.90283 -235.8482) (xy 135.856851 -235.870017)
			(xy 135.807967 -235.884177) (xy 135.757446 -235.890311) (xy 135.706594 -235.888262) (xy 135.65673 -235.878082)
			(xy 135.609144 -235.860035) (xy 135.56507 -235.834589) (xy 135.525648 -235.802402) (xy 135.4919 -235.764308)
			(xy 135.464699 -235.721294) (xy 135.444751 -235.674474) (xy 135.432572 -235.62506) (xy 135.428477 -235.574332)
			(xy 135.12038 -235.574332) (xy 135.119868 -235.599778) (xy 135.111704 -235.650012) (xy 135.095588 -235.698286)
			(xy 135.071937 -235.743349) (xy 135.041364 -235.784035) (xy 135.00466 -235.81929) (xy 134.962776 -235.8482)
			(xy 134.916797 -235.870017) (xy 134.867913 -235.884177) (xy 134.817392 -235.890311) (xy 134.76654 -235.888262)
			(xy 134.716676 -235.878082) (xy 134.66909 -235.860035) (xy 134.625016 -235.834589) (xy 134.585594 -235.802402)
			(xy 134.551846 -235.764308) (xy 134.524645 -235.721294) (xy 134.504697 -235.674474) (xy 134.492518 -235.62506)
			(xy 134.488423 -235.574332) (xy 134.170166 -235.574332) (xy 134.169671 -235.598939) (xy 134.161776 -235.647516)
			(xy 134.146192 -235.694197) (xy 134.123321 -235.737774) (xy 134.093756 -235.777118) (xy 134.058263 -235.81121)
			(xy 134.01776 -235.839166) (xy 133.973298 -235.860264) (xy 133.926027 -235.873956) (xy 133.877172 -235.879888)
			(xy 133.827997 -235.877907) (xy 133.779778 -235.868063) (xy 133.733762 -235.850611) (xy 133.691141 -235.826004)
			(xy 133.65302 -235.794879) (xy 133.620385 -235.758042) (xy 133.594082 -235.716446) (xy 133.574791 -235.67117)
			(xy 133.563014 -235.623386) (xy 133.559054 -235.574332) (xy 133.240526 -235.574332) (xy 133.240014 -235.599778)
			(xy 133.23185 -235.650012) (xy 133.215734 -235.698286) (xy 133.192083 -235.743349) (xy 133.16151 -235.784035)
			(xy 133.124806 -235.81929) (xy 133.082922 -235.8482) (xy 133.036943 -235.870017) (xy 132.988059 -235.884177)
			(xy 132.937538 -235.890311) (xy 132.886686 -235.888262) (xy 132.836822 -235.878082) (xy 132.789236 -235.860035)
			(xy 132.745162 -235.834589) (xy 132.70574 -235.802402) (xy 132.671992 -235.764308) (xy 132.644791 -235.721294)
			(xy 132.624843 -235.674474) (xy 132.612664 -235.62506) (xy 132.608569 -235.574332) (xy 132.290058 -235.574332)
			(xy 132.289563 -235.598939) (xy 132.281668 -235.647516) (xy 132.266084 -235.694197) (xy 132.243213 -235.737774)
			(xy 132.213648 -235.777118) (xy 132.178155 -235.81121) (xy 132.137652 -235.839166) (xy 132.09319 -235.860264)
			(xy 132.045919 -235.873956) (xy 131.997064 -235.879888) (xy 131.947889 -235.877907) (xy 131.89967 -235.868063)
			(xy 131.853654 -235.850611) (xy 131.811033 -235.826004) (xy 131.772912 -235.794879) (xy 131.740277 -235.758042)
			(xy 131.713974 -235.716446) (xy 131.694683 -235.67117) (xy 131.682906 -235.623386) (xy 131.678946 -235.574332)
			(xy 131.360418 -235.574332) (xy 131.359906 -235.599778) (xy 131.351742 -235.650012) (xy 131.335626 -235.698286)
			(xy 131.311975 -235.743349) (xy 131.281402 -235.784035) (xy 131.244698 -235.81929) (xy 131.202814 -235.8482)
			(xy 131.156835 -235.870017) (xy 131.107951 -235.884177) (xy 131.05743 -235.890311) (xy 131.006578 -235.888262)
			(xy 130.956714 -235.878082) (xy 130.909128 -235.860035) (xy 130.865054 -235.834589) (xy 130.825632 -235.802402)
			(xy 130.791884 -235.764308) (xy 130.764683 -235.721294) (xy 130.744735 -235.674474) (xy 130.732556 -235.62506)
			(xy 130.728461 -235.574332) (xy 130.40995 -235.574332) (xy 130.409455 -235.598939) (xy 130.40156 -235.647516)
			(xy 130.385976 -235.694197) (xy 130.363105 -235.737774) (xy 130.33354 -235.777118) (xy 130.298047 -235.81121)
			(xy 130.257544 -235.839166) (xy 130.213082 -235.860264) (xy 130.165811 -235.873956) (xy 130.116956 -235.879888)
			(xy 130.067781 -235.877907) (xy 130.019562 -235.868063) (xy 129.973546 -235.850611) (xy 129.930925 -235.826004)
			(xy 129.892804 -235.794879) (xy 129.860169 -235.758042) (xy 129.833866 -235.716446) (xy 129.814575 -235.67117)
			(xy 129.802798 -235.623386) (xy 129.798838 -235.574332) (xy 129.480564 -235.574332) (xy 129.480052 -235.599778)
			(xy 129.471888 -235.650012) (xy 129.455772 -235.698286) (xy 129.432121 -235.743349) (xy 129.401548 -235.784035)
			(xy 129.364844 -235.81929) (xy 129.32296 -235.8482) (xy 129.276981 -235.870017) (xy 129.228097 -235.884177)
			(xy 129.177576 -235.890311) (xy 129.126724 -235.888262) (xy 129.07686 -235.878082) (xy 129.029274 -235.860035)
			(xy 128.9852 -235.834589) (xy 128.945778 -235.802402) (xy 128.91203 -235.764308) (xy 128.884829 -235.721294)
			(xy 128.864881 -235.674474) (xy 128.852702 -235.62506) (xy 128.848607 -235.574332) (xy 128.54051 -235.574332)
			(xy 128.539998 -235.599778) (xy 128.531834 -235.650012) (xy 128.515718 -235.698286) (xy 128.492067 -235.743349)
			(xy 128.461494 -235.784035) (xy 128.42479 -235.81929) (xy 128.382906 -235.8482) (xy 128.336927 -235.870017)
			(xy 128.288043 -235.884177) (xy 128.237522 -235.890311) (xy 128.18667 -235.888262) (xy 128.136806 -235.878082)
			(xy 128.08922 -235.860035) (xy 128.045146 -235.834589) (xy 128.005724 -235.802402) (xy 127.971976 -235.764308)
			(xy 127.944775 -235.721294) (xy 127.924827 -235.674474) (xy 127.912648 -235.62506) (xy 127.908553 -235.574332)
			(xy 127.6794 -235.574332) (xy 127.675829 -235.671872) (xy 127.665137 -235.768891) (xy 127.647382 -235.86487)
			(xy 127.62266 -235.959294) (xy 127.607314 -236.005624) (xy 127.60452 -236.013498) (xy 127.60452 -236.031786)
			(xy 127.604938 -236.041808) (xy 127.612606 -236.060326) (xy 127.626779 -236.074498) (xy 127.645298 -236.082163)
			(xy 127.65532 -236.082586) (xy 127.662432 -236.082586) (xy 127.669036 -236.080554) (xy 127.689997 -236.074987)
			(xy 127.73295 -236.069001) (xy 127.754634 -236.068616) (xy 127.779439 -236.069105) (xy 127.828437 -236.076871)
			(xy 127.875617 -236.092205) (xy 127.919818 -236.114731) (xy 127.959952 -236.143893) (xy 127.995029 -236.178974)
			(xy 128.024187 -236.219111) (xy 128.046708 -236.263314) (xy 128.062037 -236.310496) (xy 128.069797 -236.359495)
			(xy 128.069797 -236.384338) (xy 128.388884 -236.384338) (xy 128.392844 -236.335284) (xy 128.404621 -236.2875)
			(xy 128.423912 -236.242224) (xy 128.450215 -236.200628) (xy 128.48285 -236.163791) (xy 128.520971 -236.132666)
			(xy 128.563592 -236.108059) (xy 128.609608 -236.090607) (xy 128.657827 -236.080763) (xy 128.707002 -236.078782)
			(xy 128.755857 -236.084714) (xy 128.803128 -236.098406) (xy 128.84759 -236.119504) (xy 128.888093 -236.14746)
			(xy 128.923586 -236.181552) (xy 128.953151 -236.220896) (xy 128.976022 -236.264473) (xy 128.991606 -236.311154)
			(xy 128.999501 -236.359731) (xy 128.999996 -236.384338) (xy 129.318507 -236.384338) (xy 129.322602 -236.33361)
			(xy 129.334781 -236.284196) (xy 129.354729 -236.237376) (xy 129.38193 -236.194362) (xy 129.415678 -236.156268)
			(xy 129.4551 -236.124081) (xy 129.499174 -236.098635) (xy 129.54676 -236.080588) (xy 129.596624 -236.070408)
			(xy 129.647476 -236.068359) (xy 129.697997 -236.074493) (xy 129.746881 -236.088653) (xy 129.79286 -236.11047)
			(xy 129.834744 -236.13938) (xy 129.871448 -236.174635) (xy 129.902021 -236.215321) (xy 129.925672 -236.260384)
			(xy 129.941788 -236.308658) (xy 129.949952 -236.358892) (xy 129.950464 -236.384338) (xy 130.268992 -236.384338)
			(xy 130.272952 -236.335284) (xy 130.284729 -236.2875) (xy 130.30402 -236.242224) (xy 130.330323 -236.200628)
			(xy 130.362958 -236.163791) (xy 130.401079 -236.132666) (xy 130.4437 -236.108059) (xy 130.489716 -236.090607)
			(xy 130.537935 -236.080763) (xy 130.58711 -236.078782) (xy 130.635965 -236.084714) (xy 130.683236 -236.098406)
			(xy 130.727698 -236.119504) (xy 130.768201 -236.14746) (xy 130.803694 -236.181552) (xy 130.833259 -236.220896)
			(xy 130.85613 -236.264473) (xy 130.871714 -236.311154) (xy 130.879609 -236.359731) (xy 130.880104 -236.384338)
			(xy 131.198615 -236.384338) (xy 131.20271 -236.33361) (xy 131.214889 -236.284196) (xy 131.234837 -236.237376)
			(xy 131.262038 -236.194362) (xy 131.295786 -236.156268) (xy 131.335208 -236.124081) (xy 131.379282 -236.098635)
			(xy 131.426868 -236.080588) (xy 131.476732 -236.070408) (xy 131.527584 -236.068359) (xy 131.578105 -236.074493)
			(xy 131.626989 -236.088653) (xy 131.672968 -236.11047) (xy 131.714852 -236.13938) (xy 131.751556 -236.174635)
			(xy 131.782129 -236.215321) (xy 131.80578 -236.260384) (xy 131.821896 -236.308658) (xy 131.83006 -236.358892)
			(xy 131.830572 -236.384338) (xy 132.138415 -236.384338) (xy 132.14251 -236.33361) (xy 132.154689 -236.284196)
			(xy 132.174637 -236.237376) (xy 132.201838 -236.194362) (xy 132.235586 -236.156268) (xy 132.275008 -236.124081)
			(xy 132.319082 -236.098635) (xy 132.366668 -236.080588) (xy 132.416532 -236.070408) (xy 132.467384 -236.068359)
			(xy 132.517905 -236.074493) (xy 132.566789 -236.088653) (xy 132.612768 -236.11047) (xy 132.654652 -236.13938)
			(xy 132.691356 -236.174635) (xy 132.721929 -236.215321) (xy 132.74558 -236.260384) (xy 132.761696 -236.308658)
			(xy 132.76986 -236.358892) (xy 132.770372 -236.384338) (xy 133.0889 -236.384338) (xy 133.09286 -236.335284)
			(xy 133.104637 -236.2875) (xy 133.123928 -236.242224) (xy 133.150231 -236.200628) (xy 133.182866 -236.163791)
			(xy 133.220987 -236.132666) (xy 133.263608 -236.108059) (xy 133.309624 -236.090607) (xy 133.357843 -236.080763)
			(xy 133.407018 -236.078782) (xy 133.455873 -236.084714) (xy 133.503144 -236.098406) (xy 133.547606 -236.119504)
			(xy 133.588109 -236.14746) (xy 133.623602 -236.181552) (xy 133.653167 -236.220896) (xy 133.676038 -236.264473)
			(xy 133.691622 -236.311154) (xy 133.699517 -236.359731) (xy 133.700012 -236.384338) (xy 134.018523 -236.384338)
			(xy 134.022618 -236.33361) (xy 134.034797 -236.284196) (xy 134.054745 -236.237376) (xy 134.081946 -236.194362)
			(xy 134.115694 -236.156268) (xy 134.155116 -236.124081) (xy 134.19919 -236.098635) (xy 134.246776 -236.080588)
			(xy 134.29664 -236.070408) (xy 134.347492 -236.068359) (xy 134.398013 -236.074493) (xy 134.446897 -236.088653)
			(xy 134.492876 -236.11047) (xy 134.53476 -236.13938) (xy 134.571464 -236.174635) (xy 134.602037 -236.215321)
			(xy 134.625688 -236.260384) (xy 134.641804 -236.308658) (xy 134.649968 -236.358892) (xy 134.65048 -236.384338)
			(xy 134.969008 -236.384338) (xy 134.972968 -236.335284) (xy 134.984745 -236.2875) (xy 135.004036 -236.242224)
			(xy 135.030339 -236.200628) (xy 135.062974 -236.163791) (xy 135.101095 -236.132666) (xy 135.143716 -236.108059)
			(xy 135.189732 -236.090607) (xy 135.237951 -236.080763) (xy 135.287126 -236.078782) (xy 135.335981 -236.084714)
			(xy 135.383252 -236.098406) (xy 135.427714 -236.119504) (xy 135.468217 -236.14746) (xy 135.50371 -236.181552)
			(xy 135.533275 -236.220896) (xy 135.556146 -236.264473) (xy 135.57173 -236.311154) (xy 135.579625 -236.359731)
			(xy 135.58012 -236.384338) (xy 135.898631 -236.384338) (xy 135.902726 -236.33361) (xy 135.914905 -236.284196)
			(xy 135.934853 -236.237376) (xy 135.962054 -236.194362) (xy 135.995802 -236.156268) (xy 136.035224 -236.124081)
			(xy 136.079298 -236.098635) (xy 136.126884 -236.080588) (xy 136.176748 -236.070408) (xy 136.2276 -236.068359)
			(xy 136.278121 -236.074493) (xy 136.327005 -236.088653) (xy 136.372984 -236.11047) (xy 136.414868 -236.13938)
			(xy 136.451572 -236.174635) (xy 136.482145 -236.215321) (xy 136.505796 -236.260384) (xy 136.521912 -236.308658)
			(xy 136.530076 -236.358892) (xy 136.530588 -236.384338) (xy 136.848862 -236.384338) (xy 136.852822 -236.335284)
			(xy 136.864599 -236.2875) (xy 136.88389 -236.242224) (xy 136.910193 -236.200628) (xy 136.942828 -236.163791)
			(xy 136.980949 -236.132666) (xy 137.02357 -236.108059) (xy 137.069586 -236.090607) (xy 137.117805 -236.080763)
			(xy 137.16698 -236.078782) (xy 137.215835 -236.084714) (xy 137.263106 -236.098406) (xy 137.307568 -236.119504)
			(xy 137.348071 -236.14746) (xy 137.383564 -236.181552) (xy 137.413129 -236.220896) (xy 137.436 -236.264473)
			(xy 137.451584 -236.311154) (xy 137.459479 -236.359731) (xy 137.459974 -236.384338) (xy 137.778485 -236.384338)
			(xy 137.78258 -236.33361) (xy 137.794759 -236.284196) (xy 137.814707 -236.237376) (xy 137.841908 -236.194362)
			(xy 137.875656 -236.156268) (xy 137.915078 -236.124081) (xy 137.959152 -236.098635) (xy 138.006738 -236.080588)
			(xy 138.056602 -236.070408) (xy 138.107454 -236.068359) (xy 138.157975 -236.074493) (xy 138.206859 -236.088653)
			(xy 138.252838 -236.11047) (xy 138.294722 -236.13938) (xy 138.331426 -236.174635) (xy 138.361999 -236.215321)
			(xy 138.38565 -236.260384) (xy 138.401766 -236.308658) (xy 138.40993 -236.358892) (xy 138.410442 -236.384338)
			(xy 138.718539 -236.384338) (xy 138.722634 -236.33361) (xy 138.734813 -236.284196) (xy 138.754761 -236.237376)
			(xy 138.781962 -236.194362) (xy 138.81571 -236.156268) (xy 138.855132 -236.124081) (xy 138.899206 -236.098635)
			(xy 138.946792 -236.080588) (xy 138.996656 -236.070408) (xy 139.047508 -236.068359) (xy 139.098029 -236.074493)
			(xy 139.146913 -236.088653) (xy 139.192892 -236.11047) (xy 139.234776 -236.13938) (xy 139.27148 -236.174635)
			(xy 139.302053 -236.215321) (xy 139.325704 -236.260384) (xy 139.34182 -236.308658) (xy 139.349984 -236.358892)
			(xy 139.350496 -236.384338) (xy 139.669024 -236.384338) (xy 139.672984 -236.335284) (xy 139.684761 -236.2875)
			(xy 139.704052 -236.242224) (xy 139.730355 -236.200628) (xy 139.76299 -236.163791) (xy 139.801111 -236.132666)
			(xy 139.843732 -236.108059) (xy 139.889748 -236.090607) (xy 139.937967 -236.080763) (xy 139.987142 -236.078782)
			(xy 140.035997 -236.084714) (xy 140.083268 -236.098406) (xy 140.12773 -236.119504) (xy 140.168233 -236.14746)
			(xy 140.203726 -236.181552) (xy 140.233291 -236.220896) (xy 140.256162 -236.264473) (xy 140.271746 -236.311154)
			(xy 140.279641 -236.359731) (xy 140.280136 -236.384338) (xy 140.598647 -236.384338) (xy 140.602742 -236.33361)
			(xy 140.614921 -236.284196) (xy 140.634869 -236.237376) (xy 140.66207 -236.194362) (xy 140.695818 -236.156268)
			(xy 140.73524 -236.124081) (xy 140.779314 -236.098635) (xy 140.8269 -236.080588) (xy 140.876764 -236.070408)
			(xy 140.927616 -236.068359) (xy 140.978137 -236.074493) (xy 141.027021 -236.088653) (xy 141.073 -236.11047)
			(xy 141.114884 -236.13938) (xy 141.151588 -236.174635) (xy 141.182161 -236.215321) (xy 141.205812 -236.260384)
			(xy 141.221928 -236.308658) (xy 141.230092 -236.358892) (xy 141.230604 -236.384338) (xy 141.548878 -236.384338)
			(xy 141.552838 -236.335284) (xy 141.564615 -236.2875) (xy 141.583906 -236.242224) (xy 141.610209 -236.200628)
			(xy 141.642844 -236.163791) (xy 141.680965 -236.132666) (xy 141.723586 -236.108059) (xy 141.769602 -236.090607)
			(xy 141.817821 -236.080763) (xy 141.866996 -236.078782) (xy 141.915851 -236.084714) (xy 141.963122 -236.098406)
			(xy 142.007584 -236.119504) (xy 142.048087 -236.14746) (xy 142.08358 -236.181552) (xy 142.113145 -236.220896)
			(xy 142.136016 -236.264473) (xy 142.1516 -236.311154) (xy 142.159495 -236.359731) (xy 142.15999 -236.384338)
			(xy 142.478501 -236.384338) (xy 142.482596 -236.33361) (xy 142.494775 -236.284196) (xy 142.514723 -236.237376)
			(xy 142.541924 -236.194362) (xy 142.575672 -236.156268) (xy 142.615094 -236.124081) (xy 142.659168 -236.098635)
			(xy 142.706754 -236.080588) (xy 142.756618 -236.070408) (xy 142.80747 -236.068359) (xy 142.857991 -236.074493)
			(xy 142.906875 -236.088653) (xy 142.952854 -236.11047) (xy 142.994738 -236.13938) (xy 143.031442 -236.174635)
			(xy 143.062015 -236.215321) (xy 143.085666 -236.260384) (xy 143.101782 -236.308658) (xy 143.109946 -236.358892)
			(xy 143.110458 -236.384338) (xy 143.428986 -236.384338) (xy 143.432946 -236.335284) (xy 143.444723 -236.2875)
			(xy 143.464014 -236.242224) (xy 143.490317 -236.200628) (xy 143.522952 -236.163791) (xy 143.561073 -236.132666)
			(xy 143.603694 -236.108059) (xy 143.64971 -236.090607) (xy 143.697929 -236.080763) (xy 143.747104 -236.078782)
			(xy 143.795959 -236.084714) (xy 143.84323 -236.098406) (xy 143.887692 -236.119504) (xy 143.928195 -236.14746)
			(xy 143.963688 -236.181552) (xy 143.993253 -236.220896) (xy 144.016124 -236.264473) (xy 144.031708 -236.311154)
			(xy 144.039603 -236.359731) (xy 144.040098 -236.384338) (xy 144.039603 -236.408945) (xy 144.031708 -236.457522)
			(xy 144.016124 -236.504203) (xy 143.993253 -236.54778) (xy 143.963688 -236.587124) (xy 143.928195 -236.621216)
			(xy 143.887692 -236.649172) (xy 143.84323 -236.67027) (xy 143.795959 -236.683962) (xy 143.747104 -236.689894)
			(xy 143.697929 -236.687913) (xy 143.64971 -236.678069) (xy 143.603694 -236.660617) (xy 143.561073 -236.63601)
			(xy 143.522952 -236.604885) (xy 143.490317 -236.568048) (xy 143.464014 -236.526452) (xy 143.444723 -236.481176)
			(xy 143.432946 -236.433392) (xy 143.428986 -236.384338) (xy 143.110458 -236.384338) (xy 143.109946 -236.409784)
			(xy 143.101782 -236.460018) (xy 143.085666 -236.508292) (xy 143.062015 -236.553355) (xy 143.031442 -236.594041)
			(xy 142.994738 -236.629296) (xy 142.952854 -236.658206) (xy 142.906875 -236.680023) (xy 142.857991 -236.694183)
			(xy 142.80747 -236.700317) (xy 142.756618 -236.698268) (xy 142.706754 -236.688088) (xy 142.659168 -236.670041)
			(xy 142.615094 -236.644595) (xy 142.575672 -236.612408) (xy 142.541924 -236.574314) (xy 142.514723 -236.5313)
			(xy 142.494775 -236.48448) (xy 142.482596 -236.435066) (xy 142.478501 -236.384338) (xy 142.15999 -236.384338)
			(xy 142.159495 -236.408945) (xy 142.1516 -236.457522) (xy 142.136016 -236.504203) (xy 142.113145 -236.54778)
			(xy 142.08358 -236.587124) (xy 142.048087 -236.621216) (xy 142.007584 -236.649172) (xy 141.963122 -236.67027)
			(xy 141.915851 -236.683962) (xy 141.866996 -236.689894) (xy 141.817821 -236.687913) (xy 141.769602 -236.678069)
			(xy 141.723586 -236.660617) (xy 141.680965 -236.63601) (xy 141.642844 -236.604885) (xy 141.610209 -236.568048)
			(xy 141.583906 -236.526452) (xy 141.564615 -236.481176) (xy 141.552838 -236.433392) (xy 141.548878 -236.384338)
			(xy 141.230604 -236.384338) (xy 141.230092 -236.409784) (xy 141.221928 -236.460018) (xy 141.205812 -236.508292)
			(xy 141.182161 -236.553355) (xy 141.151588 -236.594041) (xy 141.114884 -236.629296) (xy 141.073 -236.658206)
			(xy 141.027021 -236.680023) (xy 140.978137 -236.694183) (xy 140.927616 -236.700317) (xy 140.876764 -236.698268)
			(xy 140.8269 -236.688088) (xy 140.779314 -236.670041) (xy 140.73524 -236.644595) (xy 140.695818 -236.612408)
			(xy 140.66207 -236.574314) (xy 140.634869 -236.5313) (xy 140.614921 -236.48448) (xy 140.602742 -236.435066)
			(xy 140.598647 -236.384338) (xy 140.280136 -236.384338) (xy 140.279641 -236.408945) (xy 140.271746 -236.457522)
			(xy 140.256162 -236.504203) (xy 140.233291 -236.54778) (xy 140.203726 -236.587124) (xy 140.168233 -236.621216)
			(xy 140.12773 -236.649172) (xy 140.083268 -236.67027) (xy 140.035997 -236.683962) (xy 139.987142 -236.689894)
			(xy 139.937967 -236.687913) (xy 139.889748 -236.678069) (xy 139.843732 -236.660617) (xy 139.801111 -236.63601)
			(xy 139.76299 -236.604885) (xy 139.730355 -236.568048) (xy 139.704052 -236.526452) (xy 139.684761 -236.481176)
			(xy 139.672984 -236.433392) (xy 139.669024 -236.384338) (xy 139.350496 -236.384338) (xy 139.349984 -236.409784)
			(xy 139.34182 -236.460018) (xy 139.325704 -236.508292) (xy 139.302053 -236.553355) (xy 139.27148 -236.594041)
			(xy 139.234776 -236.629296) (xy 139.192892 -236.658206) (xy 139.146913 -236.680023) (xy 139.098029 -236.694183)
			(xy 139.047508 -236.700317) (xy 138.996656 -236.698268) (xy 138.946792 -236.688088) (xy 138.899206 -236.670041)
			(xy 138.855132 -236.644595) (xy 138.81571 -236.612408) (xy 138.781962 -236.574314) (xy 138.754761 -236.5313)
			(xy 138.734813 -236.48448) (xy 138.722634 -236.435066) (xy 138.718539 -236.384338) (xy 138.410442 -236.384338)
			(xy 138.40993 -236.409784) (xy 138.401766 -236.460018) (xy 138.38565 -236.508292) (xy 138.361999 -236.553355)
			(xy 138.331426 -236.594041) (xy 138.294722 -236.629296) (xy 138.252838 -236.658206) (xy 138.206859 -236.680023)
			(xy 138.157975 -236.694183) (xy 138.107454 -236.700317) (xy 138.056602 -236.698268) (xy 138.006738 -236.688088)
			(xy 137.959152 -236.670041) (xy 137.915078 -236.644595) (xy 137.875656 -236.612408) (xy 137.841908 -236.574314)
			(xy 137.814707 -236.5313) (xy 137.794759 -236.48448) (xy 137.78258 -236.435066) (xy 137.778485 -236.384338)
			(xy 137.459974 -236.384338) (xy 137.459479 -236.408945) (xy 137.451584 -236.457522) (xy 137.436 -236.504203)
			(xy 137.413129 -236.54778) (xy 137.383564 -236.587124) (xy 137.348071 -236.621216) (xy 137.307568 -236.649172)
			(xy 137.263106 -236.67027) (xy 137.215835 -236.683962) (xy 137.16698 -236.689894) (xy 137.117805 -236.687913)
			(xy 137.069586 -236.678069) (xy 137.02357 -236.660617) (xy 136.980949 -236.63601) (xy 136.942828 -236.604885)
			(xy 136.910193 -236.568048) (xy 136.88389 -236.526452) (xy 136.864599 -236.481176) (xy 136.852822 -236.433392)
			(xy 136.848862 -236.384338) (xy 136.530588 -236.384338) (xy 136.530076 -236.409784) (xy 136.521912 -236.460018)
			(xy 136.505796 -236.508292) (xy 136.482145 -236.553355) (xy 136.451572 -236.594041) (xy 136.414868 -236.629296)
			(xy 136.372984 -236.658206) (xy 136.327005 -236.680023) (xy 136.278121 -236.694183) (xy 136.2276 -236.700317)
			(xy 136.176748 -236.698268) (xy 136.126884 -236.688088) (xy 136.079298 -236.670041) (xy 136.035224 -236.644595)
			(xy 135.995802 -236.612408) (xy 135.962054 -236.574314) (xy 135.934853 -236.5313) (xy 135.914905 -236.48448)
			(xy 135.902726 -236.435066) (xy 135.898631 -236.384338) (xy 135.58012 -236.384338) (xy 135.579625 -236.408945)
			(xy 135.57173 -236.457522) (xy 135.556146 -236.504203) (xy 135.533275 -236.54778) (xy 135.50371 -236.587124)
			(xy 135.468217 -236.621216) (xy 135.427714 -236.649172) (xy 135.383252 -236.67027) (xy 135.335981 -236.683962)
			(xy 135.287126 -236.689894) (xy 135.237951 -236.687913) (xy 135.189732 -236.678069) (xy 135.143716 -236.660617)
			(xy 135.101095 -236.63601) (xy 135.062974 -236.604885) (xy 135.030339 -236.568048) (xy 135.004036 -236.526452)
			(xy 134.984745 -236.481176) (xy 134.972968 -236.433392) (xy 134.969008 -236.384338) (xy 134.65048 -236.384338)
			(xy 134.649968 -236.409784) (xy 134.641804 -236.460018) (xy 134.625688 -236.508292) (xy 134.602037 -236.553355)
			(xy 134.571464 -236.594041) (xy 134.53476 -236.629296) (xy 134.492876 -236.658206) (xy 134.446897 -236.680023)
			(xy 134.398013 -236.694183) (xy 134.347492 -236.700317) (xy 134.29664 -236.698268) (xy 134.246776 -236.688088)
			(xy 134.19919 -236.670041) (xy 134.155116 -236.644595) (xy 134.115694 -236.612408) (xy 134.081946 -236.574314)
			(xy 134.054745 -236.5313) (xy 134.034797 -236.48448) (xy 134.022618 -236.435066) (xy 134.018523 -236.384338)
			(xy 133.700012 -236.384338) (xy 133.699517 -236.408945) (xy 133.691622 -236.457522) (xy 133.676038 -236.504203)
			(xy 133.653167 -236.54778) (xy 133.623602 -236.587124) (xy 133.588109 -236.621216) (xy 133.547606 -236.649172)
			(xy 133.503144 -236.67027) (xy 133.455873 -236.683962) (xy 133.407018 -236.689894) (xy 133.357843 -236.687913)
			(xy 133.309624 -236.678069) (xy 133.263608 -236.660617) (xy 133.220987 -236.63601) (xy 133.182866 -236.604885)
			(xy 133.150231 -236.568048) (xy 133.123928 -236.526452) (xy 133.104637 -236.481176) (xy 133.09286 -236.433392)
			(xy 133.0889 -236.384338) (xy 132.770372 -236.384338) (xy 132.76986 -236.409784) (xy 132.761696 -236.460018)
			(xy 132.74558 -236.508292) (xy 132.721929 -236.553355) (xy 132.691356 -236.594041) (xy 132.654652 -236.629296)
			(xy 132.612768 -236.658206) (xy 132.566789 -236.680023) (xy 132.517905 -236.694183) (xy 132.467384 -236.700317)
			(xy 132.416532 -236.698268) (xy 132.366668 -236.688088) (xy 132.319082 -236.670041) (xy 132.275008 -236.644595)
			(xy 132.235586 -236.612408) (xy 132.201838 -236.574314) (xy 132.174637 -236.5313) (xy 132.154689 -236.48448)
			(xy 132.14251 -236.435066) (xy 132.138415 -236.384338) (xy 131.830572 -236.384338) (xy 131.83006 -236.409784)
			(xy 131.821896 -236.460018) (xy 131.80578 -236.508292) (xy 131.782129 -236.553355) (xy 131.751556 -236.594041)
			(xy 131.714852 -236.629296) (xy 131.672968 -236.658206) (xy 131.626989 -236.680023) (xy 131.578105 -236.694183)
			(xy 131.527584 -236.700317) (xy 131.476732 -236.698268) (xy 131.426868 -236.688088) (xy 131.379282 -236.670041)
			(xy 131.335208 -236.644595) (xy 131.295786 -236.612408) (xy 131.262038 -236.574314) (xy 131.234837 -236.5313)
			(xy 131.214889 -236.48448) (xy 131.20271 -236.435066) (xy 131.198615 -236.384338) (xy 130.880104 -236.384338)
			(xy 130.879609 -236.408945) (xy 130.871714 -236.457522) (xy 130.85613 -236.504203) (xy 130.833259 -236.54778)
			(xy 130.803694 -236.587124) (xy 130.768201 -236.621216) (xy 130.727698 -236.649172) (xy 130.683236 -236.67027)
			(xy 130.635965 -236.683962) (xy 130.58711 -236.689894) (xy 130.537935 -236.687913) (xy 130.489716 -236.678069)
			(xy 130.4437 -236.660617) (xy 130.401079 -236.63601) (xy 130.362958 -236.604885) (xy 130.330323 -236.568048)
			(xy 130.30402 -236.526452) (xy 130.284729 -236.481176) (xy 130.272952 -236.433392) (xy 130.268992 -236.384338)
			(xy 129.950464 -236.384338) (xy 129.949952 -236.409784) (xy 129.941788 -236.460018) (xy 129.925672 -236.508292)
			(xy 129.902021 -236.553355) (xy 129.871448 -236.594041) (xy 129.834744 -236.629296) (xy 129.79286 -236.658206)
			(xy 129.746881 -236.680023) (xy 129.697997 -236.694183) (xy 129.647476 -236.700317) (xy 129.596624 -236.698268)
			(xy 129.54676 -236.688088) (xy 129.499174 -236.670041) (xy 129.4551 -236.644595) (xy 129.415678 -236.612408)
			(xy 129.38193 -236.574314) (xy 129.354729 -236.5313) (xy 129.334781 -236.48448) (xy 129.322602 -236.435066)
			(xy 129.318507 -236.384338) (xy 128.999996 -236.384338) (xy 128.999501 -236.408945) (xy 128.991606 -236.457522)
			(xy 128.976022 -236.504203) (xy 128.953151 -236.54778) (xy 128.923586 -236.587124) (xy 128.888093 -236.621216)
			(xy 128.84759 -236.649172) (xy 128.803128 -236.67027) (xy 128.755857 -236.683962) (xy 128.707002 -236.689894)
			(xy 128.657827 -236.687913) (xy 128.609608 -236.678069) (xy 128.563592 -236.660617) (xy 128.520971 -236.63601)
			(xy 128.48285 -236.604885) (xy 128.450215 -236.568048) (xy 128.423912 -236.526452) (xy 128.404621 -236.481176)
			(xy 128.392844 -236.433392) (xy 128.388884 -236.384338) (xy 128.069797 -236.384338) (xy 128.069797 -236.409105)
			(xy 128.062037 -236.458104) (xy 128.046708 -236.505286) (xy 128.024187 -236.549489) (xy 127.995029 -236.589626)
			(xy 127.959952 -236.624707) (xy 127.919818 -236.653869) (xy 127.875617 -236.676395) (xy 127.828437 -236.691729)
			(xy 127.779439 -236.699495) (xy 127.754634 -236.70006) (xy 127.732953 -236.699645) (xy 127.690005 -236.69365)
			(xy 127.669036 -236.688122) (xy 127.662432 -236.68609) (xy 127.65532 -236.68609) (xy 127.645295 -236.686506)
			(xy 127.62677 -236.694172) (xy 127.612589 -236.708345) (xy 127.604912 -236.726866) (xy 127.60452 -236.73689)
			(xy 127.60452 -236.755178) (xy 127.607314 -236.763052) (xy 127.622677 -236.809376) (xy 127.647394 -236.903801)
			(xy 127.665144 -236.99978) (xy 127.67583 -237.0968) (xy 127.679396 -237.194342) (xy 127.679396 -237.194344)
			(xy 127.908553 -237.194344) (xy 127.912648 -237.143616) (xy 127.924827 -237.094202) (xy 127.944775 -237.047382)
			(xy 127.971976 -237.004368) (xy 128.005724 -236.966274) (xy 128.045146 -236.934087) (xy 128.08922 -236.908641)
			(xy 128.136806 -236.890594) (xy 128.18667 -236.880414) (xy 128.237522 -236.878365) (xy 128.288043 -236.884499)
			(xy 128.336927 -236.898659) (xy 128.382906 -236.920476) (xy 128.42479 -236.949386) (xy 128.461494 -236.984641)
			(xy 128.492067 -237.025327) (xy 128.515718 -237.07039) (xy 128.531834 -237.118664) (xy 128.539998 -237.168898)
			(xy 128.54051 -237.194344) (xy 128.848607 -237.194344) (xy 128.852702 -237.143616) (xy 128.864881 -237.094202)
			(xy 128.884829 -237.047382) (xy 128.91203 -237.004368) (xy 128.945778 -236.966274) (xy 128.9852 -236.934087)
			(xy 129.029274 -236.908641) (xy 129.07686 -236.890594) (xy 129.126724 -236.880414) (xy 129.177576 -236.878365)
			(xy 129.228097 -236.884499) (xy 129.276981 -236.898659) (xy 129.32296 -236.920476) (xy 129.364844 -236.949386)
			(xy 129.401548 -236.984641) (xy 129.432121 -237.025327) (xy 129.455772 -237.07039) (xy 129.471888 -237.118664)
			(xy 129.480052 -237.168898) (xy 129.480564 -237.194344) (xy 130.728461 -237.194344) (xy 130.732556 -237.143616)
			(xy 130.744735 -237.094202) (xy 130.764683 -237.047382) (xy 130.791884 -237.004368) (xy 130.825632 -236.966274)
			(xy 130.865054 -236.934087) (xy 130.909128 -236.908641) (xy 130.956714 -236.890594) (xy 131.006578 -236.880414)
			(xy 131.05743 -236.878365) (xy 131.107951 -236.884499) (xy 131.156835 -236.898659) (xy 131.202814 -236.920476)
			(xy 131.244698 -236.949386) (xy 131.281402 -236.984641) (xy 131.311975 -237.025327) (xy 131.335626 -237.07039)
			(xy 131.351742 -237.118664) (xy 131.359906 -237.168898) (xy 131.360418 -237.194344) (xy 131.678946 -237.194344)
			(xy 131.682906 -237.14529) (xy 131.694683 -237.097506) (xy 131.713974 -237.05223) (xy 131.740277 -237.010634)
			(xy 131.772912 -236.973797) (xy 131.811033 -236.942672) (xy 131.853654 -236.918065) (xy 131.89967 -236.900613)
			(xy 131.947889 -236.890769) (xy 131.997064 -236.888788) (xy 132.045919 -236.89472) (xy 132.09319 -236.908412)
			(xy 132.137652 -236.92951) (xy 132.178155 -236.957466) (xy 132.213648 -236.991558) (xy 132.243213 -237.030902)
			(xy 132.266084 -237.074479) (xy 132.281668 -237.12116) (xy 132.289563 -237.169737) (xy 132.290058 -237.194344)
			(xy 132.608569 -237.194344) (xy 132.612664 -237.143616) (xy 132.624843 -237.094202) (xy 132.644791 -237.047382)
			(xy 132.671992 -237.004368) (xy 132.70574 -236.966274) (xy 132.745162 -236.934087) (xy 132.789236 -236.908641)
			(xy 132.836822 -236.890594) (xy 132.886686 -236.880414) (xy 132.937538 -236.878365) (xy 132.988059 -236.884499)
			(xy 133.036943 -236.898659) (xy 133.082922 -236.920476) (xy 133.124806 -236.949386) (xy 133.16151 -236.984641)
			(xy 133.192083 -237.025327) (xy 133.215734 -237.07039) (xy 133.23185 -237.118664) (xy 133.240014 -237.168898)
			(xy 133.240526 -237.194344) (xy 133.559054 -237.194344) (xy 133.563014 -237.14529) (xy 133.574791 -237.097506)
			(xy 133.594082 -237.05223) (xy 133.620385 -237.010634) (xy 133.65302 -236.973797) (xy 133.691141 -236.942672)
			(xy 133.733762 -236.918065) (xy 133.779778 -236.900613) (xy 133.827997 -236.890769) (xy 133.877172 -236.888788)
			(xy 133.926027 -236.89472) (xy 133.973298 -236.908412) (xy 134.01776 -236.92951) (xy 134.058263 -236.957466)
			(xy 134.093756 -236.991558) (xy 134.123321 -237.030902) (xy 134.146192 -237.074479) (xy 134.161776 -237.12116)
			(xy 134.169671 -237.169737) (xy 134.170166 -237.194344) (xy 134.488423 -237.194344) (xy 134.492518 -237.143616)
			(xy 134.504697 -237.094202) (xy 134.524645 -237.047382) (xy 134.551846 -237.004368) (xy 134.585594 -236.966274)
			(xy 134.625016 -236.934087) (xy 134.66909 -236.908641) (xy 134.716676 -236.890594) (xy 134.76654 -236.880414)
			(xy 134.817392 -236.878365) (xy 134.867913 -236.884499) (xy 134.916797 -236.898659) (xy 134.962776 -236.920476)
			(xy 135.00466 -236.949386) (xy 135.041364 -236.984641) (xy 135.071937 -237.025327) (xy 135.095588 -237.07039)
			(xy 135.111704 -237.118664) (xy 135.119868 -237.168898) (xy 135.12038 -237.194344) (xy 135.428477 -237.194344)
			(xy 135.432572 -237.143616) (xy 135.444751 -237.094202) (xy 135.464699 -237.047382) (xy 135.4919 -237.004368)
			(xy 135.525648 -236.966274) (xy 135.56507 -236.934087) (xy 135.609144 -236.908641) (xy 135.65673 -236.890594)
			(xy 135.706594 -236.880414) (xy 135.757446 -236.878365) (xy 135.807967 -236.884499) (xy 135.856851 -236.898659)
			(xy 135.90283 -236.920476) (xy 135.944714 -236.949386) (xy 135.981418 -236.984641) (xy 136.011991 -237.025327)
			(xy 136.035642 -237.07039) (xy 136.051758 -237.118664) (xy 136.059922 -237.168898) (xy 136.060434 -237.194344)
			(xy 137.308585 -237.194344) (xy 137.31268 -237.143616) (xy 137.324859 -237.094202) (xy 137.344807 -237.047382)
			(xy 137.372008 -237.004368) (xy 137.405756 -236.966274) (xy 137.445178 -236.934087) (xy 137.489252 -236.908641)
			(xy 137.536838 -236.890594) (xy 137.586702 -236.880414) (xy 137.637554 -236.878365) (xy 137.688075 -236.884499)
			(xy 137.736959 -236.898659) (xy 137.782938 -236.920476) (xy 137.824822 -236.949386) (xy 137.861526 -236.984641)
			(xy 137.892099 -237.025327) (xy 137.91575 -237.07039) (xy 137.931866 -237.118664) (xy 137.94003 -237.168898)
			(xy 137.940542 -237.194344) (xy 138.25907 -237.194344) (xy 138.26303 -237.14529) (xy 138.274807 -237.097506)
			(xy 138.294098 -237.05223) (xy 138.320401 -237.010634) (xy 138.353036 -236.973797) (xy 138.391157 -236.942672)
			(xy 138.433778 -236.918065) (xy 138.479794 -236.900613) (xy 138.528013 -236.890769) (xy 138.577188 -236.888788)
			(xy 138.626043 -236.89472) (xy 138.673314 -236.908412) (xy 138.717776 -236.92951) (xy 138.758279 -236.957466)
			(xy 138.793772 -236.991558) (xy 138.823337 -237.030902) (xy 138.846208 -237.074479) (xy 138.861792 -237.12116)
			(xy 138.869687 -237.169737) (xy 138.870182 -237.194344) (xy 139.188439 -237.194344) (xy 139.192534 -237.143616)
			(xy 139.204713 -237.094202) (xy 139.224661 -237.047382) (xy 139.251862 -237.004368) (xy 139.28561 -236.966274)
			(xy 139.325032 -236.934087) (xy 139.369106 -236.908641) (xy 139.416692 -236.890594) (xy 139.466556 -236.880414)
			(xy 139.517408 -236.878365) (xy 139.567929 -236.884499) (xy 139.616813 -236.898659) (xy 139.662792 -236.920476)
			(xy 139.704676 -236.949386) (xy 139.74138 -236.984641) (xy 139.771953 -237.025327) (xy 139.795604 -237.07039)
			(xy 139.81172 -237.118664) (xy 139.819884 -237.168898) (xy 139.820396 -237.194344) (xy 140.138924 -237.194344)
			(xy 140.142884 -237.14529) (xy 140.154661 -237.097506) (xy 140.173952 -237.05223) (xy 140.200255 -237.010634)
			(xy 140.23289 -236.973797) (xy 140.271011 -236.942672) (xy 140.313632 -236.918065) (xy 140.359648 -236.900613)
			(xy 140.407867 -236.890769) (xy 140.457042 -236.888788) (xy 140.505897 -236.89472) (xy 140.553168 -236.908412)
			(xy 140.59763 -236.92951) (xy 140.638133 -236.957466) (xy 140.673626 -236.991558) (xy 140.703191 -237.030902)
			(xy 140.726062 -237.074479) (xy 140.741646 -237.12116) (xy 140.749541 -237.169737) (xy 140.750036 -237.194344)
			(xy 141.068547 -237.194344) (xy 141.072642 -237.143616) (xy 141.084821 -237.094202) (xy 141.104769 -237.047382)
			(xy 141.13197 -237.004368) (xy 141.165718 -236.966274) (xy 141.20514 -236.934087) (xy 141.249214 -236.908641)
			(xy 141.2968 -236.890594) (xy 141.346664 -236.880414) (xy 141.397516 -236.878365) (xy 141.448037 -236.884499)
			(xy 141.496921 -236.898659) (xy 141.5429 -236.920476) (xy 141.584784 -236.949386) (xy 141.621488 -236.984641)
			(xy 141.652061 -237.025327) (xy 141.675712 -237.07039) (xy 141.691828 -237.118664) (xy 141.699992 -237.168898)
			(xy 141.700504 -237.194344) (xy 142.008601 -237.194344) (xy 142.012696 -237.143616) (xy 142.024875 -237.094202)
			(xy 142.044823 -237.047382) (xy 142.072024 -237.004368) (xy 142.105772 -236.966274) (xy 142.145194 -236.934087)
			(xy 142.189268 -236.908641) (xy 142.236854 -236.890594) (xy 142.286718 -236.880414) (xy 142.33757 -236.878365)
			(xy 142.388091 -236.884499) (xy 142.436975 -236.898659) (xy 142.482954 -236.920476) (xy 142.524838 -236.949386)
			(xy 142.561542 -236.984641) (xy 142.592115 -237.025327) (xy 142.615766 -237.07039) (xy 142.631882 -237.118664)
			(xy 142.640046 -237.168898) (xy 142.640558 -237.194344) (xy 144.83894 -237.194344) (xy 144.8429 -237.14529)
			(xy 144.854677 -237.097506) (xy 144.873968 -237.05223) (xy 144.900271 -237.010634) (xy 144.932906 -236.973797)
			(xy 144.971027 -236.942672) (xy 145.013648 -236.918065) (xy 145.059664 -236.900613) (xy 145.107883 -236.890769)
			(xy 145.157058 -236.888788) (xy 145.205913 -236.89472) (xy 145.253184 -236.908412) (xy 145.297646 -236.92951)
			(xy 145.338149 -236.957466) (xy 145.373642 -236.991558) (xy 145.403207 -237.030902) (xy 145.426078 -237.074479)
			(xy 145.441662 -237.12116) (xy 145.449557 -237.169737) (xy 145.450052 -237.194344) (xy 145.449557 -237.218951)
			(xy 145.441662 -237.267528) (xy 145.426078 -237.314209) (xy 145.403207 -237.357786) (xy 145.373642 -237.39713)
			(xy 145.338149 -237.431222) (xy 145.297646 -237.459178) (xy 145.253184 -237.480276) (xy 145.205913 -237.493968)
			(xy 145.157058 -237.4999) (xy 145.107883 -237.497919) (xy 145.059664 -237.488075) (xy 145.013648 -237.470623)
			(xy 144.971027 -237.446016) (xy 144.932906 -237.414891) (xy 144.900271 -237.378054) (xy 144.873968 -237.336458)
			(xy 144.854677 -237.291182) (xy 144.8429 -237.243398) (xy 144.83894 -237.194344) (xy 142.640558 -237.194344)
			(xy 142.640046 -237.21979) (xy 142.631882 -237.270024) (xy 142.615766 -237.318298) (xy 142.592115 -237.363361)
			(xy 142.561542 -237.404047) (xy 142.524838 -237.439302) (xy 142.482954 -237.468212) (xy 142.436975 -237.490029)
			(xy 142.388091 -237.504189) (xy 142.33757 -237.510323) (xy 142.286718 -237.508274) (xy 142.236854 -237.498094)
			(xy 142.189268 -237.480047) (xy 142.145194 -237.454601) (xy 142.105772 -237.422414) (xy 142.072024 -237.38432)
			(xy 142.044823 -237.341306) (xy 142.024875 -237.294486) (xy 142.012696 -237.245072) (xy 142.008601 -237.194344)
			(xy 141.700504 -237.194344) (xy 141.699992 -237.21979) (xy 141.691828 -237.270024) (xy 141.675712 -237.318298)
			(xy 141.652061 -237.363361) (xy 141.621488 -237.404047) (xy 141.584784 -237.439302) (xy 141.5429 -237.468212)
			(xy 141.496921 -237.490029) (xy 141.448037 -237.504189) (xy 141.397516 -237.510323) (xy 141.346664 -237.508274)
			(xy 141.2968 -237.498094) (xy 141.249214 -237.480047) (xy 141.20514 -237.454601) (xy 141.165718 -237.422414)
			(xy 141.13197 -237.38432) (xy 141.104769 -237.341306) (xy 141.084821 -237.294486) (xy 141.072642 -237.245072)
			(xy 141.068547 -237.194344) (xy 140.750036 -237.194344) (xy 140.749541 -237.218951) (xy 140.741646 -237.267528)
			(xy 140.726062 -237.314209) (xy 140.703191 -237.357786) (xy 140.673626 -237.39713) (xy 140.638133 -237.431222)
			(xy 140.59763 -237.459178) (xy 140.553168 -237.480276) (xy 140.505897 -237.493968) (xy 140.457042 -237.4999)
			(xy 140.407867 -237.497919) (xy 140.359648 -237.488075) (xy 140.313632 -237.470623) (xy 140.271011 -237.446016)
			(xy 140.23289 -237.414891) (xy 140.200255 -237.378054) (xy 140.173952 -237.336458) (xy 140.154661 -237.291182)
			(xy 140.142884 -237.243398) (xy 140.138924 -237.194344) (xy 139.820396 -237.194344) (xy 139.819884 -237.21979)
			(xy 139.81172 -237.270024) (xy 139.795604 -237.318298) (xy 139.771953 -237.363361) (xy 139.74138 -237.404047)
			(xy 139.704676 -237.439302) (xy 139.662792 -237.468212) (xy 139.616813 -237.490029) (xy 139.567929 -237.504189)
			(xy 139.517408 -237.510323) (xy 139.466556 -237.508274) (xy 139.416692 -237.498094) (xy 139.369106 -237.480047)
			(xy 139.325032 -237.454601) (xy 139.28561 -237.422414) (xy 139.251862 -237.38432) (xy 139.224661 -237.341306)
			(xy 139.204713 -237.294486) (xy 139.192534 -237.245072) (xy 139.188439 -237.194344) (xy 138.870182 -237.194344)
			(xy 138.869687 -237.218951) (xy 138.861792 -237.267528) (xy 138.846208 -237.314209) (xy 138.823337 -237.357786)
			(xy 138.793772 -237.39713) (xy 138.758279 -237.431222) (xy 138.717776 -237.459178) (xy 138.673314 -237.480276)
			(xy 138.626043 -237.493968) (xy 138.577188 -237.4999) (xy 138.528013 -237.497919) (xy 138.479794 -237.488075)
			(xy 138.433778 -237.470623) (xy 138.391157 -237.446016) (xy 138.353036 -237.414891) (xy 138.320401 -237.378054)
			(xy 138.294098 -237.336458) (xy 138.274807 -237.291182) (xy 138.26303 -237.243398) (xy 138.25907 -237.194344)
			(xy 137.940542 -237.194344) (xy 137.94003 -237.21979) (xy 137.931866 -237.270024) (xy 137.91575 -237.318298)
			(xy 137.892099 -237.363361) (xy 137.861526 -237.404047) (xy 137.824822 -237.439302) (xy 137.782938 -237.468212)
			(xy 137.736959 -237.490029) (xy 137.688075 -237.504189) (xy 137.637554 -237.510323) (xy 137.586702 -237.508274)
			(xy 137.536838 -237.498094) (xy 137.489252 -237.480047) (xy 137.445178 -237.454601) (xy 137.405756 -237.422414)
			(xy 137.372008 -237.38432) (xy 137.344807 -237.341306) (xy 137.324859 -237.294486) (xy 137.31268 -237.245072)
			(xy 137.308585 -237.194344) (xy 136.060434 -237.194344) (xy 136.059922 -237.21979) (xy 136.051758 -237.270024)
			(xy 136.035642 -237.318298) (xy 136.011991 -237.363361) (xy 135.981418 -237.404047) (xy 135.944714 -237.439302)
			(xy 135.90283 -237.468212) (xy 135.856851 -237.490029) (xy 135.807967 -237.504189) (xy 135.757446 -237.510323)
			(xy 135.706594 -237.508274) (xy 135.65673 -237.498094) (xy 135.609144 -237.480047) (xy 135.56507 -237.454601)
			(xy 135.525648 -237.422414) (xy 135.4919 -237.38432) (xy 135.464699 -237.341306) (xy 135.444751 -237.294486)
			(xy 135.432572 -237.245072) (xy 135.428477 -237.194344) (xy 135.12038 -237.194344) (xy 135.119868 -237.21979)
			(xy 135.111704 -237.270024) (xy 135.095588 -237.318298) (xy 135.071937 -237.363361) (xy 135.041364 -237.404047)
			(xy 135.00466 -237.439302) (xy 134.962776 -237.468212) (xy 134.916797 -237.490029) (xy 134.867913 -237.504189)
			(xy 134.817392 -237.510323) (xy 134.76654 -237.508274) (xy 134.716676 -237.498094) (xy 134.66909 -237.480047)
			(xy 134.625016 -237.454601) (xy 134.585594 -237.422414) (xy 134.551846 -237.38432) (xy 134.524645 -237.341306)
			(xy 134.504697 -237.294486) (xy 134.492518 -237.245072) (xy 134.488423 -237.194344) (xy 134.170166 -237.194344)
			(xy 134.169671 -237.218951) (xy 134.161776 -237.267528) (xy 134.146192 -237.314209) (xy 134.123321 -237.357786)
			(xy 134.093756 -237.39713) (xy 134.058263 -237.431222) (xy 134.01776 -237.459178) (xy 133.973298 -237.480276)
			(xy 133.926027 -237.493968) (xy 133.877172 -237.4999) (xy 133.827997 -237.497919) (xy 133.779778 -237.488075)
			(xy 133.733762 -237.470623) (xy 133.691141 -237.446016) (xy 133.65302 -237.414891) (xy 133.620385 -237.378054)
			(xy 133.594082 -237.336458) (xy 133.574791 -237.291182) (xy 133.563014 -237.243398) (xy 133.559054 -237.194344)
			(xy 133.240526 -237.194344) (xy 133.240014 -237.21979) (xy 133.23185 -237.270024) (xy 133.215734 -237.318298)
			(xy 133.192083 -237.363361) (xy 133.16151 -237.404047) (xy 133.124806 -237.439302) (xy 133.082922 -237.468212)
			(xy 133.036943 -237.490029) (xy 132.988059 -237.504189) (xy 132.937538 -237.510323) (xy 132.886686 -237.508274)
			(xy 132.836822 -237.498094) (xy 132.789236 -237.480047) (xy 132.745162 -237.454601) (xy 132.70574 -237.422414)
			(xy 132.671992 -237.38432) (xy 132.644791 -237.341306) (xy 132.624843 -237.294486) (xy 132.612664 -237.245072)
			(xy 132.608569 -237.194344) (xy 132.290058 -237.194344) (xy 132.289563 -237.218951) (xy 132.281668 -237.267528)
			(xy 132.266084 -237.314209) (xy 132.243213 -237.357786) (xy 132.213648 -237.39713) (xy 132.178155 -237.431222)
			(xy 132.137652 -237.459178) (xy 132.09319 -237.480276) (xy 132.045919 -237.493968) (xy 131.997064 -237.4999)
			(xy 131.947889 -237.497919) (xy 131.89967 -237.488075) (xy 131.853654 -237.470623) (xy 131.811033 -237.446016)
			(xy 131.772912 -237.414891) (xy 131.740277 -237.378054) (xy 131.713974 -237.336458) (xy 131.694683 -237.291182)
			(xy 131.682906 -237.243398) (xy 131.678946 -237.194344) (xy 131.360418 -237.194344) (xy 131.359906 -237.21979)
			(xy 131.351742 -237.270024) (xy 131.335626 -237.318298) (xy 131.311975 -237.363361) (xy 131.281402 -237.404047)
			(xy 131.244698 -237.439302) (xy 131.202814 -237.468212) (xy 131.156835 -237.490029) (xy 131.107951 -237.504189)
			(xy 131.05743 -237.510323) (xy 131.006578 -237.508274) (xy 130.956714 -237.498094) (xy 130.909128 -237.480047)
			(xy 130.865054 -237.454601) (xy 130.825632 -237.422414) (xy 130.791884 -237.38432) (xy 130.764683 -237.341306)
			(xy 130.744735 -237.294486) (xy 130.732556 -237.245072) (xy 130.728461 -237.194344) (xy 129.480564 -237.194344)
			(xy 129.480052 -237.21979) (xy 129.471888 -237.270024) (xy 129.455772 -237.318298) (xy 129.432121 -237.363361)
			(xy 129.401548 -237.404047) (xy 129.364844 -237.439302) (xy 129.32296 -237.468212) (xy 129.276981 -237.490029)
			(xy 129.228097 -237.504189) (xy 129.177576 -237.510323) (xy 129.126724 -237.508274) (xy 129.07686 -237.498094)
			(xy 129.029274 -237.480047) (xy 128.9852 -237.454601) (xy 128.945778 -237.422414) (xy 128.91203 -237.38432)
			(xy 128.884829 -237.341306) (xy 128.864881 -237.294486) (xy 128.852702 -237.245072) (xy 128.848607 -237.194344)
			(xy 128.54051 -237.194344) (xy 128.539998 -237.21979) (xy 128.531834 -237.270024) (xy 128.515718 -237.318298)
			(xy 128.492067 -237.363361) (xy 128.461494 -237.404047) (xy 128.42479 -237.439302) (xy 128.382906 -237.468212)
			(xy 128.336927 -237.490029) (xy 128.288043 -237.504189) (xy 128.237522 -237.510323) (xy 128.18667 -237.508274)
			(xy 128.136806 -237.498094) (xy 128.08922 -237.480047) (xy 128.045146 -237.454601) (xy 128.005724 -237.422414)
			(xy 127.971976 -237.38432) (xy 127.944775 -237.341306) (xy 127.924827 -237.294486) (xy 127.912648 -237.245072)
			(xy 127.908553 -237.194344) (xy 127.679396 -237.194344) (xy 127.675824 -237.291883) (xy 127.665131 -237.388902)
			(xy 127.647376 -237.48488) (xy 127.622653 -237.579304) (xy 127.607314 -237.625636) (xy 127.60452 -237.63351)
			(xy 127.60452 -237.651798) (xy 127.60494 -237.661818) (xy 127.61261 -237.680332) (xy 127.626783 -237.6945)
			(xy 127.6453 -237.702164) (xy 127.65532 -237.702598) (xy 127.662432 -237.702598) (xy 127.669036 -237.700566)
			(xy 127.689997 -237.694999) (xy 127.73295 -237.689013) (xy 127.754634 -237.688628) (xy 127.779438 -237.689117)
			(xy 127.828434 -237.696882) (xy 127.875613 -237.712216) (xy 127.919812 -237.734741) (xy 127.959944 -237.763902)
			(xy 127.99502 -237.798982) (xy 128.024177 -237.839117) (xy 128.046697 -237.883319) (xy 128.062026 -237.930499)
			(xy 128.069786 -237.979496) (xy 128.069786 -238.00435) (xy 128.388884 -238.00435) (xy 128.392844 -237.955296)
			(xy 128.404621 -237.907512) (xy 128.423912 -237.862236) (xy 128.450215 -237.82064) (xy 128.48285 -237.783803)
			(xy 128.520971 -237.752678) (xy 128.563592 -237.728071) (xy 128.609608 -237.710619) (xy 128.657827 -237.700775)
			(xy 128.707002 -237.698794) (xy 128.755857 -237.704726) (xy 128.803128 -237.718418) (xy 128.84759 -237.739516)
			(xy 128.888093 -237.767472) (xy 128.923586 -237.801564) (xy 128.953151 -237.840908) (xy 128.976022 -237.884485)
			(xy 128.991606 -237.931166) (xy 128.999501 -237.979743) (xy 128.999996 -238.00435) (xy 129.318507 -238.00435)
			(xy 129.322602 -237.953622) (xy 129.334781 -237.904208) (xy 129.354729 -237.857388) (xy 129.38193 -237.814374)
			(xy 129.415678 -237.77628) (xy 129.4551 -237.744093) (xy 129.499174 -237.718647) (xy 129.54676 -237.7006)
			(xy 129.596624 -237.69042) (xy 129.647476 -237.688371) (xy 129.697997 -237.694505) (xy 129.746881 -237.708665)
			(xy 129.79286 -237.730482) (xy 129.834744 -237.759392) (xy 129.871448 -237.794647) (xy 129.902021 -237.835333)
			(xy 129.925672 -237.880396) (xy 129.941788 -237.92867) (xy 129.949952 -237.978904) (xy 129.950464 -238.00435)
			(xy 130.268992 -238.00435) (xy 130.272952 -237.955296) (xy 130.284729 -237.907512) (xy 130.30402 -237.862236)
			(xy 130.330323 -237.82064) (xy 130.362958 -237.783803) (xy 130.401079 -237.752678) (xy 130.4437 -237.728071)
			(xy 130.489716 -237.710619) (xy 130.537935 -237.700775) (xy 130.58711 -237.698794) (xy 130.635965 -237.704726)
			(xy 130.683236 -237.718418) (xy 130.727698 -237.739516) (xy 130.768201 -237.767472) (xy 130.803694 -237.801564)
			(xy 130.833259 -237.840908) (xy 130.85613 -237.884485) (xy 130.871714 -237.931166) (xy 130.879609 -237.979743)
			(xy 130.880104 -238.00435) (xy 131.198615 -238.00435) (xy 131.20271 -237.953622) (xy 131.214889 -237.904208)
			(xy 131.234837 -237.857388) (xy 131.262038 -237.814374) (xy 131.295786 -237.77628) (xy 131.335208 -237.744093)
			(xy 131.379282 -237.718647) (xy 131.426868 -237.7006) (xy 131.476732 -237.69042) (xy 131.527584 -237.688371)
			(xy 131.578105 -237.694505) (xy 131.626989 -237.708665) (xy 131.672968 -237.730482) (xy 131.714852 -237.759392)
			(xy 131.751556 -237.794647) (xy 131.782129 -237.835333) (xy 131.80578 -237.880396) (xy 131.821896 -237.92867)
			(xy 131.83006 -237.978904) (xy 131.830572 -238.00435) (xy 132.138415 -238.00435) (xy 132.14251 -237.953622)
			(xy 132.154689 -237.904208) (xy 132.174637 -237.857388) (xy 132.201838 -237.814374) (xy 132.235586 -237.77628)
			(xy 132.275008 -237.744093) (xy 132.319082 -237.718647) (xy 132.366668 -237.7006) (xy 132.416532 -237.69042)
			(xy 132.467384 -237.688371) (xy 132.517905 -237.694505) (xy 132.566789 -237.708665) (xy 132.612768 -237.730482)
			(xy 132.654652 -237.759392) (xy 132.691356 -237.794647) (xy 132.721929 -237.835333) (xy 132.74558 -237.880396)
			(xy 132.761696 -237.92867) (xy 132.76986 -237.978904) (xy 132.770372 -238.00435) (xy 133.0889 -238.00435)
			(xy 133.09286 -237.955296) (xy 133.104637 -237.907512) (xy 133.123928 -237.862236) (xy 133.150231 -237.82064)
			(xy 133.182866 -237.783803) (xy 133.220987 -237.752678) (xy 133.263608 -237.728071) (xy 133.309624 -237.710619)
			(xy 133.357843 -237.700775) (xy 133.407018 -237.698794) (xy 133.455873 -237.704726) (xy 133.503144 -237.718418)
			(xy 133.547606 -237.739516) (xy 133.588109 -237.767472) (xy 133.623602 -237.801564) (xy 133.653167 -237.840908)
			(xy 133.676038 -237.884485) (xy 133.691622 -237.931166) (xy 133.699517 -237.979743) (xy 133.700012 -238.00435)
			(xy 134.018523 -238.00435) (xy 134.022618 -237.953622) (xy 134.034797 -237.904208) (xy 134.054745 -237.857388)
			(xy 134.081946 -237.814374) (xy 134.115694 -237.77628) (xy 134.155116 -237.744093) (xy 134.19919 -237.718647)
			(xy 134.246776 -237.7006) (xy 134.29664 -237.69042) (xy 134.347492 -237.688371) (xy 134.398013 -237.694505)
			(xy 134.446897 -237.708665) (xy 134.492876 -237.730482) (xy 134.53476 -237.759392) (xy 134.571464 -237.794647)
			(xy 134.602037 -237.835333) (xy 134.625688 -237.880396) (xy 134.641804 -237.92867) (xy 134.649968 -237.978904)
			(xy 134.65048 -238.00435) (xy 134.969008 -238.00435) (xy 134.972968 -237.955296) (xy 134.984745 -237.907512)
			(xy 135.004036 -237.862236) (xy 135.030339 -237.82064) (xy 135.062974 -237.783803) (xy 135.101095 -237.752678)
			(xy 135.143716 -237.728071) (xy 135.189732 -237.710619) (xy 135.237951 -237.700775) (xy 135.287126 -237.698794)
			(xy 135.335981 -237.704726) (xy 135.383252 -237.718418) (xy 135.427714 -237.739516) (xy 135.468217 -237.767472)
			(xy 135.50371 -237.801564) (xy 135.533275 -237.840908) (xy 135.556146 -237.884485) (xy 135.57173 -237.931166)
			(xy 135.579625 -237.979743) (xy 135.58012 -238.00435) (xy 135.898631 -238.00435) (xy 135.902726 -237.953622)
			(xy 135.914905 -237.904208) (xy 135.934853 -237.857388) (xy 135.962054 -237.814374) (xy 135.995802 -237.77628)
			(xy 136.035224 -237.744093) (xy 136.079298 -237.718647) (xy 136.126884 -237.7006) (xy 136.176748 -237.69042)
			(xy 136.2276 -237.688371) (xy 136.278121 -237.694505) (xy 136.327005 -237.708665) (xy 136.372984 -237.730482)
			(xy 136.414868 -237.759392) (xy 136.451572 -237.794647) (xy 136.482145 -237.835333) (xy 136.505796 -237.880396)
			(xy 136.521912 -237.92867) (xy 136.530076 -237.978904) (xy 136.530588 -238.00435) (xy 136.848862 -238.00435)
			(xy 136.852822 -237.955296) (xy 136.864599 -237.907512) (xy 136.88389 -237.862236) (xy 136.910193 -237.82064)
			(xy 136.942828 -237.783803) (xy 136.980949 -237.752678) (xy 137.02357 -237.728071) (xy 137.069586 -237.710619)
			(xy 137.117805 -237.700775) (xy 137.16698 -237.698794) (xy 137.215835 -237.704726) (xy 137.263106 -237.718418)
			(xy 137.307568 -237.739516) (xy 137.348071 -237.767472) (xy 137.383564 -237.801564) (xy 137.413129 -237.840908)
			(xy 137.436 -237.884485) (xy 137.451584 -237.931166) (xy 137.459479 -237.979743) (xy 137.459974 -238.00435)
			(xy 137.778485 -238.00435) (xy 137.78258 -237.953622) (xy 137.794759 -237.904208) (xy 137.814707 -237.857388)
			(xy 137.841908 -237.814374) (xy 137.875656 -237.77628) (xy 137.915078 -237.744093) (xy 137.959152 -237.718647)
			(xy 138.006738 -237.7006) (xy 138.056602 -237.69042) (xy 138.107454 -237.688371) (xy 138.157975 -237.694505)
			(xy 138.206859 -237.708665) (xy 138.252838 -237.730482) (xy 138.294722 -237.759392) (xy 138.331426 -237.794647)
			(xy 138.361999 -237.835333) (xy 138.38565 -237.880396) (xy 138.401766 -237.92867) (xy 138.40993 -237.978904)
			(xy 138.410442 -238.00435) (xy 138.718539 -238.00435) (xy 138.722634 -237.953622) (xy 138.734813 -237.904208)
			(xy 138.754761 -237.857388) (xy 138.781962 -237.814374) (xy 138.81571 -237.77628) (xy 138.855132 -237.744093)
			(xy 138.899206 -237.718647) (xy 138.946792 -237.7006) (xy 138.996656 -237.69042) (xy 139.047508 -237.688371)
			(xy 139.098029 -237.694505) (xy 139.146913 -237.708665) (xy 139.192892 -237.730482) (xy 139.234776 -237.759392)
			(xy 139.27148 -237.794647) (xy 139.302053 -237.835333) (xy 139.325704 -237.880396) (xy 139.34182 -237.92867)
			(xy 139.349984 -237.978904) (xy 139.350496 -238.00435) (xy 139.669024 -238.00435) (xy 139.672984 -237.955296)
			(xy 139.684761 -237.907512) (xy 139.704052 -237.862236) (xy 139.730355 -237.82064) (xy 139.76299 -237.783803)
			(xy 139.801111 -237.752678) (xy 139.843732 -237.728071) (xy 139.889748 -237.710619) (xy 139.937967 -237.700775)
			(xy 139.987142 -237.698794) (xy 140.035997 -237.704726) (xy 140.083268 -237.718418) (xy 140.12773 -237.739516)
			(xy 140.168233 -237.767472) (xy 140.203726 -237.801564) (xy 140.233291 -237.840908) (xy 140.256162 -237.884485)
			(xy 140.271746 -237.931166) (xy 140.279641 -237.979743) (xy 140.280136 -238.00435) (xy 140.598647 -238.00435)
			(xy 140.602742 -237.953622) (xy 140.614921 -237.904208) (xy 140.634869 -237.857388) (xy 140.66207 -237.814374)
			(xy 140.695818 -237.77628) (xy 140.73524 -237.744093) (xy 140.779314 -237.718647) (xy 140.8269 -237.7006)
			(xy 140.876764 -237.69042) (xy 140.927616 -237.688371) (xy 140.978137 -237.694505) (xy 141.027021 -237.708665)
			(xy 141.073 -237.730482) (xy 141.114884 -237.759392) (xy 141.151588 -237.794647) (xy 141.182161 -237.835333)
			(xy 141.205812 -237.880396) (xy 141.221928 -237.92867) (xy 141.230092 -237.978904) (xy 141.230604 -238.00435)
			(xy 141.548878 -238.00435) (xy 141.552838 -237.955296) (xy 141.564615 -237.907512) (xy 141.583906 -237.862236)
			(xy 141.610209 -237.82064) (xy 141.642844 -237.783803) (xy 141.680965 -237.752678) (xy 141.723586 -237.728071)
			(xy 141.769602 -237.710619) (xy 141.817821 -237.700775) (xy 141.866996 -237.698794) (xy 141.915851 -237.704726)
			(xy 141.963122 -237.718418) (xy 142.007584 -237.739516) (xy 142.048087 -237.767472) (xy 142.08358 -237.801564)
			(xy 142.113145 -237.840908) (xy 142.136016 -237.884485) (xy 142.1516 -237.931166) (xy 142.159495 -237.979743)
			(xy 142.15999 -238.00435) (xy 142.478501 -238.00435) (xy 142.482596 -237.953622) (xy 142.494775 -237.904208)
			(xy 142.514723 -237.857388) (xy 142.541924 -237.814374) (xy 142.575672 -237.77628) (xy 142.615094 -237.744093)
			(xy 142.659168 -237.718647) (xy 142.706754 -237.7006) (xy 142.756618 -237.69042) (xy 142.80747 -237.688371)
			(xy 142.857991 -237.694505) (xy 142.906875 -237.708665) (xy 142.952854 -237.730482) (xy 142.994738 -237.759392)
			(xy 143.031442 -237.794647) (xy 143.062015 -237.835333) (xy 143.085666 -237.880396) (xy 143.101782 -237.92867)
			(xy 143.109946 -237.978904) (xy 143.110458 -238.00435) (xy 143.428986 -238.00435) (xy 143.432946 -237.955296)
			(xy 143.444723 -237.907512) (xy 143.464014 -237.862236) (xy 143.490317 -237.82064) (xy 143.522952 -237.783803)
			(xy 143.561073 -237.752678) (xy 143.603694 -237.728071) (xy 143.64971 -237.710619) (xy 143.697929 -237.700775)
			(xy 143.747104 -237.698794) (xy 143.795959 -237.704726) (xy 143.84323 -237.718418) (xy 143.887692 -237.739516)
			(xy 143.928195 -237.767472) (xy 143.963688 -237.801564) (xy 143.993253 -237.840908) (xy 144.016124 -237.884485)
			(xy 144.031708 -237.931166) (xy 144.039603 -237.979743) (xy 144.040098 -238.00435) (xy 144.039603 -238.028957)
			(xy 144.031708 -238.077534) (xy 144.016124 -238.124215) (xy 143.993253 -238.167792) (xy 143.963688 -238.207136)
			(xy 143.928195 -238.241228) (xy 143.887692 -238.269184) (xy 143.84323 -238.290282) (xy 143.795959 -238.303974)
			(xy 143.747104 -238.309906) (xy 143.697929 -238.307925) (xy 143.64971 -238.298081) (xy 143.603694 -238.280629)
			(xy 143.561073 -238.256022) (xy 143.522952 -238.224897) (xy 143.490317 -238.18806) (xy 143.464014 -238.146464)
			(xy 143.444723 -238.101188) (xy 143.432946 -238.053404) (xy 143.428986 -238.00435) (xy 143.110458 -238.00435)
			(xy 143.109946 -238.029796) (xy 143.101782 -238.08003) (xy 143.085666 -238.128304) (xy 143.062015 -238.173367)
			(xy 143.031442 -238.214053) (xy 142.994738 -238.249308) (xy 142.952854 -238.278218) (xy 142.906875 -238.300035)
			(xy 142.857991 -238.314195) (xy 142.80747 -238.320329) (xy 142.756618 -238.31828) (xy 142.706754 -238.3081)
			(xy 142.659168 -238.290053) (xy 142.615094 -238.264607) (xy 142.575672 -238.23242) (xy 142.541924 -238.194326)
			(xy 142.514723 -238.151312) (xy 142.494775 -238.104492) (xy 142.482596 -238.055078) (xy 142.478501 -238.00435)
			(xy 142.15999 -238.00435) (xy 142.159495 -238.028957) (xy 142.1516 -238.077534) (xy 142.136016 -238.124215)
			(xy 142.113145 -238.167792) (xy 142.08358 -238.207136) (xy 142.048087 -238.241228) (xy 142.007584 -238.269184)
			(xy 141.963122 -238.290282) (xy 141.915851 -238.303974) (xy 141.866996 -238.309906) (xy 141.817821 -238.307925)
			(xy 141.769602 -238.298081) (xy 141.723586 -238.280629) (xy 141.680965 -238.256022) (xy 141.642844 -238.224897)
			(xy 141.610209 -238.18806) (xy 141.583906 -238.146464) (xy 141.564615 -238.101188) (xy 141.552838 -238.053404)
			(xy 141.548878 -238.00435) (xy 141.230604 -238.00435) (xy 141.230092 -238.029796) (xy 141.221928 -238.08003)
			(xy 141.205812 -238.128304) (xy 141.182161 -238.173367) (xy 141.151588 -238.214053) (xy 141.114884 -238.249308)
			(xy 141.073 -238.278218) (xy 141.027021 -238.300035) (xy 140.978137 -238.314195) (xy 140.927616 -238.320329)
			(xy 140.876764 -238.31828) (xy 140.8269 -238.3081) (xy 140.779314 -238.290053) (xy 140.73524 -238.264607)
			(xy 140.695818 -238.23242) (xy 140.66207 -238.194326) (xy 140.634869 -238.151312) (xy 140.614921 -238.104492)
			(xy 140.602742 -238.055078) (xy 140.598647 -238.00435) (xy 140.280136 -238.00435) (xy 140.279641 -238.028957)
			(xy 140.271746 -238.077534) (xy 140.256162 -238.124215) (xy 140.233291 -238.167792) (xy 140.203726 -238.207136)
			(xy 140.168233 -238.241228) (xy 140.12773 -238.269184) (xy 140.083268 -238.290282) (xy 140.035997 -238.303974)
			(xy 139.987142 -238.309906) (xy 139.937967 -238.307925) (xy 139.889748 -238.298081) (xy 139.843732 -238.280629)
			(xy 139.801111 -238.256022) (xy 139.76299 -238.224897) (xy 139.730355 -238.18806) (xy 139.704052 -238.146464)
			(xy 139.684761 -238.101188) (xy 139.672984 -238.053404) (xy 139.669024 -238.00435) (xy 139.350496 -238.00435)
			(xy 139.349984 -238.029796) (xy 139.34182 -238.08003) (xy 139.325704 -238.128304) (xy 139.302053 -238.173367)
			(xy 139.27148 -238.214053) (xy 139.234776 -238.249308) (xy 139.192892 -238.278218) (xy 139.146913 -238.300035)
			(xy 139.098029 -238.314195) (xy 139.047508 -238.320329) (xy 138.996656 -238.31828) (xy 138.946792 -238.3081)
			(xy 138.899206 -238.290053) (xy 138.855132 -238.264607) (xy 138.81571 -238.23242) (xy 138.781962 -238.194326)
			(xy 138.754761 -238.151312) (xy 138.734813 -238.104492) (xy 138.722634 -238.055078) (xy 138.718539 -238.00435)
			(xy 138.410442 -238.00435) (xy 138.40993 -238.029796) (xy 138.401766 -238.08003) (xy 138.38565 -238.128304)
			(xy 138.361999 -238.173367) (xy 138.331426 -238.214053) (xy 138.294722 -238.249308) (xy 138.252838 -238.278218)
			(xy 138.206859 -238.300035) (xy 138.157975 -238.314195) (xy 138.107454 -238.320329) (xy 138.056602 -238.31828)
			(xy 138.006738 -238.3081) (xy 137.959152 -238.290053) (xy 137.915078 -238.264607) (xy 137.875656 -238.23242)
			(xy 137.841908 -238.194326) (xy 137.814707 -238.151312) (xy 137.794759 -238.104492) (xy 137.78258 -238.055078)
			(xy 137.778485 -238.00435) (xy 137.459974 -238.00435) (xy 137.459479 -238.028957) (xy 137.451584 -238.077534)
			(xy 137.436 -238.124215) (xy 137.413129 -238.167792) (xy 137.383564 -238.207136) (xy 137.348071 -238.241228)
			(xy 137.307568 -238.269184) (xy 137.263106 -238.290282) (xy 137.215835 -238.303974) (xy 137.16698 -238.309906)
			(xy 137.117805 -238.307925) (xy 137.069586 -238.298081) (xy 137.02357 -238.280629) (xy 136.980949 -238.256022)
			(xy 136.942828 -238.224897) (xy 136.910193 -238.18806) (xy 136.88389 -238.146464) (xy 136.864599 -238.101188)
			(xy 136.852822 -238.053404) (xy 136.848862 -238.00435) (xy 136.530588 -238.00435) (xy 136.530076 -238.029796)
			(xy 136.521912 -238.08003) (xy 136.505796 -238.128304) (xy 136.482145 -238.173367) (xy 136.451572 -238.214053)
			(xy 136.414868 -238.249308) (xy 136.372984 -238.278218) (xy 136.327005 -238.300035) (xy 136.278121 -238.314195)
			(xy 136.2276 -238.320329) (xy 136.176748 -238.31828) (xy 136.126884 -238.3081) (xy 136.079298 -238.290053)
			(xy 136.035224 -238.264607) (xy 135.995802 -238.23242) (xy 135.962054 -238.194326) (xy 135.934853 -238.151312)
			(xy 135.914905 -238.104492) (xy 135.902726 -238.055078) (xy 135.898631 -238.00435) (xy 135.58012 -238.00435)
			(xy 135.579625 -238.028957) (xy 135.57173 -238.077534) (xy 135.556146 -238.124215) (xy 135.533275 -238.167792)
			(xy 135.50371 -238.207136) (xy 135.468217 -238.241228) (xy 135.427714 -238.269184) (xy 135.383252 -238.290282)
			(xy 135.335981 -238.303974) (xy 135.287126 -238.309906) (xy 135.237951 -238.307925) (xy 135.189732 -238.298081)
			(xy 135.143716 -238.280629) (xy 135.101095 -238.256022) (xy 135.062974 -238.224897) (xy 135.030339 -238.18806)
			(xy 135.004036 -238.146464) (xy 134.984745 -238.101188) (xy 134.972968 -238.053404) (xy 134.969008 -238.00435)
			(xy 134.65048 -238.00435) (xy 134.649968 -238.029796) (xy 134.641804 -238.08003) (xy 134.625688 -238.128304)
			(xy 134.602037 -238.173367) (xy 134.571464 -238.214053) (xy 134.53476 -238.249308) (xy 134.492876 -238.278218)
			(xy 134.446897 -238.300035) (xy 134.398013 -238.314195) (xy 134.347492 -238.320329) (xy 134.29664 -238.31828)
			(xy 134.246776 -238.3081) (xy 134.19919 -238.290053) (xy 134.155116 -238.264607) (xy 134.115694 -238.23242)
			(xy 134.081946 -238.194326) (xy 134.054745 -238.151312) (xy 134.034797 -238.104492) (xy 134.022618 -238.055078)
			(xy 134.018523 -238.00435) (xy 133.700012 -238.00435) (xy 133.699517 -238.028957) (xy 133.691622 -238.077534)
			(xy 133.676038 -238.124215) (xy 133.653167 -238.167792) (xy 133.623602 -238.207136) (xy 133.588109 -238.241228)
			(xy 133.547606 -238.269184) (xy 133.503144 -238.290282) (xy 133.455873 -238.303974) (xy 133.407018 -238.309906)
			(xy 133.357843 -238.307925) (xy 133.309624 -238.298081) (xy 133.263608 -238.280629) (xy 133.220987 -238.256022)
			(xy 133.182866 -238.224897) (xy 133.150231 -238.18806) (xy 133.123928 -238.146464) (xy 133.104637 -238.101188)
			(xy 133.09286 -238.053404) (xy 133.0889 -238.00435) (xy 132.770372 -238.00435) (xy 132.76986 -238.029796)
			(xy 132.761696 -238.08003) (xy 132.74558 -238.128304) (xy 132.721929 -238.173367) (xy 132.691356 -238.214053)
			(xy 132.654652 -238.249308) (xy 132.612768 -238.278218) (xy 132.566789 -238.300035) (xy 132.517905 -238.314195)
			(xy 132.467384 -238.320329) (xy 132.416532 -238.31828) (xy 132.366668 -238.3081) (xy 132.319082 -238.290053)
			(xy 132.275008 -238.264607) (xy 132.235586 -238.23242) (xy 132.201838 -238.194326) (xy 132.174637 -238.151312)
			(xy 132.154689 -238.104492) (xy 132.14251 -238.055078) (xy 132.138415 -238.00435) (xy 131.830572 -238.00435)
			(xy 131.83006 -238.029796) (xy 131.821896 -238.08003) (xy 131.80578 -238.128304) (xy 131.782129 -238.173367)
			(xy 131.751556 -238.214053) (xy 131.714852 -238.249308) (xy 131.672968 -238.278218) (xy 131.626989 -238.300035)
			(xy 131.578105 -238.314195) (xy 131.527584 -238.320329) (xy 131.476732 -238.31828) (xy 131.426868 -238.3081)
			(xy 131.379282 -238.290053) (xy 131.335208 -238.264607) (xy 131.295786 -238.23242) (xy 131.262038 -238.194326)
			(xy 131.234837 -238.151312) (xy 131.214889 -238.104492) (xy 131.20271 -238.055078) (xy 131.198615 -238.00435)
			(xy 130.880104 -238.00435) (xy 130.879609 -238.028957) (xy 130.871714 -238.077534) (xy 130.85613 -238.124215)
			(xy 130.833259 -238.167792) (xy 130.803694 -238.207136) (xy 130.768201 -238.241228) (xy 130.727698 -238.269184)
			(xy 130.683236 -238.290282) (xy 130.635965 -238.303974) (xy 130.58711 -238.309906) (xy 130.537935 -238.307925)
			(xy 130.489716 -238.298081) (xy 130.4437 -238.280629) (xy 130.401079 -238.256022) (xy 130.362958 -238.224897)
			(xy 130.330323 -238.18806) (xy 130.30402 -238.146464) (xy 130.284729 -238.101188) (xy 130.272952 -238.053404)
			(xy 130.268992 -238.00435) (xy 129.950464 -238.00435) (xy 129.949952 -238.029796) (xy 129.941788 -238.08003)
			(xy 129.925672 -238.128304) (xy 129.902021 -238.173367) (xy 129.871448 -238.214053) (xy 129.834744 -238.249308)
			(xy 129.79286 -238.278218) (xy 129.746881 -238.300035) (xy 129.697997 -238.314195) (xy 129.647476 -238.320329)
			(xy 129.596624 -238.31828) (xy 129.54676 -238.3081) (xy 129.499174 -238.290053) (xy 129.4551 -238.264607)
			(xy 129.415678 -238.23242) (xy 129.38193 -238.194326) (xy 129.354729 -238.151312) (xy 129.334781 -238.104492)
			(xy 129.322602 -238.055078) (xy 129.318507 -238.00435) (xy 128.999996 -238.00435) (xy 128.999501 -238.028957)
			(xy 128.991606 -238.077534) (xy 128.976022 -238.124215) (xy 128.953151 -238.167792) (xy 128.923586 -238.207136)
			(xy 128.888093 -238.241228) (xy 128.84759 -238.269184) (xy 128.803128 -238.290282) (xy 128.755857 -238.303974)
			(xy 128.707002 -238.309906) (xy 128.657827 -238.307925) (xy 128.609608 -238.298081) (xy 128.563592 -238.280629)
			(xy 128.520971 -238.256022) (xy 128.48285 -238.224897) (xy 128.450215 -238.18806) (xy 128.423912 -238.146464)
			(xy 128.404621 -238.101188) (xy 128.392844 -238.053404) (xy 128.388884 -238.00435) (xy 128.069786 -238.00435)
			(xy 128.069786 -238.029104) (xy 128.062026 -238.078101) (xy 128.046697 -238.125281) (xy 128.024177 -238.169483)
			(xy 127.99502 -238.209618) (xy 127.959944 -238.244698) (xy 127.919812 -238.273859) (xy 127.875613 -238.296384)
			(xy 127.828434 -238.311718) (xy 127.779438 -238.319483) (xy 127.754634 -238.320072) (xy 127.732953 -238.319657)
			(xy 127.690005 -238.313662) (xy 127.669036 -238.308134) (xy 127.662432 -238.306102) (xy 127.65532 -238.306102)
			(xy 127.645296 -238.306518) (xy 127.626773 -238.314185) (xy 127.612595 -238.328358) (xy 127.604922 -238.346878)
			(xy 127.60452 -238.356902) (xy 127.60452 -238.37519) (xy 127.607314 -238.383064) (xy 127.62268 -238.429388)
			(xy 127.647404 -238.523814) (xy 127.66516 -238.619794) (xy 127.675852 -238.716815) (xy 127.679425 -238.814356)
			(xy 127.908553 -238.814356) (xy 127.912648 -238.763628) (xy 127.924827 -238.714214) (xy 127.944775 -238.667394)
			(xy 127.971976 -238.62438) (xy 128.005724 -238.586286) (xy 128.045146 -238.554099) (xy 128.08922 -238.528653)
			(xy 128.136806 -238.510606) (xy 128.18667 -238.500426) (xy 128.237522 -238.498377) (xy 128.288043 -238.504511)
			(xy 128.336927 -238.518671) (xy 128.382906 -238.540488) (xy 128.42479 -238.569398) (xy 128.461494 -238.604653)
			(xy 128.492067 -238.645339) (xy 128.515718 -238.690402) (xy 128.531834 -238.738676) (xy 128.539998 -238.78891)
			(xy 128.54051 -238.814356) (xy 128.848607 -238.814356) (xy 128.852702 -238.763628) (xy 128.864881 -238.714214)
			(xy 128.884829 -238.667394) (xy 128.91203 -238.62438) (xy 128.945778 -238.586286) (xy 128.9852 -238.554099)
			(xy 129.029274 -238.528653) (xy 129.07686 -238.510606) (xy 129.126724 -238.500426) (xy 129.177576 -238.498377)
			(xy 129.228097 -238.504511) (xy 129.276981 -238.518671) (xy 129.32296 -238.540488) (xy 129.364844 -238.569398)
			(xy 129.401548 -238.604653) (xy 129.432121 -238.645339) (xy 129.455772 -238.690402) (xy 129.471888 -238.738676)
			(xy 129.480052 -238.78891) (xy 129.480564 -238.814356) (xy 129.798838 -238.814356) (xy 129.802798 -238.765302)
			(xy 129.814575 -238.717518) (xy 129.833866 -238.672242) (xy 129.860169 -238.630646) (xy 129.892804 -238.593809)
			(xy 129.930925 -238.562684) (xy 129.973546 -238.538077) (xy 130.019562 -238.520625) (xy 130.067781 -238.510781)
			(xy 130.116956 -238.5088) (xy 130.165811 -238.514732) (xy 130.213082 -238.528424) (xy 130.257544 -238.549522)
			(xy 130.298047 -238.577478) (xy 130.33354 -238.61157) (xy 130.363105 -238.650914) (xy 130.385976 -238.694491)
			(xy 130.40156 -238.741172) (xy 130.409455 -238.789749) (xy 130.40995 -238.814356) (xy 130.728461 -238.814356)
			(xy 130.732556 -238.763628) (xy 130.744735 -238.714214) (xy 130.764683 -238.667394) (xy 130.791884 -238.62438)
			(xy 130.825632 -238.586286) (xy 130.865054 -238.554099) (xy 130.909128 -238.528653) (xy 130.956714 -238.510606)
			(xy 131.006578 -238.500426) (xy 131.05743 -238.498377) (xy 131.107951 -238.504511) (xy 131.156835 -238.518671)
			(xy 131.202814 -238.540488) (xy 131.244698 -238.569398) (xy 131.281402 -238.604653) (xy 131.311975 -238.645339)
			(xy 131.335626 -238.690402) (xy 131.351742 -238.738676) (xy 131.359906 -238.78891) (xy 131.360418 -238.814356)
			(xy 131.678946 -238.814356) (xy 131.682906 -238.765302) (xy 131.694683 -238.717518) (xy 131.713974 -238.672242)
			(xy 131.740277 -238.630646) (xy 131.772912 -238.593809) (xy 131.811033 -238.562684) (xy 131.853654 -238.538077)
			(xy 131.89967 -238.520625) (xy 131.947889 -238.510781) (xy 131.997064 -238.5088) (xy 132.045919 -238.514732)
			(xy 132.09319 -238.528424) (xy 132.137652 -238.549522) (xy 132.178155 -238.577478) (xy 132.213648 -238.61157)
			(xy 132.243213 -238.650914) (xy 132.266084 -238.694491) (xy 132.281668 -238.741172) (xy 132.289563 -238.789749)
			(xy 132.290058 -238.814356) (xy 132.608569 -238.814356) (xy 132.612664 -238.763628) (xy 132.624843 -238.714214)
			(xy 132.644791 -238.667394) (xy 132.671992 -238.62438) (xy 132.70574 -238.586286) (xy 132.745162 -238.554099)
			(xy 132.789236 -238.528653) (xy 132.836822 -238.510606) (xy 132.886686 -238.500426) (xy 132.937538 -238.498377)
			(xy 132.988059 -238.504511) (xy 133.036943 -238.518671) (xy 133.082922 -238.540488) (xy 133.124806 -238.569398)
			(xy 133.16151 -238.604653) (xy 133.192083 -238.645339) (xy 133.215734 -238.690402) (xy 133.23185 -238.738676)
			(xy 133.240014 -238.78891) (xy 133.240526 -238.814356) (xy 133.559054 -238.814356) (xy 133.563014 -238.765302)
			(xy 133.574791 -238.717518) (xy 133.594082 -238.672242) (xy 133.620385 -238.630646) (xy 133.65302 -238.593809)
			(xy 133.691141 -238.562684) (xy 133.733762 -238.538077) (xy 133.779778 -238.520625) (xy 133.827997 -238.510781)
			(xy 133.877172 -238.5088) (xy 133.926027 -238.514732) (xy 133.973298 -238.528424) (xy 134.01776 -238.549522)
			(xy 134.058263 -238.577478) (xy 134.093756 -238.61157) (xy 134.123321 -238.650914) (xy 134.146192 -238.694491)
			(xy 134.161776 -238.741172) (xy 134.169671 -238.789749) (xy 134.170166 -238.814356) (xy 134.488423 -238.814356)
			(xy 134.492518 -238.763628) (xy 134.504697 -238.714214) (xy 134.524645 -238.667394) (xy 134.551846 -238.62438)
			(xy 134.585594 -238.586286) (xy 134.625016 -238.554099) (xy 134.66909 -238.528653) (xy 134.716676 -238.510606)
			(xy 134.76654 -238.500426) (xy 134.817392 -238.498377) (xy 134.867913 -238.504511) (xy 134.916797 -238.518671)
			(xy 134.962776 -238.540488) (xy 135.00466 -238.569398) (xy 135.041364 -238.604653) (xy 135.071937 -238.645339)
			(xy 135.095588 -238.690402) (xy 135.111704 -238.738676) (xy 135.119868 -238.78891) (xy 135.12038 -238.814356)
			(xy 135.428477 -238.814356) (xy 135.432572 -238.763628) (xy 135.444751 -238.714214) (xy 135.464699 -238.667394)
			(xy 135.4919 -238.62438) (xy 135.525648 -238.586286) (xy 135.56507 -238.554099) (xy 135.609144 -238.528653)
			(xy 135.65673 -238.510606) (xy 135.706594 -238.500426) (xy 135.757446 -238.498377) (xy 135.807967 -238.504511)
			(xy 135.856851 -238.518671) (xy 135.90283 -238.540488) (xy 135.944714 -238.569398) (xy 135.981418 -238.604653)
			(xy 136.011991 -238.645339) (xy 136.035642 -238.690402) (xy 136.051758 -238.738676) (xy 136.059922 -238.78891)
			(xy 136.060434 -238.814356) (xy 136.378962 -238.814356) (xy 136.382922 -238.765302) (xy 136.394699 -238.717518)
			(xy 136.41399 -238.672242) (xy 136.440293 -238.630646) (xy 136.472928 -238.593809) (xy 136.511049 -238.562684)
			(xy 136.55367 -238.538077) (xy 136.599686 -238.520625) (xy 136.647905 -238.510781) (xy 136.69708 -238.5088)
			(xy 136.745935 -238.514732) (xy 136.793206 -238.528424) (xy 136.837668 -238.549522) (xy 136.878171 -238.577478)
			(xy 136.913664 -238.61157) (xy 136.943229 -238.650914) (xy 136.9661 -238.694491) (xy 136.981684 -238.741172)
			(xy 136.989579 -238.789749) (xy 136.990074 -238.814356) (xy 137.308585 -238.814356) (xy 137.31268 -238.763628)
			(xy 137.324859 -238.714214) (xy 137.344807 -238.667394) (xy 137.372008 -238.62438) (xy 137.405756 -238.586286)
			(xy 137.445178 -238.554099) (xy 137.489252 -238.528653) (xy 137.536838 -238.510606) (xy 137.586702 -238.500426)
			(xy 137.637554 -238.498377) (xy 137.688075 -238.504511) (xy 137.736959 -238.518671) (xy 137.782938 -238.540488)
			(xy 137.824822 -238.569398) (xy 137.861526 -238.604653) (xy 137.892099 -238.645339) (xy 137.91575 -238.690402)
			(xy 137.931866 -238.738676) (xy 137.94003 -238.78891) (xy 137.940542 -238.814356) (xy 138.25907 -238.814356)
			(xy 138.26303 -238.765302) (xy 138.274807 -238.717518) (xy 138.294098 -238.672242) (xy 138.320401 -238.630646)
			(xy 138.353036 -238.593809) (xy 138.391157 -238.562684) (xy 138.433778 -238.538077) (xy 138.479794 -238.520625)
			(xy 138.528013 -238.510781) (xy 138.577188 -238.5088) (xy 138.626043 -238.514732) (xy 138.673314 -238.528424)
			(xy 138.717776 -238.549522) (xy 138.758279 -238.577478) (xy 138.793772 -238.61157) (xy 138.823337 -238.650914)
			(xy 138.846208 -238.694491) (xy 138.861792 -238.741172) (xy 138.869687 -238.789749) (xy 138.870182 -238.814356)
			(xy 139.188439 -238.814356) (xy 139.192534 -238.763628) (xy 139.204713 -238.714214) (xy 139.224661 -238.667394)
			(xy 139.251862 -238.62438) (xy 139.28561 -238.586286) (xy 139.325032 -238.554099) (xy 139.369106 -238.528653)
			(xy 139.416692 -238.510606) (xy 139.466556 -238.500426) (xy 139.517408 -238.498377) (xy 139.567929 -238.504511)
			(xy 139.616813 -238.518671) (xy 139.662792 -238.540488) (xy 139.704676 -238.569398) (xy 139.74138 -238.604653)
			(xy 139.771953 -238.645339) (xy 139.795604 -238.690402) (xy 139.81172 -238.738676) (xy 139.819884 -238.78891)
			(xy 139.820396 -238.814356) (xy 140.138924 -238.814356) (xy 140.142884 -238.765302) (xy 140.154661 -238.717518)
			(xy 140.173952 -238.672242) (xy 140.200255 -238.630646) (xy 140.23289 -238.593809) (xy 140.271011 -238.562684)
			(xy 140.313632 -238.538077) (xy 140.359648 -238.520625) (xy 140.407867 -238.510781) (xy 140.457042 -238.5088)
			(xy 140.505897 -238.514732) (xy 140.553168 -238.528424) (xy 140.59763 -238.549522) (xy 140.638133 -238.577478)
			(xy 140.673626 -238.61157) (xy 140.703191 -238.650914) (xy 140.726062 -238.694491) (xy 140.741646 -238.741172)
			(xy 140.749541 -238.789749) (xy 140.750036 -238.814356) (xy 141.068547 -238.814356) (xy 141.072642 -238.763628)
			(xy 141.084821 -238.714214) (xy 141.104769 -238.667394) (xy 141.13197 -238.62438) (xy 141.165718 -238.586286)
			(xy 141.20514 -238.554099) (xy 141.249214 -238.528653) (xy 141.2968 -238.510606) (xy 141.346664 -238.500426)
			(xy 141.397516 -238.498377) (xy 141.448037 -238.504511) (xy 141.496921 -238.518671) (xy 141.5429 -238.540488)
			(xy 141.584784 -238.569398) (xy 141.621488 -238.604653) (xy 141.652061 -238.645339) (xy 141.675712 -238.690402)
			(xy 141.691828 -238.738676) (xy 141.699992 -238.78891) (xy 141.700504 -238.814356) (xy 142.008601 -238.814356)
			(xy 142.012696 -238.763628) (xy 142.024875 -238.714214) (xy 142.044823 -238.667394) (xy 142.072024 -238.62438)
			(xy 142.105772 -238.586286) (xy 142.145194 -238.554099) (xy 142.189268 -238.528653) (xy 142.236854 -238.510606)
			(xy 142.286718 -238.500426) (xy 142.33757 -238.498377) (xy 142.388091 -238.504511) (xy 142.436975 -238.518671)
			(xy 142.482954 -238.540488) (xy 142.524838 -238.569398) (xy 142.561542 -238.604653) (xy 142.592115 -238.645339)
			(xy 142.615766 -238.690402) (xy 142.631882 -238.738676) (xy 142.640046 -238.78891) (xy 142.640558 -238.814356)
			(xy 142.958832 -238.814356) (xy 142.962792 -238.765302) (xy 142.974569 -238.717518) (xy 142.99386 -238.672242)
			(xy 143.020163 -238.630646) (xy 143.052798 -238.593809) (xy 143.090919 -238.562684) (xy 143.13354 -238.538077)
			(xy 143.179556 -238.520625) (xy 143.227775 -238.510781) (xy 143.27695 -238.5088) (xy 143.325805 -238.514732)
			(xy 143.373076 -238.528424) (xy 143.417538 -238.549522) (xy 143.458041 -238.577478) (xy 143.493534 -238.61157)
			(xy 143.523099 -238.650914) (xy 143.54597 -238.694491) (xy 143.561554 -238.741172) (xy 143.569449 -238.789749)
			(xy 143.569944 -238.814356) (xy 144.83894 -238.814356) (xy 144.8429 -238.765302) (xy 144.854677 -238.717518)
			(xy 144.873968 -238.672242) (xy 144.900271 -238.630646) (xy 144.932906 -238.593809) (xy 144.971027 -238.562684)
			(xy 145.013648 -238.538077) (xy 145.059664 -238.520625) (xy 145.107883 -238.510781) (xy 145.157058 -238.5088)
			(xy 145.205913 -238.514732) (xy 145.253184 -238.528424) (xy 145.297646 -238.549522) (xy 145.338149 -238.577478)
			(xy 145.373642 -238.61157) (xy 145.403207 -238.650914) (xy 145.426078 -238.694491) (xy 145.441662 -238.741172)
			(xy 145.449557 -238.789749) (xy 145.450052 -238.814356) (xy 145.449557 -238.838963) (xy 145.441662 -238.88754)
			(xy 145.426078 -238.934221) (xy 145.403207 -238.977798) (xy 145.373642 -239.017142) (xy 145.338149 -239.051234)
			(xy 145.297646 -239.07919) (xy 145.253184 -239.100288) (xy 145.205913 -239.11398) (xy 145.157058 -239.119912)
			(xy 145.107883 -239.117931) (xy 145.059664 -239.108087) (xy 145.013648 -239.090635) (xy 144.971027 -239.066028)
			(xy 144.932906 -239.034903) (xy 144.900271 -238.998066) (xy 144.873968 -238.95647) (xy 144.854677 -238.911194)
			(xy 144.8429 -238.86341) (xy 144.83894 -238.814356) (xy 143.569944 -238.814356) (xy 143.569449 -238.838963)
			(xy 143.561554 -238.88754) (xy 143.54597 -238.934221) (xy 143.523099 -238.977798) (xy 143.493534 -239.017142)
			(xy 143.458041 -239.051234) (xy 143.417538 -239.07919) (xy 143.373076 -239.100288) (xy 143.325805 -239.11398)
			(xy 143.27695 -239.119912) (xy 143.227775 -239.117931) (xy 143.179556 -239.108087) (xy 143.13354 -239.090635)
			(xy 143.090919 -239.066028) (xy 143.052798 -239.034903) (xy 143.020163 -238.998066) (xy 142.99386 -238.95647)
			(xy 142.974569 -238.911194) (xy 142.962792 -238.86341) (xy 142.958832 -238.814356) (xy 142.640558 -238.814356)
			(xy 142.640046 -238.839802) (xy 142.631882 -238.890036) (xy 142.615766 -238.93831) (xy 142.592115 -238.983373)
			(xy 142.561542 -239.024059) (xy 142.524838 -239.059314) (xy 142.482954 -239.088224) (xy 142.436975 -239.110041)
			(xy 142.388091 -239.124201) (xy 142.33757 -239.130335) (xy 142.286718 -239.128286) (xy 142.236854 -239.118106)
			(xy 142.189268 -239.100059) (xy 142.145194 -239.074613) (xy 142.105772 -239.042426) (xy 142.072024 -239.004332)
			(xy 142.044823 -238.961318) (xy 142.024875 -238.914498) (xy 142.012696 -238.865084) (xy 142.008601 -238.814356)
			(xy 141.700504 -238.814356) (xy 141.699992 -238.839802) (xy 141.691828 -238.890036) (xy 141.675712 -238.93831)
			(xy 141.652061 -238.983373) (xy 141.621488 -239.024059) (xy 141.584784 -239.059314) (xy 141.5429 -239.088224)
			(xy 141.496921 -239.110041) (xy 141.448037 -239.124201) (xy 141.397516 -239.130335) (xy 141.346664 -239.128286)
			(xy 141.2968 -239.118106) (xy 141.249214 -239.100059) (xy 141.20514 -239.074613) (xy 141.165718 -239.042426)
			(xy 141.13197 -239.004332) (xy 141.104769 -238.961318) (xy 141.084821 -238.914498) (xy 141.072642 -238.865084)
			(xy 141.068547 -238.814356) (xy 140.750036 -238.814356) (xy 140.749541 -238.838963) (xy 140.741646 -238.88754)
			(xy 140.726062 -238.934221) (xy 140.703191 -238.977798) (xy 140.673626 -239.017142) (xy 140.638133 -239.051234)
			(xy 140.59763 -239.07919) (xy 140.553168 -239.100288) (xy 140.505897 -239.11398) (xy 140.457042 -239.119912)
			(xy 140.407867 -239.117931) (xy 140.359648 -239.108087) (xy 140.313632 -239.090635) (xy 140.271011 -239.066028)
			(xy 140.23289 -239.034903) (xy 140.200255 -238.998066) (xy 140.173952 -238.95647) (xy 140.154661 -238.911194)
			(xy 140.142884 -238.86341) (xy 140.138924 -238.814356) (xy 139.820396 -238.814356) (xy 139.819884 -238.839802)
			(xy 139.81172 -238.890036) (xy 139.795604 -238.93831) (xy 139.771953 -238.983373) (xy 139.74138 -239.024059)
			(xy 139.704676 -239.059314) (xy 139.662792 -239.088224) (xy 139.616813 -239.110041) (xy 139.567929 -239.124201)
			(xy 139.517408 -239.130335) (xy 139.466556 -239.128286) (xy 139.416692 -239.118106) (xy 139.369106 -239.100059)
			(xy 139.325032 -239.074613) (xy 139.28561 -239.042426) (xy 139.251862 -239.004332) (xy 139.224661 -238.961318)
			(xy 139.204713 -238.914498) (xy 139.192534 -238.865084) (xy 139.188439 -238.814356) (xy 138.870182 -238.814356)
			(xy 138.869687 -238.838963) (xy 138.861792 -238.88754) (xy 138.846208 -238.934221) (xy 138.823337 -238.977798)
			(xy 138.793772 -239.017142) (xy 138.758279 -239.051234) (xy 138.717776 -239.07919) (xy 138.673314 -239.100288)
			(xy 138.626043 -239.11398) (xy 138.577188 -239.119912) (xy 138.528013 -239.117931) (xy 138.479794 -239.108087)
			(xy 138.433778 -239.090635) (xy 138.391157 -239.066028) (xy 138.353036 -239.034903) (xy 138.320401 -238.998066)
			(xy 138.294098 -238.95647) (xy 138.274807 -238.911194) (xy 138.26303 -238.86341) (xy 138.25907 -238.814356)
			(xy 137.940542 -238.814356) (xy 137.94003 -238.839802) (xy 137.931866 -238.890036) (xy 137.91575 -238.93831)
			(xy 137.892099 -238.983373) (xy 137.861526 -239.024059) (xy 137.824822 -239.059314) (xy 137.782938 -239.088224)
			(xy 137.736959 -239.110041) (xy 137.688075 -239.124201) (xy 137.637554 -239.130335) (xy 137.586702 -239.128286)
			(xy 137.536838 -239.118106) (xy 137.489252 -239.100059) (xy 137.445178 -239.074613) (xy 137.405756 -239.042426)
			(xy 137.372008 -239.004332) (xy 137.344807 -238.961318) (xy 137.324859 -238.914498) (xy 137.31268 -238.865084)
			(xy 137.308585 -238.814356) (xy 136.990074 -238.814356) (xy 136.989579 -238.838963) (xy 136.981684 -238.88754)
			(xy 136.9661 -238.934221) (xy 136.943229 -238.977798) (xy 136.913664 -239.017142) (xy 136.878171 -239.051234)
			(xy 136.837668 -239.07919) (xy 136.793206 -239.100288) (xy 136.745935 -239.11398) (xy 136.69708 -239.119912)
			(xy 136.647905 -239.117931) (xy 136.599686 -239.108087) (xy 136.55367 -239.090635) (xy 136.511049 -239.066028)
			(xy 136.472928 -239.034903) (xy 136.440293 -238.998066) (xy 136.41399 -238.95647) (xy 136.394699 -238.911194)
			(xy 136.382922 -238.86341) (xy 136.378962 -238.814356) (xy 136.060434 -238.814356) (xy 136.059922 -238.839802)
			(xy 136.051758 -238.890036) (xy 136.035642 -238.93831) (xy 136.011991 -238.983373) (xy 135.981418 -239.024059)
			(xy 135.944714 -239.059314) (xy 135.90283 -239.088224) (xy 135.856851 -239.110041) (xy 135.807967 -239.124201)
			(xy 135.757446 -239.130335) (xy 135.706594 -239.128286) (xy 135.65673 -239.118106) (xy 135.609144 -239.100059)
			(xy 135.56507 -239.074613) (xy 135.525648 -239.042426) (xy 135.4919 -239.004332) (xy 135.464699 -238.961318)
			(xy 135.444751 -238.914498) (xy 135.432572 -238.865084) (xy 135.428477 -238.814356) (xy 135.12038 -238.814356)
			(xy 135.119868 -238.839802) (xy 135.111704 -238.890036) (xy 135.095588 -238.93831) (xy 135.071937 -238.983373)
			(xy 135.041364 -239.024059) (xy 135.00466 -239.059314) (xy 134.962776 -239.088224) (xy 134.916797 -239.110041)
			(xy 134.867913 -239.124201) (xy 134.817392 -239.130335) (xy 134.76654 -239.128286) (xy 134.716676 -239.118106)
			(xy 134.66909 -239.100059) (xy 134.625016 -239.074613) (xy 134.585594 -239.042426) (xy 134.551846 -239.004332)
			(xy 134.524645 -238.961318) (xy 134.504697 -238.914498) (xy 134.492518 -238.865084) (xy 134.488423 -238.814356)
			(xy 134.170166 -238.814356) (xy 134.169671 -238.838963) (xy 134.161776 -238.88754) (xy 134.146192 -238.934221)
			(xy 134.123321 -238.977798) (xy 134.093756 -239.017142) (xy 134.058263 -239.051234) (xy 134.01776 -239.07919)
			(xy 133.973298 -239.100288) (xy 133.926027 -239.11398) (xy 133.877172 -239.119912) (xy 133.827997 -239.117931)
			(xy 133.779778 -239.108087) (xy 133.733762 -239.090635) (xy 133.691141 -239.066028) (xy 133.65302 -239.034903)
			(xy 133.620385 -238.998066) (xy 133.594082 -238.95647) (xy 133.574791 -238.911194) (xy 133.563014 -238.86341)
			(xy 133.559054 -238.814356) (xy 133.240526 -238.814356) (xy 133.240014 -238.839802) (xy 133.23185 -238.890036)
			(xy 133.215734 -238.93831) (xy 133.192083 -238.983373) (xy 133.16151 -239.024059) (xy 133.124806 -239.059314)
			(xy 133.082922 -239.088224) (xy 133.036943 -239.110041) (xy 132.988059 -239.124201) (xy 132.937538 -239.130335)
			(xy 132.886686 -239.128286) (xy 132.836822 -239.118106) (xy 132.789236 -239.100059) (xy 132.745162 -239.074613)
			(xy 132.70574 -239.042426) (xy 132.671992 -239.004332) (xy 132.644791 -238.961318) (xy 132.624843 -238.914498)
			(xy 132.612664 -238.865084) (xy 132.608569 -238.814356) (xy 132.290058 -238.814356) (xy 132.289563 -238.838963)
			(xy 132.281668 -238.88754) (xy 132.266084 -238.934221) (xy 132.243213 -238.977798) (xy 132.213648 -239.017142)
			(xy 132.178155 -239.051234) (xy 132.137652 -239.07919) (xy 132.09319 -239.100288) (xy 132.045919 -239.11398)
			(xy 131.997064 -239.119912) (xy 131.947889 -239.117931) (xy 131.89967 -239.108087) (xy 131.853654 -239.090635)
			(xy 131.811033 -239.066028) (xy 131.772912 -239.034903) (xy 131.740277 -238.998066) (xy 131.713974 -238.95647)
			(xy 131.694683 -238.911194) (xy 131.682906 -238.86341) (xy 131.678946 -238.814356) (xy 131.360418 -238.814356)
			(xy 131.359906 -238.839802) (xy 131.351742 -238.890036) (xy 131.335626 -238.93831) (xy 131.311975 -238.983373)
			(xy 131.281402 -239.024059) (xy 131.244698 -239.059314) (xy 131.202814 -239.088224) (xy 131.156835 -239.110041)
			(xy 131.107951 -239.124201) (xy 131.05743 -239.130335) (xy 131.006578 -239.128286) (xy 130.956714 -239.118106)
			(xy 130.909128 -239.100059) (xy 130.865054 -239.074613) (xy 130.825632 -239.042426) (xy 130.791884 -239.004332)
			(xy 130.764683 -238.961318) (xy 130.744735 -238.914498) (xy 130.732556 -238.865084) (xy 130.728461 -238.814356)
			(xy 130.40995 -238.814356) (xy 130.409455 -238.838963) (xy 130.40156 -238.88754) (xy 130.385976 -238.934221)
			(xy 130.363105 -238.977798) (xy 130.33354 -239.017142) (xy 130.298047 -239.051234) (xy 130.257544 -239.07919)
			(xy 130.213082 -239.100288) (xy 130.165811 -239.11398) (xy 130.116956 -239.119912) (xy 130.067781 -239.117931)
			(xy 130.019562 -239.108087) (xy 129.973546 -239.090635) (xy 129.930925 -239.066028) (xy 129.892804 -239.034903)
			(xy 129.860169 -238.998066) (xy 129.833866 -238.95647) (xy 129.814575 -238.911194) (xy 129.802798 -238.86341)
			(xy 129.798838 -238.814356) (xy 129.480564 -238.814356) (xy 129.480052 -238.839802) (xy 129.471888 -238.890036)
			(xy 129.455772 -238.93831) (xy 129.432121 -238.983373) (xy 129.401548 -239.024059) (xy 129.364844 -239.059314)
			(xy 129.32296 -239.088224) (xy 129.276981 -239.110041) (xy 129.228097 -239.124201) (xy 129.177576 -239.130335)
			(xy 129.126724 -239.128286) (xy 129.07686 -239.118106) (xy 129.029274 -239.100059) (xy 128.9852 -239.074613)
			(xy 128.945778 -239.042426) (xy 128.91203 -239.004332) (xy 128.884829 -238.961318) (xy 128.864881 -238.914498)
			(xy 128.852702 -238.865084) (xy 128.848607 -238.814356) (xy 128.54051 -238.814356) (xy 128.539998 -238.839802)
			(xy 128.531834 -238.890036) (xy 128.515718 -238.93831) (xy 128.492067 -238.983373) (xy 128.461494 -239.024059)
			(xy 128.42479 -239.059314) (xy 128.382906 -239.088224) (xy 128.336927 -239.110041) (xy 128.288043 -239.124201)
			(xy 128.237522 -239.130335) (xy 128.18667 -239.128286) (xy 128.136806 -239.118106) (xy 128.08922 -239.100059)
			(xy 128.045146 -239.074613) (xy 128.005724 -239.042426) (xy 127.971976 -239.004332) (xy 127.944775 -238.961318)
			(xy 127.924827 -238.914498) (xy 127.912648 -238.865084) (xy 127.908553 -238.814356) (xy 127.679425 -238.814356)
			(xy 127.679425 -238.814358) (xy 127.675858 -238.911902) (xy 127.665172 -239.008924) (xy 127.647422 -239.104905)
			(xy 127.622704 -239.199332) (xy 127.607314 -239.245648) (xy 127.60452 -239.253522) (xy 127.60452 -239.27181)
			(xy 127.604942 -239.281828) (xy 127.612614 -239.300338) (xy 127.626787 -239.314503) (xy 127.645301 -239.322164)
			(xy 127.65532 -239.32261) (xy 127.662432 -239.32261) (xy 127.669036 -239.320578) (xy 127.689997 -239.315011)
			(xy 127.73295 -239.309025) (xy 127.754634 -239.30864) (xy 127.779445 -239.309129) (xy 127.828455 -239.316897)
			(xy 127.875646 -239.332235) (xy 127.919858 -239.354766) (xy 127.960001 -239.383935) (xy 127.995087 -239.419025)
			(xy 128.024252 -239.459171) (xy 128.046778 -239.503385) (xy 128.062111 -239.550578) (xy 128.069873 -239.599589)
			(xy 128.069873 -239.624362) (xy 128.388884 -239.624362) (xy 128.392844 -239.575308) (xy 128.404621 -239.527524)
			(xy 128.423912 -239.482248) (xy 128.450215 -239.440652) (xy 128.48285 -239.403815) (xy 128.520971 -239.37269)
			(xy 128.563592 -239.348083) (xy 128.609608 -239.330631) (xy 128.657827 -239.320787) (xy 128.707002 -239.318806)
			(xy 128.755857 -239.324738) (xy 128.803128 -239.33843) (xy 128.84759 -239.359528) (xy 128.888093 -239.387484)
			(xy 128.923586 -239.421576) (xy 128.953151 -239.46092) (xy 128.976022 -239.504497) (xy 128.991606 -239.551178)
			(xy 128.999501 -239.599755) (xy 128.999996 -239.624362) (xy 129.318507 -239.624362) (xy 129.322602 -239.573634)
			(xy 129.334781 -239.52422) (xy 129.354729 -239.4774) (xy 129.38193 -239.434386) (xy 129.415678 -239.396292)
			(xy 129.4551 -239.364105) (xy 129.499174 -239.338659) (xy 129.54676 -239.320612) (xy 129.596624 -239.310432)
			(xy 129.647476 -239.308383) (xy 129.697997 -239.314517) (xy 129.746881 -239.328677) (xy 129.79286 -239.350494)
			(xy 129.834744 -239.379404) (xy 129.871448 -239.414659) (xy 129.902021 -239.455345) (xy 129.925672 -239.500408)
			(xy 129.941788 -239.548682) (xy 129.949952 -239.598916) (xy 129.950464 -239.624362) (xy 131.198615 -239.624362)
			(xy 131.20271 -239.573634) (xy 131.214889 -239.52422) (xy 131.234837 -239.4774) (xy 131.262038 -239.434386)
			(xy 131.295786 -239.396292) (xy 131.335208 -239.364105) (xy 131.379282 -239.338659) (xy 131.426868 -239.320612)
			(xy 131.476732 -239.310432) (xy 131.527584 -239.308383) (xy 131.578105 -239.314517) (xy 131.626989 -239.328677)
			(xy 131.672968 -239.350494) (xy 131.714852 -239.379404) (xy 131.751556 -239.414659) (xy 131.782129 -239.455345)
			(xy 131.80578 -239.500408) (xy 131.821896 -239.548682) (xy 131.83006 -239.598916) (xy 131.830572 -239.624362)
			(xy 132.138415 -239.624362) (xy 132.14251 -239.573634) (xy 132.154689 -239.52422) (xy 132.174637 -239.4774)
			(xy 132.201838 -239.434386) (xy 132.235586 -239.396292) (xy 132.275008 -239.364105) (xy 132.319082 -239.338659)
			(xy 132.366668 -239.320612) (xy 132.416532 -239.310432) (xy 132.467384 -239.308383) (xy 132.517905 -239.314517)
			(xy 132.566789 -239.328677) (xy 132.612768 -239.350494) (xy 132.654652 -239.379404) (xy 132.691356 -239.414659)
			(xy 132.721929 -239.455345) (xy 132.74558 -239.500408) (xy 132.761696 -239.548682) (xy 132.76986 -239.598916)
			(xy 132.770372 -239.624362) (xy 133.0889 -239.624362) (xy 133.09286 -239.575308) (xy 133.104637 -239.527524)
			(xy 133.123928 -239.482248) (xy 133.150231 -239.440652) (xy 133.182866 -239.403815) (xy 133.220987 -239.37269)
			(xy 133.263608 -239.348083) (xy 133.309624 -239.330631) (xy 133.357843 -239.320787) (xy 133.407018 -239.318806)
			(xy 133.455873 -239.324738) (xy 133.503144 -239.33843) (xy 133.547606 -239.359528) (xy 133.588109 -239.387484)
			(xy 133.623602 -239.421576) (xy 133.653167 -239.46092) (xy 133.676038 -239.504497) (xy 133.691622 -239.551178)
			(xy 133.699517 -239.599755) (xy 133.700012 -239.624362) (xy 134.018523 -239.624362) (xy 134.022618 -239.573634)
			(xy 134.034797 -239.52422) (xy 134.054745 -239.4774) (xy 134.081946 -239.434386) (xy 134.115694 -239.396292)
			(xy 134.155116 -239.364105) (xy 134.19919 -239.338659) (xy 134.246776 -239.320612) (xy 134.29664 -239.310432)
			(xy 134.347492 -239.308383) (xy 134.398013 -239.314517) (xy 134.446897 -239.328677) (xy 134.492876 -239.350494)
			(xy 134.53476 -239.379404) (xy 134.571464 -239.414659) (xy 134.602037 -239.455345) (xy 134.625688 -239.500408)
			(xy 134.641804 -239.548682) (xy 134.649968 -239.598916) (xy 134.65048 -239.624362) (xy 134.969008 -239.624362)
			(xy 134.972968 -239.575308) (xy 134.984745 -239.527524) (xy 135.004036 -239.482248) (xy 135.030339 -239.440652)
			(xy 135.062974 -239.403815) (xy 135.101095 -239.37269) (xy 135.143716 -239.348083) (xy 135.189732 -239.330631)
			(xy 135.237951 -239.320787) (xy 135.287126 -239.318806) (xy 135.335981 -239.324738) (xy 135.383252 -239.33843)
			(xy 135.427714 -239.359528) (xy 135.468217 -239.387484) (xy 135.50371 -239.421576) (xy 135.533275 -239.46092)
			(xy 135.556146 -239.504497) (xy 135.57173 -239.551178) (xy 135.579625 -239.599755) (xy 135.58012 -239.624362)
			(xy 135.898631 -239.624362) (xy 135.902726 -239.573634) (xy 135.914905 -239.52422) (xy 135.934853 -239.4774)
			(xy 135.962054 -239.434386) (xy 135.995802 -239.396292) (xy 136.035224 -239.364105) (xy 136.079298 -239.338659)
			(xy 136.126884 -239.320612) (xy 136.176748 -239.310432) (xy 136.2276 -239.308383) (xy 136.278121 -239.314517)
			(xy 136.327005 -239.328677) (xy 136.372984 -239.350494) (xy 136.414868 -239.379404) (xy 136.451572 -239.414659)
			(xy 136.482145 -239.455345) (xy 136.505796 -239.500408) (xy 136.521912 -239.548682) (xy 136.530076 -239.598916)
			(xy 136.530588 -239.624362) (xy 137.778485 -239.624362) (xy 137.78258 -239.573634) (xy 137.794759 -239.52422)
			(xy 137.814707 -239.4774) (xy 137.841908 -239.434386) (xy 137.875656 -239.396292) (xy 137.915078 -239.364105)
			(xy 137.959152 -239.338659) (xy 138.006738 -239.320612) (xy 138.056602 -239.310432) (xy 138.107454 -239.308383)
			(xy 138.157975 -239.314517) (xy 138.206859 -239.328677) (xy 138.252838 -239.350494) (xy 138.294722 -239.379404)
			(xy 138.331426 -239.414659) (xy 138.361999 -239.455345) (xy 138.38565 -239.500408) (xy 138.401766 -239.548682)
			(xy 138.40993 -239.598916) (xy 138.410442 -239.624362) (xy 138.718539 -239.624362) (xy 138.722634 -239.573634)
			(xy 138.734813 -239.52422) (xy 138.754761 -239.4774) (xy 138.781962 -239.434386) (xy 138.81571 -239.396292)
			(xy 138.855132 -239.364105) (xy 138.899206 -239.338659) (xy 138.946792 -239.320612) (xy 138.996656 -239.310432)
			(xy 139.047508 -239.308383) (xy 139.098029 -239.314517) (xy 139.146913 -239.328677) (xy 139.192892 -239.350494)
			(xy 139.234776 -239.379404) (xy 139.27148 -239.414659) (xy 139.302053 -239.455345) (xy 139.325704 -239.500408)
			(xy 139.34182 -239.548682) (xy 139.349984 -239.598916) (xy 139.350496 -239.624362) (xy 139.669024 -239.624362)
			(xy 139.672984 -239.575308) (xy 139.684761 -239.527524) (xy 139.704052 -239.482248) (xy 139.730355 -239.440652)
			(xy 139.76299 -239.403815) (xy 139.801111 -239.37269) (xy 139.843732 -239.348083) (xy 139.889748 -239.330631)
			(xy 139.937967 -239.320787) (xy 139.987142 -239.318806) (xy 140.035997 -239.324738) (xy 140.083268 -239.33843)
			(xy 140.12773 -239.359528) (xy 140.168233 -239.387484) (xy 140.203726 -239.421576) (xy 140.233291 -239.46092)
			(xy 140.256162 -239.504497) (xy 140.271746 -239.551178) (xy 140.279641 -239.599755) (xy 140.280136 -239.624362)
			(xy 140.598647 -239.624362) (xy 140.602742 -239.573634) (xy 140.614921 -239.52422) (xy 140.634869 -239.4774)
			(xy 140.66207 -239.434386) (xy 140.695818 -239.396292) (xy 140.73524 -239.364105) (xy 140.779314 -239.338659)
			(xy 140.8269 -239.320612) (xy 140.876764 -239.310432) (xy 140.927616 -239.308383) (xy 140.978137 -239.314517)
			(xy 141.027021 -239.328677) (xy 141.073 -239.350494) (xy 141.114884 -239.379404) (xy 141.151588 -239.414659)
			(xy 141.182161 -239.455345) (xy 141.205812 -239.500408) (xy 141.221928 -239.548682) (xy 141.230092 -239.598916)
			(xy 141.230604 -239.624362) (xy 141.548878 -239.624362) (xy 141.552838 -239.575308) (xy 141.564615 -239.527524)
			(xy 141.583906 -239.482248) (xy 141.610209 -239.440652) (xy 141.642844 -239.403815) (xy 141.680965 -239.37269)
			(xy 141.723586 -239.348083) (xy 141.769602 -239.330631) (xy 141.817821 -239.320787) (xy 141.866996 -239.318806)
			(xy 141.915851 -239.324738) (xy 141.963122 -239.33843) (xy 142.007584 -239.359528) (xy 142.048087 -239.387484)
			(xy 142.08358 -239.421576) (xy 142.113145 -239.46092) (xy 142.136016 -239.504497) (xy 142.1516 -239.551178)
			(xy 142.159495 -239.599755) (xy 142.15999 -239.624362) (xy 142.478501 -239.624362) (xy 142.482596 -239.573634)
			(xy 142.494775 -239.52422) (xy 142.514723 -239.4774) (xy 142.541924 -239.434386) (xy 142.575672 -239.396292)
			(xy 142.615094 -239.364105) (xy 142.659168 -239.338659) (xy 142.706754 -239.320612) (xy 142.756618 -239.310432)
			(xy 142.80747 -239.308383) (xy 142.857991 -239.314517) (xy 142.906875 -239.328677) (xy 142.952854 -239.350494)
			(xy 142.994738 -239.379404) (xy 143.031442 -239.414659) (xy 143.062015 -239.455345) (xy 143.085666 -239.500408)
			(xy 143.101782 -239.548682) (xy 143.109946 -239.598916) (xy 143.110458 -239.624362) (xy 143.109946 -239.649808)
			(xy 143.101782 -239.700042) (xy 143.085666 -239.748316) (xy 143.062015 -239.793379) (xy 143.031442 -239.834065)
			(xy 142.994738 -239.86932) (xy 142.952854 -239.89823) (xy 142.906875 -239.920047) (xy 142.857991 -239.934207)
			(xy 142.80747 -239.940341) (xy 142.756618 -239.938292) (xy 142.706754 -239.928112) (xy 142.659168 -239.910065)
			(xy 142.615094 -239.884619) (xy 142.575672 -239.852432) (xy 142.541924 -239.814338) (xy 142.514723 -239.771324)
			(xy 142.494775 -239.724504) (xy 142.482596 -239.67509) (xy 142.478501 -239.624362) (xy 142.15999 -239.624362)
			(xy 142.159495 -239.648969) (xy 142.1516 -239.697546) (xy 142.136016 -239.744227) (xy 142.113145 -239.787804)
			(xy 142.08358 -239.827148) (xy 142.048087 -239.86124) (xy 142.007584 -239.889196) (xy 141.963122 -239.910294)
			(xy 141.915851 -239.923986) (xy 141.866996 -239.929918) (xy 141.817821 -239.927937) (xy 141.769602 -239.918093)
			(xy 141.723586 -239.900641) (xy 141.680965 -239.876034) (xy 141.642844 -239.844909) (xy 141.610209 -239.808072)
			(xy 141.583906 -239.766476) (xy 141.564615 -239.7212) (xy 141.552838 -239.673416) (xy 141.548878 -239.624362)
			(xy 141.230604 -239.624362) (xy 141.230092 -239.649808) (xy 141.221928 -239.700042) (xy 141.205812 -239.748316)
			(xy 141.182161 -239.793379) (xy 141.151588 -239.834065) (xy 141.114884 -239.86932) (xy 141.073 -239.89823)
			(xy 141.027021 -239.920047) (xy 140.978137 -239.934207) (xy 140.927616 -239.940341) (xy 140.876764 -239.938292)
			(xy 140.8269 -239.928112) (xy 140.779314 -239.910065) (xy 140.73524 -239.884619) (xy 140.695818 -239.852432)
			(xy 140.66207 -239.814338) (xy 140.634869 -239.771324) (xy 140.614921 -239.724504) (xy 140.602742 -239.67509)
			(xy 140.598647 -239.624362) (xy 140.280136 -239.624362) (xy 140.279641 -239.648969) (xy 140.271746 -239.697546)
			(xy 140.256162 -239.744227) (xy 140.233291 -239.787804) (xy 140.203726 -239.827148) (xy 140.168233 -239.86124)
			(xy 140.12773 -239.889196) (xy 140.083268 -239.910294) (xy 140.035997 -239.923986) (xy 139.987142 -239.929918)
			(xy 139.937967 -239.927937) (xy 139.889748 -239.918093) (xy 139.843732 -239.900641) (xy 139.801111 -239.876034)
			(xy 139.76299 -239.844909) (xy 139.730355 -239.808072) (xy 139.704052 -239.766476) (xy 139.684761 -239.7212)
			(xy 139.672984 -239.673416) (xy 139.669024 -239.624362) (xy 139.350496 -239.624362) (xy 139.349984 -239.649808)
			(xy 139.34182 -239.700042) (xy 139.325704 -239.748316) (xy 139.302053 -239.793379) (xy 139.27148 -239.834065)
			(xy 139.234776 -239.86932) (xy 139.192892 -239.89823) (xy 139.146913 -239.920047) (xy 139.098029 -239.934207)
			(xy 139.047508 -239.940341) (xy 138.996656 -239.938292) (xy 138.946792 -239.928112) (xy 138.899206 -239.910065)
			(xy 138.855132 -239.884619) (xy 138.81571 -239.852432) (xy 138.781962 -239.814338) (xy 138.754761 -239.771324)
			(xy 138.734813 -239.724504) (xy 138.722634 -239.67509) (xy 138.718539 -239.624362) (xy 138.410442 -239.624362)
			(xy 138.40993 -239.649808) (xy 138.401766 -239.700042) (xy 138.38565 -239.748316) (xy 138.361999 -239.793379)
			(xy 138.331426 -239.834065) (xy 138.294722 -239.86932) (xy 138.252838 -239.89823) (xy 138.206859 -239.920047)
			(xy 138.157975 -239.934207) (xy 138.107454 -239.940341) (xy 138.056602 -239.938292) (xy 138.006738 -239.928112)
			(xy 137.959152 -239.910065) (xy 137.915078 -239.884619) (xy 137.875656 -239.852432) (xy 137.841908 -239.814338)
			(xy 137.814707 -239.771324) (xy 137.794759 -239.724504) (xy 137.78258 -239.67509) (xy 137.778485 -239.624362)
			(xy 136.530588 -239.624362) (xy 136.530076 -239.649808) (xy 136.521912 -239.700042) (xy 136.505796 -239.748316)
			(xy 136.482145 -239.793379) (xy 136.451572 -239.834065) (xy 136.414868 -239.86932) (xy 136.372984 -239.89823)
			(xy 136.327005 -239.920047) (xy 136.278121 -239.934207) (xy 136.2276 -239.940341) (xy 136.176748 -239.938292)
			(xy 136.126884 -239.928112) (xy 136.079298 -239.910065) (xy 136.035224 -239.884619) (xy 135.995802 -239.852432)
			(xy 135.962054 -239.814338) (xy 135.934853 -239.771324) (xy 135.914905 -239.724504) (xy 135.902726 -239.67509)
			(xy 135.898631 -239.624362) (xy 135.58012 -239.624362) (xy 135.579625 -239.648969) (xy 135.57173 -239.697546)
			(xy 135.556146 -239.744227) (xy 135.533275 -239.787804) (xy 135.50371 -239.827148) (xy 135.468217 -239.86124)
			(xy 135.427714 -239.889196) (xy 135.383252 -239.910294) (xy 135.335981 -239.923986) (xy 135.287126 -239.929918)
			(xy 135.237951 -239.927937) (xy 135.189732 -239.918093) (xy 135.143716 -239.900641) (xy 135.101095 -239.876034)
			(xy 135.062974 -239.844909) (xy 135.030339 -239.808072) (xy 135.004036 -239.766476) (xy 134.984745 -239.7212)
			(xy 134.972968 -239.673416) (xy 134.969008 -239.624362) (xy 134.65048 -239.624362) (xy 134.649968 -239.649808)
			(xy 134.641804 -239.700042) (xy 134.625688 -239.748316) (xy 134.602037 -239.793379) (xy 134.571464 -239.834065)
			(xy 134.53476 -239.86932) (xy 134.492876 -239.89823) (xy 134.446897 -239.920047) (xy 134.398013 -239.934207)
			(xy 134.347492 -239.940341) (xy 134.29664 -239.938292) (xy 134.246776 -239.928112) (xy 134.19919 -239.910065)
			(xy 134.155116 -239.884619) (xy 134.115694 -239.852432) (xy 134.081946 -239.814338) (xy 134.054745 -239.771324)
			(xy 134.034797 -239.724504) (xy 134.022618 -239.67509) (xy 134.018523 -239.624362) (xy 133.700012 -239.624362)
			(xy 133.699517 -239.648969) (xy 133.691622 -239.697546) (xy 133.676038 -239.744227) (xy 133.653167 -239.787804)
			(xy 133.623602 -239.827148) (xy 133.588109 -239.86124) (xy 133.547606 -239.889196) (xy 133.503144 -239.910294)
			(xy 133.455873 -239.923986) (xy 133.407018 -239.929918) (xy 133.357843 -239.927937) (xy 133.309624 -239.918093)
			(xy 133.263608 -239.900641) (xy 133.220987 -239.876034) (xy 133.182866 -239.844909) (xy 133.150231 -239.808072)
			(xy 133.123928 -239.766476) (xy 133.104637 -239.7212) (xy 133.09286 -239.673416) (xy 133.0889 -239.624362)
			(xy 132.770372 -239.624362) (xy 132.76986 -239.649808) (xy 132.761696 -239.700042) (xy 132.74558 -239.748316)
			(xy 132.721929 -239.793379) (xy 132.691356 -239.834065) (xy 132.654652 -239.86932) (xy 132.612768 -239.89823)
			(xy 132.566789 -239.920047) (xy 132.517905 -239.934207) (xy 132.467384 -239.940341) (xy 132.416532 -239.938292)
			(xy 132.366668 -239.928112) (xy 132.319082 -239.910065) (xy 132.275008 -239.884619) (xy 132.235586 -239.852432)
			(xy 132.201838 -239.814338) (xy 132.174637 -239.771324) (xy 132.154689 -239.724504) (xy 132.14251 -239.67509)
			(xy 132.138415 -239.624362) (xy 131.830572 -239.624362) (xy 131.83006 -239.649808) (xy 131.821896 -239.700042)
			(xy 131.80578 -239.748316) (xy 131.782129 -239.793379) (xy 131.751556 -239.834065) (xy 131.714852 -239.86932)
			(xy 131.672968 -239.89823) (xy 131.626989 -239.920047) (xy 131.578105 -239.934207) (xy 131.527584 -239.940341)
			(xy 131.476732 -239.938292) (xy 131.426868 -239.928112) (xy 131.379282 -239.910065) (xy 131.335208 -239.884619)
			(xy 131.295786 -239.852432) (xy 131.262038 -239.814338) (xy 131.234837 -239.771324) (xy 131.214889 -239.724504)
			(xy 131.20271 -239.67509) (xy 131.198615 -239.624362) (xy 129.950464 -239.624362) (xy 129.949952 -239.649808)
			(xy 129.941788 -239.700042) (xy 129.925672 -239.748316) (xy 129.902021 -239.793379) (xy 129.871448 -239.834065)
			(xy 129.834744 -239.86932) (xy 129.79286 -239.89823) (xy 129.746881 -239.920047) (xy 129.697997 -239.934207)
			(xy 129.647476 -239.940341) (xy 129.596624 -239.938292) (xy 129.54676 -239.928112) (xy 129.499174 -239.910065)
			(xy 129.4551 -239.884619) (xy 129.415678 -239.852432) (xy 129.38193 -239.814338) (xy 129.354729 -239.771324)
			(xy 129.334781 -239.724504) (xy 129.322602 -239.67509) (xy 129.318507 -239.624362) (xy 128.999996 -239.624362)
			(xy 128.999501 -239.648969) (xy 128.991606 -239.697546) (xy 128.976022 -239.744227) (xy 128.953151 -239.787804)
			(xy 128.923586 -239.827148) (xy 128.888093 -239.86124) (xy 128.84759 -239.889196) (xy 128.803128 -239.910294)
			(xy 128.755857 -239.923986) (xy 128.707002 -239.929918) (xy 128.657827 -239.927937) (xy 128.609608 -239.918093)
			(xy 128.563592 -239.900641) (xy 128.520971 -239.876034) (xy 128.48285 -239.844909) (xy 128.450215 -239.808072)
			(xy 128.423912 -239.766476) (xy 128.404621 -239.7212) (xy 128.392844 -239.673416) (xy 128.388884 -239.624362)
			(xy 128.069873 -239.624362) (xy 128.069873 -239.649211) (xy 128.062111 -239.698222) (xy 128.046778 -239.745415)
			(xy 128.024252 -239.789629) (xy 127.995087 -239.829775) (xy 127.960001 -239.864865) (xy 127.919858 -239.894034)
			(xy 127.875646 -239.916565) (xy 127.828455 -239.931903) (xy 127.779445 -239.939671) (xy 127.754634 -239.940084)
			(xy 127.732952 -239.939685) (xy 127.690002 -239.933689) (xy 127.669036 -239.928146) (xy 127.662432 -239.926114)
			(xy 127.65532 -239.926114) (xy 127.645297 -239.92653) (xy 127.626776 -239.934197) (xy 127.6126 -239.948371)
			(xy 127.604931 -239.966891) (xy 127.60452 -239.976914) (xy 127.60452 -239.995202) (xy 127.607314 -240.003076)
			(xy 127.62268 -240.0494) (xy 127.647403 -240.143826) (xy 127.665157 -240.239806) (xy 127.675849 -240.336827)
			(xy 127.679421 -240.434368) (xy 127.908553 -240.434368) (xy 127.912648 -240.38364) (xy 127.924827 -240.334226)
			(xy 127.944775 -240.287406) (xy 127.971976 -240.244392) (xy 128.005724 -240.206298) (xy 128.045146 -240.174111)
			(xy 128.08922 -240.148665) (xy 128.136806 -240.130618) (xy 128.18667 -240.120438) (xy 128.237522 -240.118389)
			(xy 128.288043 -240.124523) (xy 128.336927 -240.138683) (xy 128.382906 -240.1605) (xy 128.42479 -240.18941)
			(xy 128.461494 -240.224665) (xy 128.492067 -240.265351) (xy 128.515718 -240.310414) (xy 128.531834 -240.358688)
			(xy 128.539998 -240.408922) (xy 128.54051 -240.434368) (xy 128.848607 -240.434368) (xy 128.852702 -240.38364)
			(xy 128.864881 -240.334226) (xy 128.884829 -240.287406) (xy 128.91203 -240.244392) (xy 128.945778 -240.206298)
			(xy 128.9852 -240.174111) (xy 129.029274 -240.148665) (xy 129.07686 -240.130618) (xy 129.126724 -240.120438)
			(xy 129.177576 -240.118389) (xy 129.228097 -240.124523) (xy 129.276981 -240.138683) (xy 129.32296 -240.1605)
			(xy 129.364844 -240.18941) (xy 129.401548 -240.224665) (xy 129.432121 -240.265351) (xy 129.455772 -240.310414)
			(xy 129.471888 -240.358688) (xy 129.480052 -240.408922) (xy 129.480564 -240.434368) (xy 129.798838 -240.434368)
			(xy 129.802798 -240.385314) (xy 129.814575 -240.33753) (xy 129.833866 -240.292254) (xy 129.860169 -240.250658)
			(xy 129.892804 -240.213821) (xy 129.930925 -240.182696) (xy 129.973546 -240.158089) (xy 130.019562 -240.140637)
			(xy 130.067781 -240.130793) (xy 130.116956 -240.128812) (xy 130.165811 -240.134744) (xy 130.213082 -240.148436)
			(xy 130.257544 -240.169534) (xy 130.298047 -240.19749) (xy 130.33354 -240.231582) (xy 130.363105 -240.270926)
			(xy 130.385976 -240.314503) (xy 130.40156 -240.361184) (xy 130.409455 -240.409761) (xy 130.40995 -240.434368)
			(xy 130.728461 -240.434368) (xy 130.732556 -240.38364) (xy 130.744735 -240.334226) (xy 130.764683 -240.287406)
			(xy 130.791884 -240.244392) (xy 130.825632 -240.206298) (xy 130.865054 -240.174111) (xy 130.909128 -240.148665)
			(xy 130.956714 -240.130618) (xy 131.006578 -240.120438) (xy 131.05743 -240.118389) (xy 131.107951 -240.124523)
			(xy 131.156835 -240.138683) (xy 131.202814 -240.1605) (xy 131.244698 -240.18941) (xy 131.281402 -240.224665)
			(xy 131.311975 -240.265351) (xy 131.335626 -240.310414) (xy 131.351742 -240.358688) (xy 131.359906 -240.408922)
			(xy 131.360418 -240.434368) (xy 131.678946 -240.434368) (xy 131.682906 -240.385314) (xy 131.694683 -240.33753)
			(xy 131.713974 -240.292254) (xy 131.740277 -240.250658) (xy 131.772912 -240.213821) (xy 131.811033 -240.182696)
			(xy 131.853654 -240.158089) (xy 131.89967 -240.140637) (xy 131.947889 -240.130793) (xy 131.997064 -240.128812)
			(xy 132.045919 -240.134744) (xy 132.09319 -240.148436) (xy 132.137652 -240.169534) (xy 132.178155 -240.19749)
			(xy 132.213648 -240.231582) (xy 132.243213 -240.270926) (xy 132.266084 -240.314503) (xy 132.281668 -240.361184)
			(xy 132.289563 -240.409761) (xy 132.290058 -240.434368) (xy 132.608569 -240.434368) (xy 132.612664 -240.38364)
			(xy 132.624843 -240.334226) (xy 132.644791 -240.287406) (xy 132.671992 -240.244392) (xy 132.70574 -240.206298)
			(xy 132.745162 -240.174111) (xy 132.789236 -240.148665) (xy 132.836822 -240.130618) (xy 132.886686 -240.120438)
			(xy 132.937538 -240.118389) (xy 132.988059 -240.124523) (xy 133.036943 -240.138683) (xy 133.082922 -240.1605)
			(xy 133.124806 -240.18941) (xy 133.16151 -240.224665) (xy 133.192083 -240.265351) (xy 133.215734 -240.310414)
			(xy 133.23185 -240.358688) (xy 133.240014 -240.408922) (xy 133.240526 -240.434368) (xy 133.559054 -240.434368)
			(xy 133.563014 -240.385314) (xy 133.574791 -240.33753) (xy 133.594082 -240.292254) (xy 133.620385 -240.250658)
			(xy 133.65302 -240.213821) (xy 133.691141 -240.182696) (xy 133.733762 -240.158089) (xy 133.779778 -240.140637)
			(xy 133.827997 -240.130793) (xy 133.877172 -240.128812) (xy 133.926027 -240.134744) (xy 133.973298 -240.148436)
			(xy 134.01776 -240.169534) (xy 134.058263 -240.19749) (xy 134.093756 -240.231582) (xy 134.123321 -240.270926)
			(xy 134.146192 -240.314503) (xy 134.161776 -240.361184) (xy 134.169671 -240.409761) (xy 134.170166 -240.434368)
			(xy 134.488423 -240.434368) (xy 134.492518 -240.38364) (xy 134.504697 -240.334226) (xy 134.524645 -240.287406)
			(xy 134.551846 -240.244392) (xy 134.585594 -240.206298) (xy 134.625016 -240.174111) (xy 134.66909 -240.148665)
			(xy 134.716676 -240.130618) (xy 134.76654 -240.120438) (xy 134.817392 -240.118389) (xy 134.867913 -240.124523)
			(xy 134.916797 -240.138683) (xy 134.962776 -240.1605) (xy 135.00466 -240.18941) (xy 135.041364 -240.224665)
			(xy 135.071937 -240.265351) (xy 135.095588 -240.310414) (xy 135.111704 -240.358688) (xy 135.119868 -240.408922)
			(xy 135.12038 -240.434368) (xy 135.428477 -240.434368) (xy 135.432572 -240.38364) (xy 135.444751 -240.334226)
			(xy 135.464699 -240.287406) (xy 135.4919 -240.244392) (xy 135.525648 -240.206298) (xy 135.56507 -240.174111)
			(xy 135.609144 -240.148665) (xy 135.65673 -240.130618) (xy 135.706594 -240.120438) (xy 135.757446 -240.118389)
			(xy 135.807967 -240.124523) (xy 135.856851 -240.138683) (xy 135.90283 -240.1605) (xy 135.944714 -240.18941)
			(xy 135.981418 -240.224665) (xy 136.011991 -240.265351) (xy 136.035642 -240.310414) (xy 136.051758 -240.358688)
			(xy 136.059922 -240.408922) (xy 136.060434 -240.434368) (xy 136.378962 -240.434368) (xy 136.382922 -240.385314)
			(xy 136.394699 -240.33753) (xy 136.41399 -240.292254) (xy 136.440293 -240.250658) (xy 136.472928 -240.213821)
			(xy 136.511049 -240.182696) (xy 136.55367 -240.158089) (xy 136.599686 -240.140637) (xy 136.647905 -240.130793)
			(xy 136.69708 -240.128812) (xy 136.745935 -240.134744) (xy 136.793206 -240.148436) (xy 136.837668 -240.169534)
			(xy 136.878171 -240.19749) (xy 136.913664 -240.231582) (xy 136.943229 -240.270926) (xy 136.9661 -240.314503)
			(xy 136.981684 -240.361184) (xy 136.989579 -240.409761) (xy 136.990074 -240.434368) (xy 137.308585 -240.434368)
			(xy 137.31268 -240.38364) (xy 137.324859 -240.334226) (xy 137.344807 -240.287406) (xy 137.372008 -240.244392)
			(xy 137.405756 -240.206298) (xy 137.445178 -240.174111) (xy 137.489252 -240.148665) (xy 137.536838 -240.130618)
			(xy 137.586702 -240.120438) (xy 137.637554 -240.118389) (xy 137.688075 -240.124523) (xy 137.736959 -240.138683)
			(xy 137.782938 -240.1605) (xy 137.824822 -240.18941) (xy 137.861526 -240.224665) (xy 137.892099 -240.265351)
			(xy 137.91575 -240.310414) (xy 137.931866 -240.358688) (xy 137.94003 -240.408922) (xy 137.940542 -240.434368)
			(xy 138.25907 -240.434368) (xy 138.26303 -240.385314) (xy 138.274807 -240.33753) (xy 138.294098 -240.292254)
			(xy 138.320401 -240.250658) (xy 138.353036 -240.213821) (xy 138.391157 -240.182696) (xy 138.433778 -240.158089)
			(xy 138.479794 -240.140637) (xy 138.528013 -240.130793) (xy 138.577188 -240.128812) (xy 138.626043 -240.134744)
			(xy 138.673314 -240.148436) (xy 138.717776 -240.169534) (xy 138.758279 -240.19749) (xy 138.793772 -240.231582)
			(xy 138.823337 -240.270926) (xy 138.846208 -240.314503) (xy 138.861792 -240.361184) (xy 138.869687 -240.409761)
			(xy 138.870182 -240.434368) (xy 139.188439 -240.434368) (xy 139.192534 -240.38364) (xy 139.204713 -240.334226)
			(xy 139.224661 -240.287406) (xy 139.251862 -240.244392) (xy 139.28561 -240.206298) (xy 139.325032 -240.174111)
			(xy 139.369106 -240.148665) (xy 139.416692 -240.130618) (xy 139.466556 -240.120438) (xy 139.517408 -240.118389)
			(xy 139.567929 -240.124523) (xy 139.616813 -240.138683) (xy 139.662792 -240.1605) (xy 139.704676 -240.18941)
			(xy 139.74138 -240.224665) (xy 139.771953 -240.265351) (xy 139.795604 -240.310414) (xy 139.81172 -240.358688)
			(xy 139.819884 -240.408922) (xy 139.820396 -240.434368) (xy 140.138924 -240.434368) (xy 140.142884 -240.385314)
			(xy 140.154661 -240.33753) (xy 140.173952 -240.292254) (xy 140.200255 -240.250658) (xy 140.23289 -240.213821)
			(xy 140.271011 -240.182696) (xy 140.313632 -240.158089) (xy 140.359648 -240.140637) (xy 140.407867 -240.130793)
			(xy 140.457042 -240.128812) (xy 140.505897 -240.134744) (xy 140.553168 -240.148436) (xy 140.59763 -240.169534)
			(xy 140.638133 -240.19749) (xy 140.673626 -240.231582) (xy 140.703191 -240.270926) (xy 140.726062 -240.314503)
			(xy 140.741646 -240.361184) (xy 140.749541 -240.409761) (xy 140.750036 -240.434368) (xy 141.068547 -240.434368)
			(xy 141.072642 -240.38364) (xy 141.084821 -240.334226) (xy 141.104769 -240.287406) (xy 141.13197 -240.244392)
			(xy 141.165718 -240.206298) (xy 141.20514 -240.174111) (xy 141.249214 -240.148665) (xy 141.2968 -240.130618)
			(xy 141.346664 -240.120438) (xy 141.397516 -240.118389) (xy 141.448037 -240.124523) (xy 141.496921 -240.138683)
			(xy 141.5429 -240.1605) (xy 141.584784 -240.18941) (xy 141.621488 -240.224665) (xy 141.652061 -240.265351)
			(xy 141.675712 -240.310414) (xy 141.691828 -240.358688) (xy 141.699992 -240.408922) (xy 141.700504 -240.434368)
			(xy 142.008601 -240.434368) (xy 142.012696 -240.38364) (xy 142.024875 -240.334226) (xy 142.044823 -240.287406)
			(xy 142.072024 -240.244392) (xy 142.105772 -240.206298) (xy 142.145194 -240.174111) (xy 142.189268 -240.148665)
			(xy 142.236854 -240.130618) (xy 142.286718 -240.120438) (xy 142.33757 -240.118389) (xy 142.388091 -240.124523)
			(xy 142.436975 -240.138683) (xy 142.482954 -240.1605) (xy 142.524838 -240.18941) (xy 142.561542 -240.224665)
			(xy 142.592115 -240.265351) (xy 142.615766 -240.310414) (xy 142.631882 -240.358688) (xy 142.640046 -240.408922)
			(xy 142.640558 -240.434368) (xy 142.958832 -240.434368) (xy 142.962792 -240.385314) (xy 142.974569 -240.33753)
			(xy 142.99386 -240.292254) (xy 143.020163 -240.250658) (xy 143.052798 -240.213821) (xy 143.090919 -240.182696)
			(xy 143.13354 -240.158089) (xy 143.179556 -240.140637) (xy 143.227775 -240.130793) (xy 143.27695 -240.128812)
			(xy 143.325805 -240.134744) (xy 143.373076 -240.148436) (xy 143.417538 -240.169534) (xy 143.458041 -240.19749)
			(xy 143.493534 -240.231582) (xy 143.523099 -240.270926) (xy 143.54597 -240.314503) (xy 143.561554 -240.361184)
			(xy 143.569449 -240.409761) (xy 143.569944 -240.434368) (xy 144.83894 -240.434368) (xy 144.8429 -240.385314)
			(xy 144.854677 -240.33753) (xy 144.873968 -240.292254) (xy 144.900271 -240.250658) (xy 144.932906 -240.213821)
			(xy 144.971027 -240.182696) (xy 145.013648 -240.158089) (xy 145.059664 -240.140637) (xy 145.107883 -240.130793)
			(xy 145.157058 -240.128812) (xy 145.205913 -240.134744) (xy 145.253184 -240.148436) (xy 145.297646 -240.169534)
			(xy 145.338149 -240.19749) (xy 145.373642 -240.231582) (xy 145.403207 -240.270926) (xy 145.426078 -240.314503)
			(xy 145.441662 -240.361184) (xy 145.449557 -240.409761) (xy 145.450052 -240.434368) (xy 145.449557 -240.458975)
			(xy 145.441662 -240.507552) (xy 145.426078 -240.554233) (xy 145.403207 -240.59781) (xy 145.373642 -240.637154)
			(xy 145.338149 -240.671246) (xy 145.297646 -240.699202) (xy 145.253184 -240.7203) (xy 145.205913 -240.733992)
			(xy 145.157058 -240.739924) (xy 145.107883 -240.737943) (xy 145.059664 -240.728099) (xy 145.013648 -240.710647)
			(xy 144.971027 -240.68604) (xy 144.932906 -240.654915) (xy 144.900271 -240.618078) (xy 144.873968 -240.576482)
			(xy 144.854677 -240.531206) (xy 144.8429 -240.483422) (xy 144.83894 -240.434368) (xy 143.569944 -240.434368)
			(xy 143.569449 -240.458975) (xy 143.561554 -240.507552) (xy 143.54597 -240.554233) (xy 143.523099 -240.59781)
			(xy 143.493534 -240.637154) (xy 143.458041 -240.671246) (xy 143.417538 -240.699202) (xy 143.373076 -240.7203)
			(xy 143.325805 -240.733992) (xy 143.27695 -240.739924) (xy 143.227775 -240.737943) (xy 143.179556 -240.728099)
			(xy 143.13354 -240.710647) (xy 143.090919 -240.68604) (xy 143.052798 -240.654915) (xy 143.020163 -240.618078)
			(xy 142.99386 -240.576482) (xy 142.974569 -240.531206) (xy 142.962792 -240.483422) (xy 142.958832 -240.434368)
			(xy 142.640558 -240.434368) (xy 142.640046 -240.459814) (xy 142.631882 -240.510048) (xy 142.615766 -240.558322)
			(xy 142.592115 -240.603385) (xy 142.561542 -240.644071) (xy 142.524838 -240.679326) (xy 142.482954 -240.708236)
			(xy 142.436975 -240.730053) (xy 142.388091 -240.744213) (xy 142.33757 -240.750347) (xy 142.286718 -240.748298)
			(xy 142.236854 -240.738118) (xy 142.189268 -240.720071) (xy 142.145194 -240.694625) (xy 142.105772 -240.662438)
			(xy 142.072024 -240.624344) (xy 142.044823 -240.58133) (xy 142.024875 -240.53451) (xy 142.012696 -240.485096)
			(xy 142.008601 -240.434368) (xy 141.700504 -240.434368) (xy 141.699992 -240.459814) (xy 141.691828 -240.510048)
			(xy 141.675712 -240.558322) (xy 141.652061 -240.603385) (xy 141.621488 -240.644071) (xy 141.584784 -240.679326)
			(xy 141.5429 -240.708236) (xy 141.496921 -240.730053) (xy 141.448037 -240.744213) (xy 141.397516 -240.750347)
			(xy 141.346664 -240.748298) (xy 141.2968 -240.738118) (xy 141.249214 -240.720071) (xy 141.20514 -240.694625)
			(xy 141.165718 -240.662438) (xy 141.13197 -240.624344) (xy 141.104769 -240.58133) (xy 141.084821 -240.53451)
			(xy 141.072642 -240.485096) (xy 141.068547 -240.434368) (xy 140.750036 -240.434368) (xy 140.749541 -240.458975)
			(xy 140.741646 -240.507552) (xy 140.726062 -240.554233) (xy 140.703191 -240.59781) (xy 140.673626 -240.637154)
			(xy 140.638133 -240.671246) (xy 140.59763 -240.699202) (xy 140.553168 -240.7203) (xy 140.505897 -240.733992)
			(xy 140.457042 -240.739924) (xy 140.407867 -240.737943) (xy 140.359648 -240.728099) (xy 140.313632 -240.710647)
			(xy 140.271011 -240.68604) (xy 140.23289 -240.654915) (xy 140.200255 -240.618078) (xy 140.173952 -240.576482)
			(xy 140.154661 -240.531206) (xy 140.142884 -240.483422) (xy 140.138924 -240.434368) (xy 139.820396 -240.434368)
			(xy 139.819884 -240.459814) (xy 139.81172 -240.510048) (xy 139.795604 -240.558322) (xy 139.771953 -240.603385)
			(xy 139.74138 -240.644071) (xy 139.704676 -240.679326) (xy 139.662792 -240.708236) (xy 139.616813 -240.730053)
			(xy 139.567929 -240.744213) (xy 139.517408 -240.750347) (xy 139.466556 -240.748298) (xy 139.416692 -240.738118)
			(xy 139.369106 -240.720071) (xy 139.325032 -240.694625) (xy 139.28561 -240.662438) (xy 139.251862 -240.624344)
			(xy 139.224661 -240.58133) (xy 139.204713 -240.53451) (xy 139.192534 -240.485096) (xy 139.188439 -240.434368)
			(xy 138.870182 -240.434368) (xy 138.869687 -240.458975) (xy 138.861792 -240.507552) (xy 138.846208 -240.554233)
			(xy 138.823337 -240.59781) (xy 138.793772 -240.637154) (xy 138.758279 -240.671246) (xy 138.717776 -240.699202)
			(xy 138.673314 -240.7203) (xy 138.626043 -240.733992) (xy 138.577188 -240.739924) (xy 138.528013 -240.737943)
			(xy 138.479794 -240.728099) (xy 138.433778 -240.710647) (xy 138.391157 -240.68604) (xy 138.353036 -240.654915)
			(xy 138.320401 -240.618078) (xy 138.294098 -240.576482) (xy 138.274807 -240.531206) (xy 138.26303 -240.483422)
			(xy 138.25907 -240.434368) (xy 137.940542 -240.434368) (xy 137.94003 -240.459814) (xy 137.931866 -240.510048)
			(xy 137.91575 -240.558322) (xy 137.892099 -240.603385) (xy 137.861526 -240.644071) (xy 137.824822 -240.679326)
			(xy 137.782938 -240.708236) (xy 137.736959 -240.730053) (xy 137.688075 -240.744213) (xy 137.637554 -240.750347)
			(xy 137.586702 -240.748298) (xy 137.536838 -240.738118) (xy 137.489252 -240.720071) (xy 137.445178 -240.694625)
			(xy 137.405756 -240.662438) (xy 137.372008 -240.624344) (xy 137.344807 -240.58133) (xy 137.324859 -240.53451)
			(xy 137.31268 -240.485096) (xy 137.308585 -240.434368) (xy 136.990074 -240.434368) (xy 136.989579 -240.458975)
			(xy 136.981684 -240.507552) (xy 136.9661 -240.554233) (xy 136.943229 -240.59781) (xy 136.913664 -240.637154)
			(xy 136.878171 -240.671246) (xy 136.837668 -240.699202) (xy 136.793206 -240.7203) (xy 136.745935 -240.733992)
			(xy 136.69708 -240.739924) (xy 136.647905 -240.737943) (xy 136.599686 -240.728099) (xy 136.55367 -240.710647)
			(xy 136.511049 -240.68604) (xy 136.472928 -240.654915) (xy 136.440293 -240.618078) (xy 136.41399 -240.576482)
			(xy 136.394699 -240.531206) (xy 136.382922 -240.483422) (xy 136.378962 -240.434368) (xy 136.060434 -240.434368)
			(xy 136.059922 -240.459814) (xy 136.051758 -240.510048) (xy 136.035642 -240.558322) (xy 136.011991 -240.603385)
			(xy 135.981418 -240.644071) (xy 135.944714 -240.679326) (xy 135.90283 -240.708236) (xy 135.856851 -240.730053)
			(xy 135.807967 -240.744213) (xy 135.757446 -240.750347) (xy 135.706594 -240.748298) (xy 135.65673 -240.738118)
			(xy 135.609144 -240.720071) (xy 135.56507 -240.694625) (xy 135.525648 -240.662438) (xy 135.4919 -240.624344)
			(xy 135.464699 -240.58133) (xy 135.444751 -240.53451) (xy 135.432572 -240.485096) (xy 135.428477 -240.434368)
			(xy 135.12038 -240.434368) (xy 135.119868 -240.459814) (xy 135.111704 -240.510048) (xy 135.095588 -240.558322)
			(xy 135.071937 -240.603385) (xy 135.041364 -240.644071) (xy 135.00466 -240.679326) (xy 134.962776 -240.708236)
			(xy 134.916797 -240.730053) (xy 134.867913 -240.744213) (xy 134.817392 -240.750347) (xy 134.76654 -240.748298)
			(xy 134.716676 -240.738118) (xy 134.66909 -240.720071) (xy 134.625016 -240.694625) (xy 134.585594 -240.662438)
			(xy 134.551846 -240.624344) (xy 134.524645 -240.58133) (xy 134.504697 -240.53451) (xy 134.492518 -240.485096)
			(xy 134.488423 -240.434368) (xy 134.170166 -240.434368) (xy 134.169671 -240.458975) (xy 134.161776 -240.507552)
			(xy 134.146192 -240.554233) (xy 134.123321 -240.59781) (xy 134.093756 -240.637154) (xy 134.058263 -240.671246)
			(xy 134.01776 -240.699202) (xy 133.973298 -240.7203) (xy 133.926027 -240.733992) (xy 133.877172 -240.739924)
			(xy 133.827997 -240.737943) (xy 133.779778 -240.728099) (xy 133.733762 -240.710647) (xy 133.691141 -240.68604)
			(xy 133.65302 -240.654915) (xy 133.620385 -240.618078) (xy 133.594082 -240.576482) (xy 133.574791 -240.531206)
			(xy 133.563014 -240.483422) (xy 133.559054 -240.434368) (xy 133.240526 -240.434368) (xy 133.240014 -240.459814)
			(xy 133.23185 -240.510048) (xy 133.215734 -240.558322) (xy 133.192083 -240.603385) (xy 133.16151 -240.644071)
			(xy 133.124806 -240.679326) (xy 133.082922 -240.708236) (xy 133.036943 -240.730053) (xy 132.988059 -240.744213)
			(xy 132.937538 -240.750347) (xy 132.886686 -240.748298) (xy 132.836822 -240.738118) (xy 132.789236 -240.720071)
			(xy 132.745162 -240.694625) (xy 132.70574 -240.662438) (xy 132.671992 -240.624344) (xy 132.644791 -240.58133)
			(xy 132.624843 -240.53451) (xy 132.612664 -240.485096) (xy 132.608569 -240.434368) (xy 132.290058 -240.434368)
			(xy 132.289563 -240.458975) (xy 132.281668 -240.507552) (xy 132.266084 -240.554233) (xy 132.243213 -240.59781)
			(xy 132.213648 -240.637154) (xy 132.178155 -240.671246) (xy 132.137652 -240.699202) (xy 132.09319 -240.7203)
			(xy 132.045919 -240.733992) (xy 131.997064 -240.739924) (xy 131.947889 -240.737943) (xy 131.89967 -240.728099)
			(xy 131.853654 -240.710647) (xy 131.811033 -240.68604) (xy 131.772912 -240.654915) (xy 131.740277 -240.618078)
			(xy 131.713974 -240.576482) (xy 131.694683 -240.531206) (xy 131.682906 -240.483422) (xy 131.678946 -240.434368)
			(xy 131.360418 -240.434368) (xy 131.359906 -240.459814) (xy 131.351742 -240.510048) (xy 131.335626 -240.558322)
			(xy 131.311975 -240.603385) (xy 131.281402 -240.644071) (xy 131.244698 -240.679326) (xy 131.202814 -240.708236)
			(xy 131.156835 -240.730053) (xy 131.107951 -240.744213) (xy 131.05743 -240.750347) (xy 131.006578 -240.748298)
			(xy 130.956714 -240.738118) (xy 130.909128 -240.720071) (xy 130.865054 -240.694625) (xy 130.825632 -240.662438)
			(xy 130.791884 -240.624344) (xy 130.764683 -240.58133) (xy 130.744735 -240.53451) (xy 130.732556 -240.485096)
			(xy 130.728461 -240.434368) (xy 130.40995 -240.434368) (xy 130.409455 -240.458975) (xy 130.40156 -240.507552)
			(xy 130.385976 -240.554233) (xy 130.363105 -240.59781) (xy 130.33354 -240.637154) (xy 130.298047 -240.671246)
			(xy 130.257544 -240.699202) (xy 130.213082 -240.7203) (xy 130.165811 -240.733992) (xy 130.116956 -240.739924)
			(xy 130.067781 -240.737943) (xy 130.019562 -240.728099) (xy 129.973546 -240.710647) (xy 129.930925 -240.68604)
			(xy 129.892804 -240.654915) (xy 129.860169 -240.618078) (xy 129.833866 -240.576482) (xy 129.814575 -240.531206)
			(xy 129.802798 -240.483422) (xy 129.798838 -240.434368) (xy 129.480564 -240.434368) (xy 129.480052 -240.459814)
			(xy 129.471888 -240.510048) (xy 129.455772 -240.558322) (xy 129.432121 -240.603385) (xy 129.401548 -240.644071)
			(xy 129.364844 -240.679326) (xy 129.32296 -240.708236) (xy 129.276981 -240.730053) (xy 129.228097 -240.744213)
			(xy 129.177576 -240.750347) (xy 129.126724 -240.748298) (xy 129.07686 -240.738118) (xy 129.029274 -240.720071)
			(xy 128.9852 -240.694625) (xy 128.945778 -240.662438) (xy 128.91203 -240.624344) (xy 128.884829 -240.58133)
			(xy 128.864881 -240.53451) (xy 128.852702 -240.485096) (xy 128.848607 -240.434368) (xy 128.54051 -240.434368)
			(xy 128.539998 -240.459814) (xy 128.531834 -240.510048) (xy 128.515718 -240.558322) (xy 128.492067 -240.603385)
			(xy 128.461494 -240.644071) (xy 128.42479 -240.679326) (xy 128.382906 -240.708236) (xy 128.336927 -240.730053)
			(xy 128.288043 -240.744213) (xy 128.237522 -240.750347) (xy 128.18667 -240.748298) (xy 128.136806 -240.738118)
			(xy 128.08922 -240.720071) (xy 128.045146 -240.694625) (xy 128.005724 -240.662438) (xy 127.971976 -240.624344)
			(xy 127.944775 -240.58133) (xy 127.924827 -240.53451) (xy 127.912648 -240.485096) (xy 127.908553 -240.434368)
			(xy 127.679421 -240.434368) (xy 127.679421 -240.43437) (xy 127.675854 -240.531913) (xy 127.665166 -240.628934)
			(xy 127.647416 -240.724915) (xy 127.622697 -240.819342) (xy 127.607314 -240.86566) (xy 127.60452 -240.873534)
			(xy 127.60452 -240.891822) (xy 127.605012 -240.901825) (xy 127.612676 -240.920306) (xy 127.626829 -240.934447)
			(xy 127.645316 -240.942096) (xy 127.65532 -240.942622) (xy 127.662432 -240.942622) (xy 127.669036 -240.94059)
			(xy 127.689997 -240.935023) (xy 127.73295 -240.929036) (xy 127.754634 -240.928652) (xy 127.779444 -240.929141)
			(xy 127.828452 -240.936908) (xy 127.875642 -240.952246) (xy 127.919852 -240.974776) (xy 127.959993 -241.003944)
			(xy 127.995078 -241.039033) (xy 128.024242 -241.079177) (xy 128.046767 -241.12339) (xy 128.0621 -241.170581)
			(xy 128.069861 -241.21959) (xy 128.069861 -241.244374) (xy 128.388884 -241.244374) (xy 128.392844 -241.19532)
			(xy 128.404621 -241.147536) (xy 128.423912 -241.10226) (xy 128.450215 -241.060664) (xy 128.48285 -241.023827)
			(xy 128.520971 -240.992702) (xy 128.563592 -240.968095) (xy 128.609608 -240.950643) (xy 128.657827 -240.940799)
			(xy 128.707002 -240.938818) (xy 128.755857 -240.94475) (xy 128.803128 -240.958442) (xy 128.84759 -240.97954)
			(xy 128.888093 -241.007496) (xy 128.923586 -241.041588) (xy 128.953151 -241.080932) (xy 128.976022 -241.124509)
			(xy 128.991606 -241.17119) (xy 128.999501 -241.219767) (xy 128.999996 -241.244374) (xy 129.318507 -241.244374)
			(xy 129.322602 -241.193646) (xy 129.334781 -241.144232) (xy 129.354729 -241.097412) (xy 129.38193 -241.054398)
			(xy 129.415678 -241.016304) (xy 129.4551 -240.984117) (xy 129.499174 -240.958671) (xy 129.54676 -240.940624)
			(xy 129.596624 -240.930444) (xy 129.647476 -240.928395) (xy 129.697997 -240.934529) (xy 129.746881 -240.948689)
			(xy 129.79286 -240.970506) (xy 129.834744 -240.999416) (xy 129.871448 -241.034671) (xy 129.902021 -241.075357)
			(xy 129.925672 -241.12042) (xy 129.941788 -241.168694) (xy 129.949952 -241.218928) (xy 129.950464 -241.244374)
			(xy 130.268992 -241.244374) (xy 130.272952 -241.19532) (xy 130.284729 -241.147536) (xy 130.30402 -241.10226)
			(xy 130.330323 -241.060664) (xy 130.362958 -241.023827) (xy 130.401079 -240.992702) (xy 130.4437 -240.968095)
			(xy 130.489716 -240.950643) (xy 130.537935 -240.940799) (xy 130.58711 -240.938818) (xy 130.635965 -240.94475)
			(xy 130.683236 -240.958442) (xy 130.727698 -240.97954) (xy 130.768201 -241.007496) (xy 130.803694 -241.041588)
			(xy 130.833259 -241.080932) (xy 130.85613 -241.124509) (xy 130.871714 -241.17119) (xy 130.879609 -241.219767)
			(xy 130.880104 -241.244374) (xy 131.198615 -241.244374) (xy 131.20271 -241.193646) (xy 131.214889 -241.144232)
			(xy 131.234837 -241.097412) (xy 131.262038 -241.054398) (xy 131.295786 -241.016304) (xy 131.335208 -240.984117)
			(xy 131.379282 -240.958671) (xy 131.426868 -240.940624) (xy 131.476732 -240.930444) (xy 131.527584 -240.928395)
			(xy 131.578105 -240.934529) (xy 131.626989 -240.948689) (xy 131.672968 -240.970506) (xy 131.714852 -240.999416)
			(xy 131.751556 -241.034671) (xy 131.782129 -241.075357) (xy 131.80578 -241.12042) (xy 131.821896 -241.168694)
			(xy 131.83006 -241.218928) (xy 131.830572 -241.244374) (xy 132.138415 -241.244374) (xy 132.14251 -241.193646)
			(xy 132.154689 -241.144232) (xy 132.174637 -241.097412) (xy 132.201838 -241.054398) (xy 132.235586 -241.016304)
			(xy 132.275008 -240.984117) (xy 132.319082 -240.958671) (xy 132.366668 -240.940624) (xy 132.416532 -240.930444)
			(xy 132.467384 -240.928395) (xy 132.517905 -240.934529) (xy 132.566789 -240.948689) (xy 132.612768 -240.970506)
			(xy 132.654652 -240.999416) (xy 132.691356 -241.034671) (xy 132.721929 -241.075357) (xy 132.74558 -241.12042)
			(xy 132.761696 -241.168694) (xy 132.76986 -241.218928) (xy 132.770372 -241.244374) (xy 133.0889 -241.244374)
			(xy 133.09286 -241.19532) (xy 133.104637 -241.147536) (xy 133.123928 -241.10226) (xy 133.150231 -241.060664)
			(xy 133.182866 -241.023827) (xy 133.220987 -240.992702) (xy 133.263608 -240.968095) (xy 133.309624 -240.950643)
			(xy 133.357843 -240.940799) (xy 133.407018 -240.938818) (xy 133.455873 -240.94475) (xy 133.503144 -240.958442)
			(xy 133.547606 -240.97954) (xy 133.588109 -241.007496) (xy 133.623602 -241.041588) (xy 133.653167 -241.080932)
			(xy 133.676038 -241.124509) (xy 133.691622 -241.17119) (xy 133.699517 -241.219767) (xy 133.700012 -241.244374)
			(xy 134.018523 -241.244374) (xy 134.022618 -241.193646) (xy 134.034797 -241.144232) (xy 134.054745 -241.097412)
			(xy 134.081946 -241.054398) (xy 134.115694 -241.016304) (xy 134.155116 -240.984117) (xy 134.19919 -240.958671)
			(xy 134.246776 -240.940624) (xy 134.29664 -240.930444) (xy 134.347492 -240.928395) (xy 134.398013 -240.934529)
			(xy 134.446897 -240.948689) (xy 134.492876 -240.970506) (xy 134.53476 -240.999416) (xy 134.571464 -241.034671)
			(xy 134.602037 -241.075357) (xy 134.625688 -241.12042) (xy 134.641804 -241.168694) (xy 134.649968 -241.218928)
			(xy 134.65048 -241.244374) (xy 134.969008 -241.244374) (xy 134.972968 -241.19532) (xy 134.984745 -241.147536)
			(xy 135.004036 -241.10226) (xy 135.030339 -241.060664) (xy 135.062974 -241.023827) (xy 135.101095 -240.992702)
			(xy 135.143716 -240.968095) (xy 135.189732 -240.950643) (xy 135.237951 -240.940799) (xy 135.287126 -240.938818)
			(xy 135.335981 -240.94475) (xy 135.383252 -240.958442) (xy 135.427714 -240.97954) (xy 135.468217 -241.007496)
			(xy 135.50371 -241.041588) (xy 135.533275 -241.080932) (xy 135.556146 -241.124509) (xy 135.57173 -241.17119)
			(xy 135.579625 -241.219767) (xy 135.58012 -241.244374) (xy 135.898631 -241.244374) (xy 135.902726 -241.193646)
			(xy 135.914905 -241.144232) (xy 135.934853 -241.097412) (xy 135.962054 -241.054398) (xy 135.995802 -241.016304)
			(xy 136.035224 -240.984117) (xy 136.079298 -240.958671) (xy 136.126884 -240.940624) (xy 136.176748 -240.930444)
			(xy 136.2276 -240.928395) (xy 136.278121 -240.934529) (xy 136.327005 -240.948689) (xy 136.372984 -240.970506)
			(xy 136.414868 -240.999416) (xy 136.451572 -241.034671) (xy 136.482145 -241.075357) (xy 136.505796 -241.12042)
			(xy 136.521912 -241.168694) (xy 136.530076 -241.218928) (xy 136.530588 -241.244374) (xy 136.848862 -241.244374)
			(xy 136.852822 -241.19532) (xy 136.864599 -241.147536) (xy 136.88389 -241.10226) (xy 136.910193 -241.060664)
			(xy 136.942828 -241.023827) (xy 136.980949 -240.992702) (xy 137.02357 -240.968095) (xy 137.069586 -240.950643)
			(xy 137.117805 -240.940799) (xy 137.16698 -240.938818) (xy 137.215835 -240.94475) (xy 137.263106 -240.958442)
			(xy 137.307568 -240.97954) (xy 137.348071 -241.007496) (xy 137.383564 -241.041588) (xy 137.413129 -241.080932)
			(xy 137.436 -241.124509) (xy 137.451584 -241.17119) (xy 137.459479 -241.219767) (xy 137.459974 -241.244374)
			(xy 137.778485 -241.244374) (xy 137.78258 -241.193646) (xy 137.794759 -241.144232) (xy 137.814707 -241.097412)
			(xy 137.841908 -241.054398) (xy 137.875656 -241.016304) (xy 137.915078 -240.984117) (xy 137.959152 -240.958671)
			(xy 138.006738 -240.940624) (xy 138.056602 -240.930444) (xy 138.107454 -240.928395) (xy 138.157975 -240.934529)
			(xy 138.206859 -240.948689) (xy 138.252838 -240.970506) (xy 138.294722 -240.999416) (xy 138.331426 -241.034671)
			(xy 138.361999 -241.075357) (xy 138.38565 -241.12042) (xy 138.401766 -241.168694) (xy 138.40993 -241.218928)
			(xy 138.410442 -241.244374) (xy 138.718539 -241.244374) (xy 138.722634 -241.193646) (xy 138.734813 -241.144232)
			(xy 138.754761 -241.097412) (xy 138.781962 -241.054398) (xy 138.81571 -241.016304) (xy 138.855132 -240.984117)
			(xy 138.899206 -240.958671) (xy 138.946792 -240.940624) (xy 138.996656 -240.930444) (xy 139.047508 -240.928395)
			(xy 139.098029 -240.934529) (xy 139.146913 -240.948689) (xy 139.192892 -240.970506) (xy 139.234776 -240.999416)
			(xy 139.27148 -241.034671) (xy 139.302053 -241.075357) (xy 139.325704 -241.12042) (xy 139.34182 -241.168694)
			(xy 139.349984 -241.218928) (xy 139.350496 -241.244374) (xy 139.669024 -241.244374) (xy 139.672984 -241.19532)
			(xy 139.684761 -241.147536) (xy 139.704052 -241.10226) (xy 139.730355 -241.060664) (xy 139.76299 -241.023827)
			(xy 139.801111 -240.992702) (xy 139.843732 -240.968095) (xy 139.889748 -240.950643) (xy 139.937967 -240.940799)
			(xy 139.987142 -240.938818) (xy 140.035997 -240.94475) (xy 140.083268 -240.958442) (xy 140.12773 -240.97954)
			(xy 140.168233 -241.007496) (xy 140.203726 -241.041588) (xy 140.233291 -241.080932) (xy 140.256162 -241.124509)
			(xy 140.271746 -241.17119) (xy 140.279641 -241.219767) (xy 140.280136 -241.244374) (xy 140.598647 -241.244374)
			(xy 140.602742 -241.193646) (xy 140.614921 -241.144232) (xy 140.634869 -241.097412) (xy 140.66207 -241.054398)
			(xy 140.695818 -241.016304) (xy 140.73524 -240.984117) (xy 140.779314 -240.958671) (xy 140.8269 -240.940624)
			(xy 140.876764 -240.930444) (xy 140.927616 -240.928395) (xy 140.978137 -240.934529) (xy 141.027021 -240.948689)
			(xy 141.073 -240.970506) (xy 141.114884 -240.999416) (xy 141.151588 -241.034671) (xy 141.182161 -241.075357)
			(xy 141.205812 -241.12042) (xy 141.221928 -241.168694) (xy 141.230092 -241.218928) (xy 141.230604 -241.244374)
			(xy 141.548878 -241.244374) (xy 141.552838 -241.19532) (xy 141.564615 -241.147536) (xy 141.583906 -241.10226)
			(xy 141.610209 -241.060664) (xy 141.642844 -241.023827) (xy 141.680965 -240.992702) (xy 141.723586 -240.968095)
			(xy 141.769602 -240.950643) (xy 141.817821 -240.940799) (xy 141.866996 -240.938818) (xy 141.915851 -240.94475)
			(xy 141.963122 -240.958442) (xy 142.007584 -240.97954) (xy 142.048087 -241.007496) (xy 142.08358 -241.041588)
			(xy 142.113145 -241.080932) (xy 142.136016 -241.124509) (xy 142.1516 -241.17119) (xy 142.159495 -241.219767)
			(xy 142.15999 -241.244374) (xy 142.478501 -241.244374) (xy 142.482596 -241.193646) (xy 142.494775 -241.144232)
			(xy 142.514723 -241.097412) (xy 142.541924 -241.054398) (xy 142.575672 -241.016304) (xy 142.615094 -240.984117)
			(xy 142.659168 -240.958671) (xy 142.706754 -240.940624) (xy 142.756618 -240.930444) (xy 142.80747 -240.928395)
			(xy 142.857991 -240.934529) (xy 142.906875 -240.948689) (xy 142.952854 -240.970506) (xy 142.994738 -240.999416)
			(xy 143.031442 -241.034671) (xy 143.062015 -241.075357) (xy 143.085666 -241.12042) (xy 143.101782 -241.168694)
			(xy 143.109946 -241.218928) (xy 143.110458 -241.244374) (xy 143.428986 -241.244374) (xy 143.432946 -241.19532)
			(xy 143.444723 -241.147536) (xy 143.464014 -241.10226) (xy 143.490317 -241.060664) (xy 143.522952 -241.023827)
			(xy 143.561073 -240.992702) (xy 143.603694 -240.968095) (xy 143.64971 -240.950643) (xy 143.697929 -240.940799)
			(xy 143.747104 -240.938818) (xy 143.795959 -240.94475) (xy 143.84323 -240.958442) (xy 143.887692 -240.97954)
			(xy 143.928195 -241.007496) (xy 143.963688 -241.041588) (xy 143.993253 -241.080932) (xy 144.016124 -241.124509)
			(xy 144.031708 -241.17119) (xy 144.039603 -241.219767) (xy 144.040098 -241.244374) (xy 144.039603 -241.268981)
			(xy 144.031708 -241.317558) (xy 144.016124 -241.364239) (xy 143.993253 -241.407816) (xy 143.963688 -241.44716)
			(xy 143.928195 -241.481252) (xy 143.887692 -241.509208) (xy 143.84323 -241.530306) (xy 143.795959 -241.543998)
			(xy 143.747104 -241.54993) (xy 143.697929 -241.547949) (xy 143.64971 -241.538105) (xy 143.603694 -241.520653)
			(xy 143.561073 -241.496046) (xy 143.522952 -241.464921) (xy 143.490317 -241.428084) (xy 143.464014 -241.386488)
			(xy 143.444723 -241.341212) (xy 143.432946 -241.293428) (xy 143.428986 -241.244374) (xy 143.110458 -241.244374)
			(xy 143.109946 -241.26982) (xy 143.101782 -241.320054) (xy 143.085666 -241.368328) (xy 143.062015 -241.413391)
			(xy 143.031442 -241.454077) (xy 142.994738 -241.489332) (xy 142.952854 -241.518242) (xy 142.906875 -241.540059)
			(xy 142.857991 -241.554219) (xy 142.80747 -241.560353) (xy 142.756618 -241.558304) (xy 142.706754 -241.548124)
			(xy 142.659168 -241.530077) (xy 142.615094 -241.504631) (xy 142.575672 -241.472444) (xy 142.541924 -241.43435)
			(xy 142.514723 -241.391336) (xy 142.494775 -241.344516) (xy 142.482596 -241.295102) (xy 142.478501 -241.244374)
			(xy 142.15999 -241.244374) (xy 142.159495 -241.268981) (xy 142.1516 -241.317558) (xy 142.136016 -241.364239)
			(xy 142.113145 -241.407816) (xy 142.08358 -241.44716) (xy 142.048087 -241.481252) (xy 142.007584 -241.509208)
			(xy 141.963122 -241.530306) (xy 141.915851 -241.543998) (xy 141.866996 -241.54993) (xy 141.817821 -241.547949)
			(xy 141.769602 -241.538105) (xy 141.723586 -241.520653) (xy 141.680965 -241.496046) (xy 141.642844 -241.464921)
			(xy 141.610209 -241.428084) (xy 141.583906 -241.386488) (xy 141.564615 -241.341212) (xy 141.552838 -241.293428)
			(xy 141.548878 -241.244374) (xy 141.230604 -241.244374) (xy 141.230092 -241.26982) (xy 141.221928 -241.320054)
			(xy 141.205812 -241.368328) (xy 141.182161 -241.413391) (xy 141.151588 -241.454077) (xy 141.114884 -241.489332)
			(xy 141.073 -241.518242) (xy 141.027021 -241.540059) (xy 140.978137 -241.554219) (xy 140.927616 -241.560353)
			(xy 140.876764 -241.558304) (xy 140.8269 -241.548124) (xy 140.779314 -241.530077) (xy 140.73524 -241.504631)
			(xy 140.695818 -241.472444) (xy 140.66207 -241.43435) (xy 140.634869 -241.391336) (xy 140.614921 -241.344516)
			(xy 140.602742 -241.295102) (xy 140.598647 -241.244374) (xy 140.280136 -241.244374) (xy 140.279641 -241.268981)
			(xy 140.271746 -241.317558) (xy 140.256162 -241.364239) (xy 140.233291 -241.407816) (xy 140.203726 -241.44716)
			(xy 140.168233 -241.481252) (xy 140.12773 -241.509208) (xy 140.083268 -241.530306) (xy 140.035997 -241.543998)
			(xy 139.987142 -241.54993) (xy 139.937967 -241.547949) (xy 139.889748 -241.538105) (xy 139.843732 -241.520653)
			(xy 139.801111 -241.496046) (xy 139.76299 -241.464921) (xy 139.730355 -241.428084) (xy 139.704052 -241.386488)
			(xy 139.684761 -241.341212) (xy 139.672984 -241.293428) (xy 139.669024 -241.244374) (xy 139.350496 -241.244374)
			(xy 139.349984 -241.26982) (xy 139.34182 -241.320054) (xy 139.325704 -241.368328) (xy 139.302053 -241.413391)
			(xy 139.27148 -241.454077) (xy 139.234776 -241.489332) (xy 139.192892 -241.518242) (xy 139.146913 -241.540059)
			(xy 139.098029 -241.554219) (xy 139.047508 -241.560353) (xy 138.996656 -241.558304) (xy 138.946792 -241.548124)
			(xy 138.899206 -241.530077) (xy 138.855132 -241.504631) (xy 138.81571 -241.472444) (xy 138.781962 -241.43435)
			(xy 138.754761 -241.391336) (xy 138.734813 -241.344516) (xy 138.722634 -241.295102) (xy 138.718539 -241.244374)
			(xy 138.410442 -241.244374) (xy 138.40993 -241.26982) (xy 138.401766 -241.320054) (xy 138.38565 -241.368328)
			(xy 138.361999 -241.413391) (xy 138.331426 -241.454077) (xy 138.294722 -241.489332) (xy 138.252838 -241.518242)
			(xy 138.206859 -241.540059) (xy 138.157975 -241.554219) (xy 138.107454 -241.560353) (xy 138.056602 -241.558304)
			(xy 138.006738 -241.548124) (xy 137.959152 -241.530077) (xy 137.915078 -241.504631) (xy 137.875656 -241.472444)
			(xy 137.841908 -241.43435) (xy 137.814707 -241.391336) (xy 137.794759 -241.344516) (xy 137.78258 -241.295102)
			(xy 137.778485 -241.244374) (xy 137.459974 -241.244374) (xy 137.459479 -241.268981) (xy 137.451584 -241.317558)
			(xy 137.436 -241.364239) (xy 137.413129 -241.407816) (xy 137.383564 -241.44716) (xy 137.348071 -241.481252)
			(xy 137.307568 -241.509208) (xy 137.263106 -241.530306) (xy 137.215835 -241.543998) (xy 137.16698 -241.54993)
			(xy 137.117805 -241.547949) (xy 137.069586 -241.538105) (xy 137.02357 -241.520653) (xy 136.980949 -241.496046)
			(xy 136.942828 -241.464921) (xy 136.910193 -241.428084) (xy 136.88389 -241.386488) (xy 136.864599 -241.341212)
			(xy 136.852822 -241.293428) (xy 136.848862 -241.244374) (xy 136.530588 -241.244374) (xy 136.530076 -241.26982)
			(xy 136.521912 -241.320054) (xy 136.505796 -241.368328) (xy 136.482145 -241.413391) (xy 136.451572 -241.454077)
			(xy 136.414868 -241.489332) (xy 136.372984 -241.518242) (xy 136.327005 -241.540059) (xy 136.278121 -241.554219)
			(xy 136.2276 -241.560353) (xy 136.176748 -241.558304) (xy 136.126884 -241.548124) (xy 136.079298 -241.530077)
			(xy 136.035224 -241.504631) (xy 135.995802 -241.472444) (xy 135.962054 -241.43435) (xy 135.934853 -241.391336)
			(xy 135.914905 -241.344516) (xy 135.902726 -241.295102) (xy 135.898631 -241.244374) (xy 135.58012 -241.244374)
			(xy 135.579625 -241.268981) (xy 135.57173 -241.317558) (xy 135.556146 -241.364239) (xy 135.533275 -241.407816)
			(xy 135.50371 -241.44716) (xy 135.468217 -241.481252) (xy 135.427714 -241.509208) (xy 135.383252 -241.530306)
			(xy 135.335981 -241.543998) (xy 135.287126 -241.54993) (xy 135.237951 -241.547949) (xy 135.189732 -241.538105)
			(xy 135.143716 -241.520653) (xy 135.101095 -241.496046) (xy 135.062974 -241.464921) (xy 135.030339 -241.428084)
			(xy 135.004036 -241.386488) (xy 134.984745 -241.341212) (xy 134.972968 -241.293428) (xy 134.969008 -241.244374)
			(xy 134.65048 -241.244374) (xy 134.649968 -241.26982) (xy 134.641804 -241.320054) (xy 134.625688 -241.368328)
			(xy 134.602037 -241.413391) (xy 134.571464 -241.454077) (xy 134.53476 -241.489332) (xy 134.492876 -241.518242)
			(xy 134.446897 -241.540059) (xy 134.398013 -241.554219) (xy 134.347492 -241.560353) (xy 134.29664 -241.558304)
			(xy 134.246776 -241.548124) (xy 134.19919 -241.530077) (xy 134.155116 -241.504631) (xy 134.115694 -241.472444)
			(xy 134.081946 -241.43435) (xy 134.054745 -241.391336) (xy 134.034797 -241.344516) (xy 134.022618 -241.295102)
			(xy 134.018523 -241.244374) (xy 133.700012 -241.244374) (xy 133.699517 -241.268981) (xy 133.691622 -241.317558)
			(xy 133.676038 -241.364239) (xy 133.653167 -241.407816) (xy 133.623602 -241.44716) (xy 133.588109 -241.481252)
			(xy 133.547606 -241.509208) (xy 133.503144 -241.530306) (xy 133.455873 -241.543998) (xy 133.407018 -241.54993)
			(xy 133.357843 -241.547949) (xy 133.309624 -241.538105) (xy 133.263608 -241.520653) (xy 133.220987 -241.496046)
			(xy 133.182866 -241.464921) (xy 133.150231 -241.428084) (xy 133.123928 -241.386488) (xy 133.104637 -241.341212)
			(xy 133.09286 -241.293428) (xy 133.0889 -241.244374) (xy 132.770372 -241.244374) (xy 132.76986 -241.26982)
			(xy 132.761696 -241.320054) (xy 132.74558 -241.368328) (xy 132.721929 -241.413391) (xy 132.691356 -241.454077)
			(xy 132.654652 -241.489332) (xy 132.612768 -241.518242) (xy 132.566789 -241.540059) (xy 132.517905 -241.554219)
			(xy 132.467384 -241.560353) (xy 132.416532 -241.558304) (xy 132.366668 -241.548124) (xy 132.319082 -241.530077)
			(xy 132.275008 -241.504631) (xy 132.235586 -241.472444) (xy 132.201838 -241.43435) (xy 132.174637 -241.391336)
			(xy 132.154689 -241.344516) (xy 132.14251 -241.295102) (xy 132.138415 -241.244374) (xy 131.830572 -241.244374)
			(xy 131.83006 -241.26982) (xy 131.821896 -241.320054) (xy 131.80578 -241.368328) (xy 131.782129 -241.413391)
			(xy 131.751556 -241.454077) (xy 131.714852 -241.489332) (xy 131.672968 -241.518242) (xy 131.626989 -241.540059)
			(xy 131.578105 -241.554219) (xy 131.527584 -241.560353) (xy 131.476732 -241.558304) (xy 131.426868 -241.548124)
			(xy 131.379282 -241.530077) (xy 131.335208 -241.504631) (xy 131.295786 -241.472444) (xy 131.262038 -241.43435)
			(xy 131.234837 -241.391336) (xy 131.214889 -241.344516) (xy 131.20271 -241.295102) (xy 131.198615 -241.244374)
			(xy 130.880104 -241.244374) (xy 130.879609 -241.268981) (xy 130.871714 -241.317558) (xy 130.85613 -241.364239)
			(xy 130.833259 -241.407816) (xy 130.803694 -241.44716) (xy 130.768201 -241.481252) (xy 130.727698 -241.509208)
			(xy 130.683236 -241.530306) (xy 130.635965 -241.543998) (xy 130.58711 -241.54993) (xy 130.537935 -241.547949)
			(xy 130.489716 -241.538105) (xy 130.4437 -241.520653) (xy 130.401079 -241.496046) (xy 130.362958 -241.464921)
			(xy 130.330323 -241.428084) (xy 130.30402 -241.386488) (xy 130.284729 -241.341212) (xy 130.272952 -241.293428)
			(xy 130.268992 -241.244374) (xy 129.950464 -241.244374) (xy 129.949952 -241.26982) (xy 129.941788 -241.320054)
			(xy 129.925672 -241.368328) (xy 129.902021 -241.413391) (xy 129.871448 -241.454077) (xy 129.834744 -241.489332)
			(xy 129.79286 -241.518242) (xy 129.746881 -241.540059) (xy 129.697997 -241.554219) (xy 129.647476 -241.560353)
			(xy 129.596624 -241.558304) (xy 129.54676 -241.548124) (xy 129.499174 -241.530077) (xy 129.4551 -241.504631)
			(xy 129.415678 -241.472444) (xy 129.38193 -241.43435) (xy 129.354729 -241.391336) (xy 129.334781 -241.344516)
			(xy 129.322602 -241.295102) (xy 129.318507 -241.244374) (xy 128.999996 -241.244374) (xy 128.999501 -241.268981)
			(xy 128.991606 -241.317558) (xy 128.976022 -241.364239) (xy 128.953151 -241.407816) (xy 128.923586 -241.44716)
			(xy 128.888093 -241.481252) (xy 128.84759 -241.509208) (xy 128.803128 -241.530306) (xy 128.755857 -241.543998)
			(xy 128.707002 -241.54993) (xy 128.657827 -241.547949) (xy 128.609608 -241.538105) (xy 128.563592 -241.520653)
			(xy 128.520971 -241.496046) (xy 128.48285 -241.464921) (xy 128.450215 -241.428084) (xy 128.423912 -241.386488)
			(xy 128.404621 -241.341212) (xy 128.392844 -241.293428) (xy 128.388884 -241.244374) (xy 128.069861 -241.244374)
			(xy 128.069861 -241.26921) (xy 128.0621 -241.318219) (xy 128.046767 -241.36541) (xy 128.024242 -241.409623)
			(xy 127.995078 -241.449767) (xy 127.959993 -241.484856) (xy 127.919852 -241.514024) (xy 127.875642 -241.536554)
			(xy 127.828452 -241.551892) (xy 127.779444 -241.559659) (xy 127.754634 -241.560096) (xy 127.732952 -241.559697)
			(xy 127.690002 -241.553701) (xy 127.669036 -241.548158) (xy 127.662432 -241.546126) (xy 127.65532 -241.546126)
			(xy 127.645298 -241.546543) (xy 127.626779 -241.55421) (xy 127.612607 -241.568384) (xy 127.604942 -241.586904)
			(xy 127.60452 -241.596926) (xy 127.60452 -241.615214) (xy 127.607314 -241.623088) (xy 127.622679 -241.669412)
			(xy 127.647401 -241.763838) (xy 127.665155 -241.859818) (xy 127.675846 -241.956838) (xy 127.679417 -242.05438)
			(xy 127.908553 -242.05438) (xy 127.912648 -242.003652) (xy 127.924827 -241.954238) (xy 127.944775 -241.907418)
			(xy 127.971976 -241.864404) (xy 128.005724 -241.82631) (xy 128.045146 -241.794123) (xy 128.08922 -241.768677)
			(xy 128.136806 -241.75063) (xy 128.18667 -241.74045) (xy 128.237522 -241.738401) (xy 128.288043 -241.744535)
			(xy 128.336927 -241.758695) (xy 128.382906 -241.780512) (xy 128.42479 -241.809422) (xy 128.461494 -241.844677)
			(xy 128.492067 -241.885363) (xy 128.515718 -241.930426) (xy 128.531834 -241.9787) (xy 128.539998 -242.028934)
			(xy 128.54051 -242.05438) (xy 128.848607 -242.05438) (xy 128.852702 -242.003652) (xy 128.864881 -241.954238)
			(xy 128.884829 -241.907418) (xy 128.91203 -241.864404) (xy 128.945778 -241.82631) (xy 128.9852 -241.794123)
			(xy 129.029274 -241.768677) (xy 129.07686 -241.75063) (xy 129.126724 -241.74045) (xy 129.177576 -241.738401)
			(xy 129.228097 -241.744535) (xy 129.276981 -241.758695) (xy 129.32296 -241.780512) (xy 129.364844 -241.809422)
			(xy 129.401548 -241.844677) (xy 129.432121 -241.885363) (xy 129.455772 -241.930426) (xy 129.471888 -241.9787)
			(xy 129.480052 -242.028934) (xy 129.480564 -242.05438) (xy 130.728461 -242.05438) (xy 130.732556 -242.003652)
			(xy 130.744735 -241.954238) (xy 130.764683 -241.907418) (xy 130.791884 -241.864404) (xy 130.825632 -241.82631)
			(xy 130.865054 -241.794123) (xy 130.909128 -241.768677) (xy 130.956714 -241.75063) (xy 131.006578 -241.74045)
			(xy 131.05743 -241.738401) (xy 131.107951 -241.744535) (xy 131.156835 -241.758695) (xy 131.202814 -241.780512)
			(xy 131.244698 -241.809422) (xy 131.281402 -241.844677) (xy 131.311975 -241.885363) (xy 131.335626 -241.930426)
			(xy 131.351742 -241.9787) (xy 131.359906 -242.028934) (xy 131.360418 -242.05438) (xy 131.678946 -242.05438)
			(xy 131.682906 -242.005326) (xy 131.694683 -241.957542) (xy 131.713974 -241.912266) (xy 131.740277 -241.87067)
			(xy 131.772912 -241.833833) (xy 131.811033 -241.802708) (xy 131.853654 -241.778101) (xy 131.89967 -241.760649)
			(xy 131.947889 -241.750805) (xy 131.997064 -241.748824) (xy 132.045919 -241.754756) (xy 132.09319 -241.768448)
			(xy 132.137652 -241.789546) (xy 132.178155 -241.817502) (xy 132.213648 -241.851594) (xy 132.243213 -241.890938)
			(xy 132.266084 -241.934515) (xy 132.281668 -241.981196) (xy 132.289563 -242.029773) (xy 132.290058 -242.05438)
			(xy 132.608569 -242.05438) (xy 132.612664 -242.003652) (xy 132.624843 -241.954238) (xy 132.644791 -241.907418)
			(xy 132.671992 -241.864404) (xy 132.70574 -241.82631) (xy 132.745162 -241.794123) (xy 132.789236 -241.768677)
			(xy 132.836822 -241.75063) (xy 132.886686 -241.74045) (xy 132.937538 -241.738401) (xy 132.988059 -241.744535)
			(xy 133.036943 -241.758695) (xy 133.082922 -241.780512) (xy 133.124806 -241.809422) (xy 133.16151 -241.844677)
			(xy 133.192083 -241.885363) (xy 133.215734 -241.930426) (xy 133.23185 -241.9787) (xy 133.240014 -242.028934)
			(xy 133.240526 -242.05438) (xy 133.559054 -242.05438) (xy 133.563014 -242.005326) (xy 133.574791 -241.957542)
			(xy 133.594082 -241.912266) (xy 133.620385 -241.87067) (xy 133.65302 -241.833833) (xy 133.691141 -241.802708)
			(xy 133.733762 -241.778101) (xy 133.779778 -241.760649) (xy 133.827997 -241.750805) (xy 133.877172 -241.748824)
			(xy 133.926027 -241.754756) (xy 133.973298 -241.768448) (xy 134.01776 -241.789546) (xy 134.058263 -241.817502)
			(xy 134.093756 -241.851594) (xy 134.123321 -241.890938) (xy 134.146192 -241.934515) (xy 134.161776 -241.981196)
			(xy 134.169671 -242.029773) (xy 134.170166 -242.05438) (xy 134.488423 -242.05438) (xy 134.492518 -242.003652)
			(xy 134.504697 -241.954238) (xy 134.524645 -241.907418) (xy 134.551846 -241.864404) (xy 134.585594 -241.82631)
			(xy 134.625016 -241.794123) (xy 134.66909 -241.768677) (xy 134.716676 -241.75063) (xy 134.76654 -241.74045)
			(xy 134.817392 -241.738401) (xy 134.867913 -241.744535) (xy 134.916797 -241.758695) (xy 134.962776 -241.780512)
			(xy 135.00466 -241.809422) (xy 135.041364 -241.844677) (xy 135.071937 -241.885363) (xy 135.095588 -241.930426)
			(xy 135.111704 -241.9787) (xy 135.119868 -242.028934) (xy 135.12038 -242.05438) (xy 135.428477 -242.05438)
			(xy 135.432572 -242.003652) (xy 135.444751 -241.954238) (xy 135.464699 -241.907418) (xy 135.4919 -241.864404)
			(xy 135.525648 -241.82631) (xy 135.56507 -241.794123) (xy 135.609144 -241.768677) (xy 135.65673 -241.75063)
			(xy 135.706594 -241.74045) (xy 135.757446 -241.738401) (xy 135.807967 -241.744535) (xy 135.856851 -241.758695)
			(xy 135.90283 -241.780512) (xy 135.944714 -241.809422) (xy 135.981418 -241.844677) (xy 136.011991 -241.885363)
			(xy 136.035642 -241.930426) (xy 136.051758 -241.9787) (xy 136.059922 -242.028934) (xy 136.060434 -242.05438)
			(xy 137.308585 -242.05438) (xy 137.31268 -242.003652) (xy 137.324859 -241.954238) (xy 137.344807 -241.907418)
			(xy 137.372008 -241.864404) (xy 137.405756 -241.82631) (xy 137.445178 -241.794123) (xy 137.489252 -241.768677)
			(xy 137.536838 -241.75063) (xy 137.586702 -241.74045) (xy 137.637554 -241.738401) (xy 137.688075 -241.744535)
			(xy 137.736959 -241.758695) (xy 137.782938 -241.780512) (xy 137.824822 -241.809422) (xy 137.861526 -241.844677)
			(xy 137.892099 -241.885363) (xy 137.91575 -241.930426) (xy 137.931866 -241.9787) (xy 137.94003 -242.028934)
			(xy 137.940542 -242.05438) (xy 138.25907 -242.05438) (xy 138.26303 -242.005326) (xy 138.274807 -241.957542)
			(xy 138.294098 -241.912266) (xy 138.320401 -241.87067) (xy 138.353036 -241.833833) (xy 138.391157 -241.802708)
			(xy 138.433778 -241.778101) (xy 138.479794 -241.760649) (xy 138.528013 -241.750805) (xy 138.577188 -241.748824)
			(xy 138.626043 -241.754756) (xy 138.673314 -241.768448) (xy 138.717776 -241.789546) (xy 138.758279 -241.817502)
			(xy 138.793772 -241.851594) (xy 138.823337 -241.890938) (xy 138.846208 -241.934515) (xy 138.861792 -241.981196)
			(xy 138.869687 -242.029773) (xy 138.870182 -242.05438) (xy 139.188439 -242.05438) (xy 139.192534 -242.003652)
			(xy 139.204713 -241.954238) (xy 139.224661 -241.907418) (xy 139.251862 -241.864404) (xy 139.28561 -241.82631)
			(xy 139.325032 -241.794123) (xy 139.369106 -241.768677) (xy 139.416692 -241.75063) (xy 139.466556 -241.74045)
			(xy 139.517408 -241.738401) (xy 139.567929 -241.744535) (xy 139.616813 -241.758695) (xy 139.662792 -241.780512)
			(xy 139.704676 -241.809422) (xy 139.74138 -241.844677) (xy 139.771953 -241.885363) (xy 139.795604 -241.930426)
			(xy 139.81172 -241.9787) (xy 139.819884 -242.028934) (xy 139.820396 -242.05438) (xy 140.138924 -242.05438)
			(xy 140.142884 -242.005326) (xy 140.154661 -241.957542) (xy 140.173952 -241.912266) (xy 140.200255 -241.87067)
			(xy 140.23289 -241.833833) (xy 140.271011 -241.802708) (xy 140.313632 -241.778101) (xy 140.359648 -241.760649)
			(xy 140.407867 -241.750805) (xy 140.457042 -241.748824) (xy 140.505897 -241.754756) (xy 140.553168 -241.768448)
			(xy 140.59763 -241.789546) (xy 140.638133 -241.817502) (xy 140.673626 -241.851594) (xy 140.703191 -241.890938)
			(xy 140.726062 -241.934515) (xy 140.741646 -241.981196) (xy 140.749541 -242.029773) (xy 140.750036 -242.05438)
			(xy 141.068547 -242.05438) (xy 141.072642 -242.003652) (xy 141.084821 -241.954238) (xy 141.104769 -241.907418)
			(xy 141.13197 -241.864404) (xy 141.165718 -241.82631) (xy 141.20514 -241.794123) (xy 141.249214 -241.768677)
			(xy 141.2968 -241.75063) (xy 141.346664 -241.74045) (xy 141.397516 -241.738401) (xy 141.448037 -241.744535)
			(xy 141.496921 -241.758695) (xy 141.5429 -241.780512) (xy 141.584784 -241.809422) (xy 141.621488 -241.844677)
			(xy 141.652061 -241.885363) (xy 141.675712 -241.930426) (xy 141.691828 -241.9787) (xy 141.699992 -242.028934)
			(xy 141.700504 -242.05438) (xy 142.008601 -242.05438) (xy 142.012696 -242.003652) (xy 142.024875 -241.954238)
			(xy 142.044823 -241.907418) (xy 142.072024 -241.864404) (xy 142.105772 -241.82631) (xy 142.145194 -241.794123)
			(xy 142.189268 -241.768677) (xy 142.236854 -241.75063) (xy 142.286718 -241.74045) (xy 142.33757 -241.738401)
			(xy 142.388091 -241.744535) (xy 142.436975 -241.758695) (xy 142.482954 -241.780512) (xy 142.524838 -241.809422)
			(xy 142.561542 -241.844677) (xy 142.592115 -241.885363) (xy 142.615766 -241.930426) (xy 142.631882 -241.9787)
			(xy 142.640046 -242.028934) (xy 142.640558 -242.05438) (xy 144.83894 -242.05438) (xy 144.8429 -242.005326)
			(xy 144.854677 -241.957542) (xy 144.873968 -241.912266) (xy 144.900271 -241.87067) (xy 144.932906 -241.833833)
			(xy 144.971027 -241.802708) (xy 145.013648 -241.778101) (xy 145.059664 -241.760649) (xy 145.107883 -241.750805)
			(xy 145.157058 -241.748824) (xy 145.205913 -241.754756) (xy 145.253184 -241.768448) (xy 145.297646 -241.789546)
			(xy 145.338149 -241.817502) (xy 145.373642 -241.851594) (xy 145.403207 -241.890938) (xy 145.426078 -241.934515)
			(xy 145.441662 -241.981196) (xy 145.449557 -242.029773) (xy 145.450052 -242.05438) (xy 145.449557 -242.078987)
			(xy 145.441662 -242.127564) (xy 145.426078 -242.174245) (xy 145.403207 -242.217822) (xy 145.373642 -242.257166)
			(xy 145.338149 -242.291258) (xy 145.297646 -242.319214) (xy 145.253184 -242.340312) (xy 145.205913 -242.354004)
			(xy 145.157058 -242.359936) (xy 145.107883 -242.357955) (xy 145.059664 -242.348111) (xy 145.013648 -242.330659)
			(xy 144.971027 -242.306052) (xy 144.932906 -242.274927) (xy 144.900271 -242.23809) (xy 144.873968 -242.196494)
			(xy 144.854677 -242.151218) (xy 144.8429 -242.103434) (xy 144.83894 -242.05438) (xy 142.640558 -242.05438)
			(xy 142.640046 -242.079826) (xy 142.631882 -242.13006) (xy 142.615766 -242.178334) (xy 142.592115 -242.223397)
			(xy 142.561542 -242.264083) (xy 142.524838 -242.299338) (xy 142.482954 -242.328248) (xy 142.436975 -242.350065)
			(xy 142.388091 -242.364225) (xy 142.33757 -242.370359) (xy 142.286718 -242.36831) (xy 142.236854 -242.35813)
			(xy 142.189268 -242.340083) (xy 142.145194 -242.314637) (xy 142.105772 -242.28245) (xy 142.072024 -242.244356)
			(xy 142.044823 -242.201342) (xy 142.024875 -242.154522) (xy 142.012696 -242.105108) (xy 142.008601 -242.05438)
			(xy 141.700504 -242.05438) (xy 141.699992 -242.079826) (xy 141.691828 -242.13006) (xy 141.675712 -242.178334)
			(xy 141.652061 -242.223397) (xy 141.621488 -242.264083) (xy 141.584784 -242.299338) (xy 141.5429 -242.328248)
			(xy 141.496921 -242.350065) (xy 141.448037 -242.364225) (xy 141.397516 -242.370359) (xy 141.346664 -242.36831)
			(xy 141.2968 -242.35813) (xy 141.249214 -242.340083) (xy 141.20514 -242.314637) (xy 141.165718 -242.28245)
			(xy 141.13197 -242.244356) (xy 141.104769 -242.201342) (xy 141.084821 -242.154522) (xy 141.072642 -242.105108)
			(xy 141.068547 -242.05438) (xy 140.750036 -242.05438) (xy 140.749541 -242.078987) (xy 140.741646 -242.127564)
			(xy 140.726062 -242.174245) (xy 140.703191 -242.217822) (xy 140.673626 -242.257166) (xy 140.638133 -242.291258)
			(xy 140.59763 -242.319214) (xy 140.553168 -242.340312) (xy 140.505897 -242.354004) (xy 140.457042 -242.359936)
			(xy 140.407867 -242.357955) (xy 140.359648 -242.348111) (xy 140.313632 -242.330659) (xy 140.271011 -242.306052)
			(xy 140.23289 -242.274927) (xy 140.200255 -242.23809) (xy 140.173952 -242.196494) (xy 140.154661 -242.151218)
			(xy 140.142884 -242.103434) (xy 140.138924 -242.05438) (xy 139.820396 -242.05438) (xy 139.819884 -242.079826)
			(xy 139.81172 -242.13006) (xy 139.795604 -242.178334) (xy 139.771953 -242.223397) (xy 139.74138 -242.264083)
			(xy 139.704676 -242.299338) (xy 139.662792 -242.328248) (xy 139.616813 -242.350065) (xy 139.567929 -242.364225)
			(xy 139.517408 -242.370359) (xy 139.466556 -242.36831) (xy 139.416692 -242.35813) (xy 139.369106 -242.340083)
			(xy 139.325032 -242.314637) (xy 139.28561 -242.28245) (xy 139.251862 -242.244356) (xy 139.224661 -242.201342)
			(xy 139.204713 -242.154522) (xy 139.192534 -242.105108) (xy 139.188439 -242.05438) (xy 138.870182 -242.05438)
			(xy 138.869687 -242.078987) (xy 138.861792 -242.127564) (xy 138.846208 -242.174245) (xy 138.823337 -242.217822)
			(xy 138.793772 -242.257166) (xy 138.758279 -242.291258) (xy 138.717776 -242.319214) (xy 138.673314 -242.340312)
			(xy 138.626043 -242.354004) (xy 138.577188 -242.359936) (xy 138.528013 -242.357955) (xy 138.479794 -242.348111)
			(xy 138.433778 -242.330659) (xy 138.391157 -242.306052) (xy 138.353036 -242.274927) (xy 138.320401 -242.23809)
			(xy 138.294098 -242.196494) (xy 138.274807 -242.151218) (xy 138.26303 -242.103434) (xy 138.25907 -242.05438)
			(xy 137.940542 -242.05438) (xy 137.94003 -242.079826) (xy 137.931866 -242.13006) (xy 137.91575 -242.178334)
			(xy 137.892099 -242.223397) (xy 137.861526 -242.264083) (xy 137.824822 -242.299338) (xy 137.782938 -242.328248)
			(xy 137.736959 -242.350065) (xy 137.688075 -242.364225) (xy 137.637554 -242.370359) (xy 137.586702 -242.36831)
			(xy 137.536838 -242.35813) (xy 137.489252 -242.340083) (xy 137.445178 -242.314637) (xy 137.405756 -242.28245)
			(xy 137.372008 -242.244356) (xy 137.344807 -242.201342) (xy 137.324859 -242.154522) (xy 137.31268 -242.105108)
			(xy 137.308585 -242.05438) (xy 136.060434 -242.05438) (xy 136.059922 -242.079826) (xy 136.051758 -242.13006)
			(xy 136.035642 -242.178334) (xy 136.011991 -242.223397) (xy 135.981418 -242.264083) (xy 135.944714 -242.299338)
			(xy 135.90283 -242.328248) (xy 135.856851 -242.350065) (xy 135.807967 -242.364225) (xy 135.757446 -242.370359)
			(xy 135.706594 -242.36831) (xy 135.65673 -242.35813) (xy 135.609144 -242.340083) (xy 135.56507 -242.314637)
			(xy 135.525648 -242.28245) (xy 135.4919 -242.244356) (xy 135.464699 -242.201342) (xy 135.444751 -242.154522)
			(xy 135.432572 -242.105108) (xy 135.428477 -242.05438) (xy 135.12038 -242.05438) (xy 135.119868 -242.079826)
			(xy 135.111704 -242.13006) (xy 135.095588 -242.178334) (xy 135.071937 -242.223397) (xy 135.041364 -242.264083)
			(xy 135.00466 -242.299338) (xy 134.962776 -242.328248) (xy 134.916797 -242.350065) (xy 134.867913 -242.364225)
			(xy 134.817392 -242.370359) (xy 134.76654 -242.36831) (xy 134.716676 -242.35813) (xy 134.66909 -242.340083)
			(xy 134.625016 -242.314637) (xy 134.585594 -242.28245) (xy 134.551846 -242.244356) (xy 134.524645 -242.201342)
			(xy 134.504697 -242.154522) (xy 134.492518 -242.105108) (xy 134.488423 -242.05438) (xy 134.170166 -242.05438)
			(xy 134.169671 -242.078987) (xy 134.161776 -242.127564) (xy 134.146192 -242.174245) (xy 134.123321 -242.217822)
			(xy 134.093756 -242.257166) (xy 134.058263 -242.291258) (xy 134.01776 -242.319214) (xy 133.973298 -242.340312)
			(xy 133.926027 -242.354004) (xy 133.877172 -242.359936) (xy 133.827997 -242.357955) (xy 133.779778 -242.348111)
			(xy 133.733762 -242.330659) (xy 133.691141 -242.306052) (xy 133.65302 -242.274927) (xy 133.620385 -242.23809)
			(xy 133.594082 -242.196494) (xy 133.574791 -242.151218) (xy 133.563014 -242.103434) (xy 133.559054 -242.05438)
			(xy 133.240526 -242.05438) (xy 133.240014 -242.079826) (xy 133.23185 -242.13006) (xy 133.215734 -242.178334)
			(xy 133.192083 -242.223397) (xy 133.16151 -242.264083) (xy 133.124806 -242.299338) (xy 133.082922 -242.328248)
			(xy 133.036943 -242.350065) (xy 132.988059 -242.364225) (xy 132.937538 -242.370359) (xy 132.886686 -242.36831)
			(xy 132.836822 -242.35813) (xy 132.789236 -242.340083) (xy 132.745162 -242.314637) (xy 132.70574 -242.28245)
			(xy 132.671992 -242.244356) (xy 132.644791 -242.201342) (xy 132.624843 -242.154522) (xy 132.612664 -242.105108)
			(xy 132.608569 -242.05438) (xy 132.290058 -242.05438) (xy 132.289563 -242.078987) (xy 132.281668 -242.127564)
			(xy 132.266084 -242.174245) (xy 132.243213 -242.217822) (xy 132.213648 -242.257166) (xy 132.178155 -242.291258)
			(xy 132.137652 -242.319214) (xy 132.09319 -242.340312) (xy 132.045919 -242.354004) (xy 131.997064 -242.359936)
			(xy 131.947889 -242.357955) (xy 131.89967 -242.348111) (xy 131.853654 -242.330659) (xy 131.811033 -242.306052)
			(xy 131.772912 -242.274927) (xy 131.740277 -242.23809) (xy 131.713974 -242.196494) (xy 131.694683 -242.151218)
			(xy 131.682906 -242.103434) (xy 131.678946 -242.05438) (xy 131.360418 -242.05438) (xy 131.359906 -242.079826)
			(xy 131.351742 -242.13006) (xy 131.335626 -242.178334) (xy 131.311975 -242.223397) (xy 131.281402 -242.264083)
			(xy 131.244698 -242.299338) (xy 131.202814 -242.328248) (xy 131.156835 -242.350065) (xy 131.107951 -242.364225)
			(xy 131.05743 -242.370359) (xy 131.006578 -242.36831) (xy 130.956714 -242.35813) (xy 130.909128 -242.340083)
			(xy 130.865054 -242.314637) (xy 130.825632 -242.28245) (xy 130.791884 -242.244356) (xy 130.764683 -242.201342)
			(xy 130.744735 -242.154522) (xy 130.732556 -242.105108) (xy 130.728461 -242.05438) (xy 129.480564 -242.05438)
			(xy 129.480052 -242.079826) (xy 129.471888 -242.13006) (xy 129.455772 -242.178334) (xy 129.432121 -242.223397)
			(xy 129.401548 -242.264083) (xy 129.364844 -242.299338) (xy 129.32296 -242.328248) (xy 129.276981 -242.350065)
			(xy 129.228097 -242.364225) (xy 129.177576 -242.370359) (xy 129.126724 -242.36831) (xy 129.07686 -242.35813)
			(xy 129.029274 -242.340083) (xy 128.9852 -242.314637) (xy 128.945778 -242.28245) (xy 128.91203 -242.244356)
			(xy 128.884829 -242.201342) (xy 128.864881 -242.154522) (xy 128.852702 -242.105108) (xy 128.848607 -242.05438)
			(xy 128.54051 -242.05438) (xy 128.539998 -242.079826) (xy 128.531834 -242.13006) (xy 128.515718 -242.178334)
			(xy 128.492067 -242.223397) (xy 128.461494 -242.264083) (xy 128.42479 -242.299338) (xy 128.382906 -242.328248)
			(xy 128.336927 -242.350065) (xy 128.288043 -242.364225) (xy 128.237522 -242.370359) (xy 128.18667 -242.36831)
			(xy 128.136806 -242.35813) (xy 128.08922 -242.340083) (xy 128.045146 -242.314637) (xy 128.005724 -242.28245)
			(xy 127.971976 -242.244356) (xy 127.944775 -242.201342) (xy 127.924827 -242.154522) (xy 127.912648 -242.105108)
			(xy 127.908553 -242.05438) (xy 127.679417 -242.05438) (xy 127.679417 -242.054381) (xy 127.675849 -242.151924)
			(xy 127.665161 -242.248945) (xy 127.64741 -242.344925) (xy 127.62269 -242.439352) (xy 127.607314 -242.485672)
			(xy 127.60452 -242.493546) (xy 127.60452 -242.511834) (xy 127.605014 -242.521836) (xy 127.61268 -242.540312)
			(xy 127.626833 -242.55445) (xy 127.645318 -242.562097) (xy 127.65532 -242.562634) (xy 127.662432 -242.562634)
			(xy 127.669036 -242.560602) (xy 127.689997 -242.555034) (xy 127.73295 -242.549048) (xy 127.754634 -242.548664)
			(xy 127.779443 -242.549153) (xy 127.828449 -242.55692) (xy 127.875637 -242.572257) (xy 127.919845 -242.594786)
			(xy 127.959985 -242.623954) (xy 127.995069 -242.659041) (xy 128.024232 -242.699184) (xy 128.046756 -242.743394)
			(xy 128.062088 -242.790584) (xy 128.069849 -242.839591) (xy 128.069849 -242.864386) (xy 128.388884 -242.864386)
			(xy 128.392844 -242.815332) (xy 128.404621 -242.767548) (xy 128.423912 -242.722272) (xy 128.450215 -242.680676)
			(xy 128.48285 -242.643839) (xy 128.520971 -242.612714) (xy 128.563592 -242.588107) (xy 128.609608 -242.570655)
			(xy 128.657827 -242.560811) (xy 128.707002 -242.55883) (xy 128.755857 -242.564762) (xy 128.803128 -242.578454)
			(xy 128.84759 -242.599552) (xy 128.888093 -242.627508) (xy 128.923586 -242.6616) (xy 128.953151 -242.700944)
			(xy 128.976022 -242.744521) (xy 128.991606 -242.791202) (xy 128.999501 -242.839779) (xy 128.999996 -242.864386)
			(xy 129.318507 -242.864386) (xy 129.322602 -242.813658) (xy 129.334781 -242.764244) (xy 129.354729 -242.717424)
			(xy 129.38193 -242.67441) (xy 129.415678 -242.636316) (xy 129.4551 -242.604129) (xy 129.499174 -242.578683)
			(xy 129.54676 -242.560636) (xy 129.596624 -242.550456) (xy 129.647476 -242.548407) (xy 129.697997 -242.554541)
			(xy 129.746881 -242.568701) (xy 129.79286 -242.590518) (xy 129.834744 -242.619428) (xy 129.871448 -242.654683)
			(xy 129.902021 -242.695369) (xy 129.925672 -242.740432) (xy 129.941788 -242.788706) (xy 129.949952 -242.83894)
			(xy 129.950464 -242.864386) (xy 130.268992 -242.864386) (xy 130.272952 -242.815332) (xy 130.284729 -242.767548)
			(xy 130.30402 -242.722272) (xy 130.330323 -242.680676) (xy 130.362958 -242.643839) (xy 130.401079 -242.612714)
			(xy 130.4437 -242.588107) (xy 130.489716 -242.570655) (xy 130.537935 -242.560811) (xy 130.58711 -242.55883)
			(xy 130.635965 -242.564762) (xy 130.683236 -242.578454) (xy 130.727698 -242.599552) (xy 130.768201 -242.627508)
			(xy 130.803694 -242.6616) (xy 130.833259 -242.700944) (xy 130.85613 -242.744521) (xy 130.871714 -242.791202)
			(xy 130.879609 -242.839779) (xy 130.880104 -242.864386) (xy 131.198615 -242.864386) (xy 131.20271 -242.813658)
			(xy 131.214889 -242.764244) (xy 131.234837 -242.717424) (xy 131.262038 -242.67441) (xy 131.295786 -242.636316)
			(xy 131.335208 -242.604129) (xy 131.379282 -242.578683) (xy 131.426868 -242.560636) (xy 131.476732 -242.550456)
			(xy 131.527584 -242.548407) (xy 131.578105 -242.554541) (xy 131.626989 -242.568701) (xy 131.672968 -242.590518)
			(xy 131.714852 -242.619428) (xy 131.751556 -242.654683) (xy 131.782129 -242.695369) (xy 131.80578 -242.740432)
			(xy 131.821896 -242.788706) (xy 131.83006 -242.83894) (xy 131.830572 -242.864386) (xy 132.138415 -242.864386)
			(xy 132.14251 -242.813658) (xy 132.154689 -242.764244) (xy 132.174637 -242.717424) (xy 132.201838 -242.67441)
			(xy 132.235586 -242.636316) (xy 132.275008 -242.604129) (xy 132.319082 -242.578683) (xy 132.366668 -242.560636)
			(xy 132.416532 -242.550456) (xy 132.467384 -242.548407) (xy 132.517905 -242.554541) (xy 132.566789 -242.568701)
			(xy 132.612768 -242.590518) (xy 132.654652 -242.619428) (xy 132.691356 -242.654683) (xy 132.721929 -242.695369)
			(xy 132.74558 -242.740432) (xy 132.761696 -242.788706) (xy 132.76986 -242.83894) (xy 132.770372 -242.864386)
			(xy 133.0889 -242.864386) (xy 133.09286 -242.815332) (xy 133.104637 -242.767548) (xy 133.123928 -242.722272)
			(xy 133.150231 -242.680676) (xy 133.182866 -242.643839) (xy 133.220987 -242.612714) (xy 133.263608 -242.588107)
			(xy 133.309624 -242.570655) (xy 133.357843 -242.560811) (xy 133.407018 -242.55883) (xy 133.455873 -242.564762)
			(xy 133.503144 -242.578454) (xy 133.547606 -242.599552) (xy 133.588109 -242.627508) (xy 133.623602 -242.6616)
			(xy 133.653167 -242.700944) (xy 133.676038 -242.744521) (xy 133.691622 -242.791202) (xy 133.699517 -242.839779)
			(xy 133.700012 -242.864386) (xy 134.018523 -242.864386) (xy 134.022618 -242.813658) (xy 134.034797 -242.764244)
			(xy 134.054745 -242.717424) (xy 134.081946 -242.67441) (xy 134.115694 -242.636316) (xy 134.155116 -242.604129)
			(xy 134.19919 -242.578683) (xy 134.246776 -242.560636) (xy 134.29664 -242.550456) (xy 134.347492 -242.548407)
			(xy 134.398013 -242.554541) (xy 134.446897 -242.568701) (xy 134.492876 -242.590518) (xy 134.53476 -242.619428)
			(xy 134.571464 -242.654683) (xy 134.602037 -242.695369) (xy 134.625688 -242.740432) (xy 134.641804 -242.788706)
			(xy 134.649968 -242.83894) (xy 134.65048 -242.864386) (xy 134.969008 -242.864386) (xy 134.972968 -242.815332)
			(xy 134.984745 -242.767548) (xy 135.004036 -242.722272) (xy 135.030339 -242.680676) (xy 135.062974 -242.643839)
			(xy 135.101095 -242.612714) (xy 135.143716 -242.588107) (xy 135.189732 -242.570655) (xy 135.237951 -242.560811)
			(xy 135.287126 -242.55883) (xy 135.335981 -242.564762) (xy 135.383252 -242.578454) (xy 135.427714 -242.599552)
			(xy 135.468217 -242.627508) (xy 135.50371 -242.6616) (xy 135.533275 -242.700944) (xy 135.556146 -242.744521)
			(xy 135.57173 -242.791202) (xy 135.579625 -242.839779) (xy 135.58012 -242.864386) (xy 135.898631 -242.864386)
			(xy 135.902726 -242.813658) (xy 135.914905 -242.764244) (xy 135.934853 -242.717424) (xy 135.962054 -242.67441)
			(xy 135.995802 -242.636316) (xy 136.035224 -242.604129) (xy 136.079298 -242.578683) (xy 136.126884 -242.560636)
			(xy 136.176748 -242.550456) (xy 136.2276 -242.548407) (xy 136.278121 -242.554541) (xy 136.327005 -242.568701)
			(xy 136.372984 -242.590518) (xy 136.414868 -242.619428) (xy 136.451572 -242.654683) (xy 136.482145 -242.695369)
			(xy 136.505796 -242.740432) (xy 136.521912 -242.788706) (xy 136.530076 -242.83894) (xy 136.530588 -242.864386)
			(xy 136.848862 -242.864386) (xy 136.852822 -242.815332) (xy 136.864599 -242.767548) (xy 136.88389 -242.722272)
			(xy 136.910193 -242.680676) (xy 136.942828 -242.643839) (xy 136.980949 -242.612714) (xy 137.02357 -242.588107)
			(xy 137.069586 -242.570655) (xy 137.117805 -242.560811) (xy 137.16698 -242.55883) (xy 137.215835 -242.564762)
			(xy 137.263106 -242.578454) (xy 137.307568 -242.599552) (xy 137.348071 -242.627508) (xy 137.383564 -242.6616)
			(xy 137.413129 -242.700944) (xy 137.436 -242.744521) (xy 137.451584 -242.791202) (xy 137.459479 -242.839779)
			(xy 137.459974 -242.864386) (xy 137.778485 -242.864386) (xy 137.78258 -242.813658) (xy 137.794759 -242.764244)
			(xy 137.814707 -242.717424) (xy 137.841908 -242.67441) (xy 137.875656 -242.636316) (xy 137.915078 -242.604129)
			(xy 137.959152 -242.578683) (xy 138.006738 -242.560636) (xy 138.056602 -242.550456) (xy 138.107454 -242.548407)
			(xy 138.157975 -242.554541) (xy 138.206859 -242.568701) (xy 138.252838 -242.590518) (xy 138.294722 -242.619428)
			(xy 138.331426 -242.654683) (xy 138.361999 -242.695369) (xy 138.38565 -242.740432) (xy 138.401766 -242.788706)
			(xy 138.40993 -242.83894) (xy 138.410442 -242.864386) (xy 138.718539 -242.864386) (xy 138.722634 -242.813658)
			(xy 138.734813 -242.764244) (xy 138.754761 -242.717424) (xy 138.781962 -242.67441) (xy 138.81571 -242.636316)
			(xy 138.855132 -242.604129) (xy 138.899206 -242.578683) (xy 138.946792 -242.560636) (xy 138.996656 -242.550456)
			(xy 139.047508 -242.548407) (xy 139.098029 -242.554541) (xy 139.146913 -242.568701) (xy 139.192892 -242.590518)
			(xy 139.234776 -242.619428) (xy 139.27148 -242.654683) (xy 139.302053 -242.695369) (xy 139.325704 -242.740432)
			(xy 139.34182 -242.788706) (xy 139.349984 -242.83894) (xy 139.350496 -242.864386) (xy 139.669024 -242.864386)
			(xy 139.672984 -242.815332) (xy 139.684761 -242.767548) (xy 139.704052 -242.722272) (xy 139.730355 -242.680676)
			(xy 139.76299 -242.643839) (xy 139.801111 -242.612714) (xy 139.843732 -242.588107) (xy 139.889748 -242.570655)
			(xy 139.937967 -242.560811) (xy 139.987142 -242.55883) (xy 140.035997 -242.564762) (xy 140.083268 -242.578454)
			(xy 140.12773 -242.599552) (xy 140.168233 -242.627508) (xy 140.203726 -242.6616) (xy 140.233291 -242.700944)
			(xy 140.256162 -242.744521) (xy 140.271746 -242.791202) (xy 140.279641 -242.839779) (xy 140.280136 -242.864386)
			(xy 140.598647 -242.864386) (xy 140.602742 -242.813658) (xy 140.614921 -242.764244) (xy 140.634869 -242.717424)
			(xy 140.66207 -242.67441) (xy 140.695818 -242.636316) (xy 140.73524 -242.604129) (xy 140.779314 -242.578683)
			(xy 140.8269 -242.560636) (xy 140.876764 -242.550456) (xy 140.927616 -242.548407) (xy 140.978137 -242.554541)
			(xy 141.027021 -242.568701) (xy 141.073 -242.590518) (xy 141.114884 -242.619428) (xy 141.151588 -242.654683)
			(xy 141.182161 -242.695369) (xy 141.205812 -242.740432) (xy 141.221928 -242.788706) (xy 141.230092 -242.83894)
			(xy 141.230604 -242.864386) (xy 141.548878 -242.864386) (xy 141.552838 -242.815332) (xy 141.564615 -242.767548)
			(xy 141.583906 -242.722272) (xy 141.610209 -242.680676) (xy 141.642844 -242.643839) (xy 141.680965 -242.612714)
			(xy 141.723586 -242.588107) (xy 141.769602 -242.570655) (xy 141.817821 -242.560811) (xy 141.866996 -242.55883)
			(xy 141.915851 -242.564762) (xy 141.963122 -242.578454) (xy 142.007584 -242.599552) (xy 142.048087 -242.627508)
			(xy 142.08358 -242.6616) (xy 142.113145 -242.700944) (xy 142.136016 -242.744521) (xy 142.1516 -242.791202)
			(xy 142.159495 -242.839779) (xy 142.15999 -242.864386) (xy 142.478501 -242.864386) (xy 142.482596 -242.813658)
			(xy 142.494775 -242.764244) (xy 142.514723 -242.717424) (xy 142.541924 -242.67441) (xy 142.575672 -242.636316)
			(xy 142.615094 -242.604129) (xy 142.659168 -242.578683) (xy 142.706754 -242.560636) (xy 142.756618 -242.550456)
			(xy 142.80747 -242.548407) (xy 142.857991 -242.554541) (xy 142.906875 -242.568701) (xy 142.952854 -242.590518)
			(xy 142.994738 -242.619428) (xy 143.031442 -242.654683) (xy 143.062015 -242.695369) (xy 143.085666 -242.740432)
			(xy 143.101782 -242.788706) (xy 143.109946 -242.83894) (xy 143.110458 -242.864386) (xy 143.428986 -242.864386)
			(xy 143.432946 -242.815332) (xy 143.444723 -242.767548) (xy 143.464014 -242.722272) (xy 143.490317 -242.680676)
			(xy 143.522952 -242.643839) (xy 143.561073 -242.612714) (xy 143.603694 -242.588107) (xy 143.64971 -242.570655)
			(xy 143.697929 -242.560811) (xy 143.747104 -242.55883) (xy 143.795959 -242.564762) (xy 143.84323 -242.578454)
			(xy 143.887692 -242.599552) (xy 143.928195 -242.627508) (xy 143.963688 -242.6616) (xy 143.993253 -242.700944)
			(xy 144.016124 -242.744521) (xy 144.031708 -242.791202) (xy 144.039603 -242.839779) (xy 144.040098 -242.864386)
			(xy 144.039603 -242.888993) (xy 144.031708 -242.93757) (xy 144.016124 -242.984251) (xy 143.993253 -243.027828)
			(xy 143.963688 -243.067172) (xy 143.928195 -243.101264) (xy 143.887692 -243.12922) (xy 143.84323 -243.150318)
			(xy 143.795959 -243.16401) (xy 143.747104 -243.169942) (xy 143.697929 -243.167961) (xy 143.64971 -243.158117)
			(xy 143.603694 -243.140665) (xy 143.561073 -243.116058) (xy 143.522952 -243.084933) (xy 143.490317 -243.048096)
			(xy 143.464014 -243.0065) (xy 143.444723 -242.961224) (xy 143.432946 -242.91344) (xy 143.428986 -242.864386)
			(xy 143.110458 -242.864386) (xy 143.109946 -242.889832) (xy 143.101782 -242.940066) (xy 143.085666 -242.98834)
			(xy 143.062015 -243.033403) (xy 143.031442 -243.074089) (xy 142.994738 -243.109344) (xy 142.952854 -243.138254)
			(xy 142.906875 -243.160071) (xy 142.857991 -243.174231) (xy 142.80747 -243.180365) (xy 142.756618 -243.178316)
			(xy 142.706754 -243.168136) (xy 142.659168 -243.150089) (xy 142.615094 -243.124643) (xy 142.575672 -243.092456)
			(xy 142.541924 -243.054362) (xy 142.514723 -243.011348) (xy 142.494775 -242.964528) (xy 142.482596 -242.915114)
			(xy 142.478501 -242.864386) (xy 142.15999 -242.864386) (xy 142.159495 -242.888993) (xy 142.1516 -242.93757)
			(xy 142.136016 -242.984251) (xy 142.113145 -243.027828) (xy 142.08358 -243.067172) (xy 142.048087 -243.101264)
			(xy 142.007584 -243.12922) (xy 141.963122 -243.150318) (xy 141.915851 -243.16401) (xy 141.866996 -243.169942)
			(xy 141.817821 -243.167961) (xy 141.769602 -243.158117) (xy 141.723586 -243.140665) (xy 141.680965 -243.116058)
			(xy 141.642844 -243.084933) (xy 141.610209 -243.048096) (xy 141.583906 -243.0065) (xy 141.564615 -242.961224)
			(xy 141.552838 -242.91344) (xy 141.548878 -242.864386) (xy 141.230604 -242.864386) (xy 141.230092 -242.889832)
			(xy 141.221928 -242.940066) (xy 141.205812 -242.98834) (xy 141.182161 -243.033403) (xy 141.151588 -243.074089)
			(xy 141.114884 -243.109344) (xy 141.073 -243.138254) (xy 141.027021 -243.160071) (xy 140.978137 -243.174231)
			(xy 140.927616 -243.180365) (xy 140.876764 -243.178316) (xy 140.8269 -243.168136) (xy 140.779314 -243.150089)
			(xy 140.73524 -243.124643) (xy 140.695818 -243.092456) (xy 140.66207 -243.054362) (xy 140.634869 -243.011348)
			(xy 140.614921 -242.964528) (xy 140.602742 -242.915114) (xy 140.598647 -242.864386) (xy 140.280136 -242.864386)
			(xy 140.279641 -242.888993) (xy 140.271746 -242.93757) (xy 140.256162 -242.984251) (xy 140.233291 -243.027828)
			(xy 140.203726 -243.067172) (xy 140.168233 -243.101264) (xy 140.12773 -243.12922) (xy 140.083268 -243.150318)
			(xy 140.035997 -243.16401) (xy 139.987142 -243.169942) (xy 139.937967 -243.167961) (xy 139.889748 -243.158117)
			(xy 139.843732 -243.140665) (xy 139.801111 -243.116058) (xy 139.76299 -243.084933) (xy 139.730355 -243.048096)
			(xy 139.704052 -243.0065) (xy 139.684761 -242.961224) (xy 139.672984 -242.91344) (xy 139.669024 -242.864386)
			(xy 139.350496 -242.864386) (xy 139.349984 -242.889832) (xy 139.34182 -242.940066) (xy 139.325704 -242.98834)
			(xy 139.302053 -243.033403) (xy 139.27148 -243.074089) (xy 139.234776 -243.109344) (xy 139.192892 -243.138254)
			(xy 139.146913 -243.160071) (xy 139.098029 -243.174231) (xy 139.047508 -243.180365) (xy 138.996656 -243.178316)
			(xy 138.946792 -243.168136) (xy 138.899206 -243.150089) (xy 138.855132 -243.124643) (xy 138.81571 -243.092456)
			(xy 138.781962 -243.054362) (xy 138.754761 -243.011348) (xy 138.734813 -242.964528) (xy 138.722634 -242.915114)
			(xy 138.718539 -242.864386) (xy 138.410442 -242.864386) (xy 138.40993 -242.889832) (xy 138.401766 -242.940066)
			(xy 138.38565 -242.98834) (xy 138.361999 -243.033403) (xy 138.331426 -243.074089) (xy 138.294722 -243.109344)
			(xy 138.252838 -243.138254) (xy 138.206859 -243.160071) (xy 138.157975 -243.174231) (xy 138.107454 -243.180365)
			(xy 138.056602 -243.178316) (xy 138.006738 -243.168136) (xy 137.959152 -243.150089) (xy 137.915078 -243.124643)
			(xy 137.875656 -243.092456) (xy 137.841908 -243.054362) (xy 137.814707 -243.011348) (xy 137.794759 -242.964528)
			(xy 137.78258 -242.915114) (xy 137.778485 -242.864386) (xy 137.459974 -242.864386) (xy 137.459479 -242.888993)
			(xy 137.451584 -242.93757) (xy 137.436 -242.984251) (xy 137.413129 -243.027828) (xy 137.383564 -243.067172)
			(xy 137.348071 -243.101264) (xy 137.307568 -243.12922) (xy 137.263106 -243.150318) (xy 137.215835 -243.16401)
			(xy 137.16698 -243.169942) (xy 137.117805 -243.167961) (xy 137.069586 -243.158117) (xy 137.02357 -243.140665)
			(xy 136.980949 -243.116058) (xy 136.942828 -243.084933) (xy 136.910193 -243.048096) (xy 136.88389 -243.0065)
			(xy 136.864599 -242.961224) (xy 136.852822 -242.91344) (xy 136.848862 -242.864386) (xy 136.530588 -242.864386)
			(xy 136.530076 -242.889832) (xy 136.521912 -242.940066) (xy 136.505796 -242.98834) (xy 136.482145 -243.033403)
			(xy 136.451572 -243.074089) (xy 136.414868 -243.109344) (xy 136.372984 -243.138254) (xy 136.327005 -243.160071)
			(xy 136.278121 -243.174231) (xy 136.2276 -243.180365) (xy 136.176748 -243.178316) (xy 136.126884 -243.168136)
			(xy 136.079298 -243.150089) (xy 136.035224 -243.124643) (xy 135.995802 -243.092456) (xy 135.962054 -243.054362)
			(xy 135.934853 -243.011348) (xy 135.914905 -242.964528) (xy 135.902726 -242.915114) (xy 135.898631 -242.864386)
			(xy 135.58012 -242.864386) (xy 135.579625 -242.888993) (xy 135.57173 -242.93757) (xy 135.556146 -242.984251)
			(xy 135.533275 -243.027828) (xy 135.50371 -243.067172) (xy 135.468217 -243.101264) (xy 135.427714 -243.12922)
			(xy 135.383252 -243.150318) (xy 135.335981 -243.16401) (xy 135.287126 -243.169942) (xy 135.237951 -243.167961)
			(xy 135.189732 -243.158117) (xy 135.143716 -243.140665) (xy 135.101095 -243.116058) (xy 135.062974 -243.084933)
			(xy 135.030339 -243.048096) (xy 135.004036 -243.0065) (xy 134.984745 -242.961224) (xy 134.972968 -242.91344)
			(xy 134.969008 -242.864386) (xy 134.65048 -242.864386) (xy 134.649968 -242.889832) (xy 134.641804 -242.940066)
			(xy 134.625688 -242.98834) (xy 134.602037 -243.033403) (xy 134.571464 -243.074089) (xy 134.53476 -243.109344)
			(xy 134.492876 -243.138254) (xy 134.446897 -243.160071) (xy 134.398013 -243.174231) (xy 134.347492 -243.180365)
			(xy 134.29664 -243.178316) (xy 134.246776 -243.168136) (xy 134.19919 -243.150089) (xy 134.155116 -243.124643)
			(xy 134.115694 -243.092456) (xy 134.081946 -243.054362) (xy 134.054745 -243.011348) (xy 134.034797 -242.964528)
			(xy 134.022618 -242.915114) (xy 134.018523 -242.864386) (xy 133.700012 -242.864386) (xy 133.699517 -242.888993)
			(xy 133.691622 -242.93757) (xy 133.676038 -242.984251) (xy 133.653167 -243.027828) (xy 133.623602 -243.067172)
			(xy 133.588109 -243.101264) (xy 133.547606 -243.12922) (xy 133.503144 -243.150318) (xy 133.455873 -243.16401)
			(xy 133.407018 -243.169942) (xy 133.357843 -243.167961) (xy 133.309624 -243.158117) (xy 133.263608 -243.140665)
			(xy 133.220987 -243.116058) (xy 133.182866 -243.084933) (xy 133.150231 -243.048096) (xy 133.123928 -243.0065)
			(xy 133.104637 -242.961224) (xy 133.09286 -242.91344) (xy 133.0889 -242.864386) (xy 132.770372 -242.864386)
			(xy 132.76986 -242.889832) (xy 132.761696 -242.940066) (xy 132.74558 -242.98834) (xy 132.721929 -243.033403)
			(xy 132.691356 -243.074089) (xy 132.654652 -243.109344) (xy 132.612768 -243.138254) (xy 132.566789 -243.160071)
			(xy 132.517905 -243.174231) (xy 132.467384 -243.180365) (xy 132.416532 -243.178316) (xy 132.366668 -243.168136)
			(xy 132.319082 -243.150089) (xy 132.275008 -243.124643) (xy 132.235586 -243.092456) (xy 132.201838 -243.054362)
			(xy 132.174637 -243.011348) (xy 132.154689 -242.964528) (xy 132.14251 -242.915114) (xy 132.138415 -242.864386)
			(xy 131.830572 -242.864386) (xy 131.83006 -242.889832) (xy 131.821896 -242.940066) (xy 131.80578 -242.98834)
			(xy 131.782129 -243.033403) (xy 131.751556 -243.074089) (xy 131.714852 -243.109344) (xy 131.672968 -243.138254)
			(xy 131.626989 -243.160071) (xy 131.578105 -243.174231) (xy 131.527584 -243.180365) (xy 131.476732 -243.178316)
			(xy 131.426868 -243.168136) (xy 131.379282 -243.150089) (xy 131.335208 -243.124643) (xy 131.295786 -243.092456)
			(xy 131.262038 -243.054362) (xy 131.234837 -243.011348) (xy 131.214889 -242.964528) (xy 131.20271 -242.915114)
			(xy 131.198615 -242.864386) (xy 130.880104 -242.864386) (xy 130.879609 -242.888993) (xy 130.871714 -242.93757)
			(xy 130.85613 -242.984251) (xy 130.833259 -243.027828) (xy 130.803694 -243.067172) (xy 130.768201 -243.101264)
			(xy 130.727698 -243.12922) (xy 130.683236 -243.150318) (xy 130.635965 -243.16401) (xy 130.58711 -243.169942)
			(xy 130.537935 -243.167961) (xy 130.489716 -243.158117) (xy 130.4437 -243.140665) (xy 130.401079 -243.116058)
			(xy 130.362958 -243.084933) (xy 130.330323 -243.048096) (xy 130.30402 -243.0065) (xy 130.284729 -242.961224)
			(xy 130.272952 -242.91344) (xy 130.268992 -242.864386) (xy 129.950464 -242.864386) (xy 129.949952 -242.889832)
			(xy 129.941788 -242.940066) (xy 129.925672 -242.98834) (xy 129.902021 -243.033403) (xy 129.871448 -243.074089)
			(xy 129.834744 -243.109344) (xy 129.79286 -243.138254) (xy 129.746881 -243.160071) (xy 129.697997 -243.174231)
			(xy 129.647476 -243.180365) (xy 129.596624 -243.178316) (xy 129.54676 -243.168136) (xy 129.499174 -243.150089)
			(xy 129.4551 -243.124643) (xy 129.415678 -243.092456) (xy 129.38193 -243.054362) (xy 129.354729 -243.011348)
			(xy 129.334781 -242.964528) (xy 129.322602 -242.915114) (xy 129.318507 -242.864386) (xy 128.999996 -242.864386)
			(xy 128.999501 -242.888993) (xy 128.991606 -242.93757) (xy 128.976022 -242.984251) (xy 128.953151 -243.027828)
			(xy 128.923586 -243.067172) (xy 128.888093 -243.101264) (xy 128.84759 -243.12922) (xy 128.803128 -243.150318)
			(xy 128.755857 -243.16401) (xy 128.707002 -243.169942) (xy 128.657827 -243.167961) (xy 128.609608 -243.158117)
			(xy 128.563592 -243.140665) (xy 128.520971 -243.116058) (xy 128.48285 -243.084933) (xy 128.450215 -243.048096)
			(xy 128.423912 -243.0065) (xy 128.404621 -242.961224) (xy 128.392844 -242.91344) (xy 128.388884 -242.864386)
			(xy 128.069849 -242.864386) (xy 128.069849 -242.889209) (xy 128.062088 -242.938216) (xy 128.046756 -242.985406)
			(xy 128.024232 -243.029616) (xy 127.995069 -243.069759) (xy 127.959985 -243.104846) (xy 127.919845 -243.134014)
			(xy 127.875637 -243.156543) (xy 127.828449 -243.17188) (xy 127.779443 -243.179647) (xy 127.754634 -243.180108)
			(xy 127.732952 -243.179709) (xy 127.690002 -243.173713) (xy 127.669036 -243.16817) (xy 127.662432 -243.166138)
			(xy 127.65532 -243.166138) (xy 127.645299 -243.166555) (xy 127.626782 -243.174222) (xy 127.612612 -243.188397)
			(xy 127.604951 -243.206917) (xy 127.60452 -243.216938) (xy 127.60452 -243.235226) (xy 127.607314 -243.2431)
			(xy 127.622679 -243.289424) (xy 127.6474 -243.38385) (xy 127.665153 -243.479829) (xy 127.675843 -243.57685)
			(xy 127.679413 -243.674392) (xy 127.908553 -243.674392) (xy 127.912648 -243.623664) (xy 127.924827 -243.57425)
			(xy 127.944775 -243.52743) (xy 127.971976 -243.484416) (xy 128.005724 -243.446322) (xy 128.045146 -243.414135)
			(xy 128.08922 -243.388689) (xy 128.136806 -243.370642) (xy 128.18667 -243.360462) (xy 128.237522 -243.358413)
			(xy 128.288043 -243.364547) (xy 128.336927 -243.378707) (xy 128.382906 -243.400524) (xy 128.42479 -243.429434)
			(xy 128.461494 -243.464689) (xy 128.492067 -243.505375) (xy 128.515718 -243.550438) (xy 128.531834 -243.598712)
			(xy 128.539998 -243.648946) (xy 128.54051 -243.674392) (xy 128.848607 -243.674392) (xy 128.852702 -243.623664)
			(xy 128.864881 -243.57425) (xy 128.884829 -243.52743) (xy 128.91203 -243.484416) (xy 128.945778 -243.446322)
			(xy 128.9852 -243.414135) (xy 129.029274 -243.388689) (xy 129.07686 -243.370642) (xy 129.126724 -243.360462)
			(xy 129.177576 -243.358413) (xy 129.228097 -243.364547) (xy 129.276981 -243.378707) (xy 129.32296 -243.400524)
			(xy 129.364844 -243.429434) (xy 129.401548 -243.464689) (xy 129.432121 -243.505375) (xy 129.455772 -243.550438)
			(xy 129.471888 -243.598712) (xy 129.480052 -243.648946) (xy 129.480564 -243.674392) (xy 129.798838 -243.674392)
			(xy 129.802798 -243.625338) (xy 129.814575 -243.577554) (xy 129.833866 -243.532278) (xy 129.860169 -243.490682)
			(xy 129.892804 -243.453845) (xy 129.930925 -243.42272) (xy 129.973546 -243.398113) (xy 130.019562 -243.380661)
			(xy 130.067781 -243.370817) (xy 130.116956 -243.368836) (xy 130.165811 -243.374768) (xy 130.213082 -243.38846)
			(xy 130.257544 -243.409558) (xy 130.298047 -243.437514) (xy 130.33354 -243.471606) (xy 130.363105 -243.51095)
			(xy 130.385976 -243.554527) (xy 130.40156 -243.601208) (xy 130.409455 -243.649785) (xy 130.40995 -243.674392)
			(xy 130.728461 -243.674392) (xy 130.732556 -243.623664) (xy 130.744735 -243.57425) (xy 130.764683 -243.52743)
			(xy 130.791884 -243.484416) (xy 130.825632 -243.446322) (xy 130.865054 -243.414135) (xy 130.909128 -243.388689)
			(xy 130.956714 -243.370642) (xy 131.006578 -243.360462) (xy 131.05743 -243.358413) (xy 131.107951 -243.364547)
			(xy 131.156835 -243.378707) (xy 131.202814 -243.400524) (xy 131.244698 -243.429434) (xy 131.281402 -243.464689)
			(xy 131.311975 -243.505375) (xy 131.335626 -243.550438) (xy 131.351742 -243.598712) (xy 131.359906 -243.648946)
			(xy 131.360418 -243.674392) (xy 131.678946 -243.674392) (xy 131.682906 -243.625338) (xy 131.694683 -243.577554)
			(xy 131.713974 -243.532278) (xy 131.740277 -243.490682) (xy 131.772912 -243.453845) (xy 131.811033 -243.42272)
			(xy 131.853654 -243.398113) (xy 131.89967 -243.380661) (xy 131.947889 -243.370817) (xy 131.997064 -243.368836)
			(xy 132.045919 -243.374768) (xy 132.09319 -243.38846) (xy 132.137652 -243.409558) (xy 132.178155 -243.437514)
			(xy 132.213648 -243.471606) (xy 132.243213 -243.51095) (xy 132.266084 -243.554527) (xy 132.281668 -243.601208)
			(xy 132.289563 -243.649785) (xy 132.290058 -243.674392) (xy 132.608569 -243.674392) (xy 132.612664 -243.623664)
			(xy 132.624843 -243.57425) (xy 132.644791 -243.52743) (xy 132.671992 -243.484416) (xy 132.70574 -243.446322)
			(xy 132.745162 -243.414135) (xy 132.789236 -243.388689) (xy 132.836822 -243.370642) (xy 132.886686 -243.360462)
			(xy 132.937538 -243.358413) (xy 132.988059 -243.364547) (xy 133.036943 -243.378707) (xy 133.082922 -243.400524)
			(xy 133.124806 -243.429434) (xy 133.16151 -243.464689) (xy 133.192083 -243.505375) (xy 133.215734 -243.550438)
			(xy 133.23185 -243.598712) (xy 133.240014 -243.648946) (xy 133.240526 -243.674392) (xy 133.559054 -243.674392)
			(xy 133.563014 -243.625338) (xy 133.574791 -243.577554) (xy 133.594082 -243.532278) (xy 133.620385 -243.490682)
			(xy 133.65302 -243.453845) (xy 133.691141 -243.42272) (xy 133.733762 -243.398113) (xy 133.779778 -243.380661)
			(xy 133.827997 -243.370817) (xy 133.877172 -243.368836) (xy 133.926027 -243.374768) (xy 133.973298 -243.38846)
			(xy 134.01776 -243.409558) (xy 134.058263 -243.437514) (xy 134.093756 -243.471606) (xy 134.123321 -243.51095)
			(xy 134.146192 -243.554527) (xy 134.161776 -243.601208) (xy 134.169671 -243.649785) (xy 134.170166 -243.674392)
			(xy 134.488423 -243.674392) (xy 134.492518 -243.623664) (xy 134.504697 -243.57425) (xy 134.524645 -243.52743)
			(xy 134.551846 -243.484416) (xy 134.585594 -243.446322) (xy 134.625016 -243.414135) (xy 134.66909 -243.388689)
			(xy 134.716676 -243.370642) (xy 134.76654 -243.360462) (xy 134.817392 -243.358413) (xy 134.867913 -243.364547)
			(xy 134.916797 -243.378707) (xy 134.962776 -243.400524) (xy 135.00466 -243.429434) (xy 135.041364 -243.464689)
			(xy 135.071937 -243.505375) (xy 135.095588 -243.550438) (xy 135.111704 -243.598712) (xy 135.119868 -243.648946)
			(xy 135.12038 -243.674392) (xy 135.428477 -243.674392) (xy 135.432572 -243.623664) (xy 135.444751 -243.57425)
			(xy 135.464699 -243.52743) (xy 135.4919 -243.484416) (xy 135.525648 -243.446322) (xy 135.56507 -243.414135)
			(xy 135.609144 -243.388689) (xy 135.65673 -243.370642) (xy 135.706594 -243.360462) (xy 135.757446 -243.358413)
			(xy 135.807967 -243.364547) (xy 135.856851 -243.378707) (xy 135.90283 -243.400524) (xy 135.944714 -243.429434)
			(xy 135.981418 -243.464689) (xy 136.011991 -243.505375) (xy 136.035642 -243.550438) (xy 136.051758 -243.598712)
			(xy 136.059922 -243.648946) (xy 136.060434 -243.674392) (xy 136.378962 -243.674392) (xy 136.382922 -243.625338)
			(xy 136.394699 -243.577554) (xy 136.41399 -243.532278) (xy 136.440293 -243.490682) (xy 136.472928 -243.453845)
			(xy 136.511049 -243.42272) (xy 136.55367 -243.398113) (xy 136.599686 -243.380661) (xy 136.647905 -243.370817)
			(xy 136.69708 -243.368836) (xy 136.745935 -243.374768) (xy 136.793206 -243.38846) (xy 136.837668 -243.409558)
			(xy 136.878171 -243.437514) (xy 136.913664 -243.471606) (xy 136.943229 -243.51095) (xy 136.9661 -243.554527)
			(xy 136.981684 -243.601208) (xy 136.989579 -243.649785) (xy 136.990074 -243.674392) (xy 137.308585 -243.674392)
			(xy 137.31268 -243.623664) (xy 137.324859 -243.57425) (xy 137.344807 -243.52743) (xy 137.372008 -243.484416)
			(xy 137.405756 -243.446322) (xy 137.445178 -243.414135) (xy 137.489252 -243.388689) (xy 137.536838 -243.370642)
			(xy 137.586702 -243.360462) (xy 137.637554 -243.358413) (xy 137.688075 -243.364547) (xy 137.736959 -243.378707)
			(xy 137.782938 -243.400524) (xy 137.824822 -243.429434) (xy 137.861526 -243.464689) (xy 137.892099 -243.505375)
			(xy 137.91575 -243.550438) (xy 137.931866 -243.598712) (xy 137.94003 -243.648946) (xy 137.940542 -243.674392)
			(xy 138.25907 -243.674392) (xy 138.26303 -243.625338) (xy 138.274807 -243.577554) (xy 138.294098 -243.532278)
			(xy 138.320401 -243.490682) (xy 138.353036 -243.453845) (xy 138.391157 -243.42272) (xy 138.433778 -243.398113)
			(xy 138.479794 -243.380661) (xy 138.528013 -243.370817) (xy 138.577188 -243.368836) (xy 138.626043 -243.374768)
			(xy 138.673314 -243.38846) (xy 138.717776 -243.409558) (xy 138.758279 -243.437514) (xy 138.793772 -243.471606)
			(xy 138.823337 -243.51095) (xy 138.846208 -243.554527) (xy 138.861792 -243.601208) (xy 138.869687 -243.649785)
			(xy 138.870182 -243.674392) (xy 139.188439 -243.674392) (xy 139.192534 -243.623664) (xy 139.204713 -243.57425)
			(xy 139.224661 -243.52743) (xy 139.251862 -243.484416) (xy 139.28561 -243.446322) (xy 139.325032 -243.414135)
			(xy 139.369106 -243.388689) (xy 139.416692 -243.370642) (xy 139.466556 -243.360462) (xy 139.517408 -243.358413)
			(xy 139.567929 -243.364547) (xy 139.616813 -243.378707) (xy 139.662792 -243.400524) (xy 139.704676 -243.429434)
			(xy 139.74138 -243.464689) (xy 139.771953 -243.505375) (xy 139.795604 -243.550438) (xy 139.81172 -243.598712)
			(xy 139.819884 -243.648946) (xy 139.820396 -243.674392) (xy 140.138924 -243.674392) (xy 140.142884 -243.625338)
			(xy 140.154661 -243.577554) (xy 140.173952 -243.532278) (xy 140.200255 -243.490682) (xy 140.23289 -243.453845)
			(xy 140.271011 -243.42272) (xy 140.313632 -243.398113) (xy 140.359648 -243.380661) (xy 140.407867 -243.370817)
			(xy 140.457042 -243.368836) (xy 140.505897 -243.374768) (xy 140.553168 -243.38846) (xy 140.59763 -243.409558)
			(xy 140.638133 -243.437514) (xy 140.673626 -243.471606) (xy 140.703191 -243.51095) (xy 140.726062 -243.554527)
			(xy 140.741646 -243.601208) (xy 140.749541 -243.649785) (xy 140.750036 -243.674392) (xy 141.068547 -243.674392)
			(xy 141.072642 -243.623664) (xy 141.084821 -243.57425) (xy 141.104769 -243.52743) (xy 141.13197 -243.484416)
			(xy 141.165718 -243.446322) (xy 141.20514 -243.414135) (xy 141.249214 -243.388689) (xy 141.2968 -243.370642)
			(xy 141.346664 -243.360462) (xy 141.397516 -243.358413) (xy 141.448037 -243.364547) (xy 141.496921 -243.378707)
			(xy 141.5429 -243.400524) (xy 141.584784 -243.429434) (xy 141.621488 -243.464689) (xy 141.652061 -243.505375)
			(xy 141.675712 -243.550438) (xy 141.691828 -243.598712) (xy 141.699992 -243.648946) (xy 141.700504 -243.674392)
			(xy 142.008601 -243.674392) (xy 142.012696 -243.623664) (xy 142.024875 -243.57425) (xy 142.044823 -243.52743)
			(xy 142.072024 -243.484416) (xy 142.105772 -243.446322) (xy 142.145194 -243.414135) (xy 142.189268 -243.388689)
			(xy 142.236854 -243.370642) (xy 142.286718 -243.360462) (xy 142.33757 -243.358413) (xy 142.388091 -243.364547)
			(xy 142.436975 -243.378707) (xy 142.482954 -243.400524) (xy 142.524838 -243.429434) (xy 142.561542 -243.464689)
			(xy 142.592115 -243.505375) (xy 142.615766 -243.550438) (xy 142.631882 -243.598712) (xy 142.640046 -243.648946)
			(xy 142.640558 -243.674392) (xy 142.958832 -243.674392) (xy 142.962792 -243.625338) (xy 142.974569 -243.577554)
			(xy 142.99386 -243.532278) (xy 143.020163 -243.490682) (xy 143.052798 -243.453845) (xy 143.090919 -243.42272)
			(xy 143.13354 -243.398113) (xy 143.179556 -243.380661) (xy 143.227775 -243.370817) (xy 143.27695 -243.368836)
			(xy 143.325805 -243.374768) (xy 143.373076 -243.38846) (xy 143.417538 -243.409558) (xy 143.458041 -243.437514)
			(xy 143.493534 -243.471606) (xy 143.523099 -243.51095) (xy 143.54597 -243.554527) (xy 143.561554 -243.601208)
			(xy 143.569449 -243.649785) (xy 143.569944 -243.674392) (xy 144.83894 -243.674392) (xy 144.8429 -243.625338)
			(xy 144.854677 -243.577554) (xy 144.873968 -243.532278) (xy 144.900271 -243.490682) (xy 144.932906 -243.453845)
			(xy 144.971027 -243.42272) (xy 145.013648 -243.398113) (xy 145.059664 -243.380661) (xy 145.107883 -243.370817)
			(xy 145.157058 -243.368836) (xy 145.205913 -243.374768) (xy 145.253184 -243.38846) (xy 145.297646 -243.409558)
			(xy 145.338149 -243.437514) (xy 145.373642 -243.471606) (xy 145.403207 -243.51095) (xy 145.426078 -243.554527)
			(xy 145.441662 -243.601208) (xy 145.449557 -243.649785) (xy 145.450052 -243.674392) (xy 145.449557 -243.698999)
			(xy 145.441662 -243.747576) (xy 145.426078 -243.794257) (xy 145.403207 -243.837834) (xy 145.373642 -243.877178)
			(xy 145.338149 -243.91127) (xy 145.297646 -243.939226) (xy 145.253184 -243.960324) (xy 145.205913 -243.974016)
			(xy 145.157058 -243.979948) (xy 145.107883 -243.977967) (xy 145.059664 -243.968123) (xy 145.013648 -243.950671)
			(xy 144.971027 -243.926064) (xy 144.932906 -243.894939) (xy 144.900271 -243.858102) (xy 144.873968 -243.816506)
			(xy 144.854677 -243.77123) (xy 144.8429 -243.723446) (xy 144.83894 -243.674392) (xy 143.569944 -243.674392)
			(xy 143.569449 -243.698999) (xy 143.561554 -243.747576) (xy 143.54597 -243.794257) (xy 143.523099 -243.837834)
			(xy 143.493534 -243.877178) (xy 143.458041 -243.91127) (xy 143.417538 -243.939226) (xy 143.373076 -243.960324)
			(xy 143.325805 -243.974016) (xy 143.27695 -243.979948) (xy 143.227775 -243.977967) (xy 143.179556 -243.968123)
			(xy 143.13354 -243.950671) (xy 143.090919 -243.926064) (xy 143.052798 -243.894939) (xy 143.020163 -243.858102)
			(xy 142.99386 -243.816506) (xy 142.974569 -243.77123) (xy 142.962792 -243.723446) (xy 142.958832 -243.674392)
			(xy 142.640558 -243.674392) (xy 142.640046 -243.699838) (xy 142.631882 -243.750072) (xy 142.615766 -243.798346)
			(xy 142.592115 -243.843409) (xy 142.561542 -243.884095) (xy 142.524838 -243.91935) (xy 142.482954 -243.94826)
			(xy 142.436975 -243.970077) (xy 142.388091 -243.984237) (xy 142.33757 -243.990371) (xy 142.286718 -243.988322)
			(xy 142.236854 -243.978142) (xy 142.189268 -243.960095) (xy 142.145194 -243.934649) (xy 142.105772 -243.902462)
			(xy 142.072024 -243.864368) (xy 142.044823 -243.821354) (xy 142.024875 -243.774534) (xy 142.012696 -243.72512)
			(xy 142.008601 -243.674392) (xy 141.700504 -243.674392) (xy 141.699992 -243.699838) (xy 141.691828 -243.750072)
			(xy 141.675712 -243.798346) (xy 141.652061 -243.843409) (xy 141.621488 -243.884095) (xy 141.584784 -243.91935)
			(xy 141.5429 -243.94826) (xy 141.496921 -243.970077) (xy 141.448037 -243.984237) (xy 141.397516 -243.990371)
			(xy 141.346664 -243.988322) (xy 141.2968 -243.978142) (xy 141.249214 -243.960095) (xy 141.20514 -243.934649)
			(xy 141.165718 -243.902462) (xy 141.13197 -243.864368) (xy 141.104769 -243.821354) (xy 141.084821 -243.774534)
			(xy 141.072642 -243.72512) (xy 141.068547 -243.674392) (xy 140.750036 -243.674392) (xy 140.749541 -243.698999)
			(xy 140.741646 -243.747576) (xy 140.726062 -243.794257) (xy 140.703191 -243.837834) (xy 140.673626 -243.877178)
			(xy 140.638133 -243.91127) (xy 140.59763 -243.939226) (xy 140.553168 -243.960324) (xy 140.505897 -243.974016)
			(xy 140.457042 -243.979948) (xy 140.407867 -243.977967) (xy 140.359648 -243.968123) (xy 140.313632 -243.950671)
			(xy 140.271011 -243.926064) (xy 140.23289 -243.894939) (xy 140.200255 -243.858102) (xy 140.173952 -243.816506)
			(xy 140.154661 -243.77123) (xy 140.142884 -243.723446) (xy 140.138924 -243.674392) (xy 139.820396 -243.674392)
			(xy 139.819884 -243.699838) (xy 139.81172 -243.750072) (xy 139.795604 -243.798346) (xy 139.771953 -243.843409)
			(xy 139.74138 -243.884095) (xy 139.704676 -243.91935) (xy 139.662792 -243.94826) (xy 139.616813 -243.970077)
			(xy 139.567929 -243.984237) (xy 139.517408 -243.990371) (xy 139.466556 -243.988322) (xy 139.416692 -243.978142)
			(xy 139.369106 -243.960095) (xy 139.325032 -243.934649) (xy 139.28561 -243.902462) (xy 139.251862 -243.864368)
			(xy 139.224661 -243.821354) (xy 139.204713 -243.774534) (xy 139.192534 -243.72512) (xy 139.188439 -243.674392)
			(xy 138.870182 -243.674392) (xy 138.869687 -243.698999) (xy 138.861792 -243.747576) (xy 138.846208 -243.794257)
			(xy 138.823337 -243.837834) (xy 138.793772 -243.877178) (xy 138.758279 -243.91127) (xy 138.717776 -243.939226)
			(xy 138.673314 -243.960324) (xy 138.626043 -243.974016) (xy 138.577188 -243.979948) (xy 138.528013 -243.977967)
			(xy 138.479794 -243.968123) (xy 138.433778 -243.950671) (xy 138.391157 -243.926064) (xy 138.353036 -243.894939)
			(xy 138.320401 -243.858102) (xy 138.294098 -243.816506) (xy 138.274807 -243.77123) (xy 138.26303 -243.723446)
			(xy 138.25907 -243.674392) (xy 137.940542 -243.674392) (xy 137.94003 -243.699838) (xy 137.931866 -243.750072)
			(xy 137.91575 -243.798346) (xy 137.892099 -243.843409) (xy 137.861526 -243.884095) (xy 137.824822 -243.91935)
			(xy 137.782938 -243.94826) (xy 137.736959 -243.970077) (xy 137.688075 -243.984237) (xy 137.637554 -243.990371)
			(xy 137.586702 -243.988322) (xy 137.536838 -243.978142) (xy 137.489252 -243.960095) (xy 137.445178 -243.934649)
			(xy 137.405756 -243.902462) (xy 137.372008 -243.864368) (xy 137.344807 -243.821354) (xy 137.324859 -243.774534)
			(xy 137.31268 -243.72512) (xy 137.308585 -243.674392) (xy 136.990074 -243.674392) (xy 136.989579 -243.698999)
			(xy 136.981684 -243.747576) (xy 136.9661 -243.794257) (xy 136.943229 -243.837834) (xy 136.913664 -243.877178)
			(xy 136.878171 -243.91127) (xy 136.837668 -243.939226) (xy 136.793206 -243.960324) (xy 136.745935 -243.974016)
			(xy 136.69708 -243.979948) (xy 136.647905 -243.977967) (xy 136.599686 -243.968123) (xy 136.55367 -243.950671)
			(xy 136.511049 -243.926064) (xy 136.472928 -243.894939) (xy 136.440293 -243.858102) (xy 136.41399 -243.816506)
			(xy 136.394699 -243.77123) (xy 136.382922 -243.723446) (xy 136.378962 -243.674392) (xy 136.060434 -243.674392)
			(xy 136.059922 -243.699838) (xy 136.051758 -243.750072) (xy 136.035642 -243.798346) (xy 136.011991 -243.843409)
			(xy 135.981418 -243.884095) (xy 135.944714 -243.91935) (xy 135.90283 -243.94826) (xy 135.856851 -243.970077)
			(xy 135.807967 -243.984237) (xy 135.757446 -243.990371) (xy 135.706594 -243.988322) (xy 135.65673 -243.978142)
			(xy 135.609144 -243.960095) (xy 135.56507 -243.934649) (xy 135.525648 -243.902462) (xy 135.4919 -243.864368)
			(xy 135.464699 -243.821354) (xy 135.444751 -243.774534) (xy 135.432572 -243.72512) (xy 135.428477 -243.674392)
			(xy 135.12038 -243.674392) (xy 135.119868 -243.699838) (xy 135.111704 -243.750072) (xy 135.095588 -243.798346)
			(xy 135.071937 -243.843409) (xy 135.041364 -243.884095) (xy 135.00466 -243.91935) (xy 134.962776 -243.94826)
			(xy 134.916797 -243.970077) (xy 134.867913 -243.984237) (xy 134.817392 -243.990371) (xy 134.76654 -243.988322)
			(xy 134.716676 -243.978142) (xy 134.66909 -243.960095) (xy 134.625016 -243.934649) (xy 134.585594 -243.902462)
			(xy 134.551846 -243.864368) (xy 134.524645 -243.821354) (xy 134.504697 -243.774534) (xy 134.492518 -243.72512)
			(xy 134.488423 -243.674392) (xy 134.170166 -243.674392) (xy 134.169671 -243.698999) (xy 134.161776 -243.747576)
			(xy 134.146192 -243.794257) (xy 134.123321 -243.837834) (xy 134.093756 -243.877178) (xy 134.058263 -243.91127)
			(xy 134.01776 -243.939226) (xy 133.973298 -243.960324) (xy 133.926027 -243.974016) (xy 133.877172 -243.979948)
			(xy 133.827997 -243.977967) (xy 133.779778 -243.968123) (xy 133.733762 -243.950671) (xy 133.691141 -243.926064)
			(xy 133.65302 -243.894939) (xy 133.620385 -243.858102) (xy 133.594082 -243.816506) (xy 133.574791 -243.77123)
			(xy 133.563014 -243.723446) (xy 133.559054 -243.674392) (xy 133.240526 -243.674392) (xy 133.240014 -243.699838)
			(xy 133.23185 -243.750072) (xy 133.215734 -243.798346) (xy 133.192083 -243.843409) (xy 133.16151 -243.884095)
			(xy 133.124806 -243.91935) (xy 133.082922 -243.94826) (xy 133.036943 -243.970077) (xy 132.988059 -243.984237)
			(xy 132.937538 -243.990371) (xy 132.886686 -243.988322) (xy 132.836822 -243.978142) (xy 132.789236 -243.960095)
			(xy 132.745162 -243.934649) (xy 132.70574 -243.902462) (xy 132.671992 -243.864368) (xy 132.644791 -243.821354)
			(xy 132.624843 -243.774534) (xy 132.612664 -243.72512) (xy 132.608569 -243.674392) (xy 132.290058 -243.674392)
			(xy 132.289563 -243.698999) (xy 132.281668 -243.747576) (xy 132.266084 -243.794257) (xy 132.243213 -243.837834)
			(xy 132.213648 -243.877178) (xy 132.178155 -243.91127) (xy 132.137652 -243.939226) (xy 132.09319 -243.960324)
			(xy 132.045919 -243.974016) (xy 131.997064 -243.979948) (xy 131.947889 -243.977967) (xy 131.89967 -243.968123)
			(xy 131.853654 -243.950671) (xy 131.811033 -243.926064) (xy 131.772912 -243.894939) (xy 131.740277 -243.858102)
			(xy 131.713974 -243.816506) (xy 131.694683 -243.77123) (xy 131.682906 -243.723446) (xy 131.678946 -243.674392)
			(xy 131.360418 -243.674392) (xy 131.359906 -243.699838) (xy 131.351742 -243.750072) (xy 131.335626 -243.798346)
			(xy 131.311975 -243.843409) (xy 131.281402 -243.884095) (xy 131.244698 -243.91935) (xy 131.202814 -243.94826)
			(xy 131.156835 -243.970077) (xy 131.107951 -243.984237) (xy 131.05743 -243.990371) (xy 131.006578 -243.988322)
			(xy 130.956714 -243.978142) (xy 130.909128 -243.960095) (xy 130.865054 -243.934649) (xy 130.825632 -243.902462)
			(xy 130.791884 -243.864368) (xy 130.764683 -243.821354) (xy 130.744735 -243.774534) (xy 130.732556 -243.72512)
			(xy 130.728461 -243.674392) (xy 130.40995 -243.674392) (xy 130.409455 -243.698999) (xy 130.40156 -243.747576)
			(xy 130.385976 -243.794257) (xy 130.363105 -243.837834) (xy 130.33354 -243.877178) (xy 130.298047 -243.91127)
			(xy 130.257544 -243.939226) (xy 130.213082 -243.960324) (xy 130.165811 -243.974016) (xy 130.116956 -243.979948)
			(xy 130.067781 -243.977967) (xy 130.019562 -243.968123) (xy 129.973546 -243.950671) (xy 129.930925 -243.926064)
			(xy 129.892804 -243.894939) (xy 129.860169 -243.858102) (xy 129.833866 -243.816506) (xy 129.814575 -243.77123)
			(xy 129.802798 -243.723446) (xy 129.798838 -243.674392) (xy 129.480564 -243.674392) (xy 129.480052 -243.699838)
			(xy 129.471888 -243.750072) (xy 129.455772 -243.798346) (xy 129.432121 -243.843409) (xy 129.401548 -243.884095)
			(xy 129.364844 -243.91935) (xy 129.32296 -243.94826) (xy 129.276981 -243.970077) (xy 129.228097 -243.984237)
			(xy 129.177576 -243.990371) (xy 129.126724 -243.988322) (xy 129.07686 -243.978142) (xy 129.029274 -243.960095)
			(xy 128.9852 -243.934649) (xy 128.945778 -243.902462) (xy 128.91203 -243.864368) (xy 128.884829 -243.821354)
			(xy 128.864881 -243.774534) (xy 128.852702 -243.72512) (xy 128.848607 -243.674392) (xy 128.54051 -243.674392)
			(xy 128.539998 -243.699838) (xy 128.531834 -243.750072) (xy 128.515718 -243.798346) (xy 128.492067 -243.843409)
			(xy 128.461494 -243.884095) (xy 128.42479 -243.91935) (xy 128.382906 -243.94826) (xy 128.336927 -243.970077)
			(xy 128.288043 -243.984237) (xy 128.237522 -243.990371) (xy 128.18667 -243.988322) (xy 128.136806 -243.978142)
			(xy 128.08922 -243.960095) (xy 128.045146 -243.934649) (xy 128.005724 -243.902462) (xy 127.971976 -243.864368)
			(xy 127.944775 -243.821354) (xy 127.924827 -243.774534) (xy 127.912648 -243.72512) (xy 127.908553 -243.674392)
			(xy 127.679413 -243.674392) (xy 127.675844 -243.771935) (xy 127.665155 -243.868956) (xy 127.647403 -243.964936)
			(xy 127.622683 -244.059361) (xy 127.607314 -244.105684) (xy 127.60452 -244.113558) (xy 127.60452 -244.131846)
			(xy 127.605016 -244.141846) (xy 127.612685 -244.160319) (xy 127.626837 -244.174452) (xy 127.645319 -244.182097)
			(xy 127.65532 -244.182646) (xy 127.662432 -244.182646) (xy 127.669036 -244.180614) (xy 127.689996 -244.175046)
			(xy 127.73295 -244.169059) (xy 127.754634 -244.168676) (xy 127.779442 -244.169165) (xy 127.828446 -244.176932)
			(xy 127.875633 -244.192268) (xy 127.919839 -244.214797) (xy 127.959978 -244.243963) (xy 127.995059 -244.279048)
			(xy 128.024221 -244.31919) (xy 128.046745 -244.363399) (xy 128.062076 -244.410587) (xy 128.069837 -244.459592)
			(xy 128.069837 -244.484398) (xy 128.388884 -244.484398) (xy 128.392844 -244.435344) (xy 128.404621 -244.38756)
			(xy 128.423912 -244.342284) (xy 128.450215 -244.300688) (xy 128.48285 -244.263851) (xy 128.520971 -244.232726)
			(xy 128.563592 -244.208119) (xy 128.609608 -244.190667) (xy 128.657827 -244.180823) (xy 128.707002 -244.178842)
			(xy 128.755857 -244.184774) (xy 128.803128 -244.198466) (xy 128.84759 -244.219564) (xy 128.888093 -244.24752)
			(xy 128.923586 -244.281612) (xy 128.953151 -244.320956) (xy 128.976022 -244.364533) (xy 128.991606 -244.411214)
			(xy 128.999501 -244.459791) (xy 128.999996 -244.484398) (xy 129.318507 -244.484398) (xy 129.322602 -244.43367)
			(xy 129.334781 -244.384256) (xy 129.354729 -244.337436) (xy 129.38193 -244.294422) (xy 129.415678 -244.256328)
			(xy 129.4551 -244.224141) (xy 129.499174 -244.198695) (xy 129.54676 -244.180648) (xy 129.596624 -244.170468)
			(xy 129.647476 -244.168419) (xy 129.697997 -244.174553) (xy 129.746881 -244.188713) (xy 129.79286 -244.21053)
			(xy 129.834744 -244.23944) (xy 129.871448 -244.274695) (xy 129.902021 -244.315381) (xy 129.925672 -244.360444)
			(xy 129.941788 -244.408718) (xy 129.949952 -244.458952) (xy 129.950464 -244.484398) (xy 131.198615 -244.484398)
			(xy 131.20271 -244.43367) (xy 131.214889 -244.384256) (xy 131.234837 -244.337436) (xy 131.262038 -244.294422)
			(xy 131.295786 -244.256328) (xy 131.335208 -244.224141) (xy 131.379282 -244.198695) (xy 131.426868 -244.180648)
			(xy 131.476732 -244.170468) (xy 131.527584 -244.168419) (xy 131.578105 -244.174553) (xy 131.626989 -244.188713)
			(xy 131.672968 -244.21053) (xy 131.714852 -244.23944) (xy 131.751556 -244.274695) (xy 131.782129 -244.315381)
			(xy 131.80578 -244.360444) (xy 131.821896 -244.408718) (xy 131.83006 -244.458952) (xy 131.830572 -244.484398)
			(xy 132.138415 -244.484398) (xy 132.14251 -244.43367) (xy 132.154689 -244.384256) (xy 132.174637 -244.337436)
			(xy 132.201838 -244.294422) (xy 132.235586 -244.256328) (xy 132.275008 -244.224141) (xy 132.319082 -244.198695)
			(xy 132.366668 -244.180648) (xy 132.416532 -244.170468) (xy 132.467384 -244.168419) (xy 132.517905 -244.174553)
			(xy 132.566789 -244.188713) (xy 132.612768 -244.21053) (xy 132.654652 -244.23944) (xy 132.691356 -244.274695)
			(xy 132.721929 -244.315381) (xy 132.74558 -244.360444) (xy 132.761696 -244.408718) (xy 132.76986 -244.458952)
			(xy 132.770372 -244.484398) (xy 133.0889 -244.484398) (xy 133.09286 -244.435344) (xy 133.104637 -244.38756)
			(xy 133.123928 -244.342284) (xy 133.150231 -244.300688) (xy 133.182866 -244.263851) (xy 133.220987 -244.232726)
			(xy 133.263608 -244.208119) (xy 133.309624 -244.190667) (xy 133.357843 -244.180823) (xy 133.407018 -244.178842)
			(xy 133.455873 -244.184774) (xy 133.503144 -244.198466) (xy 133.547606 -244.219564) (xy 133.588109 -244.24752)
			(xy 133.623602 -244.281612) (xy 133.653167 -244.320956) (xy 133.676038 -244.364533) (xy 133.691622 -244.411214)
			(xy 133.699517 -244.459791) (xy 133.700012 -244.484398) (xy 134.018523 -244.484398) (xy 134.022618 -244.43367)
			(xy 134.034797 -244.384256) (xy 134.054745 -244.337436) (xy 134.081946 -244.294422) (xy 134.115694 -244.256328)
			(xy 134.155116 -244.224141) (xy 134.19919 -244.198695) (xy 134.246776 -244.180648) (xy 134.29664 -244.170468)
			(xy 134.347492 -244.168419) (xy 134.398013 -244.174553) (xy 134.446897 -244.188713) (xy 134.492876 -244.21053)
			(xy 134.53476 -244.23944) (xy 134.571464 -244.274695) (xy 134.602037 -244.315381) (xy 134.625688 -244.360444)
			(xy 134.641804 -244.408718) (xy 134.649968 -244.458952) (xy 134.65048 -244.484398) (xy 134.969008 -244.484398)
			(xy 134.972968 -244.435344) (xy 134.984745 -244.38756) (xy 135.004036 -244.342284) (xy 135.030339 -244.300688)
			(xy 135.062974 -244.263851) (xy 135.101095 -244.232726) (xy 135.143716 -244.208119) (xy 135.189732 -244.190667)
			(xy 135.237951 -244.180823) (xy 135.287126 -244.178842) (xy 135.335981 -244.184774) (xy 135.383252 -244.198466)
			(xy 135.427714 -244.219564) (xy 135.468217 -244.24752) (xy 135.50371 -244.281612) (xy 135.533275 -244.320956)
			(xy 135.556146 -244.364533) (xy 135.57173 -244.411214) (xy 135.579625 -244.459791) (xy 135.58012 -244.484398)
			(xy 135.898631 -244.484398) (xy 135.902726 -244.43367) (xy 135.914905 -244.384256) (xy 135.934853 -244.337436)
			(xy 135.962054 -244.294422) (xy 135.995802 -244.256328) (xy 136.035224 -244.224141) (xy 136.079298 -244.198695)
			(xy 136.126884 -244.180648) (xy 136.176748 -244.170468) (xy 136.2276 -244.168419) (xy 136.278121 -244.174553)
			(xy 136.327005 -244.188713) (xy 136.372984 -244.21053) (xy 136.414868 -244.23944) (xy 136.451572 -244.274695)
			(xy 136.482145 -244.315381) (xy 136.505796 -244.360444) (xy 136.521912 -244.408718) (xy 136.530076 -244.458952)
			(xy 136.530588 -244.484398) (xy 137.778485 -244.484398) (xy 137.78258 -244.43367) (xy 137.794759 -244.384256)
			(xy 137.814707 -244.337436) (xy 137.841908 -244.294422) (xy 137.875656 -244.256328) (xy 137.915078 -244.224141)
			(xy 137.959152 -244.198695) (xy 138.006738 -244.180648) (xy 138.056602 -244.170468) (xy 138.107454 -244.168419)
			(xy 138.157975 -244.174553) (xy 138.206859 -244.188713) (xy 138.252838 -244.21053) (xy 138.294722 -244.23944)
			(xy 138.331426 -244.274695) (xy 138.361999 -244.315381) (xy 138.38565 -244.360444) (xy 138.401766 -244.408718)
			(xy 138.40993 -244.458952) (xy 138.410442 -244.484398) (xy 138.718539 -244.484398) (xy 138.722634 -244.43367)
			(xy 138.734813 -244.384256) (xy 138.754761 -244.337436) (xy 138.781962 -244.294422) (xy 138.81571 -244.256328)
			(xy 138.855132 -244.224141) (xy 138.899206 -244.198695) (xy 138.946792 -244.180648) (xy 138.996656 -244.170468)
			(xy 139.047508 -244.168419) (xy 139.098029 -244.174553) (xy 139.146913 -244.188713) (xy 139.192892 -244.21053)
			(xy 139.234776 -244.23944) (xy 139.27148 -244.274695) (xy 139.302053 -244.315381) (xy 139.325704 -244.360444)
			(xy 139.34182 -244.408718) (xy 139.349984 -244.458952) (xy 139.350496 -244.484398) (xy 139.669024 -244.484398)
			(xy 139.672984 -244.435344) (xy 139.684761 -244.38756) (xy 139.704052 -244.342284) (xy 139.730355 -244.300688)
			(xy 139.76299 -244.263851) (xy 139.801111 -244.232726) (xy 139.843732 -244.208119) (xy 139.889748 -244.190667)
			(xy 139.937967 -244.180823) (xy 139.987142 -244.178842) (xy 140.035997 -244.184774) (xy 140.083268 -244.198466)
			(xy 140.12773 -244.219564) (xy 140.168233 -244.24752) (xy 140.203726 -244.281612) (xy 140.233291 -244.320956)
			(xy 140.256162 -244.364533) (xy 140.271746 -244.411214) (xy 140.279641 -244.459791) (xy 140.280136 -244.484398)
			(xy 140.598647 -244.484398) (xy 140.602742 -244.43367) (xy 140.614921 -244.384256) (xy 140.634869 -244.337436)
			(xy 140.66207 -244.294422) (xy 140.695818 -244.256328) (xy 140.73524 -244.224141) (xy 140.779314 -244.198695)
			(xy 140.8269 -244.180648) (xy 140.876764 -244.170468) (xy 140.927616 -244.168419) (xy 140.978137 -244.174553)
			(xy 141.027021 -244.188713) (xy 141.073 -244.21053) (xy 141.114884 -244.23944) (xy 141.151588 -244.274695)
			(xy 141.182161 -244.315381) (xy 141.205812 -244.360444) (xy 141.221928 -244.408718) (xy 141.230092 -244.458952)
			(xy 141.230604 -244.484398) (xy 141.548878 -244.484398) (xy 141.552838 -244.435344) (xy 141.564615 -244.38756)
			(xy 141.583906 -244.342284) (xy 141.610209 -244.300688) (xy 141.642844 -244.263851) (xy 141.680965 -244.232726)
			(xy 141.723586 -244.208119) (xy 141.769602 -244.190667) (xy 141.817821 -244.180823) (xy 141.866996 -244.178842)
			(xy 141.915851 -244.184774) (xy 141.963122 -244.198466) (xy 142.007584 -244.219564) (xy 142.048087 -244.24752)
			(xy 142.08358 -244.281612) (xy 142.113145 -244.320956) (xy 142.136016 -244.364533) (xy 142.1516 -244.411214)
			(xy 142.159495 -244.459791) (xy 142.15999 -244.484398) (xy 142.478501 -244.484398) (xy 142.482596 -244.43367)
			(xy 142.494775 -244.384256) (xy 142.514723 -244.337436) (xy 142.541924 -244.294422) (xy 142.575672 -244.256328)
			(xy 142.615094 -244.224141) (xy 142.659168 -244.198695) (xy 142.706754 -244.180648) (xy 142.756618 -244.170468)
			(xy 142.80747 -244.168419) (xy 142.857991 -244.174553) (xy 142.906875 -244.188713) (xy 142.952854 -244.21053)
			(xy 142.994738 -244.23944) (xy 143.031442 -244.274695) (xy 143.062015 -244.315381) (xy 143.085666 -244.360444)
			(xy 143.101782 -244.408718) (xy 143.109946 -244.458952) (xy 143.110458 -244.484398) (xy 143.109946 -244.509844)
			(xy 143.101782 -244.560078) (xy 143.085666 -244.608352) (xy 143.062015 -244.653415) (xy 143.031442 -244.694101)
			(xy 142.994738 -244.729356) (xy 142.952854 -244.758266) (xy 142.906875 -244.780083) (xy 142.857991 -244.794243)
			(xy 142.80747 -244.800377) (xy 142.756618 -244.798328) (xy 142.706754 -244.788148) (xy 142.659168 -244.770101)
			(xy 142.615094 -244.744655) (xy 142.575672 -244.712468) (xy 142.541924 -244.674374) (xy 142.514723 -244.63136)
			(xy 142.494775 -244.58454) (xy 142.482596 -244.535126) (xy 142.478501 -244.484398) (xy 142.15999 -244.484398)
			(xy 142.159495 -244.509005) (xy 142.1516 -244.557582) (xy 142.136016 -244.604263) (xy 142.113145 -244.64784)
			(xy 142.08358 -244.687184) (xy 142.048087 -244.721276) (xy 142.007584 -244.749232) (xy 141.963122 -244.77033)
			(xy 141.915851 -244.784022) (xy 141.866996 -244.789954) (xy 141.817821 -244.787973) (xy 141.769602 -244.778129)
			(xy 141.723586 -244.760677) (xy 141.680965 -244.73607) (xy 141.642844 -244.704945) (xy 141.610209 -244.668108)
			(xy 141.583906 -244.626512) (xy 141.564615 -244.581236) (xy 141.552838 -244.533452) (xy 141.548878 -244.484398)
			(xy 141.230604 -244.484398) (xy 141.230092 -244.509844) (xy 141.221928 -244.560078) (xy 141.205812 -244.608352)
			(xy 141.182161 -244.653415) (xy 141.151588 -244.694101) (xy 141.114884 -244.729356) (xy 141.073 -244.758266)
			(xy 141.027021 -244.780083) (xy 140.978137 -244.794243) (xy 140.927616 -244.800377) (xy 140.876764 -244.798328)
			(xy 140.8269 -244.788148) (xy 140.779314 -244.770101) (xy 140.73524 -244.744655) (xy 140.695818 -244.712468)
			(xy 140.66207 -244.674374) (xy 140.634869 -244.63136) (xy 140.614921 -244.58454) (xy 140.602742 -244.535126)
			(xy 140.598647 -244.484398) (xy 140.280136 -244.484398) (xy 140.279641 -244.509005) (xy 140.271746 -244.557582)
			(xy 140.256162 -244.604263) (xy 140.233291 -244.64784) (xy 140.203726 -244.687184) (xy 140.168233 -244.721276)
			(xy 140.12773 -244.749232) (xy 140.083268 -244.77033) (xy 140.035997 -244.784022) (xy 139.987142 -244.789954)
			(xy 139.937967 -244.787973) (xy 139.889748 -244.778129) (xy 139.843732 -244.760677) (xy 139.801111 -244.73607)
			(xy 139.76299 -244.704945) (xy 139.730355 -244.668108) (xy 139.704052 -244.626512) (xy 139.684761 -244.581236)
			(xy 139.672984 -244.533452) (xy 139.669024 -244.484398) (xy 139.350496 -244.484398) (xy 139.349984 -244.509844)
			(xy 139.34182 -244.560078) (xy 139.325704 -244.608352) (xy 139.302053 -244.653415) (xy 139.27148 -244.694101)
			(xy 139.234776 -244.729356) (xy 139.192892 -244.758266) (xy 139.146913 -244.780083) (xy 139.098029 -244.794243)
			(xy 139.047508 -244.800377) (xy 138.996656 -244.798328) (xy 138.946792 -244.788148) (xy 138.899206 -244.770101)
			(xy 138.855132 -244.744655) (xy 138.81571 -244.712468) (xy 138.781962 -244.674374) (xy 138.754761 -244.63136)
			(xy 138.734813 -244.58454) (xy 138.722634 -244.535126) (xy 138.718539 -244.484398) (xy 138.410442 -244.484398)
			(xy 138.40993 -244.509844) (xy 138.401766 -244.560078) (xy 138.38565 -244.608352) (xy 138.361999 -244.653415)
			(xy 138.331426 -244.694101) (xy 138.294722 -244.729356) (xy 138.252838 -244.758266) (xy 138.206859 -244.780083)
			(xy 138.157975 -244.794243) (xy 138.107454 -244.800377) (xy 138.056602 -244.798328) (xy 138.006738 -244.788148)
			(xy 137.959152 -244.770101) (xy 137.915078 -244.744655) (xy 137.875656 -244.712468) (xy 137.841908 -244.674374)
			(xy 137.814707 -244.63136) (xy 137.794759 -244.58454) (xy 137.78258 -244.535126) (xy 137.778485 -244.484398)
			(xy 136.530588 -244.484398) (xy 136.530076 -244.509844) (xy 136.521912 -244.560078) (xy 136.505796 -244.608352)
			(xy 136.482145 -244.653415) (xy 136.451572 -244.694101) (xy 136.414868 -244.729356) (xy 136.372984 -244.758266)
			(xy 136.327005 -244.780083) (xy 136.278121 -244.794243) (xy 136.2276 -244.800377) (xy 136.176748 -244.798328)
			(xy 136.126884 -244.788148) (xy 136.079298 -244.770101) (xy 136.035224 -244.744655) (xy 135.995802 -244.712468)
			(xy 135.962054 -244.674374) (xy 135.934853 -244.63136) (xy 135.914905 -244.58454) (xy 135.902726 -244.535126)
			(xy 135.898631 -244.484398) (xy 135.58012 -244.484398) (xy 135.579625 -244.509005) (xy 135.57173 -244.557582)
			(xy 135.556146 -244.604263) (xy 135.533275 -244.64784) (xy 135.50371 -244.687184) (xy 135.468217 -244.721276)
			(xy 135.427714 -244.749232) (xy 135.383252 -244.77033) (xy 135.335981 -244.784022) (xy 135.287126 -244.789954)
			(xy 135.237951 -244.787973) (xy 135.189732 -244.778129) (xy 135.143716 -244.760677) (xy 135.101095 -244.73607)
			(xy 135.062974 -244.704945) (xy 135.030339 -244.668108) (xy 135.004036 -244.626512) (xy 134.984745 -244.581236)
			(xy 134.972968 -244.533452) (xy 134.969008 -244.484398) (xy 134.65048 -244.484398) (xy 134.649968 -244.509844)
			(xy 134.641804 -244.560078) (xy 134.625688 -244.608352) (xy 134.602037 -244.653415) (xy 134.571464 -244.694101)
			(xy 134.53476 -244.729356) (xy 134.492876 -244.758266) (xy 134.446897 -244.780083) (xy 134.398013 -244.794243)
			(xy 134.347492 -244.800377) (xy 134.29664 -244.798328) (xy 134.246776 -244.788148) (xy 134.19919 -244.770101)
			(xy 134.155116 -244.744655) (xy 134.115694 -244.712468) (xy 134.081946 -244.674374) (xy 134.054745 -244.63136)
			(xy 134.034797 -244.58454) (xy 134.022618 -244.535126) (xy 134.018523 -244.484398) (xy 133.700012 -244.484398)
			(xy 133.699517 -244.509005) (xy 133.691622 -244.557582) (xy 133.676038 -244.604263) (xy 133.653167 -244.64784)
			(xy 133.623602 -244.687184) (xy 133.588109 -244.721276) (xy 133.547606 -244.749232) (xy 133.503144 -244.77033)
			(xy 133.455873 -244.784022) (xy 133.407018 -244.789954) (xy 133.357843 -244.787973) (xy 133.309624 -244.778129)
			(xy 133.263608 -244.760677) (xy 133.220987 -244.73607) (xy 133.182866 -244.704945) (xy 133.150231 -244.668108)
			(xy 133.123928 -244.626512) (xy 133.104637 -244.581236) (xy 133.09286 -244.533452) (xy 133.0889 -244.484398)
			(xy 132.770372 -244.484398) (xy 132.76986 -244.509844) (xy 132.761696 -244.560078) (xy 132.74558 -244.608352)
			(xy 132.721929 -244.653415) (xy 132.691356 -244.694101) (xy 132.654652 -244.729356) (xy 132.612768 -244.758266)
			(xy 132.566789 -244.780083) (xy 132.517905 -244.794243) (xy 132.467384 -244.800377) (xy 132.416532 -244.798328)
			(xy 132.366668 -244.788148) (xy 132.319082 -244.770101) (xy 132.275008 -244.744655) (xy 132.235586 -244.712468)
			(xy 132.201838 -244.674374) (xy 132.174637 -244.63136) (xy 132.154689 -244.58454) (xy 132.14251 -244.535126)
			(xy 132.138415 -244.484398) (xy 131.830572 -244.484398) (xy 131.83006 -244.509844) (xy 131.821896 -244.560078)
			(xy 131.80578 -244.608352) (xy 131.782129 -244.653415) (xy 131.751556 -244.694101) (xy 131.714852 -244.729356)
			(xy 131.672968 -244.758266) (xy 131.626989 -244.780083) (xy 131.578105 -244.794243) (xy 131.527584 -244.800377)
			(xy 131.476732 -244.798328) (xy 131.426868 -244.788148) (xy 131.379282 -244.770101) (xy 131.335208 -244.744655)
			(xy 131.295786 -244.712468) (xy 131.262038 -244.674374) (xy 131.234837 -244.63136) (xy 131.214889 -244.58454)
			(xy 131.20271 -244.535126) (xy 131.198615 -244.484398) (xy 129.950464 -244.484398) (xy 129.949952 -244.509844)
			(xy 129.941788 -244.560078) (xy 129.925672 -244.608352) (xy 129.902021 -244.653415) (xy 129.871448 -244.694101)
			(xy 129.834744 -244.729356) (xy 129.79286 -244.758266) (xy 129.746881 -244.780083) (xy 129.697997 -244.794243)
			(xy 129.647476 -244.800377) (xy 129.596624 -244.798328) (xy 129.54676 -244.788148) (xy 129.499174 -244.770101)
			(xy 129.4551 -244.744655) (xy 129.415678 -244.712468) (xy 129.38193 -244.674374) (xy 129.354729 -244.63136)
			(xy 129.334781 -244.58454) (xy 129.322602 -244.535126) (xy 129.318507 -244.484398) (xy 128.999996 -244.484398)
			(xy 128.999501 -244.509005) (xy 128.991606 -244.557582) (xy 128.976022 -244.604263) (xy 128.953151 -244.64784)
			(xy 128.923586 -244.687184) (xy 128.888093 -244.721276) (xy 128.84759 -244.749232) (xy 128.803128 -244.77033)
			(xy 128.755857 -244.784022) (xy 128.707002 -244.789954) (xy 128.657827 -244.787973) (xy 128.609608 -244.778129)
			(xy 128.563592 -244.760677) (xy 128.520971 -244.73607) (xy 128.48285 -244.704945) (xy 128.450215 -244.668108)
			(xy 128.423912 -244.626512) (xy 128.404621 -244.581236) (xy 128.392844 -244.533452) (xy 128.388884 -244.484398)
			(xy 128.069837 -244.484398) (xy 128.069837 -244.509208) (xy 128.062076 -244.558213) (xy 128.046745 -244.605401)
			(xy 128.024221 -244.64961) (xy 127.995059 -244.689752) (xy 127.959978 -244.724837) (xy 127.919839 -244.754003)
			(xy 127.875633 -244.776532) (xy 127.828446 -244.791868) (xy 127.779442 -244.799635) (xy 127.754634 -244.80012)
			(xy 127.729113 -244.799607) (xy 127.678742 -244.791348) (xy 127.630357 -244.775088) (xy 127.585221 -244.751252)
			(xy 127.54451 -244.720461) (xy 127.526542 -244.70233) (xy 127.52197 -244.700806) (xy 127.442214 -244.702838)
			(xy 127.432487 -244.703517) (xy 127.414595 -244.711226) (xy 127.407416 -244.717824) (xy 127.300228 -244.825012)
			(xy 127.298958 -244.826282) (xy 127.293195 -244.832962) (xy 127.286207 -244.849148) (xy 127.285137 -244.866744)
			(xy 127.287274 -244.875304) (xy 127.312166 -244.960902) (xy 127.315126 -244.969528) (xy 127.326092 -244.984084)
			(xy 127.341441 -244.993909) (xy 127.350266 -244.996208) (xy 127.375406 -245.002292) (xy 127.423327 -245.021751)
			(xy 127.467283 -245.049006) (xy 127.506019 -245.083278) (xy 127.538427 -245.123586) (xy 127.56358 -245.168778)
			(xy 127.580759 -245.217562) (xy 127.589472 -245.268544) (xy 127.590042 -245.294404) (xy 127.908553 -245.294404)
			(xy 127.912648 -245.243676) (xy 127.924827 -245.194262) (xy 127.944775 -245.147442) (xy 127.971976 -245.104428)
			(xy 128.005724 -245.066334) (xy 128.045146 -245.034147) (xy 128.08922 -245.008701) (xy 128.136806 -244.990654)
			(xy 128.18667 -244.980474) (xy 128.237522 -244.978425) (xy 128.288043 -244.984559) (xy 128.336927 -244.998719)
			(xy 128.382906 -245.020536) (xy 128.42479 -245.049446) (xy 128.461494 -245.084701) (xy 128.492067 -245.125387)
			(xy 128.515718 -245.17045) (xy 128.531834 -245.218724) (xy 128.539998 -245.268958) (xy 128.54051 -245.294404)
			(xy 128.848607 -245.294404) (xy 128.852702 -245.243676) (xy 128.864881 -245.194262) (xy 128.884829 -245.147442)
			(xy 128.91203 -245.104428) (xy 128.945778 -245.066334) (xy 128.9852 -245.034147) (xy 129.029274 -245.008701)
			(xy 129.07686 -244.990654) (xy 129.126724 -244.980474) (xy 129.177576 -244.978425) (xy 129.228097 -244.984559)
			(xy 129.276981 -244.998719) (xy 129.32296 -245.020536) (xy 129.364844 -245.049446) (xy 129.401548 -245.084701)
			(xy 129.432121 -245.125387) (xy 129.455772 -245.17045) (xy 129.471888 -245.218724) (xy 129.480052 -245.268958)
			(xy 129.480564 -245.294404) (xy 129.798838 -245.294404) (xy 129.802798 -245.24535) (xy 129.814575 -245.197566)
			(xy 129.833866 -245.15229) (xy 129.860169 -245.110694) (xy 129.892804 -245.073857) (xy 129.930925 -245.042732)
			(xy 129.973546 -245.018125) (xy 130.019562 -245.000673) (xy 130.067781 -244.990829) (xy 130.116956 -244.988848)
			(xy 130.165811 -244.99478) (xy 130.213082 -245.008472) (xy 130.257544 -245.02957) (xy 130.298047 -245.057526)
			(xy 130.33354 -245.091618) (xy 130.363105 -245.130962) (xy 130.385976 -245.174539) (xy 130.40156 -245.22122)
			(xy 130.409455 -245.269797) (xy 130.40995 -245.294404) (xy 130.728461 -245.294404) (xy 130.732556 -245.243676)
			(xy 130.744735 -245.194262) (xy 130.764683 -245.147442) (xy 130.791884 -245.104428) (xy 130.825632 -245.066334)
			(xy 130.865054 -245.034147) (xy 130.909128 -245.008701) (xy 130.956714 -244.990654) (xy 131.006578 -244.980474)
			(xy 131.05743 -244.978425) (xy 131.107951 -244.984559) (xy 131.156835 -244.998719) (xy 131.202814 -245.020536)
			(xy 131.244698 -245.049446) (xy 131.281402 -245.084701) (xy 131.311975 -245.125387) (xy 131.335626 -245.17045)
			(xy 131.351742 -245.218724) (xy 131.359906 -245.268958) (xy 131.360418 -245.294404) (xy 131.678946 -245.294404)
			(xy 131.682906 -245.24535) (xy 131.694683 -245.197566) (xy 131.713974 -245.15229) (xy 131.740277 -245.110694)
			(xy 131.772912 -245.073857) (xy 131.811033 -245.042732) (xy 131.853654 -245.018125) (xy 131.89967 -245.000673)
			(xy 131.947889 -244.990829) (xy 131.997064 -244.988848) (xy 132.045919 -244.99478) (xy 132.09319 -245.008472)
			(xy 132.137652 -245.02957) (xy 132.178155 -245.057526) (xy 132.213648 -245.091618) (xy 132.243213 -245.130962)
			(xy 132.266084 -245.174539) (xy 132.281668 -245.22122) (xy 132.289563 -245.269797) (xy 132.290058 -245.294404)
			(xy 132.608569 -245.294404) (xy 132.612664 -245.243676) (xy 132.624843 -245.194262) (xy 132.644791 -245.147442)
			(xy 132.671992 -245.104428) (xy 132.70574 -245.066334) (xy 132.745162 -245.034147) (xy 132.789236 -245.008701)
			(xy 132.836822 -244.990654) (xy 132.886686 -244.980474) (xy 132.937538 -244.978425) (xy 132.988059 -244.984559)
			(xy 133.036943 -244.998719) (xy 133.082922 -245.020536) (xy 133.124806 -245.049446) (xy 133.16151 -245.084701)
			(xy 133.192083 -245.125387) (xy 133.215734 -245.17045) (xy 133.23185 -245.218724) (xy 133.240014 -245.268958)
			(xy 133.240526 -245.294404) (xy 133.559054 -245.294404) (xy 133.563014 -245.24535) (xy 133.574791 -245.197566)
			(xy 133.594082 -245.15229) (xy 133.620385 -245.110694) (xy 133.65302 -245.073857) (xy 133.691141 -245.042732)
			(xy 133.733762 -245.018125) (xy 133.779778 -245.000673) (xy 133.827997 -244.990829) (xy 133.877172 -244.988848)
			(xy 133.926027 -244.99478) (xy 133.973298 -245.008472) (xy 134.01776 -245.02957) (xy 134.058263 -245.057526)
			(xy 134.093756 -245.091618) (xy 134.123321 -245.130962) (xy 134.146192 -245.174539) (xy 134.161776 -245.22122)
			(xy 134.169671 -245.269797) (xy 134.170166 -245.294404) (xy 134.488423 -245.294404) (xy 134.492518 -245.243676)
			(xy 134.504697 -245.194262) (xy 134.524645 -245.147442) (xy 134.551846 -245.104428) (xy 134.585594 -245.066334)
			(xy 134.625016 -245.034147) (xy 134.66909 -245.008701) (xy 134.716676 -244.990654) (xy 134.76654 -244.980474)
			(xy 134.817392 -244.978425) (xy 134.867913 -244.984559) (xy 134.916797 -244.998719) (xy 134.962776 -245.020536)
			(xy 135.00466 -245.049446) (xy 135.041364 -245.084701) (xy 135.071937 -245.125387) (xy 135.095588 -245.17045)
			(xy 135.111704 -245.218724) (xy 135.119868 -245.268958) (xy 135.12038 -245.294404) (xy 135.428477 -245.294404)
			(xy 135.432572 -245.243676) (xy 135.444751 -245.194262) (xy 135.464699 -245.147442) (xy 135.4919 -245.104428)
			(xy 135.525648 -245.066334) (xy 135.56507 -245.034147) (xy 135.609144 -245.008701) (xy 135.65673 -244.990654)
			(xy 135.706594 -244.980474) (xy 135.757446 -244.978425) (xy 135.807967 -244.984559) (xy 135.856851 -244.998719)
			(xy 135.90283 -245.020536) (xy 135.944714 -245.049446) (xy 135.981418 -245.084701) (xy 136.011991 -245.125387)
			(xy 136.035642 -245.17045) (xy 136.051758 -245.218724) (xy 136.059922 -245.268958) (xy 136.060434 -245.294404)
			(xy 136.378962 -245.294404) (xy 136.382922 -245.24535) (xy 136.394699 -245.197566) (xy 136.41399 -245.15229)
			(xy 136.440293 -245.110694) (xy 136.472928 -245.073857) (xy 136.511049 -245.042732) (xy 136.55367 -245.018125)
			(xy 136.599686 -245.000673) (xy 136.647905 -244.990829) (xy 136.69708 -244.988848) (xy 136.745935 -244.99478)
			(xy 136.793206 -245.008472) (xy 136.837668 -245.02957) (xy 136.878171 -245.057526) (xy 136.913664 -245.091618)
			(xy 136.943229 -245.130962) (xy 136.9661 -245.174539) (xy 136.981684 -245.22122) (xy 136.989579 -245.269797)
			(xy 136.990074 -245.294404) (xy 137.308585 -245.294404) (xy 137.31268 -245.243676) (xy 137.324859 -245.194262)
			(xy 137.344807 -245.147442) (xy 137.372008 -245.104428) (xy 137.405756 -245.066334) (xy 137.445178 -245.034147)
			(xy 137.489252 -245.008701) (xy 137.536838 -244.990654) (xy 137.586702 -244.980474) (xy 137.637554 -244.978425)
			(xy 137.688075 -244.984559) (xy 137.736959 -244.998719) (xy 137.782938 -245.020536) (xy 137.824822 -245.049446)
			(xy 137.861526 -245.084701) (xy 137.892099 -245.125387) (xy 137.91575 -245.17045) (xy 137.931866 -245.218724)
			(xy 137.94003 -245.268958) (xy 137.940542 -245.294404) (xy 138.25907 -245.294404) (xy 138.26303 -245.24535)
			(xy 138.274807 -245.197566) (xy 138.294098 -245.15229) (xy 138.320401 -245.110694) (xy 138.353036 -245.073857)
			(xy 138.391157 -245.042732) (xy 138.433778 -245.018125) (xy 138.479794 -245.000673) (xy 138.528013 -244.990829)
			(xy 138.577188 -244.988848) (xy 138.626043 -244.99478) (xy 138.673314 -245.008472) (xy 138.717776 -245.02957)
			(xy 138.758279 -245.057526) (xy 138.793772 -245.091618) (xy 138.823337 -245.130962) (xy 138.846208 -245.174539)
			(xy 138.861792 -245.22122) (xy 138.869687 -245.269797) (xy 138.870182 -245.294404) (xy 139.188439 -245.294404)
			(xy 139.192534 -245.243676) (xy 139.204713 -245.194262) (xy 139.224661 -245.147442) (xy 139.251862 -245.104428)
			(xy 139.28561 -245.066334) (xy 139.325032 -245.034147) (xy 139.369106 -245.008701) (xy 139.416692 -244.990654)
			(xy 139.466556 -244.980474) (xy 139.517408 -244.978425) (xy 139.567929 -244.984559) (xy 139.616813 -244.998719)
			(xy 139.662792 -245.020536) (xy 139.704676 -245.049446) (xy 139.74138 -245.084701) (xy 139.771953 -245.125387)
			(xy 139.795604 -245.17045) (xy 139.81172 -245.218724) (xy 139.819884 -245.268958) (xy 139.820396 -245.294404)
			(xy 140.138924 -245.294404) (xy 140.142884 -245.24535) (xy 140.154661 -245.197566) (xy 140.173952 -245.15229)
			(xy 140.200255 -245.110694) (xy 140.23289 -245.073857) (xy 140.271011 -245.042732) (xy 140.313632 -245.018125)
			(xy 140.359648 -245.000673) (xy 140.407867 -244.990829) (xy 140.457042 -244.988848) (xy 140.505897 -244.99478)
			(xy 140.553168 -245.008472) (xy 140.59763 -245.02957) (xy 140.638133 -245.057526) (xy 140.673626 -245.091618)
			(xy 140.703191 -245.130962) (xy 140.726062 -245.174539) (xy 140.741646 -245.22122) (xy 140.749541 -245.269797)
			(xy 140.750036 -245.294404) (xy 141.068547 -245.294404) (xy 141.072642 -245.243676) (xy 141.084821 -245.194262)
			(xy 141.104769 -245.147442) (xy 141.13197 -245.104428) (xy 141.165718 -245.066334) (xy 141.20514 -245.034147)
			(xy 141.249214 -245.008701) (xy 141.2968 -244.990654) (xy 141.346664 -244.980474) (xy 141.397516 -244.978425)
			(xy 141.448037 -244.984559) (xy 141.496921 -244.998719) (xy 141.5429 -245.020536) (xy 141.584784 -245.049446)
			(xy 141.621488 -245.084701) (xy 141.652061 -245.125387) (xy 141.675712 -245.17045) (xy 141.691828 -245.218724)
			(xy 141.699992 -245.268958) (xy 141.700504 -245.294404) (xy 142.008601 -245.294404) (xy 142.012696 -245.243676)
			(xy 142.024875 -245.194262) (xy 142.044823 -245.147442) (xy 142.072024 -245.104428) (xy 142.105772 -245.066334)
			(xy 142.145194 -245.034147) (xy 142.189268 -245.008701) (xy 142.236854 -244.990654) (xy 142.286718 -244.980474)
			(xy 142.33757 -244.978425) (xy 142.388091 -244.984559) (xy 142.436975 -244.998719) (xy 142.482954 -245.020536)
			(xy 142.524838 -245.049446) (xy 142.561542 -245.084701) (xy 142.592115 -245.125387) (xy 142.615766 -245.17045)
			(xy 142.631882 -245.218724) (xy 142.640046 -245.268958) (xy 142.640558 -245.294404) (xy 142.958832 -245.294404)
			(xy 142.962792 -245.24535) (xy 142.974569 -245.197566) (xy 142.99386 -245.15229) (xy 143.020163 -245.110694)
			(xy 143.052798 -245.073857) (xy 143.090919 -245.042732) (xy 143.13354 -245.018125) (xy 143.179556 -245.000673)
			(xy 143.227775 -244.990829) (xy 143.27695 -244.988848) (xy 143.325805 -244.99478) (xy 143.373076 -245.008472)
			(xy 143.417538 -245.02957) (xy 143.458041 -245.057526) (xy 143.493534 -245.091618) (xy 143.523099 -245.130962)
			(xy 143.54597 -245.174539) (xy 143.561554 -245.22122) (xy 143.569449 -245.269797) (xy 143.569944 -245.294404)
			(xy 144.83894 -245.294404) (xy 144.8429 -245.24535) (xy 144.854677 -245.197566) (xy 144.873968 -245.15229)
			(xy 144.900271 -245.110694) (xy 144.932906 -245.073857) (xy 144.971027 -245.042732) (xy 145.013648 -245.018125)
			(xy 145.059664 -245.000673) (xy 145.107883 -244.990829) (xy 145.157058 -244.988848) (xy 145.205913 -244.99478)
			(xy 145.253184 -245.008472) (xy 145.297646 -245.02957) (xy 145.338149 -245.057526) (xy 145.373642 -245.091618)
			(xy 145.403207 -245.130962) (xy 145.426078 -245.174539) (xy 145.441662 -245.22122) (xy 145.449557 -245.269797)
			(xy 145.450052 -245.294404) (xy 145.449557 -245.319011) (xy 145.441662 -245.367588) (xy 145.426078 -245.414269)
			(xy 145.403207 -245.457846) (xy 145.373642 -245.49719) (xy 145.338149 -245.531282) (xy 145.297646 -245.559238)
			(xy 145.253184 -245.580336) (xy 145.205913 -245.594028) (xy 145.157058 -245.59996) (xy 145.107883 -245.597979)
			(xy 145.059664 -245.588135) (xy 145.013648 -245.570683) (xy 144.971027 -245.546076) (xy 144.932906 -245.514951)
			(xy 144.900271 -245.478114) (xy 144.873968 -245.436518) (xy 144.854677 -245.391242) (xy 144.8429 -245.343458)
			(xy 144.83894 -245.294404) (xy 143.569944 -245.294404) (xy 143.569449 -245.319011) (xy 143.561554 -245.367588)
			(xy 143.54597 -245.414269) (xy 143.523099 -245.457846) (xy 143.493534 -245.49719) (xy 143.458041 -245.531282)
			(xy 143.417538 -245.559238) (xy 143.373076 -245.580336) (xy 143.325805 -245.594028) (xy 143.27695 -245.59996)
			(xy 143.227775 -245.597979) (xy 143.179556 -245.588135) (xy 143.13354 -245.570683) (xy 143.090919 -245.546076)
			(xy 143.052798 -245.514951) (xy 143.020163 -245.478114) (xy 142.99386 -245.436518) (xy 142.974569 -245.391242)
			(xy 142.962792 -245.343458) (xy 142.958832 -245.294404) (xy 142.640558 -245.294404) (xy 142.640046 -245.31985)
			(xy 142.631882 -245.370084) (xy 142.615766 -245.418358) (xy 142.592115 -245.463421) (xy 142.561542 -245.504107)
			(xy 142.524838 -245.539362) (xy 142.482954 -245.568272) (xy 142.436975 -245.590089) (xy 142.388091 -245.604249)
			(xy 142.33757 -245.610383) (xy 142.286718 -245.608334) (xy 142.236854 -245.598154) (xy 142.189268 -245.580107)
			(xy 142.145194 -245.554661) (xy 142.105772 -245.522474) (xy 142.072024 -245.48438) (xy 142.044823 -245.441366)
			(xy 142.024875 -245.394546) (xy 142.012696 -245.345132) (xy 142.008601 -245.294404) (xy 141.700504 -245.294404)
			(xy 141.699992 -245.31985) (xy 141.691828 -245.370084) (xy 141.675712 -245.418358) (xy 141.652061 -245.463421)
			(xy 141.621488 -245.504107) (xy 141.584784 -245.539362) (xy 141.5429 -245.568272) (xy 141.496921 -245.590089)
			(xy 141.448037 -245.604249) (xy 141.397516 -245.610383) (xy 141.346664 -245.608334) (xy 141.2968 -245.598154)
			(xy 141.249214 -245.580107) (xy 141.20514 -245.554661) (xy 141.165718 -245.522474) (xy 141.13197 -245.48438)
			(xy 141.104769 -245.441366) (xy 141.084821 -245.394546) (xy 141.072642 -245.345132) (xy 141.068547 -245.294404)
			(xy 140.750036 -245.294404) (xy 140.749541 -245.319011) (xy 140.741646 -245.367588) (xy 140.726062 -245.414269)
			(xy 140.703191 -245.457846) (xy 140.673626 -245.49719) (xy 140.638133 -245.531282) (xy 140.59763 -245.559238)
			(xy 140.553168 -245.580336) (xy 140.505897 -245.594028) (xy 140.457042 -245.59996) (xy 140.407867 -245.597979)
			(xy 140.359648 -245.588135) (xy 140.313632 -245.570683) (xy 140.271011 -245.546076) (xy 140.23289 -245.514951)
			(xy 140.200255 -245.478114) (xy 140.173952 -245.436518) (xy 140.154661 -245.391242) (xy 140.142884 -245.343458)
			(xy 140.138924 -245.294404) (xy 139.820396 -245.294404) (xy 139.819884 -245.31985) (xy 139.81172 -245.370084)
			(xy 139.795604 -245.418358) (xy 139.771953 -245.463421) (xy 139.74138 -245.504107) (xy 139.704676 -245.539362)
			(xy 139.662792 -245.568272) (xy 139.616813 -245.590089) (xy 139.567929 -245.604249) (xy 139.517408 -245.610383)
			(xy 139.466556 -245.608334) (xy 139.416692 -245.598154) (xy 139.369106 -245.580107) (xy 139.325032 -245.554661)
			(xy 139.28561 -245.522474) (xy 139.251862 -245.48438) (xy 139.224661 -245.441366) (xy 139.204713 -245.394546)
			(xy 139.192534 -245.345132) (xy 139.188439 -245.294404) (xy 138.870182 -245.294404) (xy 138.869687 -245.319011)
			(xy 138.861792 -245.367588) (xy 138.846208 -245.414269) (xy 138.823337 -245.457846) (xy 138.793772 -245.49719)
			(xy 138.758279 -245.531282) (xy 138.717776 -245.559238) (xy 138.673314 -245.580336) (xy 138.626043 -245.594028)
			(xy 138.577188 -245.59996) (xy 138.528013 -245.597979) (xy 138.479794 -245.588135) (xy 138.433778 -245.570683)
			(xy 138.391157 -245.546076) (xy 138.353036 -245.514951) (xy 138.320401 -245.478114) (xy 138.294098 -245.436518)
			(xy 138.274807 -245.391242) (xy 138.26303 -245.343458) (xy 138.25907 -245.294404) (xy 137.940542 -245.294404)
			(xy 137.94003 -245.31985) (xy 137.931866 -245.370084) (xy 137.91575 -245.418358) (xy 137.892099 -245.463421)
			(xy 137.861526 -245.504107) (xy 137.824822 -245.539362) (xy 137.782938 -245.568272) (xy 137.736959 -245.590089)
			(xy 137.688075 -245.604249) (xy 137.637554 -245.610383) (xy 137.586702 -245.608334) (xy 137.536838 -245.598154)
			(xy 137.489252 -245.580107) (xy 137.445178 -245.554661) (xy 137.405756 -245.522474) (xy 137.372008 -245.48438)
			(xy 137.344807 -245.441366) (xy 137.324859 -245.394546) (xy 137.31268 -245.345132) (xy 137.308585 -245.294404)
			(xy 136.990074 -245.294404) (xy 136.989579 -245.319011) (xy 136.981684 -245.367588) (xy 136.9661 -245.414269)
			(xy 136.943229 -245.457846) (xy 136.913664 -245.49719) (xy 136.878171 -245.531282) (xy 136.837668 -245.559238)
			(xy 136.793206 -245.580336) (xy 136.745935 -245.594028) (xy 136.69708 -245.59996) (xy 136.647905 -245.597979)
			(xy 136.599686 -245.588135) (xy 136.55367 -245.570683) (xy 136.511049 -245.546076) (xy 136.472928 -245.514951)
			(xy 136.440293 -245.478114) (xy 136.41399 -245.436518) (xy 136.394699 -245.391242) (xy 136.382922 -245.343458)
			(xy 136.378962 -245.294404) (xy 136.060434 -245.294404) (xy 136.059922 -245.31985) (xy 136.051758 -245.370084)
			(xy 136.035642 -245.418358) (xy 136.011991 -245.463421) (xy 135.981418 -245.504107) (xy 135.944714 -245.539362)
			(xy 135.90283 -245.568272) (xy 135.856851 -245.590089) (xy 135.807967 -245.604249) (xy 135.757446 -245.610383)
			(xy 135.706594 -245.608334) (xy 135.65673 -245.598154) (xy 135.609144 -245.580107) (xy 135.56507 -245.554661)
			(xy 135.525648 -245.522474) (xy 135.4919 -245.48438) (xy 135.464699 -245.441366) (xy 135.444751 -245.394546)
			(xy 135.432572 -245.345132) (xy 135.428477 -245.294404) (xy 135.12038 -245.294404) (xy 135.119868 -245.31985)
			(xy 135.111704 -245.370084) (xy 135.095588 -245.418358) (xy 135.071937 -245.463421) (xy 135.041364 -245.504107)
			(xy 135.00466 -245.539362) (xy 134.962776 -245.568272) (xy 134.916797 -245.590089) (xy 134.867913 -245.604249)
			(xy 134.817392 -245.610383) (xy 134.76654 -245.608334) (xy 134.716676 -245.598154) (xy 134.66909 -245.580107)
			(xy 134.625016 -245.554661) (xy 134.585594 -245.522474) (xy 134.551846 -245.48438) (xy 134.524645 -245.441366)
			(xy 134.504697 -245.394546) (xy 134.492518 -245.345132) (xy 134.488423 -245.294404) (xy 134.170166 -245.294404)
			(xy 134.169671 -245.319011) (xy 134.161776 -245.367588) (xy 134.146192 -245.414269) (xy 134.123321 -245.457846)
			(xy 134.093756 -245.49719) (xy 134.058263 -245.531282) (xy 134.01776 -245.559238) (xy 133.973298 -245.580336)
			(xy 133.926027 -245.594028) (xy 133.877172 -245.59996) (xy 133.827997 -245.597979) (xy 133.779778 -245.588135)
			(xy 133.733762 -245.570683) (xy 133.691141 -245.546076) (xy 133.65302 -245.514951) (xy 133.620385 -245.478114)
			(xy 133.594082 -245.436518) (xy 133.574791 -245.391242) (xy 133.563014 -245.343458) (xy 133.559054 -245.294404)
			(xy 133.240526 -245.294404) (xy 133.240014 -245.31985) (xy 133.23185 -245.370084) (xy 133.215734 -245.418358)
			(xy 133.192083 -245.463421) (xy 133.16151 -245.504107) (xy 133.124806 -245.539362) (xy 133.082922 -245.568272)
			(xy 133.036943 -245.590089) (xy 132.988059 -245.604249) (xy 132.937538 -245.610383) (xy 132.886686 -245.608334)
			(xy 132.836822 -245.598154) (xy 132.789236 -245.580107) (xy 132.745162 -245.554661) (xy 132.70574 -245.522474)
			(xy 132.671992 -245.48438) (xy 132.644791 -245.441366) (xy 132.624843 -245.394546) (xy 132.612664 -245.345132)
			(xy 132.608569 -245.294404) (xy 132.290058 -245.294404) (xy 132.289563 -245.319011) (xy 132.281668 -245.367588)
			(xy 132.266084 -245.414269) (xy 132.243213 -245.457846) (xy 132.213648 -245.49719) (xy 132.178155 -245.531282)
			(xy 132.137652 -245.559238) (xy 132.09319 -245.580336) (xy 132.045919 -245.594028) (xy 131.997064 -245.59996)
			(xy 131.947889 -245.597979) (xy 131.89967 -245.588135) (xy 131.853654 -245.570683) (xy 131.811033 -245.546076)
			(xy 131.772912 -245.514951) (xy 131.740277 -245.478114) (xy 131.713974 -245.436518) (xy 131.694683 -245.391242)
			(xy 131.682906 -245.343458) (xy 131.678946 -245.294404) (xy 131.360418 -245.294404) (xy 131.359906 -245.31985)
			(xy 131.351742 -245.370084) (xy 131.335626 -245.418358) (xy 131.311975 -245.463421) (xy 131.281402 -245.504107)
			(xy 131.244698 -245.539362) (xy 131.202814 -245.568272) (xy 131.156835 -245.590089) (xy 131.107951 -245.604249)
			(xy 131.05743 -245.610383) (xy 131.006578 -245.608334) (xy 130.956714 -245.598154) (xy 130.909128 -245.580107)
			(xy 130.865054 -245.554661) (xy 130.825632 -245.522474) (xy 130.791884 -245.48438) (xy 130.764683 -245.441366)
			(xy 130.744735 -245.394546) (xy 130.732556 -245.345132) (xy 130.728461 -245.294404) (xy 130.40995 -245.294404)
			(xy 130.409455 -245.319011) (xy 130.40156 -245.367588) (xy 130.385976 -245.414269) (xy 130.363105 -245.457846)
			(xy 130.33354 -245.49719) (xy 130.298047 -245.531282) (xy 130.257544 -245.559238) (xy 130.213082 -245.580336)
			(xy 130.165811 -245.594028) (xy 130.116956 -245.59996) (xy 130.067781 -245.597979) (xy 130.019562 -245.588135)
			(xy 129.973546 -245.570683) (xy 129.930925 -245.546076) (xy 129.892804 -245.514951) (xy 129.860169 -245.478114)
			(xy 129.833866 -245.436518) (xy 129.814575 -245.391242) (xy 129.802798 -245.343458) (xy 129.798838 -245.294404)
			(xy 129.480564 -245.294404) (xy 129.480052 -245.31985) (xy 129.471888 -245.370084) (xy 129.455772 -245.418358)
			(xy 129.432121 -245.463421) (xy 129.401548 -245.504107) (xy 129.364844 -245.539362) (xy 129.32296 -245.568272)
			(xy 129.276981 -245.590089) (xy 129.228097 -245.604249) (xy 129.177576 -245.610383) (xy 129.126724 -245.608334)
			(xy 129.07686 -245.598154) (xy 129.029274 -245.580107) (xy 128.9852 -245.554661) (xy 128.945778 -245.522474)
			(xy 128.91203 -245.48438) (xy 128.884829 -245.441366) (xy 128.864881 -245.394546) (xy 128.852702 -245.345132)
			(xy 128.848607 -245.294404) (xy 128.54051 -245.294404) (xy 128.539998 -245.31985) (xy 128.531834 -245.370084)
			(xy 128.515718 -245.418358) (xy 128.492067 -245.463421) (xy 128.461494 -245.504107) (xy 128.42479 -245.539362)
			(xy 128.382906 -245.568272) (xy 128.336927 -245.590089) (xy 128.288043 -245.604249) (xy 128.237522 -245.610383)
			(xy 128.18667 -245.608334) (xy 128.136806 -245.598154) (xy 128.08922 -245.580107) (xy 128.045146 -245.554661)
			(xy 128.005724 -245.522474) (xy 127.971976 -245.48438) (xy 127.944775 -245.441366) (xy 127.924827 -245.394546)
			(xy 127.912648 -245.345132) (xy 127.908553 -245.294404) (xy 127.590042 -245.294404) (xy 127.589571 -245.318396)
			(xy 127.582065 -245.365789) (xy 127.567237 -245.411425) (xy 127.545454 -245.454179) (xy 127.517251 -245.493)
			(xy 127.483323 -245.526932) (xy 127.444505 -245.555138) (xy 127.401753 -245.576926) (xy 127.356118 -245.591758)
			(xy 127.308726 -245.599269) (xy 127.284734 -245.599712) (xy 127.269325 -245.599546) (xy 127.238659 -245.596494)
			(xy 127.22352 -245.593616) (xy 127.21209 -245.59133) (xy 127.190246 -245.596664) (xy 127.120142 -245.654068)
			(xy 127.11186 -245.66167) (xy 127.102242 -245.68196) (xy 127.1016 -245.693184) (xy 127.1016 -245.999254)
			(xy 127.10414 -246.007128) (xy 127.111597 -246.030755) (xy 127.119639 -246.07964) (xy 127.120142 -246.10441)
			(xy 127.438399 -246.10441) (xy 127.442494 -246.053682) (xy 127.454673 -246.004268) (xy 127.474621 -245.957448)
			(xy 127.501822 -245.914434) (xy 127.53557 -245.87634) (xy 127.574992 -245.844153) (xy 127.619066 -245.818707)
			(xy 127.666652 -245.80066) (xy 127.716516 -245.79048) (xy 127.767368 -245.788431) (xy 127.817889 -245.794565)
			(xy 127.866773 -245.808725) (xy 127.912752 -245.830542) (xy 127.954636 -245.859452) (xy 127.99134 -245.894707)
			(xy 128.021913 -245.935393) (xy 128.045564 -245.980456) (xy 128.06168 -246.02873) (xy 128.069844 -246.078964)
			(xy 128.070356 -246.10441) (xy 128.388884 -246.10441) (xy 128.392844 -246.055356) (xy 128.404621 -246.007572)
			(xy 128.423912 -245.962296) (xy 128.450215 -245.9207) (xy 128.48285 -245.883863) (xy 128.520971 -245.852738)
			(xy 128.563592 -245.828131) (xy 128.609608 -245.810679) (xy 128.657827 -245.800835) (xy 128.707002 -245.798854)
			(xy 128.755857 -245.804786) (xy 128.803128 -245.818478) (xy 128.84759 -245.839576) (xy 128.888093 -245.867532)
			(xy 128.923586 -245.901624) (xy 128.953151 -245.940968) (xy 128.976022 -245.984545) (xy 128.991606 -246.031226)
			(xy 128.999501 -246.079803) (xy 128.999996 -246.10441) (xy 129.318507 -246.10441) (xy 129.322602 -246.053682)
			(xy 129.334781 -246.004268) (xy 129.354729 -245.957448) (xy 129.38193 -245.914434) (xy 129.415678 -245.87634)
			(xy 129.4551 -245.844153) (xy 129.499174 -245.818707) (xy 129.54676 -245.80066) (xy 129.596624 -245.79048)
			(xy 129.647476 -245.788431) (xy 129.697997 -245.794565) (xy 129.746881 -245.808725) (xy 129.79286 -245.830542)
			(xy 129.834744 -245.859452) (xy 129.871448 -245.894707) (xy 129.902021 -245.935393) (xy 129.925672 -245.980456)
			(xy 129.941788 -246.02873) (xy 129.949952 -246.078964) (xy 129.950464 -246.10441) (xy 130.268992 -246.10441)
			(xy 130.272952 -246.055356) (xy 130.284729 -246.007572) (xy 130.30402 -245.962296) (xy 130.330323 -245.9207)
			(xy 130.362958 -245.883863) (xy 130.401079 -245.852738) (xy 130.4437 -245.828131) (xy 130.489716 -245.810679)
			(xy 130.537935 -245.800835) (xy 130.58711 -245.798854) (xy 130.635965 -245.804786) (xy 130.683236 -245.818478)
			(xy 130.727698 -245.839576) (xy 130.768201 -245.867532) (xy 130.803694 -245.901624) (xy 130.833259 -245.940968)
			(xy 130.85613 -245.984545) (xy 130.871714 -246.031226) (xy 130.879609 -246.079803) (xy 130.880104 -246.10441)
			(xy 131.198615 -246.10441) (xy 131.20271 -246.053682) (xy 131.214889 -246.004268) (xy 131.234837 -245.957448)
			(xy 131.262038 -245.914434) (xy 131.295786 -245.87634) (xy 131.335208 -245.844153) (xy 131.379282 -245.818707)
			(xy 131.426868 -245.80066) (xy 131.476732 -245.79048) (xy 131.527584 -245.788431) (xy 131.578105 -245.794565)
			(xy 131.626989 -245.808725) (xy 131.672968 -245.830542) (xy 131.714852 -245.859452) (xy 131.751556 -245.894707)
			(xy 131.782129 -245.935393) (xy 131.80578 -245.980456) (xy 131.821896 -246.02873) (xy 131.83006 -246.078964)
			(xy 131.830572 -246.10441) (xy 132.138415 -246.10441) (xy 132.14251 -246.053682) (xy 132.154689 -246.004268)
			(xy 132.174637 -245.957448) (xy 132.201838 -245.914434) (xy 132.235586 -245.87634) (xy 132.275008 -245.844153)
			(xy 132.319082 -245.818707) (xy 132.366668 -245.80066) (xy 132.416532 -245.79048) (xy 132.467384 -245.788431)
			(xy 132.517905 -245.794565) (xy 132.566789 -245.808725) (xy 132.612768 -245.830542) (xy 132.654652 -245.859452)
			(xy 132.691356 -245.894707) (xy 132.721929 -245.935393) (xy 132.74558 -245.980456) (xy 132.761696 -246.02873)
			(xy 132.76986 -246.078964) (xy 132.770372 -246.10441) (xy 133.0889 -246.10441) (xy 133.09286 -246.055356)
			(xy 133.104637 -246.007572) (xy 133.123928 -245.962296) (xy 133.150231 -245.9207) (xy 133.182866 -245.883863)
			(xy 133.220987 -245.852738) (xy 133.263608 -245.828131) (xy 133.309624 -245.810679) (xy 133.357843 -245.800835)
			(xy 133.407018 -245.798854) (xy 133.455873 -245.804786) (xy 133.503144 -245.818478) (xy 133.547606 -245.839576)
			(xy 133.588109 -245.867532) (xy 133.623602 -245.901624) (xy 133.653167 -245.940968) (xy 133.676038 -245.984545)
			(xy 133.691622 -246.031226) (xy 133.699517 -246.079803) (xy 133.700012 -246.10441) (xy 134.018523 -246.10441)
			(xy 134.022618 -246.053682) (xy 134.034797 -246.004268) (xy 134.054745 -245.957448) (xy 134.081946 -245.914434)
			(xy 134.115694 -245.87634) (xy 134.155116 -245.844153) (xy 134.19919 -245.818707) (xy 134.246776 -245.80066)
			(xy 134.29664 -245.79048) (xy 134.347492 -245.788431) (xy 134.398013 -245.794565) (xy 134.446897 -245.808725)
			(xy 134.492876 -245.830542) (xy 134.53476 -245.859452) (xy 134.571464 -245.894707) (xy 134.602037 -245.935393)
			(xy 134.625688 -245.980456) (xy 134.641804 -246.02873) (xy 134.649968 -246.078964) (xy 134.65048 -246.10441)
			(xy 134.969008 -246.10441) (xy 134.972968 -246.055356) (xy 134.984745 -246.007572) (xy 135.004036 -245.962296)
			(xy 135.030339 -245.9207) (xy 135.062974 -245.883863) (xy 135.101095 -245.852738) (xy 135.143716 -245.828131)
			(xy 135.189732 -245.810679) (xy 135.237951 -245.800835) (xy 135.287126 -245.798854) (xy 135.335981 -245.804786)
			(xy 135.383252 -245.818478) (xy 135.427714 -245.839576) (xy 135.468217 -245.867532) (xy 135.50371 -245.901624)
			(xy 135.533275 -245.940968) (xy 135.556146 -245.984545) (xy 135.57173 -246.031226) (xy 135.579625 -246.079803)
			(xy 135.58012 -246.10441) (xy 135.898631 -246.10441) (xy 135.902726 -246.053682) (xy 135.914905 -246.004268)
			(xy 135.934853 -245.957448) (xy 135.962054 -245.914434) (xy 135.995802 -245.87634) (xy 136.035224 -245.844153)
			(xy 136.079298 -245.818707) (xy 136.126884 -245.80066) (xy 136.176748 -245.79048) (xy 136.2276 -245.788431)
			(xy 136.278121 -245.794565) (xy 136.327005 -245.808725) (xy 136.372984 -245.830542) (xy 136.414868 -245.859452)
			(xy 136.451572 -245.894707) (xy 136.482145 -245.935393) (xy 136.505796 -245.980456) (xy 136.521912 -246.02873)
			(xy 136.530076 -246.078964) (xy 136.530588 -246.10441) (xy 136.848862 -246.10441) (xy 136.852822 -246.055356)
			(xy 136.864599 -246.007572) (xy 136.88389 -245.962296) (xy 136.910193 -245.9207) (xy 136.942828 -245.883863)
			(xy 136.980949 -245.852738) (xy 137.02357 -245.828131) (xy 137.069586 -245.810679) (xy 137.117805 -245.800835)
			(xy 137.16698 -245.798854) (xy 137.215835 -245.804786) (xy 137.263106 -245.818478) (xy 137.307568 -245.839576)
			(xy 137.348071 -245.867532) (xy 137.383564 -245.901624) (xy 137.413129 -245.940968) (xy 137.436 -245.984545)
			(xy 137.451584 -246.031226) (xy 137.459479 -246.079803) (xy 137.459974 -246.10441) (xy 137.778485 -246.10441)
			(xy 137.78258 -246.053682) (xy 137.794759 -246.004268) (xy 137.814707 -245.957448) (xy 137.841908 -245.914434)
			(xy 137.875656 -245.87634) (xy 137.915078 -245.844153) (xy 137.959152 -245.818707) (xy 138.006738 -245.80066)
			(xy 138.056602 -245.79048) (xy 138.107454 -245.788431) (xy 138.157975 -245.794565) (xy 138.206859 -245.808725)
			(xy 138.252838 -245.830542) (xy 138.294722 -245.859452) (xy 138.331426 -245.894707) (xy 138.361999 -245.935393)
			(xy 138.38565 -245.980456) (xy 138.401766 -246.02873) (xy 138.40993 -246.078964) (xy 138.410442 -246.10441)
			(xy 138.718539 -246.10441) (xy 138.722634 -246.053682) (xy 138.734813 -246.004268) (xy 138.754761 -245.957448)
			(xy 138.781962 -245.914434) (xy 138.81571 -245.87634) (xy 138.855132 -245.844153) (xy 138.899206 -245.818707)
			(xy 138.946792 -245.80066) (xy 138.996656 -245.79048) (xy 139.047508 -245.788431) (xy 139.098029 -245.794565)
			(xy 139.146913 -245.808725) (xy 139.192892 -245.830542) (xy 139.234776 -245.859452) (xy 139.27148 -245.894707)
			(xy 139.302053 -245.935393) (xy 139.325704 -245.980456) (xy 139.34182 -246.02873) (xy 139.349984 -246.078964)
			(xy 139.350496 -246.10441) (xy 139.669024 -246.10441) (xy 139.672984 -246.055356) (xy 139.684761 -246.007572)
			(xy 139.704052 -245.962296) (xy 139.730355 -245.9207) (xy 139.76299 -245.883863) (xy 139.801111 -245.852738)
			(xy 139.843732 -245.828131) (xy 139.889748 -245.810679) (xy 139.937967 -245.800835) (xy 139.987142 -245.798854)
			(xy 140.035997 -245.804786) (xy 140.083268 -245.818478) (xy 140.12773 -245.839576) (xy 140.168233 -245.867532)
			(xy 140.203726 -245.901624) (xy 140.233291 -245.940968) (xy 140.256162 -245.984545) (xy 140.271746 -246.031226)
			(xy 140.279641 -246.079803) (xy 140.280136 -246.10441) (xy 140.598647 -246.10441) (xy 140.602742 -246.053682)
			(xy 140.614921 -246.004268) (xy 140.634869 -245.957448) (xy 140.66207 -245.914434) (xy 140.695818 -245.87634)
			(xy 140.73524 -245.844153) (xy 140.779314 -245.818707) (xy 140.8269 -245.80066) (xy 140.876764 -245.79048)
			(xy 140.927616 -245.788431) (xy 140.978137 -245.794565) (xy 141.027021 -245.808725) (xy 141.073 -245.830542)
			(xy 141.114884 -245.859452) (xy 141.151588 -245.894707) (xy 141.182161 -245.935393) (xy 141.205812 -245.980456)
			(xy 141.221928 -246.02873) (xy 141.230092 -246.078964) (xy 141.230604 -246.10441) (xy 141.548878 -246.10441)
			(xy 141.552838 -246.055356) (xy 141.564615 -246.007572) (xy 141.583906 -245.962296) (xy 141.610209 -245.9207)
			(xy 141.642844 -245.883863) (xy 141.680965 -245.852738) (xy 141.723586 -245.828131) (xy 141.769602 -245.810679)
			(xy 141.817821 -245.800835) (xy 141.866996 -245.798854) (xy 141.915851 -245.804786) (xy 141.963122 -245.818478)
			(xy 142.007584 -245.839576) (xy 142.048087 -245.867532) (xy 142.08358 -245.901624) (xy 142.113145 -245.940968)
			(xy 142.136016 -245.984545) (xy 142.1516 -246.031226) (xy 142.159495 -246.079803) (xy 142.15999 -246.10441)
			(xy 142.478501 -246.10441) (xy 142.482596 -246.053682) (xy 142.494775 -246.004268) (xy 142.514723 -245.957448)
			(xy 142.541924 -245.914434) (xy 142.575672 -245.87634) (xy 142.615094 -245.844153) (xy 142.659168 -245.818707)
			(xy 142.706754 -245.80066) (xy 142.756618 -245.79048) (xy 142.80747 -245.788431) (xy 142.857991 -245.794565)
			(xy 142.906875 -245.808725) (xy 142.952854 -245.830542) (xy 142.994738 -245.859452) (xy 143.031442 -245.894707)
			(xy 143.062015 -245.935393) (xy 143.085666 -245.980456) (xy 143.101782 -246.02873) (xy 143.109946 -246.078964)
			(xy 143.110458 -246.10441) (xy 143.428986 -246.10441) (xy 143.432946 -246.055356) (xy 143.444723 -246.007572)
			(xy 143.464014 -245.962296) (xy 143.490317 -245.9207) (xy 143.522952 -245.883863) (xy 143.561073 -245.852738)
			(xy 143.603694 -245.828131) (xy 143.64971 -245.810679) (xy 143.697929 -245.800835) (xy 143.747104 -245.798854)
			(xy 143.795959 -245.804786) (xy 143.84323 -245.818478) (xy 143.887692 -245.839576) (xy 143.928195 -245.867532)
			(xy 143.963688 -245.901624) (xy 143.993253 -245.940968) (xy 144.016124 -245.984545) (xy 144.031708 -246.031226)
			(xy 144.039603 -246.079803) (xy 144.040098 -246.10441) (xy 144.039603 -246.129017) (xy 144.031708 -246.177594)
			(xy 144.016124 -246.224275) (xy 143.993253 -246.267852) (xy 143.963688 -246.307196) (xy 143.928195 -246.341288)
			(xy 143.887692 -246.369244) (xy 143.84323 -246.390342) (xy 143.795959 -246.404034) (xy 143.747104 -246.409966)
			(xy 143.697929 -246.407985) (xy 143.64971 -246.398141) (xy 143.603694 -246.380689) (xy 143.561073 -246.356082)
			(xy 143.522952 -246.324957) (xy 143.490317 -246.28812) (xy 143.464014 -246.246524) (xy 143.444723 -246.201248)
			(xy 143.432946 -246.153464) (xy 143.428986 -246.10441) (xy 143.110458 -246.10441) (xy 143.109946 -246.129856)
			(xy 143.101782 -246.18009) (xy 143.085666 -246.228364) (xy 143.062015 -246.273427) (xy 143.031442 -246.314113)
			(xy 142.994738 -246.349368) (xy 142.952854 -246.378278) (xy 142.906875 -246.400095) (xy 142.857991 -246.414255)
			(xy 142.80747 -246.420389) (xy 142.756618 -246.41834) (xy 142.706754 -246.40816) (xy 142.659168 -246.390113)
			(xy 142.615094 -246.364667) (xy 142.575672 -246.33248) (xy 142.541924 -246.294386) (xy 142.514723 -246.251372)
			(xy 142.494775 -246.204552) (xy 142.482596 -246.155138) (xy 142.478501 -246.10441) (xy 142.15999 -246.10441)
			(xy 142.159495 -246.129017) (xy 142.1516 -246.177594) (xy 142.136016 -246.224275) (xy 142.113145 -246.267852)
			(xy 142.08358 -246.307196) (xy 142.048087 -246.341288) (xy 142.007584 -246.369244) (xy 141.963122 -246.390342)
			(xy 141.915851 -246.404034) (xy 141.866996 -246.409966) (xy 141.817821 -246.407985) (xy 141.769602 -246.398141)
			(xy 141.723586 -246.380689) (xy 141.680965 -246.356082) (xy 141.642844 -246.324957) (xy 141.610209 -246.28812)
			(xy 141.583906 -246.246524) (xy 141.564615 -246.201248) (xy 141.552838 -246.153464) (xy 141.548878 -246.10441)
			(xy 141.230604 -246.10441) (xy 141.230092 -246.129856) (xy 141.221928 -246.18009) (xy 141.205812 -246.228364)
			(xy 141.182161 -246.273427) (xy 141.151588 -246.314113) (xy 141.114884 -246.349368) (xy 141.073 -246.378278)
			(xy 141.027021 -246.400095) (xy 140.978137 -246.414255) (xy 140.927616 -246.420389) (xy 140.876764 -246.41834)
			(xy 140.8269 -246.40816) (xy 140.779314 -246.390113) (xy 140.73524 -246.364667) (xy 140.695818 -246.33248)
			(xy 140.66207 -246.294386) (xy 140.634869 -246.251372) (xy 140.614921 -246.204552) (xy 140.602742 -246.155138)
			(xy 140.598647 -246.10441) (xy 140.280136 -246.10441) (xy 140.279641 -246.129017) (xy 140.271746 -246.177594)
			(xy 140.256162 -246.224275) (xy 140.233291 -246.267852) (xy 140.203726 -246.307196) (xy 140.168233 -246.341288)
			(xy 140.12773 -246.369244) (xy 140.083268 -246.390342) (xy 140.035997 -246.404034) (xy 139.987142 -246.409966)
			(xy 139.937967 -246.407985) (xy 139.889748 -246.398141) (xy 139.843732 -246.380689) (xy 139.801111 -246.356082)
			(xy 139.76299 -246.324957) (xy 139.730355 -246.28812) (xy 139.704052 -246.246524) (xy 139.684761 -246.201248)
			(xy 139.672984 -246.153464) (xy 139.669024 -246.10441) (xy 139.350496 -246.10441) (xy 139.349984 -246.129856)
			(xy 139.34182 -246.18009) (xy 139.325704 -246.228364) (xy 139.302053 -246.273427) (xy 139.27148 -246.314113)
			(xy 139.234776 -246.349368) (xy 139.192892 -246.378278) (xy 139.146913 -246.400095) (xy 139.098029 -246.414255)
			(xy 139.047508 -246.420389) (xy 138.996656 -246.41834) (xy 138.946792 -246.40816) (xy 138.899206 -246.390113)
			(xy 138.855132 -246.364667) (xy 138.81571 -246.33248) (xy 138.781962 -246.294386) (xy 138.754761 -246.251372)
			(xy 138.734813 -246.204552) (xy 138.722634 -246.155138) (xy 138.718539 -246.10441) (xy 138.410442 -246.10441)
			(xy 138.40993 -246.129856) (xy 138.401766 -246.18009) (xy 138.38565 -246.228364) (xy 138.361999 -246.273427)
			(xy 138.331426 -246.314113) (xy 138.294722 -246.349368) (xy 138.252838 -246.378278) (xy 138.206859 -246.400095)
			(xy 138.157975 -246.414255) (xy 138.107454 -246.420389) (xy 138.056602 -246.41834) (xy 138.006738 -246.40816)
			(xy 137.959152 -246.390113) (xy 137.915078 -246.364667) (xy 137.875656 -246.33248) (xy 137.841908 -246.294386)
			(xy 137.814707 -246.251372) (xy 137.794759 -246.204552) (xy 137.78258 -246.155138) (xy 137.778485 -246.10441)
			(xy 137.459974 -246.10441) (xy 137.459479 -246.129017) (xy 137.451584 -246.177594) (xy 137.436 -246.224275)
			(xy 137.413129 -246.267852) (xy 137.383564 -246.307196) (xy 137.348071 -246.341288) (xy 137.307568 -246.369244)
			(xy 137.263106 -246.390342) (xy 137.215835 -246.404034) (xy 137.16698 -246.409966) (xy 137.117805 -246.407985)
			(xy 137.069586 -246.398141) (xy 137.02357 -246.380689) (xy 136.980949 -246.356082) (xy 136.942828 -246.324957)
			(xy 136.910193 -246.28812) (xy 136.88389 -246.246524) (xy 136.864599 -246.201248) (xy 136.852822 -246.153464)
			(xy 136.848862 -246.10441) (xy 136.530588 -246.10441) (xy 136.530076 -246.129856) (xy 136.521912 -246.18009)
			(xy 136.505796 -246.228364) (xy 136.482145 -246.273427) (xy 136.451572 -246.314113) (xy 136.414868 -246.349368)
			(xy 136.372984 -246.378278) (xy 136.327005 -246.400095) (xy 136.278121 -246.414255) (xy 136.2276 -246.420389)
			(xy 136.176748 -246.41834) (xy 136.126884 -246.40816) (xy 136.079298 -246.390113) (xy 136.035224 -246.364667)
			(xy 135.995802 -246.33248) (xy 135.962054 -246.294386) (xy 135.934853 -246.251372) (xy 135.914905 -246.204552)
			(xy 135.902726 -246.155138) (xy 135.898631 -246.10441) (xy 135.58012 -246.10441) (xy 135.579625 -246.129017)
			(xy 135.57173 -246.177594) (xy 135.556146 -246.224275) (xy 135.533275 -246.267852) (xy 135.50371 -246.307196)
			(xy 135.468217 -246.341288) (xy 135.427714 -246.369244) (xy 135.383252 -246.390342) (xy 135.335981 -246.404034)
			(xy 135.287126 -246.409966) (xy 135.237951 -246.407985) (xy 135.189732 -246.398141) (xy 135.143716 -246.380689)
			(xy 135.101095 -246.356082) (xy 135.062974 -246.324957) (xy 135.030339 -246.28812) (xy 135.004036 -246.246524)
			(xy 134.984745 -246.201248) (xy 134.972968 -246.153464) (xy 134.969008 -246.10441) (xy 134.65048 -246.10441)
			(xy 134.649968 -246.129856) (xy 134.641804 -246.18009) (xy 134.625688 -246.228364) (xy 134.602037 -246.273427)
			(xy 134.571464 -246.314113) (xy 134.53476 -246.349368) (xy 134.492876 -246.378278) (xy 134.446897 -246.400095)
			(xy 134.398013 -246.414255) (xy 134.347492 -246.420389) (xy 134.29664 -246.41834) (xy 134.246776 -246.40816)
			(xy 134.19919 -246.390113) (xy 134.155116 -246.364667) (xy 134.115694 -246.33248) (xy 134.081946 -246.294386)
			(xy 134.054745 -246.251372) (xy 134.034797 -246.204552) (xy 134.022618 -246.155138) (xy 134.018523 -246.10441)
			(xy 133.700012 -246.10441) (xy 133.699517 -246.129017) (xy 133.691622 -246.177594) (xy 133.676038 -246.224275)
			(xy 133.653167 -246.267852) (xy 133.623602 -246.307196) (xy 133.588109 -246.341288) (xy 133.547606 -246.369244)
			(xy 133.503144 -246.390342) (xy 133.455873 -246.404034) (xy 133.407018 -246.409966) (xy 133.357843 -246.407985)
			(xy 133.309624 -246.398141) (xy 133.263608 -246.380689) (xy 133.220987 -246.356082) (xy 133.182866 -246.324957)
			(xy 133.150231 -246.28812) (xy 133.123928 -246.246524) (xy 133.104637 -246.201248) (xy 133.09286 -246.153464)
			(xy 133.0889 -246.10441) (xy 132.770372 -246.10441) (xy 132.76986 -246.129856) (xy 132.761696 -246.18009)
			(xy 132.74558 -246.228364) (xy 132.721929 -246.273427) (xy 132.691356 -246.314113) (xy 132.654652 -246.349368)
			(xy 132.612768 -246.378278) (xy 132.566789 -246.400095) (xy 132.517905 -246.414255) (xy 132.467384 -246.420389)
			(xy 132.416532 -246.41834) (xy 132.366668 -246.40816) (xy 132.319082 -246.390113) (xy 132.275008 -246.364667)
			(xy 132.235586 -246.33248) (xy 132.201838 -246.294386) (xy 132.174637 -246.251372) (xy 132.154689 -246.204552)
			(xy 132.14251 -246.155138) (xy 132.138415 -246.10441) (xy 131.830572 -246.10441) (xy 131.83006 -246.129856)
			(xy 131.821896 -246.18009) (xy 131.80578 -246.228364) (xy 131.782129 -246.273427) (xy 131.751556 -246.314113)
			(xy 131.714852 -246.349368) (xy 131.672968 -246.378278) (xy 131.626989 -246.400095) (xy 131.578105 -246.414255)
			(xy 131.527584 -246.420389) (xy 131.476732 -246.41834) (xy 131.426868 -246.40816) (xy 131.379282 -246.390113)
			(xy 131.335208 -246.364667) (xy 131.295786 -246.33248) (xy 131.262038 -246.294386) (xy 131.234837 -246.251372)
			(xy 131.214889 -246.204552) (xy 131.20271 -246.155138) (xy 131.198615 -246.10441) (xy 130.880104 -246.10441)
			(xy 130.879609 -246.129017) (xy 130.871714 -246.177594) (xy 130.85613 -246.224275) (xy 130.833259 -246.267852)
			(xy 130.803694 -246.307196) (xy 130.768201 -246.341288) (xy 130.727698 -246.369244) (xy 130.683236 -246.390342)
			(xy 130.635965 -246.404034) (xy 130.58711 -246.409966) (xy 130.537935 -246.407985) (xy 130.489716 -246.398141)
			(xy 130.4437 -246.380689) (xy 130.401079 -246.356082) (xy 130.362958 -246.324957) (xy 130.330323 -246.28812)
			(xy 130.30402 -246.246524) (xy 130.284729 -246.201248) (xy 130.272952 -246.153464) (xy 130.268992 -246.10441)
			(xy 129.950464 -246.10441) (xy 129.949952 -246.129856) (xy 129.941788 -246.18009) (xy 129.925672 -246.228364)
			(xy 129.902021 -246.273427) (xy 129.871448 -246.314113) (xy 129.834744 -246.349368) (xy 129.79286 -246.378278)
			(xy 129.746881 -246.400095) (xy 129.697997 -246.414255) (xy 129.647476 -246.420389) (xy 129.596624 -246.41834)
			(xy 129.54676 -246.40816) (xy 129.499174 -246.390113) (xy 129.4551 -246.364667) (xy 129.415678 -246.33248)
			(xy 129.38193 -246.294386) (xy 129.354729 -246.251372) (xy 129.334781 -246.204552) (xy 129.322602 -246.155138)
			(xy 129.318507 -246.10441) (xy 128.999996 -246.10441) (xy 128.999501 -246.129017) (xy 128.991606 -246.177594)
			(xy 128.976022 -246.224275) (xy 128.953151 -246.267852) (xy 128.923586 -246.307196) (xy 128.888093 -246.341288)
			(xy 128.84759 -246.369244) (xy 128.803128 -246.390342) (xy 128.755857 -246.404034) (xy 128.707002 -246.409966)
			(xy 128.657827 -246.407985) (xy 128.609608 -246.398141) (xy 128.563592 -246.380689) (xy 128.520971 -246.356082)
			(xy 128.48285 -246.324957) (xy 128.450215 -246.28812) (xy 128.423912 -246.246524) (xy 128.404621 -246.201248)
			(xy 128.392844 -246.153464) (xy 128.388884 -246.10441) (xy 128.070356 -246.10441) (xy 128.069844 -246.129856)
			(xy 128.06168 -246.18009) (xy 128.045564 -246.228364) (xy 128.021913 -246.273427) (xy 127.99134 -246.314113)
			(xy 127.954636 -246.349368) (xy 127.912752 -246.378278) (xy 127.866773 -246.400095) (xy 127.817889 -246.414255)
			(xy 127.767368 -246.420389) (xy 127.716516 -246.41834) (xy 127.666652 -246.40816) (xy 127.619066 -246.390113)
			(xy 127.574992 -246.364667) (xy 127.53557 -246.33248) (xy 127.501822 -246.294386) (xy 127.474621 -246.251372)
			(xy 127.454673 -246.204552) (xy 127.442494 -246.155138) (xy 127.438399 -246.10441) (xy 127.120142 -246.10441)
			(xy 127.119643 -246.129181) (xy 127.111608 -246.178068) (xy 127.10414 -246.201692) (xy 127.1016 -246.209566)
			(xy 127.1016 -246.914416) (xy 127.908553 -246.914416) (xy 127.912648 -246.863688) (xy 127.924827 -246.814274)
			(xy 127.944775 -246.767454) (xy 127.971976 -246.72444) (xy 128.005724 -246.686346) (xy 128.045146 -246.654159)
			(xy 128.08922 -246.628713) (xy 128.136806 -246.610666) (xy 128.18667 -246.600486) (xy 128.237522 -246.598437)
			(xy 128.288043 -246.604571) (xy 128.336927 -246.618731) (xy 128.382906 -246.640548) (xy 128.42479 -246.669458)
			(xy 128.461494 -246.704713) (xy 128.492067 -246.745399) (xy 128.515718 -246.790462) (xy 128.531834 -246.838736)
			(xy 128.539998 -246.88897) (xy 128.54051 -246.914416) (xy 128.848607 -246.914416) (xy 128.852702 -246.863688)
			(xy 128.864881 -246.814274) (xy 128.884829 -246.767454) (xy 128.91203 -246.72444) (xy 128.945778 -246.686346)
			(xy 128.9852 -246.654159) (xy 129.029274 -246.628713) (xy 129.07686 -246.610666) (xy 129.126724 -246.600486)
			(xy 129.177576 -246.598437) (xy 129.228097 -246.604571) (xy 129.276981 -246.618731) (xy 129.32296 -246.640548)
			(xy 129.364844 -246.669458) (xy 129.401548 -246.704713) (xy 129.432121 -246.745399) (xy 129.455772 -246.790462)
			(xy 129.471888 -246.838736) (xy 129.480052 -246.88897) (xy 129.480564 -246.914416) (xy 130.728461 -246.914416)
			(xy 130.732556 -246.863688) (xy 130.744735 -246.814274) (xy 130.764683 -246.767454) (xy 130.791884 -246.72444)
			(xy 130.825632 -246.686346) (xy 130.865054 -246.654159) (xy 130.909128 -246.628713) (xy 130.956714 -246.610666)
			(xy 131.006578 -246.600486) (xy 131.05743 -246.598437) (xy 131.107951 -246.604571) (xy 131.156835 -246.618731)
			(xy 131.202814 -246.640548) (xy 131.244698 -246.669458) (xy 131.281402 -246.704713) (xy 131.311975 -246.745399)
			(xy 131.335626 -246.790462) (xy 131.351742 -246.838736) (xy 131.359906 -246.88897) (xy 131.360418 -246.914416)
			(xy 131.678946 -246.914416) (xy 131.682906 -246.865362) (xy 131.694683 -246.817578) (xy 131.713974 -246.772302)
			(xy 131.740277 -246.730706) (xy 131.772912 -246.693869) (xy 131.811033 -246.662744) (xy 131.853654 -246.638137)
			(xy 131.89967 -246.620685) (xy 131.947889 -246.610841) (xy 131.997064 -246.60886) (xy 132.045919 -246.614792)
			(xy 132.09319 -246.628484) (xy 132.137652 -246.649582) (xy 132.178155 -246.677538) (xy 132.213648 -246.71163)
			(xy 132.243213 -246.750974) (xy 132.266084 -246.794551) (xy 132.281668 -246.841232) (xy 132.289563 -246.889809)
			(xy 132.290058 -246.914416) (xy 132.608569 -246.914416) (xy 132.612664 -246.863688) (xy 132.624843 -246.814274)
			(xy 132.644791 -246.767454) (xy 132.671992 -246.72444) (xy 132.70574 -246.686346) (xy 132.745162 -246.654159)
			(xy 132.789236 -246.628713) (xy 132.836822 -246.610666) (xy 132.886686 -246.600486) (xy 132.937538 -246.598437)
			(xy 132.988059 -246.604571) (xy 133.036943 -246.618731) (xy 133.082922 -246.640548) (xy 133.124806 -246.669458)
			(xy 133.16151 -246.704713) (xy 133.192083 -246.745399) (xy 133.215734 -246.790462) (xy 133.23185 -246.838736)
			(xy 133.240014 -246.88897) (xy 133.240526 -246.914416) (xy 133.559054 -246.914416) (xy 133.563014 -246.865362)
			(xy 133.574791 -246.817578) (xy 133.594082 -246.772302) (xy 133.620385 -246.730706) (xy 133.65302 -246.693869)
			(xy 133.691141 -246.662744) (xy 133.733762 -246.638137) (xy 133.779778 -246.620685) (xy 133.827997 -246.610841)
			(xy 133.877172 -246.60886) (xy 133.926027 -246.614792) (xy 133.973298 -246.628484) (xy 134.01776 -246.649582)
			(xy 134.058263 -246.677538) (xy 134.093756 -246.71163) (xy 134.123321 -246.750974) (xy 134.146192 -246.794551)
			(xy 134.161776 -246.841232) (xy 134.169671 -246.889809) (xy 134.170166 -246.914416) (xy 134.488423 -246.914416)
			(xy 134.492518 -246.863688) (xy 134.504697 -246.814274) (xy 134.524645 -246.767454) (xy 134.551846 -246.72444)
			(xy 134.585594 -246.686346) (xy 134.625016 -246.654159) (xy 134.66909 -246.628713) (xy 134.716676 -246.610666)
			(xy 134.76654 -246.600486) (xy 134.817392 -246.598437) (xy 134.867913 -246.604571) (xy 134.916797 -246.618731)
			(xy 134.962776 -246.640548) (xy 135.00466 -246.669458) (xy 135.041364 -246.704713) (xy 135.071937 -246.745399)
			(xy 135.095588 -246.790462) (xy 135.111704 -246.838736) (xy 135.119868 -246.88897) (xy 135.12038 -246.914416)
			(xy 135.428477 -246.914416) (xy 135.432572 -246.863688) (xy 135.444751 -246.814274) (xy 135.464699 -246.767454)
			(xy 135.4919 -246.72444) (xy 135.525648 -246.686346) (xy 135.56507 -246.654159) (xy 135.609144 -246.628713)
			(xy 135.65673 -246.610666) (xy 135.706594 -246.600486) (xy 135.757446 -246.598437) (xy 135.807967 -246.604571)
			(xy 135.856851 -246.618731) (xy 135.90283 -246.640548) (xy 135.944714 -246.669458) (xy 135.981418 -246.704713)
			(xy 136.011991 -246.745399) (xy 136.035642 -246.790462) (xy 136.051758 -246.838736) (xy 136.059922 -246.88897)
			(xy 136.060434 -246.914416) (xy 137.308585 -246.914416) (xy 137.31268 -246.863688) (xy 137.324859 -246.814274)
			(xy 137.344807 -246.767454) (xy 137.372008 -246.72444) (xy 137.405756 -246.686346) (xy 137.445178 -246.654159)
			(xy 137.489252 -246.628713) (xy 137.536838 -246.610666) (xy 137.586702 -246.600486) (xy 137.637554 -246.598437)
			(xy 137.688075 -246.604571) (xy 137.736959 -246.618731) (xy 137.782938 -246.640548) (xy 137.824822 -246.669458)
			(xy 137.861526 -246.704713) (xy 137.892099 -246.745399) (xy 137.91575 -246.790462) (xy 137.931866 -246.838736)
			(xy 137.94003 -246.88897) (xy 137.940542 -246.914416) (xy 138.25907 -246.914416) (xy 138.26303 -246.865362)
			(xy 138.274807 -246.817578) (xy 138.294098 -246.772302) (xy 138.320401 -246.730706) (xy 138.353036 -246.693869)
			(xy 138.391157 -246.662744) (xy 138.433778 -246.638137) (xy 138.479794 -246.620685) (xy 138.528013 -246.610841)
			(xy 138.577188 -246.60886) (xy 138.626043 -246.614792) (xy 138.673314 -246.628484) (xy 138.717776 -246.649582)
			(xy 138.758279 -246.677538) (xy 138.793772 -246.71163) (xy 138.823337 -246.750974) (xy 138.846208 -246.794551)
			(xy 138.861792 -246.841232) (xy 138.869687 -246.889809) (xy 138.870182 -246.914416) (xy 139.188439 -246.914416)
			(xy 139.192534 -246.863688) (xy 139.204713 -246.814274) (xy 139.224661 -246.767454) (xy 139.251862 -246.72444)
			(xy 139.28561 -246.686346) (xy 139.325032 -246.654159) (xy 139.369106 -246.628713) (xy 139.416692 -246.610666)
			(xy 139.466556 -246.600486) (xy 139.517408 -246.598437) (xy 139.567929 -246.604571) (xy 139.616813 -246.618731)
			(xy 139.662792 -246.640548) (xy 139.704676 -246.669458) (xy 139.74138 -246.704713) (xy 139.771953 -246.745399)
			(xy 139.795604 -246.790462) (xy 139.81172 -246.838736) (xy 139.819884 -246.88897) (xy 139.820396 -246.914416)
			(xy 140.138924 -246.914416) (xy 140.142884 -246.865362) (xy 140.154661 -246.817578) (xy 140.173952 -246.772302)
			(xy 140.200255 -246.730706) (xy 140.23289 -246.693869) (xy 140.271011 -246.662744) (xy 140.313632 -246.638137)
			(xy 140.359648 -246.620685) (xy 140.407867 -246.610841) (xy 140.457042 -246.60886) (xy 140.505897 -246.614792)
			(xy 140.553168 -246.628484) (xy 140.59763 -246.649582) (xy 140.638133 -246.677538) (xy 140.673626 -246.71163)
			(xy 140.703191 -246.750974) (xy 140.726062 -246.794551) (xy 140.741646 -246.841232) (xy 140.749541 -246.889809)
			(xy 140.750036 -246.914416) (xy 141.068547 -246.914416) (xy 141.072642 -246.863688) (xy 141.084821 -246.814274)
			(xy 141.104769 -246.767454) (xy 141.13197 -246.72444) (xy 141.165718 -246.686346) (xy 141.20514 -246.654159)
			(xy 141.249214 -246.628713) (xy 141.2968 -246.610666) (xy 141.346664 -246.600486) (xy 141.397516 -246.598437)
			(xy 141.448037 -246.604571) (xy 141.496921 -246.618731) (xy 141.5429 -246.640548) (xy 141.584784 -246.669458)
			(xy 141.621488 -246.704713) (xy 141.652061 -246.745399) (xy 141.675712 -246.790462) (xy 141.691828 -246.838736)
			(xy 141.699992 -246.88897) (xy 141.700504 -246.914416) (xy 142.008601 -246.914416) (xy 142.012696 -246.863688)
			(xy 142.024875 -246.814274) (xy 142.044823 -246.767454) (xy 142.072024 -246.72444) (xy 142.105772 -246.686346)
			(xy 142.145194 -246.654159) (xy 142.189268 -246.628713) (xy 142.236854 -246.610666) (xy 142.286718 -246.600486)
			(xy 142.33757 -246.598437) (xy 142.388091 -246.604571) (xy 142.436975 -246.618731) (xy 142.482954 -246.640548)
			(xy 142.524838 -246.669458) (xy 142.561542 -246.704713) (xy 142.592115 -246.745399) (xy 142.615766 -246.790462)
			(xy 142.631882 -246.838736) (xy 142.640046 -246.88897) (xy 142.640558 -246.914416) (xy 144.83894 -246.914416)
			(xy 144.8429 -246.865362) (xy 144.854677 -246.817578) (xy 144.873968 -246.772302) (xy 144.900271 -246.730706)
			(xy 144.932906 -246.693869) (xy 144.971027 -246.662744) (xy 145.013648 -246.638137) (xy 145.059664 -246.620685)
			(xy 145.107883 -246.610841) (xy 145.157058 -246.60886) (xy 145.205913 -246.614792) (xy 145.253184 -246.628484)
			(xy 145.297646 -246.649582) (xy 145.338149 -246.677538) (xy 145.373642 -246.71163) (xy 145.403207 -246.750974)
			(xy 145.426078 -246.794551) (xy 145.441662 -246.841232) (xy 145.449557 -246.889809) (xy 145.450052 -246.914416)
			(xy 145.449557 -246.939023) (xy 145.441662 -246.9876) (xy 145.426078 -247.034281) (xy 145.403207 -247.077858)
			(xy 145.373642 -247.117202) (xy 145.338149 -247.151294) (xy 145.297646 -247.17925) (xy 145.253184 -247.200348)
			(xy 145.205913 -247.21404) (xy 145.157058 -247.219972) (xy 145.107883 -247.217991) (xy 145.059664 -247.208147)
			(xy 145.013648 -247.190695) (xy 144.971027 -247.166088) (xy 144.932906 -247.134963) (xy 144.900271 -247.098126)
			(xy 144.873968 -247.05653) (xy 144.854677 -247.011254) (xy 144.8429 -246.96347) (xy 144.83894 -246.914416)
			(xy 142.640558 -246.914416) (xy 142.640046 -246.939862) (xy 142.631882 -246.990096) (xy 142.615766 -247.03837)
			(xy 142.592115 -247.083433) (xy 142.561542 -247.124119) (xy 142.524838 -247.159374) (xy 142.482954 -247.188284)
			(xy 142.436975 -247.210101) (xy 142.388091 -247.224261) (xy 142.33757 -247.230395) (xy 142.286718 -247.228346)
			(xy 142.236854 -247.218166) (xy 142.189268 -247.200119) (xy 142.145194 -247.174673) (xy 142.105772 -247.142486)
			(xy 142.072024 -247.104392) (xy 142.044823 -247.061378) (xy 142.024875 -247.014558) (xy 142.012696 -246.965144)
			(xy 142.008601 -246.914416) (xy 141.700504 -246.914416) (xy 141.699992 -246.939862) (xy 141.691828 -246.990096)
			(xy 141.675712 -247.03837) (xy 141.652061 -247.083433) (xy 141.621488 -247.124119) (xy 141.584784 -247.159374)
			(xy 141.5429 -247.188284) (xy 141.496921 -247.210101) (xy 141.448037 -247.224261) (xy 141.397516 -247.230395)
			(xy 141.346664 -247.228346) (xy 141.2968 -247.218166) (xy 141.249214 -247.200119) (xy 141.20514 -247.174673)
			(xy 141.165718 -247.142486) (xy 141.13197 -247.104392) (xy 141.104769 -247.061378) (xy 141.084821 -247.014558)
			(xy 141.072642 -246.965144) (xy 141.068547 -246.914416) (xy 140.750036 -246.914416) (xy 140.749541 -246.939023)
			(xy 140.741646 -246.9876) (xy 140.726062 -247.034281) (xy 140.703191 -247.077858) (xy 140.673626 -247.117202)
			(xy 140.638133 -247.151294) (xy 140.59763 -247.17925) (xy 140.553168 -247.200348) (xy 140.505897 -247.21404)
			(xy 140.457042 -247.219972) (xy 140.407867 -247.217991) (xy 140.359648 -247.208147) (xy 140.313632 -247.190695)
			(xy 140.271011 -247.166088) (xy 140.23289 -247.134963) (xy 140.200255 -247.098126) (xy 140.173952 -247.05653)
			(xy 140.154661 -247.011254) (xy 140.142884 -246.96347) (xy 140.138924 -246.914416) (xy 139.820396 -246.914416)
			(xy 139.819884 -246.939862) (xy 139.81172 -246.990096) (xy 139.795604 -247.03837) (xy 139.771953 -247.083433)
			(xy 139.74138 -247.124119) (xy 139.704676 -247.159374) (xy 139.662792 -247.188284) (xy 139.616813 -247.210101)
			(xy 139.567929 -247.224261) (xy 139.517408 -247.230395) (xy 139.466556 -247.228346) (xy 139.416692 -247.218166)
			(xy 139.369106 -247.200119) (xy 139.325032 -247.174673) (xy 139.28561 -247.142486) (xy 139.251862 -247.104392)
			(xy 139.224661 -247.061378) (xy 139.204713 -247.014558) (xy 139.192534 -246.965144) (xy 139.188439 -246.914416)
			(xy 138.870182 -246.914416) (xy 138.869687 -246.939023) (xy 138.861792 -246.9876) (xy 138.846208 -247.034281)
			(xy 138.823337 -247.077858) (xy 138.793772 -247.117202) (xy 138.758279 -247.151294) (xy 138.717776 -247.17925)
			(xy 138.673314 -247.200348) (xy 138.626043 -247.21404) (xy 138.577188 -247.219972) (xy 138.528013 -247.217991)
			(xy 138.479794 -247.208147) (xy 138.433778 -247.190695) (xy 138.391157 -247.166088) (xy 138.353036 -247.134963)
			(xy 138.320401 -247.098126) (xy 138.294098 -247.05653) (xy 138.274807 -247.011254) (xy 138.26303 -246.96347)
			(xy 138.25907 -246.914416) (xy 137.940542 -246.914416) (xy 137.94003 -246.939862) (xy 137.931866 -246.990096)
			(xy 137.91575 -247.03837) (xy 137.892099 -247.083433) (xy 137.861526 -247.124119) (xy 137.824822 -247.159374)
			(xy 137.782938 -247.188284) (xy 137.736959 -247.210101) (xy 137.688075 -247.224261) (xy 137.637554 -247.230395)
			(xy 137.586702 -247.228346) (xy 137.536838 -247.218166) (xy 137.489252 -247.200119) (xy 137.445178 -247.174673)
			(xy 137.405756 -247.142486) (xy 137.372008 -247.104392) (xy 137.344807 -247.061378) (xy 137.324859 -247.014558)
			(xy 137.31268 -246.965144) (xy 137.308585 -246.914416) (xy 136.060434 -246.914416) (xy 136.059922 -246.939862)
			(xy 136.051758 -246.990096) (xy 136.035642 -247.03837) (xy 136.011991 -247.083433) (xy 135.981418 -247.124119)
			(xy 135.944714 -247.159374) (xy 135.90283 -247.188284) (xy 135.856851 -247.210101) (xy 135.807967 -247.224261)
			(xy 135.757446 -247.230395) (xy 135.706594 -247.228346) (xy 135.65673 -247.218166) (xy 135.609144 -247.200119)
			(xy 135.56507 -247.174673) (xy 135.525648 -247.142486) (xy 135.4919 -247.104392) (xy 135.464699 -247.061378)
			(xy 135.444751 -247.014558) (xy 135.432572 -246.965144) (xy 135.428477 -246.914416) (xy 135.12038 -246.914416)
			(xy 135.119868 -246.939862) (xy 135.111704 -246.990096) (xy 135.095588 -247.03837) (xy 135.071937 -247.083433)
			(xy 135.041364 -247.124119) (xy 135.00466 -247.159374) (xy 134.962776 -247.188284) (xy 134.916797 -247.210101)
			(xy 134.867913 -247.224261) (xy 134.817392 -247.230395) (xy 134.76654 -247.228346) (xy 134.716676 -247.218166)
			(xy 134.66909 -247.200119) (xy 134.625016 -247.174673) (xy 134.585594 -247.142486) (xy 134.551846 -247.104392)
			(xy 134.524645 -247.061378) (xy 134.504697 -247.014558) (xy 134.492518 -246.965144) (xy 134.488423 -246.914416)
			(xy 134.170166 -246.914416) (xy 134.169671 -246.939023) (xy 134.161776 -246.9876) (xy 134.146192 -247.034281)
			(xy 134.123321 -247.077858) (xy 134.093756 -247.117202) (xy 134.058263 -247.151294) (xy 134.01776 -247.17925)
			(xy 133.973298 -247.200348) (xy 133.926027 -247.21404) (xy 133.877172 -247.219972) (xy 133.827997 -247.217991)
			(xy 133.779778 -247.208147) (xy 133.733762 -247.190695) (xy 133.691141 -247.166088) (xy 133.65302 -247.134963)
			(xy 133.620385 -247.098126) (xy 133.594082 -247.05653) (xy 133.574791 -247.011254) (xy 133.563014 -246.96347)
			(xy 133.559054 -246.914416) (xy 133.240526 -246.914416) (xy 133.240014 -246.939862) (xy 133.23185 -246.990096)
			(xy 133.215734 -247.03837) (xy 133.192083 -247.083433) (xy 133.16151 -247.124119) (xy 133.124806 -247.159374)
			(xy 133.082922 -247.188284) (xy 133.036943 -247.210101) (xy 132.988059 -247.224261) (xy 132.937538 -247.230395)
			(xy 132.886686 -247.228346) (xy 132.836822 -247.218166) (xy 132.789236 -247.200119) (xy 132.745162 -247.174673)
			(xy 132.70574 -247.142486) (xy 132.671992 -247.104392) (xy 132.644791 -247.061378) (xy 132.624843 -247.014558)
			(xy 132.612664 -246.965144) (xy 132.608569 -246.914416) (xy 132.290058 -246.914416) (xy 132.289563 -246.939023)
			(xy 132.281668 -246.9876) (xy 132.266084 -247.034281) (xy 132.243213 -247.077858) (xy 132.213648 -247.117202)
			(xy 132.178155 -247.151294) (xy 132.137652 -247.17925) (xy 132.09319 -247.200348) (xy 132.045919 -247.21404)
			(xy 131.997064 -247.219972) (xy 131.947889 -247.217991) (xy 131.89967 -247.208147) (xy 131.853654 -247.190695)
			(xy 131.811033 -247.166088) (xy 131.772912 -247.134963) (xy 131.740277 -247.098126) (xy 131.713974 -247.05653)
			(xy 131.694683 -247.011254) (xy 131.682906 -246.96347) (xy 131.678946 -246.914416) (xy 131.360418 -246.914416)
			(xy 131.359906 -246.939862) (xy 131.351742 -246.990096) (xy 131.335626 -247.03837) (xy 131.311975 -247.083433)
			(xy 131.281402 -247.124119) (xy 131.244698 -247.159374) (xy 131.202814 -247.188284) (xy 131.156835 -247.210101)
			(xy 131.107951 -247.224261) (xy 131.05743 -247.230395) (xy 131.006578 -247.228346) (xy 130.956714 -247.218166)
			(xy 130.909128 -247.200119) (xy 130.865054 -247.174673) (xy 130.825632 -247.142486) (xy 130.791884 -247.104392)
			(xy 130.764683 -247.061378) (xy 130.744735 -247.014558) (xy 130.732556 -246.965144) (xy 130.728461 -246.914416)
			(xy 129.480564 -246.914416) (xy 129.480052 -246.939862) (xy 129.471888 -246.990096) (xy 129.455772 -247.03837)
			(xy 129.432121 -247.083433) (xy 129.401548 -247.124119) (xy 129.364844 -247.159374) (xy 129.32296 -247.188284)
			(xy 129.276981 -247.210101) (xy 129.228097 -247.224261) (xy 129.177576 -247.230395) (xy 129.126724 -247.228346)
			(xy 129.07686 -247.218166) (xy 129.029274 -247.200119) (xy 128.9852 -247.174673) (xy 128.945778 -247.142486)
			(xy 128.91203 -247.104392) (xy 128.884829 -247.061378) (xy 128.864881 -247.014558) (xy 128.852702 -246.965144)
			(xy 128.848607 -246.914416) (xy 128.54051 -246.914416) (xy 128.539998 -246.939862) (xy 128.531834 -246.990096)
			(xy 128.515718 -247.03837) (xy 128.492067 -247.083433) (xy 128.461494 -247.124119) (xy 128.42479 -247.159374)
			(xy 128.382906 -247.188284) (xy 128.336927 -247.210101) (xy 128.288043 -247.224261) (xy 128.237522 -247.230395)
			(xy 128.18667 -247.228346) (xy 128.136806 -247.218166) (xy 128.08922 -247.200119) (xy 128.045146 -247.174673)
			(xy 128.005724 -247.142486) (xy 127.971976 -247.104392) (xy 127.944775 -247.061378) (xy 127.924827 -247.014558)
			(xy 127.912648 -246.965144) (xy 127.908553 -246.914416) (xy 127.1016 -246.914416) (xy 127.1016 -247.619266)
			(xy 127.10414 -247.62714) (xy 127.111596 -247.650767) (xy 127.119636 -247.699652) (xy 127.120142 -247.724422)
			(xy 127.438399 -247.724422) (xy 127.442494 -247.673694) (xy 127.454673 -247.62428) (xy 127.474621 -247.57746)
			(xy 127.501822 -247.534446) (xy 127.53557 -247.496352) (xy 127.574992 -247.464165) (xy 127.619066 -247.438719)
			(xy 127.666652 -247.420672) (xy 127.716516 -247.410492) (xy 127.767368 -247.408443) (xy 127.817889 -247.414577)
			(xy 127.866773 -247.428737) (xy 127.912752 -247.450554) (xy 127.954636 -247.479464) (xy 127.99134 -247.514719)
			(xy 128.021913 -247.555405) (xy 128.045564 -247.600468) (xy 128.06168 -247.648742) (xy 128.069844 -247.698976)
			(xy 128.070356 -247.724422) (xy 128.388884 -247.724422) (xy 128.392844 -247.675368) (xy 128.404621 -247.627584)
			(xy 128.423912 -247.582308) (xy 128.450215 -247.540712) (xy 128.48285 -247.503875) (xy 128.520971 -247.47275)
			(xy 128.563592 -247.448143) (xy 128.609608 -247.430691) (xy 128.657827 -247.420847) (xy 128.707002 -247.418866)
			(xy 128.755857 -247.424798) (xy 128.803128 -247.43849) (xy 128.84759 -247.459588) (xy 128.888093 -247.487544)
			(xy 128.923586 -247.521636) (xy 128.953151 -247.56098) (xy 128.976022 -247.604557) (xy 128.991606 -247.651238)
			(xy 128.999501 -247.699815) (xy 128.999996 -247.724422) (xy 129.318507 -247.724422) (xy 129.322602 -247.673694)
			(xy 129.334781 -247.62428) (xy 129.354729 -247.57746) (xy 129.38193 -247.534446) (xy 129.415678 -247.496352)
			(xy 129.4551 -247.464165) (xy 129.499174 -247.438719) (xy 129.54676 -247.420672) (xy 129.596624 -247.410492)
			(xy 129.647476 -247.408443) (xy 129.697997 -247.414577) (xy 129.746881 -247.428737) (xy 129.79286 -247.450554)
			(xy 129.834744 -247.479464) (xy 129.871448 -247.514719) (xy 129.902021 -247.555405) (xy 129.925672 -247.600468)
			(xy 129.941788 -247.648742) (xy 129.949952 -247.698976) (xy 129.950464 -247.724422) (xy 130.268992 -247.724422)
			(xy 130.272952 -247.675368) (xy 130.284729 -247.627584) (xy 130.30402 -247.582308) (xy 130.330323 -247.540712)
			(xy 130.362958 -247.503875) (xy 130.401079 -247.47275) (xy 130.4437 -247.448143) (xy 130.489716 -247.430691)
			(xy 130.537935 -247.420847) (xy 130.58711 -247.418866) (xy 130.635965 -247.424798) (xy 130.683236 -247.43849)
			(xy 130.727698 -247.459588) (xy 130.768201 -247.487544) (xy 130.803694 -247.521636) (xy 130.833259 -247.56098)
			(xy 130.85613 -247.604557) (xy 130.871714 -247.651238) (xy 130.879609 -247.699815) (xy 130.880104 -247.724422)
			(xy 131.198615 -247.724422) (xy 131.20271 -247.673694) (xy 131.214889 -247.62428) (xy 131.234837 -247.57746)
			(xy 131.262038 -247.534446) (xy 131.295786 -247.496352) (xy 131.335208 -247.464165) (xy 131.379282 -247.438719)
			(xy 131.426868 -247.420672) (xy 131.476732 -247.410492) (xy 131.527584 -247.408443) (xy 131.578105 -247.414577)
			(xy 131.626989 -247.428737) (xy 131.672968 -247.450554) (xy 131.714852 -247.479464) (xy 131.751556 -247.514719)
			(xy 131.782129 -247.555405) (xy 131.80578 -247.600468) (xy 131.821896 -247.648742) (xy 131.83006 -247.698976)
			(xy 131.830572 -247.724422) (xy 132.138415 -247.724422) (xy 132.14251 -247.673694) (xy 132.154689 -247.62428)
			(xy 132.174637 -247.57746) (xy 132.201838 -247.534446) (xy 132.235586 -247.496352) (xy 132.275008 -247.464165)
			(xy 132.319082 -247.438719) (xy 132.366668 -247.420672) (xy 132.416532 -247.410492) (xy 132.467384 -247.408443)
			(xy 132.517905 -247.414577) (xy 132.566789 -247.428737) (xy 132.612768 -247.450554) (xy 132.654652 -247.479464)
			(xy 132.691356 -247.514719) (xy 132.721929 -247.555405) (xy 132.74558 -247.600468) (xy 132.761696 -247.648742)
			(xy 132.76986 -247.698976) (xy 132.770372 -247.724422) (xy 133.0889 -247.724422) (xy 133.09286 -247.675368)
			(xy 133.104637 -247.627584) (xy 133.123928 -247.582308) (xy 133.150231 -247.540712) (xy 133.182866 -247.503875)
			(xy 133.220987 -247.47275) (xy 133.263608 -247.448143) (xy 133.309624 -247.430691) (xy 133.357843 -247.420847)
			(xy 133.407018 -247.418866) (xy 133.455873 -247.424798) (xy 133.503144 -247.43849) (xy 133.547606 -247.459588)
			(xy 133.588109 -247.487544) (xy 133.623602 -247.521636) (xy 133.653167 -247.56098) (xy 133.676038 -247.604557)
			(xy 133.691622 -247.651238) (xy 133.699517 -247.699815) (xy 133.700012 -247.724422) (xy 134.018523 -247.724422)
			(xy 134.022618 -247.673694) (xy 134.034797 -247.62428) (xy 134.054745 -247.57746) (xy 134.081946 -247.534446)
			(xy 134.115694 -247.496352) (xy 134.155116 -247.464165) (xy 134.19919 -247.438719) (xy 134.246776 -247.420672)
			(xy 134.29664 -247.410492) (xy 134.347492 -247.408443) (xy 134.398013 -247.414577) (xy 134.446897 -247.428737)
			(xy 134.492876 -247.450554) (xy 134.53476 -247.479464) (xy 134.571464 -247.514719) (xy 134.602037 -247.555405)
			(xy 134.625688 -247.600468) (xy 134.641804 -247.648742) (xy 134.649968 -247.698976) (xy 134.65048 -247.724422)
			(xy 134.969008 -247.724422) (xy 134.972968 -247.675368) (xy 134.984745 -247.627584) (xy 135.004036 -247.582308)
			(xy 135.030339 -247.540712) (xy 135.062974 -247.503875) (xy 135.101095 -247.47275) (xy 135.143716 -247.448143)
			(xy 135.189732 -247.430691) (xy 135.237951 -247.420847) (xy 135.287126 -247.418866) (xy 135.335981 -247.424798)
			(xy 135.383252 -247.43849) (xy 135.427714 -247.459588) (xy 135.468217 -247.487544) (xy 135.50371 -247.521636)
			(xy 135.533275 -247.56098) (xy 135.556146 -247.604557) (xy 135.57173 -247.651238) (xy 135.579625 -247.699815)
			(xy 135.58012 -247.724422) (xy 135.898631 -247.724422) (xy 135.902726 -247.673694) (xy 135.914905 -247.62428)
			(xy 135.934853 -247.57746) (xy 135.962054 -247.534446) (xy 135.995802 -247.496352) (xy 136.035224 -247.464165)
			(xy 136.079298 -247.438719) (xy 136.126884 -247.420672) (xy 136.176748 -247.410492) (xy 136.2276 -247.408443)
			(xy 136.278121 -247.414577) (xy 136.327005 -247.428737) (xy 136.372984 -247.450554) (xy 136.414868 -247.479464)
			(xy 136.451572 -247.514719) (xy 136.482145 -247.555405) (xy 136.505796 -247.600468) (xy 136.521912 -247.648742)
			(xy 136.530076 -247.698976) (xy 136.530588 -247.724422) (xy 136.848862 -247.724422) (xy 136.852822 -247.675368)
			(xy 136.864599 -247.627584) (xy 136.88389 -247.582308) (xy 136.910193 -247.540712) (xy 136.942828 -247.503875)
			(xy 136.980949 -247.47275) (xy 137.02357 -247.448143) (xy 137.069586 -247.430691) (xy 137.117805 -247.420847)
			(xy 137.16698 -247.418866) (xy 137.215835 -247.424798) (xy 137.263106 -247.43849) (xy 137.307568 -247.459588)
			(xy 137.348071 -247.487544) (xy 137.383564 -247.521636) (xy 137.413129 -247.56098) (xy 137.436 -247.604557)
			(xy 137.451584 -247.651238) (xy 137.459479 -247.699815) (xy 137.459974 -247.724422) (xy 137.778485 -247.724422)
			(xy 137.78258 -247.673694) (xy 137.794759 -247.62428) (xy 137.814707 -247.57746) (xy 137.841908 -247.534446)
			(xy 137.875656 -247.496352) (xy 137.915078 -247.464165) (xy 137.959152 -247.438719) (xy 138.006738 -247.420672)
			(xy 138.056602 -247.410492) (xy 138.107454 -247.408443) (xy 138.157975 -247.414577) (xy 138.206859 -247.428737)
			(xy 138.252838 -247.450554) (xy 138.294722 -247.479464) (xy 138.331426 -247.514719) (xy 138.361999 -247.555405)
			(xy 138.38565 -247.600468) (xy 138.401766 -247.648742) (xy 138.40993 -247.698976) (xy 138.410442 -247.724422)
			(xy 138.718539 -247.724422) (xy 138.722634 -247.673694) (xy 138.734813 -247.62428) (xy 138.754761 -247.57746)
			(xy 138.781962 -247.534446) (xy 138.81571 -247.496352) (xy 138.855132 -247.464165) (xy 138.899206 -247.438719)
			(xy 138.946792 -247.420672) (xy 138.996656 -247.410492) (xy 139.047508 -247.408443) (xy 139.098029 -247.414577)
			(xy 139.146913 -247.428737) (xy 139.192892 -247.450554) (xy 139.234776 -247.479464) (xy 139.27148 -247.514719)
			(xy 139.302053 -247.555405) (xy 139.325704 -247.600468) (xy 139.34182 -247.648742) (xy 139.349984 -247.698976)
			(xy 139.350496 -247.724422) (xy 139.669024 -247.724422) (xy 139.672984 -247.675368) (xy 139.684761 -247.627584)
			(xy 139.704052 -247.582308) (xy 139.730355 -247.540712) (xy 139.76299 -247.503875) (xy 139.801111 -247.47275)
			(xy 139.843732 -247.448143) (xy 139.889748 -247.430691) (xy 139.937967 -247.420847) (xy 139.987142 -247.418866)
			(xy 140.035997 -247.424798) (xy 140.083268 -247.43849) (xy 140.12773 -247.459588) (xy 140.168233 -247.487544)
			(xy 140.203726 -247.521636) (xy 140.233291 -247.56098) (xy 140.256162 -247.604557) (xy 140.271746 -247.651238)
			(xy 140.279641 -247.699815) (xy 140.280136 -247.724422) (xy 140.598647 -247.724422) (xy 140.602742 -247.673694)
			(xy 140.614921 -247.62428) (xy 140.634869 -247.57746) (xy 140.66207 -247.534446) (xy 140.695818 -247.496352)
			(xy 140.73524 -247.464165) (xy 140.779314 -247.438719) (xy 140.8269 -247.420672) (xy 140.876764 -247.410492)
			(xy 140.927616 -247.408443) (xy 140.978137 -247.414577) (xy 141.027021 -247.428737) (xy 141.073 -247.450554)
			(xy 141.114884 -247.479464) (xy 141.151588 -247.514719) (xy 141.182161 -247.555405) (xy 141.205812 -247.600468)
			(xy 141.221928 -247.648742) (xy 141.230092 -247.698976) (xy 141.230604 -247.724422) (xy 141.548878 -247.724422)
			(xy 141.552838 -247.675368) (xy 141.564615 -247.627584) (xy 141.583906 -247.582308) (xy 141.610209 -247.540712)
			(xy 141.642844 -247.503875) (xy 141.680965 -247.47275) (xy 141.723586 -247.448143) (xy 141.769602 -247.430691)
			(xy 141.817821 -247.420847) (xy 141.866996 -247.418866) (xy 141.915851 -247.424798) (xy 141.963122 -247.43849)
			(xy 142.007584 -247.459588) (xy 142.048087 -247.487544) (xy 142.08358 -247.521636) (xy 142.113145 -247.56098)
			(xy 142.136016 -247.604557) (xy 142.1516 -247.651238) (xy 142.159495 -247.699815) (xy 142.15999 -247.724422)
			(xy 142.478501 -247.724422) (xy 142.482596 -247.673694) (xy 142.494775 -247.62428) (xy 142.514723 -247.57746)
			(xy 142.541924 -247.534446) (xy 142.575672 -247.496352) (xy 142.615094 -247.464165) (xy 142.659168 -247.438719)
			(xy 142.706754 -247.420672) (xy 142.756618 -247.410492) (xy 142.80747 -247.408443) (xy 142.857991 -247.414577)
			(xy 142.906875 -247.428737) (xy 142.952854 -247.450554) (xy 142.994738 -247.479464) (xy 143.031442 -247.514719)
			(xy 143.062015 -247.555405) (xy 143.085666 -247.600468) (xy 143.101782 -247.648742) (xy 143.109946 -247.698976)
			(xy 143.110458 -247.724422) (xy 143.428986 -247.724422) (xy 143.432946 -247.675368) (xy 143.444723 -247.627584)
			(xy 143.464014 -247.582308) (xy 143.490317 -247.540712) (xy 143.522952 -247.503875) (xy 143.561073 -247.47275)
			(xy 143.603694 -247.448143) (xy 143.64971 -247.430691) (xy 143.697929 -247.420847) (xy 143.747104 -247.418866)
			(xy 143.795959 -247.424798) (xy 143.84323 -247.43849) (xy 143.887692 -247.459588) (xy 143.928195 -247.487544)
			(xy 143.963688 -247.521636) (xy 143.993253 -247.56098) (xy 144.016124 -247.604557) (xy 144.031708 -247.651238)
			(xy 144.039603 -247.699815) (xy 144.040098 -247.724422) (xy 144.039603 -247.749029) (xy 144.031708 -247.797606)
			(xy 144.016124 -247.844287) (xy 143.993253 -247.887864) (xy 143.963688 -247.927208) (xy 143.928195 -247.9613)
			(xy 143.887692 -247.989256) (xy 143.84323 -248.010354) (xy 143.795959 -248.024046) (xy 143.747104 -248.029978)
			(xy 143.697929 -248.027997) (xy 143.64971 -248.018153) (xy 143.603694 -248.000701) (xy 143.561073 -247.976094)
			(xy 143.522952 -247.944969) (xy 143.490317 -247.908132) (xy 143.464014 -247.866536) (xy 143.444723 -247.82126)
			(xy 143.432946 -247.773476) (xy 143.428986 -247.724422) (xy 143.110458 -247.724422) (xy 143.109946 -247.749868)
			(xy 143.101782 -247.800102) (xy 143.085666 -247.848376) (xy 143.062015 -247.893439) (xy 143.031442 -247.934125)
			(xy 142.994738 -247.96938) (xy 142.952854 -247.99829) (xy 142.906875 -248.020107) (xy 142.857991 -248.034267)
			(xy 142.80747 -248.040401) (xy 142.756618 -248.038352) (xy 142.706754 -248.028172) (xy 142.659168 -248.010125)
			(xy 142.615094 -247.984679) (xy 142.575672 -247.952492) (xy 142.541924 -247.914398) (xy 142.514723 -247.871384)
			(xy 142.494775 -247.824564) (xy 142.482596 -247.77515) (xy 142.478501 -247.724422) (xy 142.15999 -247.724422)
			(xy 142.159495 -247.749029) (xy 142.1516 -247.797606) (xy 142.136016 -247.844287) (xy 142.113145 -247.887864)
			(xy 142.08358 -247.927208) (xy 142.048087 -247.9613) (xy 142.007584 -247.989256) (xy 141.963122 -248.010354)
			(xy 141.915851 -248.024046) (xy 141.866996 -248.029978) (xy 141.817821 -248.027997) (xy 141.769602 -248.018153)
			(xy 141.723586 -248.000701) (xy 141.680965 -247.976094) (xy 141.642844 -247.944969) (xy 141.610209 -247.908132)
			(xy 141.583906 -247.866536) (xy 141.564615 -247.82126) (xy 141.552838 -247.773476) (xy 141.548878 -247.724422)
			(xy 141.230604 -247.724422) (xy 141.230092 -247.749868) (xy 141.221928 -247.800102) (xy 141.205812 -247.848376)
			(xy 141.182161 -247.893439) (xy 141.151588 -247.934125) (xy 141.114884 -247.96938) (xy 141.073 -247.99829)
			(xy 141.027021 -248.020107) (xy 140.978137 -248.034267) (xy 140.927616 -248.040401) (xy 140.876764 -248.038352)
			(xy 140.8269 -248.028172) (xy 140.779314 -248.010125) (xy 140.73524 -247.984679) (xy 140.695818 -247.952492)
			(xy 140.66207 -247.914398) (xy 140.634869 -247.871384) (xy 140.614921 -247.824564) (xy 140.602742 -247.77515)
			(xy 140.598647 -247.724422) (xy 140.280136 -247.724422) (xy 140.279641 -247.749029) (xy 140.271746 -247.797606)
			(xy 140.256162 -247.844287) (xy 140.233291 -247.887864) (xy 140.203726 -247.927208) (xy 140.168233 -247.9613)
			(xy 140.12773 -247.989256) (xy 140.083268 -248.010354) (xy 140.035997 -248.024046) (xy 139.987142 -248.029978)
			(xy 139.937967 -248.027997) (xy 139.889748 -248.018153) (xy 139.843732 -248.000701) (xy 139.801111 -247.976094)
			(xy 139.76299 -247.944969) (xy 139.730355 -247.908132) (xy 139.704052 -247.866536) (xy 139.684761 -247.82126)
			(xy 139.672984 -247.773476) (xy 139.669024 -247.724422) (xy 139.350496 -247.724422) (xy 139.349984 -247.749868)
			(xy 139.34182 -247.800102) (xy 139.325704 -247.848376) (xy 139.302053 -247.893439) (xy 139.27148 -247.934125)
			(xy 139.234776 -247.96938) (xy 139.192892 -247.99829) (xy 139.146913 -248.020107) (xy 139.098029 -248.034267)
			(xy 139.047508 -248.040401) (xy 138.996656 -248.038352) (xy 138.946792 -248.028172) (xy 138.899206 -248.010125)
			(xy 138.855132 -247.984679) (xy 138.81571 -247.952492) (xy 138.781962 -247.914398) (xy 138.754761 -247.871384)
			(xy 138.734813 -247.824564) (xy 138.722634 -247.77515) (xy 138.718539 -247.724422) (xy 138.410442 -247.724422)
			(xy 138.40993 -247.749868) (xy 138.401766 -247.800102) (xy 138.38565 -247.848376) (xy 138.361999 -247.893439)
			(xy 138.331426 -247.934125) (xy 138.294722 -247.96938) (xy 138.252838 -247.99829) (xy 138.206859 -248.020107)
			(xy 138.157975 -248.034267) (xy 138.107454 -248.040401) (xy 138.056602 -248.038352) (xy 138.006738 -248.028172)
			(xy 137.959152 -248.010125) (xy 137.915078 -247.984679) (xy 137.875656 -247.952492) (xy 137.841908 -247.914398)
			(xy 137.814707 -247.871384) (xy 137.794759 -247.824564) (xy 137.78258 -247.77515) (xy 137.778485 -247.724422)
			(xy 137.459974 -247.724422) (xy 137.459479 -247.749029) (xy 137.451584 -247.797606) (xy 137.436 -247.844287)
			(xy 137.413129 -247.887864) (xy 137.383564 -247.927208) (xy 137.348071 -247.9613) (xy 137.307568 -247.989256)
			(xy 137.263106 -248.010354) (xy 137.215835 -248.024046) (xy 137.16698 -248.029978) (xy 137.117805 -248.027997)
			(xy 137.069586 -248.018153) (xy 137.02357 -248.000701) (xy 136.980949 -247.976094) (xy 136.942828 -247.944969)
			(xy 136.910193 -247.908132) (xy 136.88389 -247.866536) (xy 136.864599 -247.82126) (xy 136.852822 -247.773476)
			(xy 136.848862 -247.724422) (xy 136.530588 -247.724422) (xy 136.530076 -247.749868) (xy 136.521912 -247.800102)
			(xy 136.505796 -247.848376) (xy 136.482145 -247.893439) (xy 136.451572 -247.934125) (xy 136.414868 -247.96938)
			(xy 136.372984 -247.99829) (xy 136.327005 -248.020107) (xy 136.278121 -248.034267) (xy 136.2276 -248.040401)
			(xy 136.176748 -248.038352) (xy 136.126884 -248.028172) (xy 136.079298 -248.010125) (xy 136.035224 -247.984679)
			(xy 135.995802 -247.952492) (xy 135.962054 -247.914398) (xy 135.934853 -247.871384) (xy 135.914905 -247.824564)
			(xy 135.902726 -247.77515) (xy 135.898631 -247.724422) (xy 135.58012 -247.724422) (xy 135.579625 -247.749029)
			(xy 135.57173 -247.797606) (xy 135.556146 -247.844287) (xy 135.533275 -247.887864) (xy 135.50371 -247.927208)
			(xy 135.468217 -247.9613) (xy 135.427714 -247.989256) (xy 135.383252 -248.010354) (xy 135.335981 -248.024046)
			(xy 135.287126 -248.029978) (xy 135.237951 -248.027997) (xy 135.189732 -248.018153) (xy 135.143716 -248.000701)
			(xy 135.101095 -247.976094) (xy 135.062974 -247.944969) (xy 135.030339 -247.908132) (xy 135.004036 -247.866536)
			(xy 134.984745 -247.82126) (xy 134.972968 -247.773476) (xy 134.969008 -247.724422) (xy 134.65048 -247.724422)
			(xy 134.649968 -247.749868) (xy 134.641804 -247.800102) (xy 134.625688 -247.848376) (xy 134.602037 -247.893439)
			(xy 134.571464 -247.934125) (xy 134.53476 -247.96938) (xy 134.492876 -247.99829) (xy 134.446897 -248.020107)
			(xy 134.398013 -248.034267) (xy 134.347492 -248.040401) (xy 134.29664 -248.038352) (xy 134.246776 -248.028172)
			(xy 134.19919 -248.010125) (xy 134.155116 -247.984679) (xy 134.115694 -247.952492) (xy 134.081946 -247.914398)
			(xy 134.054745 -247.871384) (xy 134.034797 -247.824564) (xy 134.022618 -247.77515) (xy 134.018523 -247.724422)
			(xy 133.700012 -247.724422) (xy 133.699517 -247.749029) (xy 133.691622 -247.797606) (xy 133.676038 -247.844287)
			(xy 133.653167 -247.887864) (xy 133.623602 -247.927208) (xy 133.588109 -247.9613) (xy 133.547606 -247.989256)
			(xy 133.503144 -248.010354) (xy 133.455873 -248.024046) (xy 133.407018 -248.029978) (xy 133.357843 -248.027997)
			(xy 133.309624 -248.018153) (xy 133.263608 -248.000701) (xy 133.220987 -247.976094) (xy 133.182866 -247.944969)
			(xy 133.150231 -247.908132) (xy 133.123928 -247.866536) (xy 133.104637 -247.82126) (xy 133.09286 -247.773476)
			(xy 133.0889 -247.724422) (xy 132.770372 -247.724422) (xy 132.76986 -247.749868) (xy 132.761696 -247.800102)
			(xy 132.74558 -247.848376) (xy 132.721929 -247.893439) (xy 132.691356 -247.934125) (xy 132.654652 -247.96938)
			(xy 132.612768 -247.99829) (xy 132.566789 -248.020107) (xy 132.517905 -248.034267) (xy 132.467384 -248.040401)
			(xy 132.416532 -248.038352) (xy 132.366668 -248.028172) (xy 132.319082 -248.010125) (xy 132.275008 -247.984679)
			(xy 132.235586 -247.952492) (xy 132.201838 -247.914398) (xy 132.174637 -247.871384) (xy 132.154689 -247.824564)
			(xy 132.14251 -247.77515) (xy 132.138415 -247.724422) (xy 131.830572 -247.724422) (xy 131.83006 -247.749868)
			(xy 131.821896 -247.800102) (xy 131.80578 -247.848376) (xy 131.782129 -247.893439) (xy 131.751556 -247.934125)
			(xy 131.714852 -247.96938) (xy 131.672968 -247.99829) (xy 131.626989 -248.020107) (xy 131.578105 -248.034267)
			(xy 131.527584 -248.040401) (xy 131.476732 -248.038352) (xy 131.426868 -248.028172) (xy 131.379282 -248.010125)
			(xy 131.335208 -247.984679) (xy 131.295786 -247.952492) (xy 131.262038 -247.914398) (xy 131.234837 -247.871384)
			(xy 131.214889 -247.824564) (xy 131.20271 -247.77515) (xy 131.198615 -247.724422) (xy 130.880104 -247.724422)
			(xy 130.879609 -247.749029) (xy 130.871714 -247.797606) (xy 130.85613 -247.844287) (xy 130.833259 -247.887864)
			(xy 130.803694 -247.927208) (xy 130.768201 -247.9613) (xy 130.727698 -247.989256) (xy 130.683236 -248.010354)
			(xy 130.635965 -248.024046) (xy 130.58711 -248.029978) (xy 130.537935 -248.027997) (xy 130.489716 -248.018153)
			(xy 130.4437 -248.000701) (xy 130.401079 -247.976094) (xy 130.362958 -247.944969) (xy 130.330323 -247.908132)
			(xy 130.30402 -247.866536) (xy 130.284729 -247.82126) (xy 130.272952 -247.773476) (xy 130.268992 -247.724422)
			(xy 129.950464 -247.724422) (xy 129.949952 -247.749868) (xy 129.941788 -247.800102) (xy 129.925672 -247.848376)
			(xy 129.902021 -247.893439) (xy 129.871448 -247.934125) (xy 129.834744 -247.96938) (xy 129.79286 -247.99829)
			(xy 129.746881 -248.020107) (xy 129.697997 -248.034267) (xy 129.647476 -248.040401) (xy 129.596624 -248.038352)
			(xy 129.54676 -248.028172) (xy 129.499174 -248.010125) (xy 129.4551 -247.984679) (xy 129.415678 -247.952492)
			(xy 129.38193 -247.914398) (xy 129.354729 -247.871384) (xy 129.334781 -247.824564) (xy 129.322602 -247.77515)
			(xy 129.318507 -247.724422) (xy 128.999996 -247.724422) (xy 128.999501 -247.749029) (xy 128.991606 -247.797606)
			(xy 128.976022 -247.844287) (xy 128.953151 -247.887864) (xy 128.923586 -247.927208) (xy 128.888093 -247.9613)
			(xy 128.84759 -247.989256) (xy 128.803128 -248.010354) (xy 128.755857 -248.024046) (xy 128.707002 -248.029978)
			(xy 128.657827 -248.027997) (xy 128.609608 -248.018153) (xy 128.563592 -248.000701) (xy 128.520971 -247.976094)
			(xy 128.48285 -247.944969) (xy 128.450215 -247.908132) (xy 128.423912 -247.866536) (xy 128.404621 -247.82126)
			(xy 128.392844 -247.773476) (xy 128.388884 -247.724422) (xy 128.070356 -247.724422) (xy 128.069844 -247.749868)
			(xy 128.06168 -247.800102) (xy 128.045564 -247.848376) (xy 128.021913 -247.893439) (xy 127.99134 -247.934125)
			(xy 127.954636 -247.96938) (xy 127.912752 -247.99829) (xy 127.866773 -248.020107) (xy 127.817889 -248.034267)
			(xy 127.767368 -248.040401) (xy 127.716516 -248.038352) (xy 127.666652 -248.028172) (xy 127.619066 -248.010125)
			(xy 127.574992 -247.984679) (xy 127.53557 -247.952492) (xy 127.501822 -247.914398) (xy 127.474621 -247.871384)
			(xy 127.454673 -247.824564) (xy 127.442494 -247.77515) (xy 127.438399 -247.724422) (xy 127.120142 -247.724422)
			(xy 127.119642 -247.749193) (xy 127.111605 -247.79808) (xy 127.10414 -247.821704) (xy 127.1016 -247.829578)
			(xy 127.1016 -248.135648) (xy 127.102175 -248.146892) (xy 127.111791 -248.167215) (xy 127.120142 -248.174764)
			(xy 127.190246 -248.232168) (xy 127.21209 -248.237502) (xy 127.22352 -248.235216) (xy 127.238659 -248.232342)
			(xy 127.269325 -248.229291) (xy 127.284734 -248.22912) (xy 127.309985 -248.229644) (xy 127.359798 -248.237962)
			(xy 127.407563 -248.254364) (xy 127.451976 -248.278404) (xy 127.491828 -248.309426) (xy 127.52603 -248.346583)
			(xy 127.553651 -248.388863) (xy 127.573936 -248.435113) (xy 127.586333 -248.48407) (xy 127.590503 -248.5344)
			(xy 127.590501 -248.534428) (xy 127.908553 -248.534428) (xy 127.912648 -248.4837) (xy 127.924827 -248.434286)
			(xy 127.944775 -248.387466) (xy 127.971976 -248.344452) (xy 128.005724 -248.306358) (xy 128.045146 -248.274171)
			(xy 128.08922 -248.248725) (xy 128.136806 -248.230678) (xy 128.18667 -248.220498) (xy 128.237522 -248.218449)
			(xy 128.288043 -248.224583) (xy 128.336927 -248.238743) (xy 128.382906 -248.26056) (xy 128.42479 -248.28947)
			(xy 128.461494 -248.324725) (xy 128.492067 -248.365411) (xy 128.515718 -248.410474) (xy 128.531834 -248.458748)
			(xy 128.539998 -248.508982) (xy 128.54051 -248.534428) (xy 128.848607 -248.534428) (xy 128.852702 -248.4837)
			(xy 128.864881 -248.434286) (xy 128.884829 -248.387466) (xy 128.91203 -248.344452) (xy 128.945778 -248.306358)
			(xy 128.9852 -248.274171) (xy 129.029274 -248.248725) (xy 129.07686 -248.230678) (xy 129.126724 -248.220498)
			(xy 129.177576 -248.218449) (xy 129.228097 -248.224583) (xy 129.276981 -248.238743) (xy 129.32296 -248.26056)
			(xy 129.364844 -248.28947) (xy 129.401548 -248.324725) (xy 129.432121 -248.365411) (xy 129.455772 -248.410474)
			(xy 129.471888 -248.458748) (xy 129.480052 -248.508982) (xy 129.480564 -248.534428) (xy 129.798838 -248.534428)
			(xy 129.802798 -248.485374) (xy 129.814575 -248.43759) (xy 129.833866 -248.392314) (xy 129.860169 -248.350718)
			(xy 129.892804 -248.313881) (xy 129.930925 -248.282756) (xy 129.973546 -248.258149) (xy 130.019562 -248.240697)
			(xy 130.067781 -248.230853) (xy 130.116956 -248.228872) (xy 130.165811 -248.234804) (xy 130.213082 -248.248496)
			(xy 130.257544 -248.269594) (xy 130.298047 -248.29755) (xy 130.33354 -248.331642) (xy 130.363105 -248.370986)
			(xy 130.385976 -248.414563) (xy 130.40156 -248.461244) (xy 130.409455 -248.509821) (xy 130.40995 -248.534428)
			(xy 130.728461 -248.534428) (xy 130.732556 -248.4837) (xy 130.744735 -248.434286) (xy 130.764683 -248.387466)
			(xy 130.791884 -248.344452) (xy 130.825632 -248.306358) (xy 130.865054 -248.274171) (xy 130.909128 -248.248725)
			(xy 130.956714 -248.230678) (xy 131.006578 -248.220498) (xy 131.05743 -248.218449) (xy 131.107951 -248.224583)
			(xy 131.156835 -248.238743) (xy 131.202814 -248.26056) (xy 131.244698 -248.28947) (xy 131.281402 -248.324725)
			(xy 131.311975 -248.365411) (xy 131.335626 -248.410474) (xy 131.351742 -248.458748) (xy 131.359906 -248.508982)
			(xy 131.360418 -248.534428) (xy 131.678946 -248.534428) (xy 131.682906 -248.485374) (xy 131.694683 -248.43759)
			(xy 131.713974 -248.392314) (xy 131.740277 -248.350718) (xy 131.772912 -248.313881) (xy 131.811033 -248.282756)
			(xy 131.853654 -248.258149) (xy 131.89967 -248.240697) (xy 131.947889 -248.230853) (xy 131.997064 -248.228872)
			(xy 132.045919 -248.234804) (xy 132.09319 -248.248496) (xy 132.137652 -248.269594) (xy 132.178155 -248.29755)
			(xy 132.213648 -248.331642) (xy 132.243213 -248.370986) (xy 132.266084 -248.414563) (xy 132.281668 -248.461244)
			(xy 132.289563 -248.509821) (xy 132.290058 -248.534428) (xy 132.608569 -248.534428) (xy 132.612664 -248.4837)
			(xy 132.624843 -248.434286) (xy 132.644791 -248.387466) (xy 132.671992 -248.344452) (xy 132.70574 -248.306358)
			(xy 132.745162 -248.274171) (xy 132.789236 -248.248725) (xy 132.836822 -248.230678) (xy 132.886686 -248.220498)
			(xy 132.937538 -248.218449) (xy 132.988059 -248.224583) (xy 133.036943 -248.238743) (xy 133.082922 -248.26056)
			(xy 133.124806 -248.28947) (xy 133.16151 -248.324725) (xy 133.192083 -248.365411) (xy 133.215734 -248.410474)
			(xy 133.23185 -248.458748) (xy 133.240014 -248.508982) (xy 133.240526 -248.534428) (xy 133.559054 -248.534428)
			(xy 133.563014 -248.485374) (xy 133.574791 -248.43759) (xy 133.594082 -248.392314) (xy 133.620385 -248.350718)
			(xy 133.65302 -248.313881) (xy 133.691141 -248.282756) (xy 133.733762 -248.258149) (xy 133.779778 -248.240697)
			(xy 133.827997 -248.230853) (xy 133.877172 -248.228872) (xy 133.926027 -248.234804) (xy 133.973298 -248.248496)
			(xy 134.01776 -248.269594) (xy 134.058263 -248.29755) (xy 134.093756 -248.331642) (xy 134.123321 -248.370986)
			(xy 134.146192 -248.414563) (xy 134.161776 -248.461244) (xy 134.169671 -248.509821) (xy 134.170166 -248.534428)
			(xy 134.488423 -248.534428) (xy 134.492518 -248.4837) (xy 134.504697 -248.434286) (xy 134.524645 -248.387466)
			(xy 134.551846 -248.344452) (xy 134.585594 -248.306358) (xy 134.625016 -248.274171) (xy 134.66909 -248.248725)
			(xy 134.716676 -248.230678) (xy 134.76654 -248.220498) (xy 134.817392 -248.218449) (xy 134.867913 -248.224583)
			(xy 134.916797 -248.238743) (xy 134.962776 -248.26056) (xy 135.00466 -248.28947) (xy 135.041364 -248.324725)
			(xy 135.071937 -248.365411) (xy 135.095588 -248.410474) (xy 135.111704 -248.458748) (xy 135.119868 -248.508982)
			(xy 135.12038 -248.534428) (xy 135.428477 -248.534428) (xy 135.432572 -248.4837) (xy 135.444751 -248.434286)
			(xy 135.464699 -248.387466) (xy 135.4919 -248.344452) (xy 135.525648 -248.306358) (xy 135.56507 -248.274171)
			(xy 135.609144 -248.248725) (xy 135.65673 -248.230678) (xy 135.706594 -248.220498) (xy 135.757446 -248.218449)
			(xy 135.807967 -248.224583) (xy 135.856851 -248.238743) (xy 135.90283 -248.26056) (xy 135.944714 -248.28947)
			(xy 135.981418 -248.324725) (xy 136.011991 -248.365411) (xy 136.035642 -248.410474) (xy 136.051758 -248.458748)
			(xy 136.059922 -248.508982) (xy 136.060434 -248.534428) (xy 136.378962 -248.534428) (xy 136.382922 -248.485374)
			(xy 136.394699 -248.43759) (xy 136.41399 -248.392314) (xy 136.440293 -248.350718) (xy 136.472928 -248.313881)
			(xy 136.511049 -248.282756) (xy 136.55367 -248.258149) (xy 136.599686 -248.240697) (xy 136.647905 -248.230853)
			(xy 136.69708 -248.228872) (xy 136.745935 -248.234804) (xy 136.793206 -248.248496) (xy 136.837668 -248.269594)
			(xy 136.878171 -248.29755) (xy 136.913664 -248.331642) (xy 136.943229 -248.370986) (xy 136.9661 -248.414563)
			(xy 136.981684 -248.461244) (xy 136.989579 -248.509821) (xy 136.990074 -248.534428) (xy 137.308585 -248.534428)
			(xy 137.31268 -248.4837) (xy 137.324859 -248.434286) (xy 137.344807 -248.387466) (xy 137.372008 -248.344452)
			(xy 137.405756 -248.306358) (xy 137.445178 -248.274171) (xy 137.489252 -248.248725) (xy 137.536838 -248.230678)
			(xy 137.586702 -248.220498) (xy 137.637554 -248.218449) (xy 137.688075 -248.224583) (xy 137.736959 -248.238743)
			(xy 137.782938 -248.26056) (xy 137.824822 -248.28947) (xy 137.861526 -248.324725) (xy 137.892099 -248.365411)
			(xy 137.91575 -248.410474) (xy 137.931866 -248.458748) (xy 137.94003 -248.508982) (xy 137.940542 -248.534428)
			(xy 138.25907 -248.534428) (xy 138.26303 -248.485374) (xy 138.274807 -248.43759) (xy 138.294098 -248.392314)
			(xy 138.320401 -248.350718) (xy 138.353036 -248.313881) (xy 138.391157 -248.282756) (xy 138.433778 -248.258149)
			(xy 138.479794 -248.240697) (xy 138.528013 -248.230853) (xy 138.577188 -248.228872) (xy 138.626043 -248.234804)
			(xy 138.673314 -248.248496) (xy 138.717776 -248.269594) (xy 138.758279 -248.29755) (xy 138.793772 -248.331642)
			(xy 138.823337 -248.370986) (xy 138.846208 -248.414563) (xy 138.861792 -248.461244) (xy 138.869687 -248.509821)
			(xy 138.870182 -248.534428) (xy 139.188439 -248.534428) (xy 139.192534 -248.4837) (xy 139.204713 -248.434286)
			(xy 139.224661 -248.387466) (xy 139.251862 -248.344452) (xy 139.28561 -248.306358) (xy 139.325032 -248.274171)
			(xy 139.369106 -248.248725) (xy 139.416692 -248.230678) (xy 139.466556 -248.220498) (xy 139.517408 -248.218449)
			(xy 139.567929 -248.224583) (xy 139.616813 -248.238743) (xy 139.662792 -248.26056) (xy 139.704676 -248.28947)
			(xy 139.74138 -248.324725) (xy 139.771953 -248.365411) (xy 139.795604 -248.410474) (xy 139.81172 -248.458748)
			(xy 139.819884 -248.508982) (xy 139.820396 -248.534428) (xy 140.138924 -248.534428) (xy 140.142884 -248.485374)
			(xy 140.154661 -248.43759) (xy 140.173952 -248.392314) (xy 140.200255 -248.350718) (xy 140.23289 -248.313881)
			(xy 140.271011 -248.282756) (xy 140.313632 -248.258149) (xy 140.359648 -248.240697) (xy 140.407867 -248.230853)
			(xy 140.457042 -248.228872) (xy 140.505897 -248.234804) (xy 140.553168 -248.248496) (xy 140.59763 -248.269594)
			(xy 140.638133 -248.29755) (xy 140.673626 -248.331642) (xy 140.703191 -248.370986) (xy 140.726062 -248.414563)
			(xy 140.741646 -248.461244) (xy 140.749541 -248.509821) (xy 140.750036 -248.534428) (xy 141.068547 -248.534428)
			(xy 141.072642 -248.4837) (xy 141.084821 -248.434286) (xy 141.104769 -248.387466) (xy 141.13197 -248.344452)
			(xy 141.165718 -248.306358) (xy 141.20514 -248.274171) (xy 141.249214 -248.248725) (xy 141.2968 -248.230678)
			(xy 141.346664 -248.220498) (xy 141.397516 -248.218449) (xy 141.448037 -248.224583) (xy 141.496921 -248.238743)
			(xy 141.5429 -248.26056) (xy 141.584784 -248.28947) (xy 141.621488 -248.324725) (xy 141.652061 -248.365411)
			(xy 141.675712 -248.410474) (xy 141.691828 -248.458748) (xy 141.699992 -248.508982) (xy 141.700504 -248.534428)
			(xy 142.008601 -248.534428) (xy 142.012696 -248.4837) (xy 142.024875 -248.434286) (xy 142.044823 -248.387466)
			(xy 142.072024 -248.344452) (xy 142.105772 -248.306358) (xy 142.145194 -248.274171) (xy 142.189268 -248.248725)
			(xy 142.236854 -248.230678) (xy 142.286718 -248.220498) (xy 142.33757 -248.218449) (xy 142.388091 -248.224583)
			(xy 142.436975 -248.238743) (xy 142.482954 -248.26056) (xy 142.524838 -248.28947) (xy 142.561542 -248.324725)
			(xy 142.592115 -248.365411) (xy 142.615766 -248.410474) (xy 142.631882 -248.458748) (xy 142.640046 -248.508982)
			(xy 142.640558 -248.534428) (xy 142.958832 -248.534428) (xy 142.962792 -248.485374) (xy 142.974569 -248.43759)
			(xy 142.99386 -248.392314) (xy 143.020163 -248.350718) (xy 143.052798 -248.313881) (xy 143.090919 -248.282756)
			(xy 143.13354 -248.258149) (xy 143.179556 -248.240697) (xy 143.227775 -248.230853) (xy 143.27695 -248.228872)
			(xy 143.325805 -248.234804) (xy 143.373076 -248.248496) (xy 143.417538 -248.269594) (xy 143.458041 -248.29755)
			(xy 143.493534 -248.331642) (xy 143.523099 -248.370986) (xy 143.54597 -248.414563) (xy 143.561554 -248.461244)
			(xy 143.569449 -248.509821) (xy 143.569944 -248.534428) (xy 144.83894 -248.534428) (xy 144.8429 -248.485374)
			(xy 144.854677 -248.43759) (xy 144.873968 -248.392314) (xy 144.900271 -248.350718) (xy 144.932906 -248.313881)
			(xy 144.971027 -248.282756) (xy 145.013648 -248.258149) (xy 145.059664 -248.240697) (xy 145.107883 -248.230853)
			(xy 145.157058 -248.228872) (xy 145.205913 -248.234804) (xy 145.253184 -248.248496) (xy 145.297646 -248.269594)
			(xy 145.338149 -248.29755) (xy 145.373642 -248.331642) (xy 145.403207 -248.370986) (xy 145.426078 -248.414563)
			(xy 145.441662 -248.461244) (xy 145.449557 -248.509821) (xy 145.450052 -248.534428) (xy 145.449557 -248.559035)
			(xy 145.441662 -248.607612) (xy 145.426078 -248.654293) (xy 145.403207 -248.69787) (xy 145.373642 -248.737214)
			(xy 145.338149 -248.771306) (xy 145.297646 -248.799262) (xy 145.253184 -248.82036) (xy 145.205913 -248.834052)
			(xy 145.157058 -248.839984) (xy 145.107883 -248.838003) (xy 145.059664 -248.828159) (xy 145.013648 -248.810707)
			(xy 144.971027 -248.7861) (xy 144.932906 -248.754975) (xy 144.900271 -248.718138) (xy 144.873968 -248.676542)
			(xy 144.854677 -248.631266) (xy 144.8429 -248.583482) (xy 144.83894 -248.534428) (xy 143.569944 -248.534428)
			(xy 143.569449 -248.559035) (xy 143.561554 -248.607612) (xy 143.54597 -248.654293) (xy 143.523099 -248.69787)
			(xy 143.493534 -248.737214) (xy 143.458041 -248.771306) (xy 143.417538 -248.799262) (xy 143.373076 -248.82036)
			(xy 143.325805 -248.834052) (xy 143.27695 -248.839984) (xy 143.227775 -248.838003) (xy 143.179556 -248.828159)
			(xy 143.13354 -248.810707) (xy 143.090919 -248.7861) (xy 143.052798 -248.754975) (xy 143.020163 -248.718138)
			(xy 142.99386 -248.676542) (xy 142.974569 -248.631266) (xy 142.962792 -248.583482) (xy 142.958832 -248.534428)
			(xy 142.640558 -248.534428) (xy 142.640046 -248.559874) (xy 142.631882 -248.610108) (xy 142.615766 -248.658382)
			(xy 142.592115 -248.703445) (xy 142.561542 -248.744131) (xy 142.524838 -248.779386) (xy 142.482954 -248.808296)
			(xy 142.436975 -248.830113) (xy 142.388091 -248.844273) (xy 142.33757 -248.850407) (xy 142.286718 -248.848358)
			(xy 142.236854 -248.838178) (xy 142.189268 -248.820131) (xy 142.145194 -248.794685) (xy 142.105772 -248.762498)
			(xy 142.072024 -248.724404) (xy 142.044823 -248.68139) (xy 142.024875 -248.63457) (xy 142.012696 -248.585156)
			(xy 142.008601 -248.534428) (xy 141.700504 -248.534428) (xy 141.699992 -248.559874) (xy 141.691828 -248.610108)
			(xy 141.675712 -248.658382) (xy 141.652061 -248.703445) (xy 141.621488 -248.744131) (xy 141.584784 -248.779386)
			(xy 141.5429 -248.808296) (xy 141.496921 -248.830113) (xy 141.448037 -248.844273) (xy 141.397516 -248.850407)
			(xy 141.346664 -248.848358) (xy 141.2968 -248.838178) (xy 141.249214 -248.820131) (xy 141.20514 -248.794685)
			(xy 141.165718 -248.762498) (xy 141.13197 -248.724404) (xy 141.104769 -248.68139) (xy 141.084821 -248.63457)
			(xy 141.072642 -248.585156) (xy 141.068547 -248.534428) (xy 140.750036 -248.534428) (xy 140.749541 -248.559035)
			(xy 140.741646 -248.607612) (xy 140.726062 -248.654293) (xy 140.703191 -248.69787) (xy 140.673626 -248.737214)
			(xy 140.638133 -248.771306) (xy 140.59763 -248.799262) (xy 140.553168 -248.82036) (xy 140.505897 -248.834052)
			(xy 140.457042 -248.839984) (xy 140.407867 -248.838003) (xy 140.359648 -248.828159) (xy 140.313632 -248.810707)
			(xy 140.271011 -248.7861) (xy 140.23289 -248.754975) (xy 140.200255 -248.718138) (xy 140.173952 -248.676542)
			(xy 140.154661 -248.631266) (xy 140.142884 -248.583482) (xy 140.138924 -248.534428) (xy 139.820396 -248.534428)
			(xy 139.819884 -248.559874) (xy 139.81172 -248.610108) (xy 139.795604 -248.658382) (xy 139.771953 -248.703445)
			(xy 139.74138 -248.744131) (xy 139.704676 -248.779386) (xy 139.662792 -248.808296) (xy 139.616813 -248.830113)
			(xy 139.567929 -248.844273) (xy 139.517408 -248.850407) (xy 139.466556 -248.848358) (xy 139.416692 -248.838178)
			(xy 139.369106 -248.820131) (xy 139.325032 -248.794685) (xy 139.28561 -248.762498) (xy 139.251862 -248.724404)
			(xy 139.224661 -248.68139) (xy 139.204713 -248.63457) (xy 139.192534 -248.585156) (xy 139.188439 -248.534428)
			(xy 138.870182 -248.534428) (xy 138.869687 -248.559035) (xy 138.861792 -248.607612) (xy 138.846208 -248.654293)
			(xy 138.823337 -248.69787) (xy 138.793772 -248.737214) (xy 138.758279 -248.771306) (xy 138.717776 -248.799262)
			(xy 138.673314 -248.82036) (xy 138.626043 -248.834052) (xy 138.577188 -248.839984) (xy 138.528013 -248.838003)
			(xy 138.479794 -248.828159) (xy 138.433778 -248.810707) (xy 138.391157 -248.7861) (xy 138.353036 -248.754975)
			(xy 138.320401 -248.718138) (xy 138.294098 -248.676542) (xy 138.274807 -248.631266) (xy 138.26303 -248.583482)
			(xy 138.25907 -248.534428) (xy 137.940542 -248.534428) (xy 137.94003 -248.559874) (xy 137.931866 -248.610108)
			(xy 137.91575 -248.658382) (xy 137.892099 -248.703445) (xy 137.861526 -248.744131) (xy 137.824822 -248.779386)
			(xy 137.782938 -248.808296) (xy 137.736959 -248.830113) (xy 137.688075 -248.844273) (xy 137.637554 -248.850407)
			(xy 137.586702 -248.848358) (xy 137.536838 -248.838178) (xy 137.489252 -248.820131) (xy 137.445178 -248.794685)
			(xy 137.405756 -248.762498) (xy 137.372008 -248.724404) (xy 137.344807 -248.68139) (xy 137.324859 -248.63457)
			(xy 137.31268 -248.585156) (xy 137.308585 -248.534428) (xy 136.990074 -248.534428) (xy 136.989579 -248.559035)
			(xy 136.981684 -248.607612) (xy 136.9661 -248.654293) (xy 136.943229 -248.69787) (xy 136.913664 -248.737214)
			(xy 136.878171 -248.771306) (xy 136.837668 -248.799262) (xy 136.793206 -248.82036) (xy 136.745935 -248.834052)
			(xy 136.69708 -248.839984) (xy 136.647905 -248.838003) (xy 136.599686 -248.828159) (xy 136.55367 -248.810707)
			(xy 136.511049 -248.7861) (xy 136.472928 -248.754975) (xy 136.440293 -248.718138) (xy 136.41399 -248.676542)
			(xy 136.394699 -248.631266) (xy 136.382922 -248.583482) (xy 136.378962 -248.534428) (xy 136.060434 -248.534428)
			(xy 136.059922 -248.559874) (xy 136.051758 -248.610108) (xy 136.035642 -248.658382) (xy 136.011991 -248.703445)
			(xy 135.981418 -248.744131) (xy 135.944714 -248.779386) (xy 135.90283 -248.808296) (xy 135.856851 -248.830113)
			(xy 135.807967 -248.844273) (xy 135.757446 -248.850407) (xy 135.706594 -248.848358) (xy 135.65673 -248.838178)
			(xy 135.609144 -248.820131) (xy 135.56507 -248.794685) (xy 135.525648 -248.762498) (xy 135.4919 -248.724404)
			(xy 135.464699 -248.68139) (xy 135.444751 -248.63457) (xy 135.432572 -248.585156) (xy 135.428477 -248.534428)
			(xy 135.12038 -248.534428) (xy 135.119868 -248.559874) (xy 135.111704 -248.610108) (xy 135.095588 -248.658382)
			(xy 135.071937 -248.703445) (xy 135.041364 -248.744131) (xy 135.00466 -248.779386) (xy 134.962776 -248.808296)
			(xy 134.916797 -248.830113) (xy 134.867913 -248.844273) (xy 134.817392 -248.850407) (xy 134.76654 -248.848358)
			(xy 134.716676 -248.838178) (xy 134.66909 -248.820131) (xy 134.625016 -248.794685) (xy 134.585594 -248.762498)
			(xy 134.551846 -248.724404) (xy 134.524645 -248.68139) (xy 134.504697 -248.63457) (xy 134.492518 -248.585156)
			(xy 134.488423 -248.534428) (xy 134.170166 -248.534428) (xy 134.169671 -248.559035) (xy 134.161776 -248.607612)
			(xy 134.146192 -248.654293) (xy 134.123321 -248.69787) (xy 134.093756 -248.737214) (xy 134.058263 -248.771306)
			(xy 134.01776 -248.799262) (xy 133.973298 -248.82036) (xy 133.926027 -248.834052) (xy 133.877172 -248.839984)
			(xy 133.827997 -248.838003) (xy 133.779778 -248.828159) (xy 133.733762 -248.810707) (xy 133.691141 -248.7861)
			(xy 133.65302 -248.754975) (xy 133.620385 -248.718138) (xy 133.594082 -248.676542) (xy 133.574791 -248.631266)
			(xy 133.563014 -248.583482) (xy 133.559054 -248.534428) (xy 133.240526 -248.534428) (xy 133.240014 -248.559874)
			(xy 133.23185 -248.610108) (xy 133.215734 -248.658382) (xy 133.192083 -248.703445) (xy 133.16151 -248.744131)
			(xy 133.124806 -248.779386) (xy 133.082922 -248.808296) (xy 133.036943 -248.830113) (xy 132.988059 -248.844273)
			(xy 132.937538 -248.850407) (xy 132.886686 -248.848358) (xy 132.836822 -248.838178) (xy 132.789236 -248.820131)
			(xy 132.745162 -248.794685) (xy 132.70574 -248.762498) (xy 132.671992 -248.724404) (xy 132.644791 -248.68139)
			(xy 132.624843 -248.63457) (xy 132.612664 -248.585156) (xy 132.608569 -248.534428) (xy 132.290058 -248.534428)
			(xy 132.289563 -248.559035) (xy 132.281668 -248.607612) (xy 132.266084 -248.654293) (xy 132.243213 -248.69787)
			(xy 132.213648 -248.737214) (xy 132.178155 -248.771306) (xy 132.137652 -248.799262) (xy 132.09319 -248.82036)
			(xy 132.045919 -248.834052) (xy 131.997064 -248.839984) (xy 131.947889 -248.838003) (xy 131.89967 -248.828159)
			(xy 131.853654 -248.810707) (xy 131.811033 -248.7861) (xy 131.772912 -248.754975) (xy 131.740277 -248.718138)
			(xy 131.713974 -248.676542) (xy 131.694683 -248.631266) (xy 131.682906 -248.583482) (xy 131.678946 -248.534428)
			(xy 131.360418 -248.534428) (xy 131.359906 -248.559874) (xy 131.351742 -248.610108) (xy 131.335626 -248.658382)
			(xy 131.311975 -248.703445) (xy 131.281402 -248.744131) (xy 131.244698 -248.779386) (xy 131.202814 -248.808296)
			(xy 131.156835 -248.830113) (xy 131.107951 -248.844273) (xy 131.05743 -248.850407) (xy 131.006578 -248.848358)
			(xy 130.956714 -248.838178) (xy 130.909128 -248.820131) (xy 130.865054 -248.794685) (xy 130.825632 -248.762498)
			(xy 130.791884 -248.724404) (xy 130.764683 -248.68139) (xy 130.744735 -248.63457) (xy 130.732556 -248.585156)
			(xy 130.728461 -248.534428) (xy 130.40995 -248.534428) (xy 130.409455 -248.559035) (xy 130.40156 -248.607612)
			(xy 130.385976 -248.654293) (xy 130.363105 -248.69787) (xy 130.33354 -248.737214) (xy 130.298047 -248.771306)
			(xy 130.257544 -248.799262) (xy 130.213082 -248.82036) (xy 130.165811 -248.834052) (xy 130.116956 -248.839984)
			(xy 130.067781 -248.838003) (xy 130.019562 -248.828159) (xy 129.973546 -248.810707) (xy 129.930925 -248.7861)
			(xy 129.892804 -248.754975) (xy 129.860169 -248.718138) (xy 129.833866 -248.676542) (xy 129.814575 -248.631266)
			(xy 129.802798 -248.583482) (xy 129.798838 -248.534428) (xy 129.480564 -248.534428) (xy 129.480052 -248.559874)
			(xy 129.471888 -248.610108) (xy 129.455772 -248.658382) (xy 129.432121 -248.703445) (xy 129.401548 -248.744131)
			(xy 129.364844 -248.779386) (xy 129.32296 -248.808296) (xy 129.276981 -248.830113) (xy 129.228097 -248.844273)
			(xy 129.177576 -248.850407) (xy 129.126724 -248.848358) (xy 129.07686 -248.838178) (xy 129.029274 -248.820131)
			(xy 128.9852 -248.794685) (xy 128.945778 -248.762498) (xy 128.91203 -248.724404) (xy 128.884829 -248.68139)
			(xy 128.864881 -248.63457) (xy 128.852702 -248.585156) (xy 128.848607 -248.534428) (xy 128.54051 -248.534428)
			(xy 128.539998 -248.559874) (xy 128.531834 -248.610108) (xy 128.515718 -248.658382) (xy 128.492067 -248.703445)
			(xy 128.461494 -248.744131) (xy 128.42479 -248.779386) (xy 128.382906 -248.808296) (xy 128.336927 -248.830113)
			(xy 128.288043 -248.844273) (xy 128.237522 -248.850407) (xy 128.18667 -248.848358) (xy 128.136806 -248.838178)
			(xy 128.08922 -248.820131) (xy 128.045146 -248.794685) (xy 128.005724 -248.762498) (xy 127.971976 -248.724404)
			(xy 127.944775 -248.68139) (xy 127.924827 -248.63457) (xy 127.912648 -248.585156) (xy 127.908553 -248.534428)
			(xy 127.590501 -248.534428) (xy 127.586333 -248.58473) (xy 127.573936 -248.633687) (xy 127.553651 -248.679937)
			(xy 127.52603 -248.722217) (xy 127.491828 -248.759374) (xy 127.451976 -248.790396) (xy 127.407563 -248.814436)
			(xy 127.359798 -248.830838) (xy 127.309985 -248.839156) (xy 127.284734 -248.839736) (xy 127.269325 -248.83957)
			(xy 127.238659 -248.836518) (xy 127.22352 -248.83364) (xy 127.21209 -248.831354) (xy 127.190246 -248.836688)
			(xy 127.120142 -248.894092) (xy 127.111864 -248.901695) (xy 127.102255 -248.921986) (xy 127.1016 -248.933208)
			(xy 127.1016 -249.239278) (xy 127.10414 -249.247152) (xy 127.111595 -249.270779) (xy 127.119633 -249.319664)
			(xy 127.120142 -249.344434) (xy 127.438399 -249.344434) (xy 127.442494 -249.293706) (xy 127.454673 -249.244292)
			(xy 127.474621 -249.197472) (xy 127.501822 -249.154458) (xy 127.53557 -249.116364) (xy 127.574992 -249.084177)
			(xy 127.619066 -249.058731) (xy 127.666652 -249.040684) (xy 127.716516 -249.030504) (xy 127.767368 -249.028455)
			(xy 127.817889 -249.034589) (xy 127.866773 -249.048749) (xy 127.912752 -249.070566) (xy 127.954636 -249.099476)
			(xy 127.99134 -249.134731) (xy 128.021913 -249.175417) (xy 128.045564 -249.22048) (xy 128.06168 -249.268754)
			(xy 128.069844 -249.318988) (xy 128.070356 -249.344434) (xy 128.388884 -249.344434) (xy 128.392844 -249.29538)
			(xy 128.404621 -249.247596) (xy 128.423912 -249.20232) (xy 128.450215 -249.160724) (xy 128.48285 -249.123887)
			(xy 128.520971 -249.092762) (xy 128.563592 -249.068155) (xy 128.609608 -249.050703) (xy 128.657827 -249.040859)
			(xy 128.707002 -249.038878) (xy 128.755857 -249.04481) (xy 128.803128 -249.058502) (xy 128.84759 -249.0796)
			(xy 128.888093 -249.107556) (xy 128.923586 -249.141648) (xy 128.953151 -249.180992) (xy 128.976022 -249.224569)
			(xy 128.991606 -249.27125) (xy 128.999501 -249.319827) (xy 128.999996 -249.344434) (xy 129.328938 -249.344434)
			(xy 129.332898 -249.29538) (xy 129.344675 -249.247596) (xy 129.363966 -249.20232) (xy 129.390269 -249.160724)
			(xy 129.422904 -249.123887) (xy 129.461025 -249.092762) (xy 129.503646 -249.068155) (xy 129.549662 -249.050703)
			(xy 129.597881 -249.040859) (xy 129.647056 -249.038878) (xy 129.695911 -249.04481) (xy 129.743182 -249.058502)
			(xy 129.787644 -249.0796) (xy 129.828147 -249.107556) (xy 129.86364 -249.141648) (xy 129.893205 -249.180992)
			(xy 129.916076 -249.224569) (xy 129.93166 -249.27125) (xy 129.939555 -249.319827) (xy 129.94005 -249.344434)
			(xy 131.198615 -249.344434) (xy 131.20271 -249.293706) (xy 131.214889 -249.244292) (xy 131.234837 -249.197472)
			(xy 131.262038 -249.154458) (xy 131.295786 -249.116364) (xy 131.335208 -249.084177) (xy 131.379282 -249.058731)
			(xy 131.426868 -249.040684) (xy 131.476732 -249.030504) (xy 131.527584 -249.028455) (xy 131.578105 -249.034589)
			(xy 131.626989 -249.048749) (xy 131.672968 -249.070566) (xy 131.714852 -249.099476) (xy 131.751556 -249.134731)
			(xy 131.782129 -249.175417) (xy 131.80578 -249.22048) (xy 131.821896 -249.268754) (xy 131.83006 -249.318988)
			(xy 131.830572 -249.344434) (xy 132.148846 -249.344434) (xy 132.152806 -249.29538) (xy 132.164583 -249.247596)
			(xy 132.183874 -249.20232) (xy 132.210177 -249.160724) (xy 132.242812 -249.123887) (xy 132.280933 -249.092762)
			(xy 132.323554 -249.068155) (xy 132.36957 -249.050703) (xy 132.417789 -249.040859) (xy 132.466964 -249.038878)
			(xy 132.515819 -249.04481) (xy 132.56309 -249.058502) (xy 132.607552 -249.0796) (xy 132.648055 -249.107556)
			(xy 132.683548 -249.141648) (xy 132.713113 -249.180992) (xy 132.735984 -249.224569) (xy 132.751568 -249.27125)
			(xy 132.759463 -249.319827) (xy 132.759958 -249.344434) (xy 133.0889 -249.344434) (xy 133.09286 -249.29538)
			(xy 133.104637 -249.247596) (xy 133.123928 -249.20232) (xy 133.150231 -249.160724) (xy 133.182866 -249.123887)
			(xy 133.220987 -249.092762) (xy 133.263608 -249.068155) (xy 133.309624 -249.050703) (xy 133.357843 -249.040859)
			(xy 133.407018 -249.038878) (xy 133.455873 -249.04481) (xy 133.503144 -249.058502) (xy 133.547606 -249.0796)
			(xy 133.588109 -249.107556) (xy 133.623602 -249.141648) (xy 133.653167 -249.180992) (xy 133.676038 -249.224569)
			(xy 133.691622 -249.27125) (xy 133.699517 -249.319827) (xy 133.700012 -249.344434) (xy 134.018523 -249.344434)
			(xy 134.022618 -249.293706) (xy 134.034797 -249.244292) (xy 134.054745 -249.197472) (xy 134.081946 -249.154458)
			(xy 134.115694 -249.116364) (xy 134.155116 -249.084177) (xy 134.19919 -249.058731) (xy 134.246776 -249.040684)
			(xy 134.29664 -249.030504) (xy 134.347492 -249.028455) (xy 134.398013 -249.034589) (xy 134.446897 -249.048749)
			(xy 134.492876 -249.070566) (xy 134.53476 -249.099476) (xy 134.571464 -249.134731) (xy 134.602037 -249.175417)
			(xy 134.625688 -249.22048) (xy 134.641804 -249.268754) (xy 134.649968 -249.318988) (xy 134.65048 -249.344434)
			(xy 134.969008 -249.344434) (xy 134.972968 -249.29538) (xy 134.984745 -249.247596) (xy 135.004036 -249.20232)
			(xy 135.030339 -249.160724) (xy 135.062974 -249.123887) (xy 135.101095 -249.092762) (xy 135.143716 -249.068155)
			(xy 135.189732 -249.050703) (xy 135.237951 -249.040859) (xy 135.287126 -249.038878) (xy 135.335981 -249.04481)
			(xy 135.383252 -249.058502) (xy 135.427714 -249.0796) (xy 135.468217 -249.107556) (xy 135.50371 -249.141648)
			(xy 135.533275 -249.180992) (xy 135.556146 -249.224569) (xy 135.57173 -249.27125) (xy 135.579625 -249.319827)
			(xy 135.58012 -249.344434) (xy 135.909062 -249.344434) (xy 135.913022 -249.29538) (xy 135.924799 -249.247596)
			(xy 135.94409 -249.20232) (xy 135.970393 -249.160724) (xy 136.003028 -249.123887) (xy 136.041149 -249.092762)
			(xy 136.08377 -249.068155) (xy 136.129786 -249.050703) (xy 136.178005 -249.040859) (xy 136.22718 -249.038878)
			(xy 136.276035 -249.04481) (xy 136.323306 -249.058502) (xy 136.367768 -249.0796) (xy 136.408271 -249.107556)
			(xy 136.443764 -249.141648) (xy 136.473329 -249.180992) (xy 136.4962 -249.224569) (xy 136.511784 -249.27125)
			(xy 136.519679 -249.319827) (xy 136.520174 -249.344434) (xy 137.778485 -249.344434) (xy 137.78258 -249.293706)
			(xy 137.794759 -249.244292) (xy 137.814707 -249.197472) (xy 137.841908 -249.154458) (xy 137.875656 -249.116364)
			(xy 137.915078 -249.084177) (xy 137.959152 -249.058731) (xy 138.006738 -249.040684) (xy 138.056602 -249.030504)
			(xy 138.107454 -249.028455) (xy 138.157975 -249.034589) (xy 138.206859 -249.048749) (xy 138.252838 -249.070566)
			(xy 138.294722 -249.099476) (xy 138.331426 -249.134731) (xy 138.361999 -249.175417) (xy 138.38565 -249.22048)
			(xy 138.401766 -249.268754) (xy 138.40993 -249.318988) (xy 138.410442 -249.344434) (xy 138.72897 -249.344434)
			(xy 138.73293 -249.29538) (xy 138.744707 -249.247596) (xy 138.763998 -249.20232) (xy 138.790301 -249.160724)
			(xy 138.822936 -249.123887) (xy 138.861057 -249.092762) (xy 138.903678 -249.068155) (xy 138.949694 -249.050703)
			(xy 138.997913 -249.040859) (xy 139.047088 -249.038878) (xy 139.095943 -249.04481) (xy 139.143214 -249.058502)
			(xy 139.187676 -249.0796) (xy 139.228179 -249.107556) (xy 139.263672 -249.141648) (xy 139.293237 -249.180992)
			(xy 139.316108 -249.224569) (xy 139.331692 -249.27125) (xy 139.339587 -249.319827) (xy 139.340082 -249.344434)
			(xy 139.669024 -249.344434) (xy 139.672984 -249.29538) (xy 139.684761 -249.247596) (xy 139.704052 -249.20232)
			(xy 139.730355 -249.160724) (xy 139.76299 -249.123887) (xy 139.801111 -249.092762) (xy 139.843732 -249.068155)
			(xy 139.889748 -249.050703) (xy 139.937967 -249.040859) (xy 139.987142 -249.038878) (xy 140.035997 -249.04481)
			(xy 140.083268 -249.058502) (xy 140.12773 -249.0796) (xy 140.168233 -249.107556) (xy 140.203726 -249.141648)
			(xy 140.233291 -249.180992) (xy 140.256162 -249.224569) (xy 140.271746 -249.27125) (xy 140.279641 -249.319827)
			(xy 140.280136 -249.344434) (xy 140.598647 -249.344434) (xy 140.602742 -249.293706) (xy 140.614921 -249.244292)
			(xy 140.634869 -249.197472) (xy 140.66207 -249.154458) (xy 140.695818 -249.116364) (xy 140.73524 -249.084177)
			(xy 140.779314 -249.058731) (xy 140.8269 -249.040684) (xy 140.876764 -249.030504) (xy 140.927616 -249.028455)
			(xy 140.978137 -249.034589) (xy 141.027021 -249.048749) (xy 141.073 -249.070566) (xy 141.114884 -249.099476)
			(xy 141.151588 -249.134731) (xy 141.182161 -249.175417) (xy 141.205812 -249.22048) (xy 141.221928 -249.268754)
			(xy 141.230092 -249.318988) (xy 141.230604 -249.344434) (xy 141.548878 -249.344434) (xy 141.552838 -249.29538)
			(xy 141.564615 -249.247596) (xy 141.583906 -249.20232) (xy 141.610209 -249.160724) (xy 141.642844 -249.123887)
			(xy 141.680965 -249.092762) (xy 141.723586 -249.068155) (xy 141.769602 -249.050703) (xy 141.817821 -249.040859)
			(xy 141.866996 -249.038878) (xy 141.915851 -249.04481) (xy 141.963122 -249.058502) (xy 142.007584 -249.0796)
			(xy 142.048087 -249.107556) (xy 142.08358 -249.141648) (xy 142.113145 -249.180992) (xy 142.136016 -249.224569)
			(xy 142.1516 -249.27125) (xy 142.159495 -249.319827) (xy 142.15999 -249.344434) (xy 142.488932 -249.344434)
			(xy 142.492892 -249.29538) (xy 142.504669 -249.247596) (xy 142.52396 -249.20232) (xy 142.550263 -249.160724)
			(xy 142.582898 -249.123887) (xy 142.621019 -249.092762) (xy 142.66364 -249.068155) (xy 142.709656 -249.050703)
			(xy 142.757875 -249.040859) (xy 142.80705 -249.038878) (xy 142.855905 -249.04481) (xy 142.903176 -249.058502)
			(xy 142.947638 -249.0796) (xy 142.988141 -249.107556) (xy 143.023634 -249.141648) (xy 143.053199 -249.180992)
			(xy 143.07607 -249.224569) (xy 143.091654 -249.27125) (xy 143.099549 -249.319827) (xy 143.100044 -249.344434)
			(xy 143.099549 -249.369041) (xy 143.091654 -249.417618) (xy 143.07607 -249.464299) (xy 143.053199 -249.507876)
			(xy 143.023634 -249.54722) (xy 142.988141 -249.581312) (xy 142.947638 -249.609268) (xy 142.903176 -249.630366)
			(xy 142.855905 -249.644058) (xy 142.80705 -249.64999) (xy 142.757875 -249.648009) (xy 142.709656 -249.638165)
			(xy 142.66364 -249.620713) (xy 142.621019 -249.596106) (xy 142.582898 -249.564981) (xy 142.550263 -249.528144)
			(xy 142.52396 -249.486548) (xy 142.504669 -249.441272) (xy 142.492892 -249.393488) (xy 142.488932 -249.344434)
			(xy 142.15999 -249.344434) (xy 142.159495 -249.369041) (xy 142.1516 -249.417618) (xy 142.136016 -249.464299)
			(xy 142.113145 -249.507876) (xy 142.08358 -249.54722) (xy 142.048087 -249.581312) (xy 142.007584 -249.609268)
			(xy 141.963122 -249.630366) (xy 141.915851 -249.644058) (xy 141.866996 -249.64999) (xy 141.817821 -249.648009)
			(xy 141.769602 -249.638165) (xy 141.723586 -249.620713) (xy 141.680965 -249.596106) (xy 141.642844 -249.564981)
			(xy 141.610209 -249.528144) (xy 141.583906 -249.486548) (xy 141.564615 -249.441272) (xy 141.552838 -249.393488)
			(xy 141.548878 -249.344434) (xy 141.230604 -249.344434) (xy 141.230092 -249.36988) (xy 141.221928 -249.420114)
			(xy 141.205812 -249.468388) (xy 141.182161 -249.513451) (xy 141.151588 -249.554137) (xy 141.114884 -249.589392)
			(xy 141.073 -249.618302) (xy 141.027021 -249.640119) (xy 140.978137 -249.654279) (xy 140.927616 -249.660413)
			(xy 140.876764 -249.658364) (xy 140.8269 -249.648184) (xy 140.779314 -249.630137) (xy 140.73524 -249.604691)
			(xy 140.695818 -249.572504) (xy 140.66207 -249.53441) (xy 140.634869 -249.491396) (xy 140.614921 -249.444576)
			(xy 140.602742 -249.395162) (xy 140.598647 -249.344434) (xy 140.280136 -249.344434) (xy 140.279641 -249.369041)
			(xy 140.271746 -249.417618) (xy 140.256162 -249.464299) (xy 140.233291 -249.507876) (xy 140.203726 -249.54722)
			(xy 140.168233 -249.581312) (xy 140.12773 -249.609268) (xy 140.083268 -249.630366) (xy 140.035997 -249.644058)
			(xy 139.987142 -249.64999) (xy 139.937967 -249.648009) (xy 139.889748 -249.638165) (xy 139.843732 -249.620713)
			(xy 139.801111 -249.596106) (xy 139.76299 -249.564981) (xy 139.730355 -249.528144) (xy 139.704052 -249.486548)
			(xy 139.684761 -249.441272) (xy 139.672984 -249.393488) (xy 139.669024 -249.344434) (xy 139.340082 -249.344434)
			(xy 139.339587 -249.369041) (xy 139.331692 -249.417618) (xy 139.316108 -249.464299) (xy 139.293237 -249.507876)
			(xy 139.263672 -249.54722) (xy 139.228179 -249.581312) (xy 139.187676 -249.609268) (xy 139.143214 -249.630366)
			(xy 139.095943 -249.644058) (xy 139.047088 -249.64999) (xy 138.997913 -249.648009) (xy 138.949694 -249.638165)
			(xy 138.903678 -249.620713) (xy 138.861057 -249.596106) (xy 138.822936 -249.564981) (xy 138.790301 -249.528144)
			(xy 138.763998 -249.486548) (xy 138.744707 -249.441272) (xy 138.73293 -249.393488) (xy 138.72897 -249.344434)
			(xy 138.410442 -249.344434) (xy 138.40993 -249.36988) (xy 138.401766 -249.420114) (xy 138.38565 -249.468388)
			(xy 138.361999 -249.513451) (xy 138.331426 -249.554137) (xy 138.294722 -249.589392) (xy 138.252838 -249.618302)
			(xy 138.206859 -249.640119) (xy 138.157975 -249.654279) (xy 138.107454 -249.660413) (xy 138.056602 -249.658364)
			(xy 138.006738 -249.648184) (xy 137.959152 -249.630137) (xy 137.915078 -249.604691) (xy 137.875656 -249.572504)
			(xy 137.841908 -249.53441) (xy 137.814707 -249.491396) (xy 137.794759 -249.444576) (xy 137.78258 -249.395162)
			(xy 137.778485 -249.344434) (xy 136.520174 -249.344434) (xy 136.519679 -249.369041) (xy 136.511784 -249.417618)
			(xy 136.4962 -249.464299) (xy 136.473329 -249.507876) (xy 136.443764 -249.54722) (xy 136.408271 -249.581312)
			(xy 136.367768 -249.609268) (xy 136.323306 -249.630366) (xy 136.276035 -249.644058) (xy 136.22718 -249.64999)
			(xy 136.178005 -249.648009) (xy 136.129786 -249.638165) (xy 136.08377 -249.620713) (xy 136.041149 -249.596106)
			(xy 136.003028 -249.564981) (xy 135.970393 -249.528144) (xy 135.94409 -249.486548) (xy 135.924799 -249.441272)
			(xy 135.913022 -249.393488) (xy 135.909062 -249.344434) (xy 135.58012 -249.344434) (xy 135.579625 -249.369041)
			(xy 135.57173 -249.417618) (xy 135.556146 -249.464299) (xy 135.533275 -249.507876) (xy 135.50371 -249.54722)
			(xy 135.468217 -249.581312) (xy 135.427714 -249.609268) (xy 135.383252 -249.630366) (xy 135.335981 -249.644058)
			(xy 135.287126 -249.64999) (xy 135.237951 -249.648009) (xy 135.189732 -249.638165) (xy 135.143716 -249.620713)
			(xy 135.101095 -249.596106) (xy 135.062974 -249.564981) (xy 135.030339 -249.528144) (xy 135.004036 -249.486548)
			(xy 134.984745 -249.441272) (xy 134.972968 -249.393488) (xy 134.969008 -249.344434) (xy 134.65048 -249.344434)
			(xy 134.649968 -249.36988) (xy 134.641804 -249.420114) (xy 134.625688 -249.468388) (xy 134.602037 -249.513451)
			(xy 134.571464 -249.554137) (xy 134.53476 -249.589392) (xy 134.492876 -249.618302) (xy 134.446897 -249.640119)
			(xy 134.398013 -249.654279) (xy 134.347492 -249.660413) (xy 134.29664 -249.658364) (xy 134.246776 -249.648184)
			(xy 134.19919 -249.630137) (xy 134.155116 -249.604691) (xy 134.115694 -249.572504) (xy 134.081946 -249.53441)
			(xy 134.054745 -249.491396) (xy 134.034797 -249.444576) (xy 134.022618 -249.395162) (xy 134.018523 -249.344434)
			(xy 133.700012 -249.344434) (xy 133.699517 -249.369041) (xy 133.691622 -249.417618) (xy 133.676038 -249.464299)
			(xy 133.653167 -249.507876) (xy 133.623602 -249.54722) (xy 133.588109 -249.581312) (xy 133.547606 -249.609268)
			(xy 133.503144 -249.630366) (xy 133.455873 -249.644058) (xy 133.407018 -249.64999) (xy 133.357843 -249.648009)
			(xy 133.309624 -249.638165) (xy 133.263608 -249.620713) (xy 133.220987 -249.596106) (xy 133.182866 -249.564981)
			(xy 133.150231 -249.528144) (xy 133.123928 -249.486548) (xy 133.104637 -249.441272) (xy 133.09286 -249.393488)
			(xy 133.0889 -249.344434) (xy 132.759958 -249.344434) (xy 132.759463 -249.369041) (xy 132.751568 -249.417618)
			(xy 132.735984 -249.464299) (xy 132.713113 -249.507876) (xy 132.683548 -249.54722) (xy 132.648055 -249.581312)
			(xy 132.607552 -249.609268) (xy 132.56309 -249.630366) (xy 132.515819 -249.644058) (xy 132.466964 -249.64999)
			(xy 132.417789 -249.648009) (xy 132.36957 -249.638165) (xy 132.323554 -249.620713) (xy 132.280933 -249.596106)
			(xy 132.242812 -249.564981) (xy 132.210177 -249.528144) (xy 132.183874 -249.486548) (xy 132.164583 -249.441272)
			(xy 132.152806 -249.393488) (xy 132.148846 -249.344434) (xy 131.830572 -249.344434) (xy 131.83006 -249.36988)
			(xy 131.821896 -249.420114) (xy 131.80578 -249.468388) (xy 131.782129 -249.513451) (xy 131.751556 -249.554137)
			(xy 131.714852 -249.589392) (xy 131.672968 -249.618302) (xy 131.626989 -249.640119) (xy 131.578105 -249.654279)
			(xy 131.527584 -249.660413) (xy 131.476732 -249.658364) (xy 131.426868 -249.648184) (xy 131.379282 -249.630137)
			(xy 131.335208 -249.604691) (xy 131.295786 -249.572504) (xy 131.262038 -249.53441) (xy 131.234837 -249.491396)
			(xy 131.214889 -249.444576) (xy 131.20271 -249.395162) (xy 131.198615 -249.344434) (xy 129.94005 -249.344434)
			(xy 129.939555 -249.369041) (xy 129.93166 -249.417618) (xy 129.916076 -249.464299) (xy 129.893205 -249.507876)
			(xy 129.86364 -249.54722) (xy 129.828147 -249.581312) (xy 129.787644 -249.609268) (xy 129.743182 -249.630366)
			(xy 129.695911 -249.644058) (xy 129.647056 -249.64999) (xy 129.597881 -249.648009) (xy 129.549662 -249.638165)
			(xy 129.503646 -249.620713) (xy 129.461025 -249.596106) (xy 129.422904 -249.564981) (xy 129.390269 -249.528144)
			(xy 129.363966 -249.486548) (xy 129.344675 -249.441272) (xy 129.332898 -249.393488) (xy 129.328938 -249.344434)
			(xy 128.999996 -249.344434) (xy 128.999501 -249.369041) (xy 128.991606 -249.417618) (xy 128.976022 -249.464299)
			(xy 128.953151 -249.507876) (xy 128.923586 -249.54722) (xy 128.888093 -249.581312) (xy 128.84759 -249.609268)
			(xy 128.803128 -249.630366) (xy 128.755857 -249.644058) (xy 128.707002 -249.64999) (xy 128.657827 -249.648009)
			(xy 128.609608 -249.638165) (xy 128.563592 -249.620713) (xy 128.520971 -249.596106) (xy 128.48285 -249.564981)
			(xy 128.450215 -249.528144) (xy 128.423912 -249.486548) (xy 128.404621 -249.441272) (xy 128.392844 -249.393488)
			(xy 128.388884 -249.344434) (xy 128.070356 -249.344434) (xy 128.069844 -249.36988) (xy 128.06168 -249.420114)
			(xy 128.045564 -249.468388) (xy 128.021913 -249.513451) (xy 127.99134 -249.554137) (xy 127.954636 -249.589392)
			(xy 127.912752 -249.618302) (xy 127.866773 -249.640119) (xy 127.817889 -249.654279) (xy 127.767368 -249.660413)
			(xy 127.716516 -249.658364) (xy 127.666652 -249.648184) (xy 127.619066 -249.630137) (xy 127.574992 -249.604691)
			(xy 127.53557 -249.572504) (xy 127.501822 -249.53441) (xy 127.474621 -249.491396) (xy 127.454673 -249.444576)
			(xy 127.442494 -249.395162) (xy 127.438399 -249.344434) (xy 127.120142 -249.344434) (xy 127.119641 -249.369205)
			(xy 127.111603 -249.418091) (xy 127.10414 -249.441716) (xy 127.1016 -249.44959) (xy 127.1016 -250.15444)
			(xy 127.908553 -250.15444) (xy 127.912648 -250.103712) (xy 127.924827 -250.054298) (xy 127.944775 -250.007478)
			(xy 127.971976 -249.964464) (xy 128.005724 -249.92637) (xy 128.045146 -249.894183) (xy 128.08922 -249.868737)
			(xy 128.136806 -249.85069) (xy 128.18667 -249.84051) (xy 128.237522 -249.838461) (xy 128.288043 -249.844595)
			(xy 128.336927 -249.858755) (xy 128.382906 -249.880572) (xy 128.42479 -249.909482) (xy 128.461494 -249.944737)
			(xy 128.492067 -249.985423) (xy 128.515718 -250.030486) (xy 128.531834 -250.07876) (xy 128.539998 -250.128994)
			(xy 128.54051 -250.15444) (xy 128.859038 -250.15444) (xy 128.862998 -250.105386) (xy 128.874775 -250.057602)
			(xy 128.894066 -250.012326) (xy 128.920369 -249.97073) (xy 128.953004 -249.933893) (xy 128.991125 -249.902768)
			(xy 129.033746 -249.878161) (xy 129.079762 -249.860709) (xy 129.127981 -249.850865) (xy 129.177156 -249.848884)
			(xy 129.226011 -249.854816) (xy 129.273282 -249.868508) (xy 129.317744 -249.889606) (xy 129.358247 -249.917562)
			(xy 129.39374 -249.951654) (xy 129.423305 -249.990998) (xy 129.446176 -250.034575) (xy 129.46176 -250.081256)
			(xy 129.469655 -250.129833) (xy 129.47015 -250.15444) (xy 129.798838 -250.15444) (xy 129.802798 -250.105386)
			(xy 129.814575 -250.057602) (xy 129.833866 -250.012326) (xy 129.860169 -249.97073) (xy 129.892804 -249.933893)
			(xy 129.930925 -249.902768) (xy 129.973546 -249.878161) (xy 130.019562 -249.860709) (xy 130.067781 -249.850865)
			(xy 130.116956 -249.848884) (xy 130.165811 -249.854816) (xy 130.213082 -249.868508) (xy 130.257544 -249.889606)
			(xy 130.298047 -249.917562) (xy 130.33354 -249.951654) (xy 130.363105 -249.990998) (xy 130.385976 -250.034575)
			(xy 130.40156 -250.081256) (xy 130.409455 -250.129833) (xy 130.40995 -250.15444) (xy 130.728461 -250.15444)
			(xy 130.732556 -250.103712) (xy 130.744735 -250.054298) (xy 130.764683 -250.007478) (xy 130.791884 -249.964464)
			(xy 130.825632 -249.92637) (xy 130.865054 -249.894183) (xy 130.909128 -249.868737) (xy 130.956714 -249.85069)
			(xy 131.006578 -249.84051) (xy 131.05743 -249.838461) (xy 131.107951 -249.844595) (xy 131.156835 -249.858755)
			(xy 131.202814 -249.880572) (xy 131.244698 -249.909482) (xy 131.281402 -249.944737) (xy 131.311975 -249.985423)
			(xy 131.335626 -250.030486) (xy 131.351742 -250.07876) (xy 131.359906 -250.128994) (xy 131.360418 -250.15444)
			(xy 131.678946 -250.15444) (xy 131.682906 -250.105386) (xy 131.694683 -250.057602) (xy 131.713974 -250.012326)
			(xy 131.740277 -249.97073) (xy 131.772912 -249.933893) (xy 131.811033 -249.902768) (xy 131.853654 -249.878161)
			(xy 131.89967 -249.860709) (xy 131.947889 -249.850865) (xy 131.997064 -249.848884) (xy 132.045919 -249.854816)
			(xy 132.09319 -249.868508) (xy 132.137652 -249.889606) (xy 132.178155 -249.917562) (xy 132.213648 -249.951654)
			(xy 132.243213 -249.990998) (xy 132.266084 -250.034575) (xy 132.281668 -250.081256) (xy 132.289563 -250.129833)
			(xy 132.290058 -250.15444) (xy 132.619 -250.15444) (xy 132.62296 -250.105386) (xy 132.634737 -250.057602)
			(xy 132.654028 -250.012326) (xy 132.680331 -249.97073) (xy 132.712966 -249.933893) (xy 132.751087 -249.902768)
			(xy 132.793708 -249.878161) (xy 132.839724 -249.860709) (xy 132.887943 -249.850865) (xy 132.937118 -249.848884)
			(xy 132.985973 -249.854816) (xy 133.033244 -249.868508) (xy 133.077706 -249.889606) (xy 133.118209 -249.917562)
			(xy 133.153702 -249.951654) (xy 133.183267 -249.990998) (xy 133.206138 -250.034575) (xy 133.221722 -250.081256)
			(xy 133.229617 -250.129833) (xy 133.230112 -250.15444) (xy 133.559054 -250.15444) (xy 133.563014 -250.105386)
			(xy 133.574791 -250.057602) (xy 133.594082 -250.012326) (xy 133.620385 -249.97073) (xy 133.65302 -249.933893)
			(xy 133.691141 -249.902768) (xy 133.733762 -249.878161) (xy 133.779778 -249.860709) (xy 133.827997 -249.850865)
			(xy 133.877172 -249.848884) (xy 133.926027 -249.854816) (xy 133.973298 -249.868508) (xy 134.01776 -249.889606)
			(xy 134.058263 -249.917562) (xy 134.093756 -249.951654) (xy 134.123321 -249.990998) (xy 134.146192 -250.034575)
			(xy 134.161776 -250.081256) (xy 134.169671 -250.129833) (xy 134.170166 -250.15444) (xy 134.488423 -250.15444)
			(xy 134.492518 -250.103712) (xy 134.504697 -250.054298) (xy 134.524645 -250.007478) (xy 134.551846 -249.964464)
			(xy 134.585594 -249.92637) (xy 134.625016 -249.894183) (xy 134.66909 -249.868737) (xy 134.716676 -249.85069)
			(xy 134.76654 -249.84051) (xy 134.817392 -249.838461) (xy 134.867913 -249.844595) (xy 134.916797 -249.858755)
			(xy 134.962776 -249.880572) (xy 135.00466 -249.909482) (xy 135.041364 -249.944737) (xy 135.071937 -249.985423)
			(xy 135.095588 -250.030486) (xy 135.111704 -250.07876) (xy 135.119868 -250.128994) (xy 135.12038 -250.15444)
			(xy 135.438908 -250.15444) (xy 135.442868 -250.105386) (xy 135.454645 -250.057602) (xy 135.473936 -250.012326)
			(xy 135.500239 -249.97073) (xy 135.532874 -249.933893) (xy 135.570995 -249.902768) (xy 135.613616 -249.878161)
			(xy 135.659632 -249.860709) (xy 135.707851 -249.850865) (xy 135.757026 -249.848884) (xy 135.805881 -249.854816)
			(xy 135.853152 -249.868508) (xy 135.897614 -249.889606) (xy 135.938117 -249.917562) (xy 135.97361 -249.951654)
			(xy 136.003175 -249.990998) (xy 136.026046 -250.034575) (xy 136.04163 -250.081256) (xy 136.049525 -250.129833)
			(xy 136.05002 -250.15444) (xy 136.378962 -250.15444) (xy 136.382922 -250.105386) (xy 136.394699 -250.057602)
			(xy 136.41399 -250.012326) (xy 136.440293 -249.97073) (xy 136.472928 -249.933893) (xy 136.511049 -249.902768)
			(xy 136.55367 -249.878161) (xy 136.599686 -249.860709) (xy 136.647905 -249.850865) (xy 136.69708 -249.848884)
			(xy 136.745935 -249.854816) (xy 136.793206 -249.868508) (xy 136.837668 -249.889606) (xy 136.878171 -249.917562)
			(xy 136.913664 -249.951654) (xy 136.943229 -249.990998) (xy 136.9661 -250.034575) (xy 136.981684 -250.081256)
			(xy 136.989579 -250.129833) (xy 136.990074 -250.15444) (xy 137.308585 -250.15444) (xy 137.31268 -250.103712)
			(xy 137.324859 -250.054298) (xy 137.344807 -250.007478) (xy 137.372008 -249.964464) (xy 137.405756 -249.92637)
			(xy 137.445178 -249.894183) (xy 137.489252 -249.868737) (xy 137.536838 -249.85069) (xy 137.586702 -249.84051)
			(xy 137.637554 -249.838461) (xy 137.688075 -249.844595) (xy 137.736959 -249.858755) (xy 137.782938 -249.880572)
			(xy 137.824822 -249.909482) (xy 137.861526 -249.944737) (xy 137.892099 -249.985423) (xy 137.91575 -250.030486)
			(xy 137.931866 -250.07876) (xy 137.94003 -250.128994) (xy 137.940542 -250.15444) (xy 138.25907 -250.15444)
			(xy 138.26303 -250.105386) (xy 138.274807 -250.057602) (xy 138.294098 -250.012326) (xy 138.320401 -249.97073)
			(xy 138.353036 -249.933893) (xy 138.391157 -249.902768) (xy 138.433778 -249.878161) (xy 138.479794 -249.860709)
			(xy 138.528013 -249.850865) (xy 138.577188 -249.848884) (xy 138.626043 -249.854816) (xy 138.673314 -249.868508)
			(xy 138.717776 -249.889606) (xy 138.758279 -249.917562) (xy 138.793772 -249.951654) (xy 138.823337 -249.990998)
			(xy 138.846208 -250.034575) (xy 138.861792 -250.081256) (xy 138.869687 -250.129833) (xy 138.870182 -250.15444)
			(xy 139.19887 -250.15444) (xy 139.20283 -250.105386) (xy 139.214607 -250.057602) (xy 139.233898 -250.012326)
			(xy 139.260201 -249.97073) (xy 139.292836 -249.933893) (xy 139.330957 -249.902768) (xy 139.373578 -249.878161)
			(xy 139.419594 -249.860709) (xy 139.467813 -249.850865) (xy 139.516988 -249.848884) (xy 139.565843 -249.854816)
			(xy 139.613114 -249.868508) (xy 139.657576 -249.889606) (xy 139.698079 -249.917562) (xy 139.733572 -249.951654)
			(xy 139.763137 -249.990998) (xy 139.786008 -250.034575) (xy 139.801592 -250.081256) (xy 139.809487 -250.129833)
			(xy 139.809982 -250.15444) (xy 140.138924 -250.15444) (xy 140.142884 -250.105386) (xy 140.154661 -250.057602)
			(xy 140.173952 -250.012326) (xy 140.200255 -249.97073) (xy 140.23289 -249.933893) (xy 140.271011 -249.902768)
			(xy 140.313632 -249.878161) (xy 140.359648 -249.860709) (xy 140.407867 -249.850865) (xy 140.457042 -249.848884)
			(xy 140.505897 -249.854816) (xy 140.553168 -249.868508) (xy 140.59763 -249.889606) (xy 140.638133 -249.917562)
			(xy 140.673626 -249.951654) (xy 140.703191 -249.990998) (xy 140.726062 -250.034575) (xy 140.741646 -250.081256)
			(xy 140.749541 -250.129833) (xy 140.750036 -250.15444) (xy 141.068547 -250.15444) (xy 141.072642 -250.103712)
			(xy 141.084821 -250.054298) (xy 141.104769 -250.007478) (xy 141.13197 -249.964464) (xy 141.165718 -249.92637)
			(xy 141.20514 -249.894183) (xy 141.249214 -249.868737) (xy 141.2968 -249.85069) (xy 141.346664 -249.84051)
			(xy 141.397516 -249.838461) (xy 141.448037 -249.844595) (xy 141.496921 -249.858755) (xy 141.5429 -249.880572)
			(xy 141.584784 -249.909482) (xy 141.621488 -249.944737) (xy 141.652061 -249.985423) (xy 141.675712 -250.030486)
			(xy 141.691828 -250.07876) (xy 141.699992 -250.128994) (xy 141.700504 -250.15444) (xy 142.019032 -250.15444)
			(xy 142.022992 -250.105386) (xy 142.034769 -250.057602) (xy 142.05406 -250.012326) (xy 142.080363 -249.97073)
			(xy 142.112998 -249.933893) (xy 142.151119 -249.902768) (xy 142.19374 -249.878161) (xy 142.239756 -249.860709)
			(xy 142.287975 -249.850865) (xy 142.33715 -249.848884) (xy 142.386005 -249.854816) (xy 142.433276 -249.868508)
			(xy 142.477738 -249.889606) (xy 142.518241 -249.917562) (xy 142.553734 -249.951654) (xy 142.583299 -249.990998)
			(xy 142.60617 -250.034575) (xy 142.621754 -250.081256) (xy 142.629649 -250.129833) (xy 142.630144 -250.15444)
			(xy 142.958832 -250.15444) (xy 142.962792 -250.105386) (xy 142.974569 -250.057602) (xy 142.99386 -250.012326)
			(xy 143.020163 -249.97073) (xy 143.052798 -249.933893) (xy 143.090919 -249.902768) (xy 143.13354 -249.878161)
			(xy 143.179556 -249.860709) (xy 143.227775 -249.850865) (xy 143.27695 -249.848884) (xy 143.325805 -249.854816)
			(xy 143.373076 -249.868508) (xy 143.417538 -249.889606) (xy 143.458041 -249.917562) (xy 143.493534 -249.951654)
			(xy 143.523099 -249.990998) (xy 143.54597 -250.034575) (xy 143.561554 -250.081256) (xy 143.569449 -250.129833)
			(xy 143.569944 -250.15444) (xy 143.898886 -250.15444) (xy 143.902846 -250.105386) (xy 143.914623 -250.057602)
			(xy 143.933914 -250.012326) (xy 143.960217 -249.97073) (xy 143.992852 -249.933893) (xy 144.030973 -249.902768)
			(xy 144.073594 -249.878161) (xy 144.11961 -249.860709) (xy 144.167829 -249.850865) (xy 144.217004 -249.848884)
			(xy 144.265859 -249.854816) (xy 144.31313 -249.868508) (xy 144.357592 -249.889606) (xy 144.398095 -249.917562)
			(xy 144.433588 -249.951654) (xy 144.463153 -249.990998) (xy 144.486024 -250.034575) (xy 144.501608 -250.081256)
			(xy 144.509503 -250.129833) (xy 144.509998 -250.15444) (xy 144.83894 -250.15444) (xy 144.8429 -250.105386)
			(xy 144.854677 -250.057602) (xy 144.873968 -250.012326) (xy 144.900271 -249.97073) (xy 144.932906 -249.933893)
			(xy 144.971027 -249.902768) (xy 145.013648 -249.878161) (xy 145.059664 -249.860709) (xy 145.107883 -249.850865)
			(xy 145.157058 -249.848884) (xy 145.205913 -249.854816) (xy 145.253184 -249.868508) (xy 145.297646 -249.889606)
			(xy 145.338149 -249.917562) (xy 145.373642 -249.951654) (xy 145.403207 -249.990998) (xy 145.426078 -250.034575)
			(xy 145.441662 -250.081256) (xy 145.449557 -250.129833) (xy 145.450052 -250.15444) (xy 145.449557 -250.179047)
			(xy 145.441662 -250.227624) (xy 145.426078 -250.274305) (xy 145.403207 -250.317882) (xy 145.373642 -250.357226)
			(xy 145.338149 -250.391318) (xy 145.297646 -250.419274) (xy 145.253184 -250.440372) (xy 145.205913 -250.454064)
			(xy 145.157058 -250.459996) (xy 145.107883 -250.458015) (xy 145.059664 -250.448171) (xy 145.013648 -250.430719)
			(xy 144.971027 -250.406112) (xy 144.932906 -250.374987) (xy 144.900271 -250.33815) (xy 144.873968 -250.296554)
			(xy 144.854677 -250.251278) (xy 144.8429 -250.203494) (xy 144.83894 -250.15444) (xy 144.509998 -250.15444)
			(xy 144.509503 -250.179047) (xy 144.501608 -250.227624) (xy 144.486024 -250.274305) (xy 144.463153 -250.317882)
			(xy 144.433588 -250.357226) (xy 144.398095 -250.391318) (xy 144.357592 -250.419274) (xy 144.31313 -250.440372)
			(xy 144.265859 -250.454064) (xy 144.217004 -250.459996) (xy 144.167829 -250.458015) (xy 144.11961 -250.448171)
			(xy 144.073594 -250.430719) (xy 144.030973 -250.406112) (xy 143.992852 -250.374987) (xy 143.960217 -250.33815)
			(xy 143.933914 -250.296554) (xy 143.914623 -250.251278) (xy 143.902846 -250.203494) (xy 143.898886 -250.15444)
			(xy 143.569944 -250.15444) (xy 143.569449 -250.179047) (xy 143.561554 -250.227624) (xy 143.54597 -250.274305)
			(xy 143.523099 -250.317882) (xy 143.493534 -250.357226) (xy 143.458041 -250.391318) (xy 143.417538 -250.419274)
			(xy 143.373076 -250.440372) (xy 143.325805 -250.454064) (xy 143.27695 -250.459996) (xy 143.227775 -250.458015)
			(xy 143.179556 -250.448171) (xy 143.13354 -250.430719) (xy 143.090919 -250.406112) (xy 143.052798 -250.374987)
			(xy 143.020163 -250.33815) (xy 142.99386 -250.296554) (xy 142.974569 -250.251278) (xy 142.962792 -250.203494)
			(xy 142.958832 -250.15444) (xy 142.630144 -250.15444) (xy 142.629649 -250.179047) (xy 142.621754 -250.227624)
			(xy 142.60617 -250.274305) (xy 142.583299 -250.317882) (xy 142.553734 -250.357226) (xy 142.518241 -250.391318)
			(xy 142.477738 -250.419274) (xy 142.433276 -250.440372) (xy 142.386005 -250.454064) (xy 142.33715 -250.459996)
			(xy 142.287975 -250.458015) (xy 142.239756 -250.448171) (xy 142.19374 -250.430719) (xy 142.151119 -250.406112)
			(xy 142.112998 -250.374987) (xy 142.080363 -250.33815) (xy 142.05406 -250.296554) (xy 142.034769 -250.251278)
			(xy 142.022992 -250.203494) (xy 142.019032 -250.15444) (xy 141.700504 -250.15444) (xy 141.699992 -250.179886)
			(xy 141.691828 -250.23012) (xy 141.675712 -250.278394) (xy 141.652061 -250.323457) (xy 141.621488 -250.364143)
			(xy 141.584784 -250.399398) (xy 141.5429 -250.428308) (xy 141.496921 -250.450125) (xy 141.448037 -250.464285)
			(xy 141.397516 -250.470419) (xy 141.346664 -250.46837) (xy 141.2968 -250.45819) (xy 141.249214 -250.440143)
			(xy 141.20514 -250.414697) (xy 141.165718 -250.38251) (xy 141.13197 -250.344416) (xy 141.104769 -250.301402)
			(xy 141.084821 -250.254582) (xy 141.072642 -250.205168) (xy 141.068547 -250.15444) (xy 140.750036 -250.15444)
			(xy 140.749541 -250.179047) (xy 140.741646 -250.227624) (xy 140.726062 -250.274305) (xy 140.703191 -250.317882)
			(xy 140.673626 -250.357226) (xy 140.638133 -250.391318) (xy 140.59763 -250.419274) (xy 140.553168 -250.440372)
			(xy 140.505897 -250.454064) (xy 140.457042 -250.459996) (xy 140.407867 -250.458015) (xy 140.359648 -250.448171)
			(xy 140.313632 -250.430719) (xy 140.271011 -250.406112) (xy 140.23289 -250.374987) (xy 140.200255 -250.33815)
			(xy 140.173952 -250.296554) (xy 140.154661 -250.251278) (xy 140.142884 -250.203494) (xy 140.138924 -250.15444)
			(xy 139.809982 -250.15444) (xy 139.809487 -250.179047) (xy 139.801592 -250.227624) (xy 139.786008 -250.274305)
			(xy 139.763137 -250.317882) (xy 139.733572 -250.357226) (xy 139.698079 -250.391318) (xy 139.657576 -250.419274)
			(xy 139.613114 -250.440372) (xy 139.565843 -250.454064) (xy 139.516988 -250.459996) (xy 139.467813 -250.458015)
			(xy 139.419594 -250.448171) (xy 139.373578 -250.430719) (xy 139.330957 -250.406112) (xy 139.292836 -250.374987)
			(xy 139.260201 -250.33815) (xy 139.233898 -250.296554) (xy 139.214607 -250.251278) (xy 139.20283 -250.203494)
			(xy 139.19887 -250.15444) (xy 138.870182 -250.15444) (xy 138.869687 -250.179047) (xy 138.861792 -250.227624)
			(xy 138.846208 -250.274305) (xy 138.823337 -250.317882) (xy 138.793772 -250.357226) (xy 138.758279 -250.391318)
			(xy 138.717776 -250.419274) (xy 138.673314 -250.440372) (xy 138.626043 -250.454064) (xy 138.577188 -250.459996)
			(xy 138.528013 -250.458015) (xy 138.479794 -250.448171) (xy 138.433778 -250.430719) (xy 138.391157 -250.406112)
			(xy 138.353036 -250.374987) (xy 138.320401 -250.33815) (xy 138.294098 -250.296554) (xy 138.274807 -250.251278)
			(xy 138.26303 -250.203494) (xy 138.25907 -250.15444) (xy 137.940542 -250.15444) (xy 137.94003 -250.179886)
			(xy 137.931866 -250.23012) (xy 137.91575 -250.278394) (xy 137.892099 -250.323457) (xy 137.861526 -250.364143)
			(xy 137.824822 -250.399398) (xy 137.782938 -250.428308) (xy 137.736959 -250.450125) (xy 137.688075 -250.464285)
			(xy 137.637554 -250.470419) (xy 137.586702 -250.46837) (xy 137.536838 -250.45819) (xy 137.489252 -250.440143)
			(xy 137.445178 -250.414697) (xy 137.405756 -250.38251) (xy 137.372008 -250.344416) (xy 137.344807 -250.301402)
			(xy 137.324859 -250.254582) (xy 137.31268 -250.205168) (xy 137.308585 -250.15444) (xy 136.990074 -250.15444)
			(xy 136.989579 -250.179047) (xy 136.981684 -250.227624) (xy 136.9661 -250.274305) (xy 136.943229 -250.317882)
			(xy 136.913664 -250.357226) (xy 136.878171 -250.391318) (xy 136.837668 -250.419274) (xy 136.793206 -250.440372)
			(xy 136.745935 -250.454064) (xy 136.69708 -250.459996) (xy 136.647905 -250.458015) (xy 136.599686 -250.448171)
			(xy 136.55367 -250.430719) (xy 136.511049 -250.406112) (xy 136.472928 -250.374987) (xy 136.440293 -250.33815)
			(xy 136.41399 -250.296554) (xy 136.394699 -250.251278) (xy 136.382922 -250.203494) (xy 136.378962 -250.15444)
			(xy 136.05002 -250.15444) (xy 136.049525 -250.179047) (xy 136.04163 -250.227624) (xy 136.026046 -250.274305)
			(xy 136.003175 -250.317882) (xy 135.97361 -250.357226) (xy 135.938117 -250.391318) (xy 135.897614 -250.419274)
			(xy 135.853152 -250.440372) (xy 135.805881 -250.454064) (xy 135.757026 -250.459996) (xy 135.707851 -250.458015)
			(xy 135.659632 -250.448171) (xy 135.613616 -250.430719) (xy 135.570995 -250.406112) (xy 135.532874 -250.374987)
			(xy 135.500239 -250.33815) (xy 135.473936 -250.296554) (xy 135.454645 -250.251278) (xy 135.442868 -250.203494)
			(xy 135.438908 -250.15444) (xy 135.12038 -250.15444) (xy 135.119868 -250.179886) (xy 135.111704 -250.23012)
			(xy 135.095588 -250.278394) (xy 135.071937 -250.323457) (xy 135.041364 -250.364143) (xy 135.00466 -250.399398)
			(xy 134.962776 -250.428308) (xy 134.916797 -250.450125) (xy 134.867913 -250.464285) (xy 134.817392 -250.470419)
			(xy 134.76654 -250.46837) (xy 134.716676 -250.45819) (xy 134.66909 -250.440143) (xy 134.625016 -250.414697)
			(xy 134.585594 -250.38251) (xy 134.551846 -250.344416) (xy 134.524645 -250.301402) (xy 134.504697 -250.254582)
			(xy 134.492518 -250.205168) (xy 134.488423 -250.15444) (xy 134.170166 -250.15444) (xy 134.169671 -250.179047)
			(xy 134.161776 -250.227624) (xy 134.146192 -250.274305) (xy 134.123321 -250.317882) (xy 134.093756 -250.357226)
			(xy 134.058263 -250.391318) (xy 134.01776 -250.419274) (xy 133.973298 -250.440372) (xy 133.926027 -250.454064)
			(xy 133.877172 -250.459996) (xy 133.827997 -250.458015) (xy 133.779778 -250.448171) (xy 133.733762 -250.430719)
			(xy 133.691141 -250.406112) (xy 133.65302 -250.374987) (xy 133.620385 -250.33815) (xy 133.594082 -250.296554)
			(xy 133.574791 -250.251278) (xy 133.563014 -250.203494) (xy 133.559054 -250.15444) (xy 133.230112 -250.15444)
			(xy 133.229617 -250.179047) (xy 133.221722 -250.227624) (xy 133.206138 -250.274305) (xy 133.183267 -250.317882)
			(xy 133.153702 -250.357226) (xy 133.118209 -250.391318) (xy 133.077706 -250.419274) (xy 133.033244 -250.440372)
			(xy 132.985973 -250.454064) (xy 132.937118 -250.459996) (xy 132.887943 -250.458015) (xy 132.839724 -250.448171)
			(xy 132.793708 -250.430719) (xy 132.751087 -250.406112) (xy 132.712966 -250.374987) (xy 132.680331 -250.33815)
			(xy 132.654028 -250.296554) (xy 132.634737 -250.251278) (xy 132.62296 -250.203494) (xy 132.619 -250.15444)
			(xy 132.290058 -250.15444) (xy 132.289563 -250.179047) (xy 132.281668 -250.227624) (xy 132.266084 -250.274305)
			(xy 132.243213 -250.317882) (xy 132.213648 -250.357226) (xy 132.178155 -250.391318) (xy 132.137652 -250.419274)
			(xy 132.09319 -250.440372) (xy 132.045919 -250.454064) (xy 131.997064 -250.459996) (xy 131.947889 -250.458015)
			(xy 131.89967 -250.448171) (xy 131.853654 -250.430719) (xy 131.811033 -250.406112) (xy 131.772912 -250.374987)
			(xy 131.740277 -250.33815) (xy 131.713974 -250.296554) (xy 131.694683 -250.251278) (xy 131.682906 -250.203494)
			(xy 131.678946 -250.15444) (xy 131.360418 -250.15444) (xy 131.359906 -250.179886) (xy 131.351742 -250.23012)
			(xy 131.335626 -250.278394) (xy 131.311975 -250.323457) (xy 131.281402 -250.364143) (xy 131.244698 -250.399398)
			(xy 131.202814 -250.428308) (xy 131.156835 -250.450125) (xy 131.107951 -250.464285) (xy 131.05743 -250.470419)
			(xy 131.006578 -250.46837) (xy 130.956714 -250.45819) (xy 130.909128 -250.440143) (xy 130.865054 -250.414697)
			(xy 130.825632 -250.38251) (xy 130.791884 -250.344416) (xy 130.764683 -250.301402) (xy 130.744735 -250.254582)
			(xy 130.732556 -250.205168) (xy 130.728461 -250.15444) (xy 130.40995 -250.15444) (xy 130.409455 -250.179047)
			(xy 130.40156 -250.227624) (xy 130.385976 -250.274305) (xy 130.363105 -250.317882) (xy 130.33354 -250.357226)
			(xy 130.298047 -250.391318) (xy 130.257544 -250.419274) (xy 130.213082 -250.440372) (xy 130.165811 -250.454064)
			(xy 130.116956 -250.459996) (xy 130.067781 -250.458015) (xy 130.019562 -250.448171) (xy 129.973546 -250.430719)
			(xy 129.930925 -250.406112) (xy 129.892804 -250.374987) (xy 129.860169 -250.33815) (xy 129.833866 -250.296554)
			(xy 129.814575 -250.251278) (xy 129.802798 -250.203494) (xy 129.798838 -250.15444) (xy 129.47015 -250.15444)
			(xy 129.469655 -250.179047) (xy 129.46176 -250.227624) (xy 129.446176 -250.274305) (xy 129.423305 -250.317882)
			(xy 129.39374 -250.357226) (xy 129.358247 -250.391318) (xy 129.317744 -250.419274) (xy 129.273282 -250.440372)
			(xy 129.226011 -250.454064) (xy 129.177156 -250.459996) (xy 129.127981 -250.458015) (xy 129.079762 -250.448171)
			(xy 129.033746 -250.430719) (xy 128.991125 -250.406112) (xy 128.953004 -250.374987) (xy 128.920369 -250.33815)
			(xy 128.894066 -250.296554) (xy 128.874775 -250.251278) (xy 128.862998 -250.203494) (xy 128.859038 -250.15444)
			(xy 128.54051 -250.15444) (xy 128.539998 -250.179886) (xy 128.531834 -250.23012) (xy 128.515718 -250.278394)
			(xy 128.492067 -250.323457) (xy 128.461494 -250.364143) (xy 128.42479 -250.399398) (xy 128.382906 -250.428308)
			(xy 128.336927 -250.450125) (xy 128.288043 -250.464285) (xy 128.237522 -250.470419) (xy 128.18667 -250.46837)
			(xy 128.136806 -250.45819) (xy 128.08922 -250.440143) (xy 128.045146 -250.414697) (xy 128.005724 -250.38251)
			(xy 127.971976 -250.344416) (xy 127.944775 -250.301402) (xy 127.924827 -250.254582) (xy 127.912648 -250.205168)
			(xy 127.908553 -250.15444) (xy 127.1016 -250.15444) (xy 127.1016 -250.85929) (xy 127.10414 -250.867164)
			(xy 127.111594 -250.890791) (xy 127.119631 -250.939676) (xy 127.120142 -250.964446) (xy 127.438399 -250.964446)
			(xy 127.442494 -250.913718) (xy 127.454673 -250.864304) (xy 127.474621 -250.817484) (xy 127.501822 -250.77447)
			(xy 127.53557 -250.736376) (xy 127.574992 -250.704189) (xy 127.619066 -250.678743) (xy 127.666652 -250.660696)
			(xy 127.716516 -250.650516) (xy 127.767368 -250.648467) (xy 127.817889 -250.654601) (xy 127.866773 -250.668761)
			(xy 127.912752 -250.690578) (xy 127.954636 -250.719488) (xy 127.99134 -250.754743) (xy 128.021913 -250.795429)
			(xy 128.045564 -250.840492) (xy 128.06168 -250.888766) (xy 128.069844 -250.939) (xy 128.070356 -250.964446)
			(xy 128.388884 -250.964446) (xy 128.392844 -250.915392) (xy 128.404621 -250.867608) (xy 128.423912 -250.822332)
			(xy 128.450215 -250.780736) (xy 128.48285 -250.743899) (xy 128.520971 -250.712774) (xy 128.563592 -250.688167)
			(xy 128.609608 -250.670715) (xy 128.657827 -250.660871) (xy 128.707002 -250.65889) (xy 128.755857 -250.664822)
			(xy 128.803128 -250.678514) (xy 128.84759 -250.699612) (xy 128.888093 -250.727568) (xy 128.923586 -250.76166)
			(xy 128.953151 -250.801004) (xy 128.976022 -250.844581) (xy 128.991606 -250.891262) (xy 128.999501 -250.939839)
			(xy 128.999996 -250.964446) (xy 129.318507 -250.964446) (xy 129.322602 -250.913718) (xy 129.334781 -250.864304)
			(xy 129.354729 -250.817484) (xy 129.38193 -250.77447) (xy 129.415678 -250.736376) (xy 129.4551 -250.704189)
			(xy 129.499174 -250.678743) (xy 129.54676 -250.660696) (xy 129.596624 -250.650516) (xy 129.647476 -250.648467)
			(xy 129.697997 -250.654601) (xy 129.746881 -250.668761) (xy 129.79286 -250.690578) (xy 129.834744 -250.719488)
			(xy 129.871448 -250.754743) (xy 129.902021 -250.795429) (xy 129.925672 -250.840492) (xy 129.941788 -250.888766)
			(xy 129.949952 -250.939) (xy 129.950464 -250.964446) (xy 130.268992 -250.964446) (xy 130.272952 -250.915392)
			(xy 130.284729 -250.867608) (xy 130.30402 -250.822332) (xy 130.330323 -250.780736) (xy 130.362958 -250.743899)
			(xy 130.401079 -250.712774) (xy 130.4437 -250.688167) (xy 130.489716 -250.670715) (xy 130.537935 -250.660871)
			(xy 130.58711 -250.65889) (xy 130.635965 -250.664822) (xy 130.683236 -250.678514) (xy 130.727698 -250.699612)
			(xy 130.768201 -250.727568) (xy 130.803694 -250.76166) (xy 130.833259 -250.801004) (xy 130.85613 -250.844581)
			(xy 130.871714 -250.891262) (xy 130.879609 -250.939839) (xy 130.880104 -250.964446) (xy 131.198615 -250.964446)
			(xy 131.20271 -250.913718) (xy 131.214889 -250.864304) (xy 131.234837 -250.817484) (xy 131.262038 -250.77447)
			(xy 131.295786 -250.736376) (xy 131.335208 -250.704189) (xy 131.379282 -250.678743) (xy 131.426868 -250.660696)
			(xy 131.476732 -250.650516) (xy 131.527584 -250.648467) (xy 131.578105 -250.654601) (xy 131.626989 -250.668761)
			(xy 131.672968 -250.690578) (xy 131.714852 -250.719488) (xy 131.751556 -250.754743) (xy 131.782129 -250.795429)
			(xy 131.80578 -250.840492) (xy 131.821896 -250.888766) (xy 131.83006 -250.939) (xy 131.830572 -250.964446)
			(xy 132.138415 -250.964446) (xy 132.14251 -250.913718) (xy 132.154689 -250.864304) (xy 132.174637 -250.817484)
			(xy 132.201838 -250.77447) (xy 132.235586 -250.736376) (xy 132.275008 -250.704189) (xy 132.319082 -250.678743)
			(xy 132.366668 -250.660696) (xy 132.416532 -250.650516) (xy 132.467384 -250.648467) (xy 132.517905 -250.654601)
			(xy 132.566789 -250.668761) (xy 132.612768 -250.690578) (xy 132.654652 -250.719488) (xy 132.691356 -250.754743)
			(xy 132.721929 -250.795429) (xy 132.74558 -250.840492) (xy 132.761696 -250.888766) (xy 132.76986 -250.939)
			(xy 132.770372 -250.964446) (xy 133.0889 -250.964446) (xy 133.09286 -250.915392) (xy 133.104637 -250.867608)
			(xy 133.123928 -250.822332) (xy 133.150231 -250.780736) (xy 133.182866 -250.743899) (xy 133.220987 -250.712774)
			(xy 133.263608 -250.688167) (xy 133.309624 -250.670715) (xy 133.357843 -250.660871) (xy 133.407018 -250.65889)
			(xy 133.455873 -250.664822) (xy 133.503144 -250.678514) (xy 133.547606 -250.699612) (xy 133.588109 -250.727568)
			(xy 133.623602 -250.76166) (xy 133.653167 -250.801004) (xy 133.676038 -250.844581) (xy 133.691622 -250.891262)
			(xy 133.699517 -250.939839) (xy 133.700012 -250.964446) (xy 134.018523 -250.964446) (xy 134.022618 -250.913718)
			(xy 134.034797 -250.864304) (xy 134.054745 -250.817484) (xy 134.081946 -250.77447) (xy 134.115694 -250.736376)
			(xy 134.155116 -250.704189) (xy 134.19919 -250.678743) (xy 134.246776 -250.660696) (xy 134.29664 -250.650516)
			(xy 134.347492 -250.648467) (xy 134.398013 -250.654601) (xy 134.446897 -250.668761) (xy 134.492876 -250.690578)
			(xy 134.53476 -250.719488) (xy 134.571464 -250.754743) (xy 134.602037 -250.795429) (xy 134.625688 -250.840492)
			(xy 134.641804 -250.888766) (xy 134.649968 -250.939) (xy 134.65048 -250.964446) (xy 134.969008 -250.964446)
			(xy 134.972968 -250.915392) (xy 134.984745 -250.867608) (xy 135.004036 -250.822332) (xy 135.030339 -250.780736)
			(xy 135.062974 -250.743899) (xy 135.101095 -250.712774) (xy 135.143716 -250.688167) (xy 135.189732 -250.670715)
			(xy 135.237951 -250.660871) (xy 135.287126 -250.65889) (xy 135.335981 -250.664822) (xy 135.383252 -250.678514)
			(xy 135.427714 -250.699612) (xy 135.468217 -250.727568) (xy 135.50371 -250.76166) (xy 135.533275 -250.801004)
			(xy 135.556146 -250.844581) (xy 135.57173 -250.891262) (xy 135.579625 -250.939839) (xy 135.58012 -250.964446)
			(xy 135.898631 -250.964446) (xy 135.902726 -250.913718) (xy 135.914905 -250.864304) (xy 135.934853 -250.817484)
			(xy 135.962054 -250.77447) (xy 135.995802 -250.736376) (xy 136.035224 -250.704189) (xy 136.079298 -250.678743)
			(xy 136.126884 -250.660696) (xy 136.176748 -250.650516) (xy 136.2276 -250.648467) (xy 136.278121 -250.654601)
			(xy 136.327005 -250.668761) (xy 136.372984 -250.690578) (xy 136.414868 -250.719488) (xy 136.451572 -250.754743)
			(xy 136.482145 -250.795429) (xy 136.505796 -250.840492) (xy 136.521912 -250.888766) (xy 136.530076 -250.939)
			(xy 136.530588 -250.964446) (xy 136.848862 -250.964446) (xy 136.852822 -250.915392) (xy 136.864599 -250.867608)
			(xy 136.88389 -250.822332) (xy 136.910193 -250.780736) (xy 136.942828 -250.743899) (xy 136.980949 -250.712774)
			(xy 137.02357 -250.688167) (xy 137.069586 -250.670715) (xy 137.117805 -250.660871) (xy 137.16698 -250.65889)
			(xy 137.215835 -250.664822) (xy 137.263106 -250.678514) (xy 137.307568 -250.699612) (xy 137.348071 -250.727568)
			(xy 137.383564 -250.76166) (xy 137.413129 -250.801004) (xy 137.436 -250.844581) (xy 137.451584 -250.891262)
			(xy 137.459479 -250.939839) (xy 137.459974 -250.964446) (xy 137.778485 -250.964446) (xy 137.78258 -250.913718)
			(xy 137.794759 -250.864304) (xy 137.814707 -250.817484) (xy 137.841908 -250.77447) (xy 137.875656 -250.736376)
			(xy 137.915078 -250.704189) (xy 137.959152 -250.678743) (xy 138.006738 -250.660696) (xy 138.056602 -250.650516)
			(xy 138.107454 -250.648467) (xy 138.157975 -250.654601) (xy 138.206859 -250.668761) (xy 138.252838 -250.690578)
			(xy 138.294722 -250.719488) (xy 138.331426 -250.754743) (xy 138.361999 -250.795429) (xy 138.38565 -250.840492)
			(xy 138.401766 -250.888766) (xy 138.40993 -250.939) (xy 138.410442 -250.964446) (xy 138.718539 -250.964446)
			(xy 138.722634 -250.913718) (xy 138.734813 -250.864304) (xy 138.754761 -250.817484) (xy 138.781962 -250.77447)
			(xy 138.81571 -250.736376) (xy 138.855132 -250.704189) (xy 138.899206 -250.678743) (xy 138.946792 -250.660696)
			(xy 138.996656 -250.650516) (xy 139.047508 -250.648467) (xy 139.098029 -250.654601) (xy 139.146913 -250.668761)
			(xy 139.192892 -250.690578) (xy 139.234776 -250.719488) (xy 139.27148 -250.754743) (xy 139.302053 -250.795429)
			(xy 139.325704 -250.840492) (xy 139.34182 -250.888766) (xy 139.349984 -250.939) (xy 139.350496 -250.964446)
			(xy 139.669024 -250.964446) (xy 139.672984 -250.915392) (xy 139.684761 -250.867608) (xy 139.704052 -250.822332)
			(xy 139.730355 -250.780736) (xy 139.76299 -250.743899) (xy 139.801111 -250.712774) (xy 139.843732 -250.688167)
			(xy 139.889748 -250.670715) (xy 139.937967 -250.660871) (xy 139.987142 -250.65889) (xy 140.035997 -250.664822)
			(xy 140.083268 -250.678514) (xy 140.12773 -250.699612) (xy 140.168233 -250.727568) (xy 140.203726 -250.76166)
			(xy 140.233291 -250.801004) (xy 140.256162 -250.844581) (xy 140.271746 -250.891262) (xy 140.279641 -250.939839)
			(xy 140.280136 -250.964446) (xy 140.598647 -250.964446) (xy 140.602742 -250.913718) (xy 140.614921 -250.864304)
			(xy 140.634869 -250.817484) (xy 140.66207 -250.77447) (xy 140.695818 -250.736376) (xy 140.73524 -250.704189)
			(xy 140.779314 -250.678743) (xy 140.8269 -250.660696) (xy 140.876764 -250.650516) (xy 140.927616 -250.648467)
			(xy 140.978137 -250.654601) (xy 141.027021 -250.668761) (xy 141.073 -250.690578) (xy 141.114884 -250.719488)
			(xy 141.151588 -250.754743) (xy 141.182161 -250.795429) (xy 141.205812 -250.840492) (xy 141.221928 -250.888766)
			(xy 141.230092 -250.939) (xy 141.230604 -250.964446) (xy 141.548878 -250.964446) (xy 141.552838 -250.915392)
			(xy 141.564615 -250.867608) (xy 141.583906 -250.822332) (xy 141.610209 -250.780736) (xy 141.642844 -250.743899)
			(xy 141.680965 -250.712774) (xy 141.723586 -250.688167) (xy 141.769602 -250.670715) (xy 141.817821 -250.660871)
			(xy 141.866996 -250.65889) (xy 141.915851 -250.664822) (xy 141.963122 -250.678514) (xy 142.007584 -250.699612)
			(xy 142.048087 -250.727568) (xy 142.08358 -250.76166) (xy 142.113145 -250.801004) (xy 142.136016 -250.844581)
			(xy 142.1516 -250.891262) (xy 142.159495 -250.939839) (xy 142.15999 -250.964446) (xy 142.478501 -250.964446)
			(xy 142.482596 -250.913718) (xy 142.494775 -250.864304) (xy 142.514723 -250.817484) (xy 142.541924 -250.77447)
			(xy 142.575672 -250.736376) (xy 142.615094 -250.704189) (xy 142.659168 -250.678743) (xy 142.706754 -250.660696)
			(xy 142.756618 -250.650516) (xy 142.80747 -250.648467) (xy 142.857991 -250.654601) (xy 142.906875 -250.668761)
			(xy 142.952854 -250.690578) (xy 142.994738 -250.719488) (xy 143.031442 -250.754743) (xy 143.062015 -250.795429)
			(xy 143.085666 -250.840492) (xy 143.101782 -250.888766) (xy 143.109946 -250.939) (xy 143.110458 -250.964446)
			(xy 143.428986 -250.964446) (xy 143.432946 -250.915392) (xy 143.444723 -250.867608) (xy 143.464014 -250.822332)
			(xy 143.490317 -250.780736) (xy 143.522952 -250.743899) (xy 143.561073 -250.712774) (xy 143.603694 -250.688167)
			(xy 143.64971 -250.670715) (xy 143.697929 -250.660871) (xy 143.747104 -250.65889) (xy 143.795959 -250.664822)
			(xy 143.84323 -250.678514) (xy 143.887692 -250.699612) (xy 143.928195 -250.727568) (xy 143.963688 -250.76166)
			(xy 143.993253 -250.801004) (xy 144.016124 -250.844581) (xy 144.031708 -250.891262) (xy 144.039603 -250.939839)
			(xy 144.040098 -250.964446) (xy 144.36904 -250.964446) (xy 144.373 -250.915392) (xy 144.384777 -250.867608)
			(xy 144.404068 -250.822332) (xy 144.430371 -250.780736) (xy 144.463006 -250.743899) (xy 144.501127 -250.712774)
			(xy 144.543748 -250.688167) (xy 144.589764 -250.670715) (xy 144.637983 -250.660871) (xy 144.687158 -250.65889)
			(xy 144.736013 -250.664822) (xy 144.783284 -250.678514) (xy 144.827746 -250.699612) (xy 144.868249 -250.727568)
			(xy 144.903742 -250.76166) (xy 144.933307 -250.801004) (xy 144.956178 -250.844581) (xy 144.971762 -250.891262)
			(xy 144.979657 -250.939839) (xy 144.980152 -250.964446) (xy 144.979657 -250.989053) (xy 144.971762 -251.03763)
			(xy 144.956178 -251.084311) (xy 144.933307 -251.127888) (xy 144.903742 -251.167232) (xy 144.868249 -251.201324)
			(xy 144.827746 -251.22928) (xy 144.783284 -251.250378) (xy 144.736013 -251.26407) (xy 144.687158 -251.270002)
			(xy 144.637983 -251.268021) (xy 144.589764 -251.258177) (xy 144.543748 -251.240725) (xy 144.501127 -251.216118)
			(xy 144.463006 -251.184993) (xy 144.430371 -251.148156) (xy 144.404068 -251.10656) (xy 144.384777 -251.061284)
			(xy 144.373 -251.0135) (xy 144.36904 -250.964446) (xy 144.040098 -250.964446) (xy 144.039603 -250.989053)
			(xy 144.031708 -251.03763) (xy 144.016124 -251.084311) (xy 143.993253 -251.127888) (xy 143.963688 -251.167232)
			(xy 143.928195 -251.201324) (xy 143.887692 -251.22928) (xy 143.84323 -251.250378) (xy 143.795959 -251.26407)
			(xy 143.747104 -251.270002) (xy 143.697929 -251.268021) (xy 143.64971 -251.258177) (xy 143.603694 -251.240725)
			(xy 143.561073 -251.216118) (xy 143.522952 -251.184993) (xy 143.490317 -251.148156) (xy 143.464014 -251.10656)
			(xy 143.444723 -251.061284) (xy 143.432946 -251.0135) (xy 143.428986 -250.964446) (xy 143.110458 -250.964446)
			(xy 143.109946 -250.989892) (xy 143.101782 -251.040126) (xy 143.085666 -251.0884) (xy 143.062015 -251.133463)
			(xy 143.031442 -251.174149) (xy 142.994738 -251.209404) (xy 142.952854 -251.238314) (xy 142.906875 -251.260131)
			(xy 142.857991 -251.274291) (xy 142.80747 -251.280425) (xy 142.756618 -251.278376) (xy 142.706754 -251.268196)
			(xy 142.659168 -251.250149) (xy 142.615094 -251.224703) (xy 142.575672 -251.192516) (xy 142.541924 -251.154422)
			(xy 142.514723 -251.111408) (xy 142.494775 -251.064588) (xy 142.482596 -251.015174) (xy 142.478501 -250.964446)
			(xy 142.15999 -250.964446) (xy 142.159495 -250.989053) (xy 142.1516 -251.03763) (xy 142.136016 -251.084311)
			(xy 142.113145 -251.127888) (xy 142.08358 -251.167232) (xy 142.048087 -251.201324) (xy 142.007584 -251.22928)
			(xy 141.963122 -251.250378) (xy 141.915851 -251.26407) (xy 141.866996 -251.270002) (xy 141.817821 -251.268021)
			(xy 141.769602 -251.258177) (xy 141.723586 -251.240725) (xy 141.680965 -251.216118) (xy 141.642844 -251.184993)
			(xy 141.610209 -251.148156) (xy 141.583906 -251.10656) (xy 141.564615 -251.061284) (xy 141.552838 -251.0135)
			(xy 141.548878 -250.964446) (xy 141.230604 -250.964446) (xy 141.230092 -250.989892) (xy 141.221928 -251.040126)
			(xy 141.205812 -251.0884) (xy 141.182161 -251.133463) (xy 141.151588 -251.174149) (xy 141.114884 -251.209404)
			(xy 141.073 -251.238314) (xy 141.027021 -251.260131) (xy 140.978137 -251.274291) (xy 140.927616 -251.280425)
			(xy 140.876764 -251.278376) (xy 140.8269 -251.268196) (xy 140.779314 -251.250149) (xy 140.73524 -251.224703)
			(xy 140.695818 -251.192516) (xy 140.66207 -251.154422) (xy 140.634869 -251.111408) (xy 140.614921 -251.064588)
			(xy 140.602742 -251.015174) (xy 140.598647 -250.964446) (xy 140.280136 -250.964446) (xy 140.279641 -250.989053)
			(xy 140.271746 -251.03763) (xy 140.256162 -251.084311) (xy 140.233291 -251.127888) (xy 140.203726 -251.167232)
			(xy 140.168233 -251.201324) (xy 140.12773 -251.22928) (xy 140.083268 -251.250378) (xy 140.035997 -251.26407)
			(xy 139.987142 -251.270002) (xy 139.937967 -251.268021) (xy 139.889748 -251.258177) (xy 139.843732 -251.240725)
			(xy 139.801111 -251.216118) (xy 139.76299 -251.184993) (xy 139.730355 -251.148156) (xy 139.704052 -251.10656)
			(xy 139.684761 -251.061284) (xy 139.672984 -251.0135) (xy 139.669024 -250.964446) (xy 139.350496 -250.964446)
			(xy 139.349984 -250.989892) (xy 139.34182 -251.040126) (xy 139.325704 -251.0884) (xy 139.302053 -251.133463)
			(xy 139.27148 -251.174149) (xy 139.234776 -251.209404) (xy 139.192892 -251.238314) (xy 139.146913 -251.260131)
			(xy 139.098029 -251.274291) (xy 139.047508 -251.280425) (xy 138.996656 -251.278376) (xy 138.946792 -251.268196)
			(xy 138.899206 -251.250149) (xy 138.855132 -251.224703) (xy 138.81571 -251.192516) (xy 138.781962 -251.154422)
			(xy 138.754761 -251.111408) (xy 138.734813 -251.064588) (xy 138.722634 -251.015174) (xy 138.718539 -250.964446)
			(xy 138.410442 -250.964446) (xy 138.40993 -250.989892) (xy 138.401766 -251.040126) (xy 138.38565 -251.0884)
			(xy 138.361999 -251.133463) (xy 138.331426 -251.174149) (xy 138.294722 -251.209404) (xy 138.252838 -251.238314)
			(xy 138.206859 -251.260131) (xy 138.157975 -251.274291) (xy 138.107454 -251.280425) (xy 138.056602 -251.278376)
			(xy 138.006738 -251.268196) (xy 137.959152 -251.250149) (xy 137.915078 -251.224703) (xy 137.875656 -251.192516)
			(xy 137.841908 -251.154422) (xy 137.814707 -251.111408) (xy 137.794759 -251.064588) (xy 137.78258 -251.015174)
			(xy 137.778485 -250.964446) (xy 137.459974 -250.964446) (xy 137.459479 -250.989053) (xy 137.451584 -251.03763)
			(xy 137.436 -251.084311) (xy 137.413129 -251.127888) (xy 137.383564 -251.167232) (xy 137.348071 -251.201324)
			(xy 137.307568 -251.22928) (xy 137.263106 -251.250378) (xy 137.215835 -251.26407) (xy 137.16698 -251.270002)
			(xy 137.117805 -251.268021) (xy 137.069586 -251.258177) (xy 137.02357 -251.240725) (xy 136.980949 -251.216118)
			(xy 136.942828 -251.184993) (xy 136.910193 -251.148156) (xy 136.88389 -251.10656) (xy 136.864599 -251.061284)
			(xy 136.852822 -251.0135) (xy 136.848862 -250.964446) (xy 136.530588 -250.964446) (xy 136.530076 -250.989892)
			(xy 136.521912 -251.040126) (xy 136.505796 -251.0884) (xy 136.482145 -251.133463) (xy 136.451572 -251.174149)
			(xy 136.414868 -251.209404) (xy 136.372984 -251.238314) (xy 136.327005 -251.260131) (xy 136.278121 -251.274291)
			(xy 136.2276 -251.280425) (xy 136.176748 -251.278376) (xy 136.126884 -251.268196) (xy 136.079298 -251.250149)
			(xy 136.035224 -251.224703) (xy 135.995802 -251.192516) (xy 135.962054 -251.154422) (xy 135.934853 -251.111408)
			(xy 135.914905 -251.064588) (xy 135.902726 -251.015174) (xy 135.898631 -250.964446) (xy 135.58012 -250.964446)
			(xy 135.579625 -250.989053) (xy 135.57173 -251.03763) (xy 135.556146 -251.084311) (xy 135.533275 -251.127888)
			(xy 135.50371 -251.167232) (xy 135.468217 -251.201324) (xy 135.427714 -251.22928) (xy 135.383252 -251.250378)
			(xy 135.335981 -251.26407) (xy 135.287126 -251.270002) (xy 135.237951 -251.268021) (xy 135.189732 -251.258177)
			(xy 135.143716 -251.240725) (xy 135.101095 -251.216118) (xy 135.062974 -251.184993) (xy 135.030339 -251.148156)
			(xy 135.004036 -251.10656) (xy 134.984745 -251.061284) (xy 134.972968 -251.0135) (xy 134.969008 -250.964446)
			(xy 134.65048 -250.964446) (xy 134.649968 -250.989892) (xy 134.641804 -251.040126) (xy 134.625688 -251.0884)
			(xy 134.602037 -251.133463) (xy 134.571464 -251.174149) (xy 134.53476 -251.209404) (xy 134.492876 -251.238314)
			(xy 134.446897 -251.260131) (xy 134.398013 -251.274291) (xy 134.347492 -251.280425) (xy 134.29664 -251.278376)
			(xy 134.246776 -251.268196) (xy 134.19919 -251.250149) (xy 134.155116 -251.224703) (xy 134.115694 -251.192516)
			(xy 134.081946 -251.154422) (xy 134.054745 -251.111408) (xy 134.034797 -251.064588) (xy 134.022618 -251.015174)
			(xy 134.018523 -250.964446) (xy 133.700012 -250.964446) (xy 133.699517 -250.989053) (xy 133.691622 -251.03763)
			(xy 133.676038 -251.084311) (xy 133.653167 -251.127888) (xy 133.623602 -251.167232) (xy 133.588109 -251.201324)
			(xy 133.547606 -251.22928) (xy 133.503144 -251.250378) (xy 133.455873 -251.26407) (xy 133.407018 -251.270002)
			(xy 133.357843 -251.268021) (xy 133.309624 -251.258177) (xy 133.263608 -251.240725) (xy 133.220987 -251.216118)
			(xy 133.182866 -251.184993) (xy 133.150231 -251.148156) (xy 133.123928 -251.10656) (xy 133.104637 -251.061284)
			(xy 133.09286 -251.0135) (xy 133.0889 -250.964446) (xy 132.770372 -250.964446) (xy 132.76986 -250.989892)
			(xy 132.761696 -251.040126) (xy 132.74558 -251.0884) (xy 132.721929 -251.133463) (xy 132.691356 -251.174149)
			(xy 132.654652 -251.209404) (xy 132.612768 -251.238314) (xy 132.566789 -251.260131) (xy 132.517905 -251.274291)
			(xy 132.467384 -251.280425) (xy 132.416532 -251.278376) (xy 132.366668 -251.268196) (xy 132.319082 -251.250149)
			(xy 132.275008 -251.224703) (xy 132.235586 -251.192516) (xy 132.201838 -251.154422) (xy 132.174637 -251.111408)
			(xy 132.154689 -251.064588) (xy 132.14251 -251.015174) (xy 132.138415 -250.964446) (xy 131.830572 -250.964446)
			(xy 131.83006 -250.989892) (xy 131.821896 -251.040126) (xy 131.80578 -251.0884) (xy 131.782129 -251.133463)
			(xy 131.751556 -251.174149) (xy 131.714852 -251.209404) (xy 131.672968 -251.238314) (xy 131.626989 -251.260131)
			(xy 131.578105 -251.274291) (xy 131.527584 -251.280425) (xy 131.476732 -251.278376) (xy 131.426868 -251.268196)
			(xy 131.379282 -251.250149) (xy 131.335208 -251.224703) (xy 131.295786 -251.192516) (xy 131.262038 -251.154422)
			(xy 131.234837 -251.111408) (xy 131.214889 -251.064588) (xy 131.20271 -251.015174) (xy 131.198615 -250.964446)
			(xy 130.880104 -250.964446) (xy 130.879609 -250.989053) (xy 130.871714 -251.03763) (xy 130.85613 -251.084311)
			(xy 130.833259 -251.127888) (xy 130.803694 -251.167232) (xy 130.768201 -251.201324) (xy 130.727698 -251.22928)
			(xy 130.683236 -251.250378) (xy 130.635965 -251.26407) (xy 130.58711 -251.270002) (xy 130.537935 -251.268021)
			(xy 130.489716 -251.258177) (xy 130.4437 -251.240725) (xy 130.401079 -251.216118) (xy 130.362958 -251.184993)
			(xy 130.330323 -251.148156) (xy 130.30402 -251.10656) (xy 130.284729 -251.061284) (xy 130.272952 -251.0135)
			(xy 130.268992 -250.964446) (xy 129.950464 -250.964446) (xy 129.949952 -250.989892) (xy 129.941788 -251.040126)
			(xy 129.925672 -251.0884) (xy 129.902021 -251.133463) (xy 129.871448 -251.174149) (xy 129.834744 -251.209404)
			(xy 129.79286 -251.238314) (xy 129.746881 -251.260131) (xy 129.697997 -251.274291) (xy 129.647476 -251.280425)
			(xy 129.596624 -251.278376) (xy 129.54676 -251.268196) (xy 129.499174 -251.250149) (xy 129.4551 -251.224703)
			(xy 129.415678 -251.192516) (xy 129.38193 -251.154422) (xy 129.354729 -251.111408) (xy 129.334781 -251.064588)
			(xy 129.322602 -251.015174) (xy 129.318507 -250.964446) (xy 128.999996 -250.964446) (xy 128.999501 -250.989053)
			(xy 128.991606 -251.03763) (xy 128.976022 -251.084311) (xy 128.953151 -251.127888) (xy 128.923586 -251.167232)
			(xy 128.888093 -251.201324) (xy 128.84759 -251.22928) (xy 128.803128 -251.250378) (xy 128.755857 -251.26407)
			(xy 128.707002 -251.270002) (xy 128.657827 -251.268021) (xy 128.609608 -251.258177) (xy 128.563592 -251.240725)
			(xy 128.520971 -251.216118) (xy 128.48285 -251.184993) (xy 128.450215 -251.148156) (xy 128.423912 -251.10656)
			(xy 128.404621 -251.061284) (xy 128.392844 -251.0135) (xy 128.388884 -250.964446) (xy 128.070356 -250.964446)
			(xy 128.069844 -250.989892) (xy 128.06168 -251.040126) (xy 128.045564 -251.0884) (xy 128.021913 -251.133463)
			(xy 127.99134 -251.174149) (xy 127.954636 -251.209404) (xy 127.912752 -251.238314) (xy 127.866773 -251.260131)
			(xy 127.817889 -251.274291) (xy 127.767368 -251.280425) (xy 127.716516 -251.278376) (xy 127.666652 -251.268196)
			(xy 127.619066 -251.250149) (xy 127.574992 -251.224703) (xy 127.53557 -251.192516) (xy 127.501822 -251.154422)
			(xy 127.474621 -251.111408) (xy 127.454673 -251.064588) (xy 127.442494 -251.015174) (xy 127.438399 -250.964446)
			(xy 127.120142 -250.964446) (xy 127.119668 -250.988436) (xy 127.112156 -251.035824) (xy 127.097325 -251.081454)
			(xy 127.07554 -251.124203) (xy 127.047336 -251.163018) (xy 127.013409 -251.196944) (xy 126.974593 -251.225146)
			(xy 126.931843 -251.24693) (xy 126.886212 -251.261759) (xy 126.838824 -251.269269) (xy 126.814834 -251.269754)
			(xy 126.790064 -251.26925) (xy 126.74118 -251.261205) (xy 126.717552 -251.253752) (xy 126.703836 -251.24918)
			(xy 126.675896 -251.255784) (xy 126.53772 -251.39396) (xy 126.530693 -251.401762) (xy 126.523083 -251.421307)
			(xy 126.522988 -251.431806) (xy 126.525782 -251.506228) (xy 126.52669 -251.516616) (xy 126.535739 -251.535378)
			(xy 126.543308 -251.54255) (xy 126.543562 -251.542804) (xy 126.543816 -251.543058) (xy 126.563375 -251.560616)
			(xy 126.596751 -251.601212) (xy 126.622687 -251.646922) (xy 126.640418 -251.696396) (xy 126.649421 -251.748174)
			(xy 126.649988 -251.774452) (xy 127.908553 -251.774452) (xy 127.912648 -251.723724) (xy 127.924827 -251.67431)
			(xy 127.944775 -251.62749) (xy 127.971976 -251.584476) (xy 128.005724 -251.546382) (xy 128.045146 -251.514195)
			(xy 128.08922 -251.488749) (xy 128.136806 -251.470702) (xy 128.18667 -251.460522) (xy 128.237522 -251.458473)
			(xy 128.288043 -251.464607) (xy 128.336927 -251.478767) (xy 128.382906 -251.500584) (xy 128.42479 -251.529494)
			(xy 128.461494 -251.564749) (xy 128.492067 -251.605435) (xy 128.515718 -251.650498) (xy 128.531834 -251.698772)
			(xy 128.539998 -251.749006) (xy 128.54051 -251.774452) (xy 128.859038 -251.774452) (xy 128.862998 -251.725398)
			(xy 128.874775 -251.677614) (xy 128.894066 -251.632338) (xy 128.920369 -251.590742) (xy 128.953004 -251.553905)
			(xy 128.991125 -251.52278) (xy 129.033746 -251.498173) (xy 129.079762 -251.480721) (xy 129.127981 -251.470877)
			(xy 129.177156 -251.468896) (xy 129.226011 -251.474828) (xy 129.273282 -251.48852) (xy 129.317744 -251.509618)
			(xy 129.358247 -251.537574) (xy 129.39374 -251.571666) (xy 129.423305 -251.61101) (xy 129.446176 -251.654587)
			(xy 129.46176 -251.701268) (xy 129.469655 -251.749845) (xy 129.47015 -251.774452) (xy 130.728461 -251.774452)
			(xy 130.732556 -251.723724) (xy 130.744735 -251.67431) (xy 130.764683 -251.62749) (xy 130.791884 -251.584476)
			(xy 130.825632 -251.546382) (xy 130.865054 -251.514195) (xy 130.909128 -251.488749) (xy 130.956714 -251.470702)
			(xy 131.006578 -251.460522) (xy 131.05743 -251.458473) (xy 131.107951 -251.464607) (xy 131.156835 -251.478767)
			(xy 131.202814 -251.500584) (xy 131.244698 -251.529494) (xy 131.281402 -251.564749) (xy 131.311975 -251.605435)
			(xy 131.335626 -251.650498) (xy 131.351742 -251.698772) (xy 131.359906 -251.749006) (xy 131.360418 -251.774452)
			(xy 131.678946 -251.774452) (xy 131.682906 -251.725398) (xy 131.694683 -251.677614) (xy 131.713974 -251.632338)
			(xy 131.740277 -251.590742) (xy 131.772912 -251.553905) (xy 131.811033 -251.52278) (xy 131.853654 -251.498173)
			(xy 131.89967 -251.480721) (xy 131.947889 -251.470877) (xy 131.997064 -251.468896) (xy 132.045919 -251.474828)
			(xy 132.09319 -251.48852) (xy 132.137652 -251.509618) (xy 132.178155 -251.537574) (xy 132.213648 -251.571666)
			(xy 132.243213 -251.61101) (xy 132.266084 -251.654587) (xy 132.281668 -251.701268) (xy 132.289563 -251.749845)
			(xy 132.290058 -251.774452) (xy 132.619 -251.774452) (xy 132.62296 -251.725398) (xy 132.634737 -251.677614)
			(xy 132.654028 -251.632338) (xy 132.680331 -251.590742) (xy 132.712966 -251.553905) (xy 132.751087 -251.52278)
			(xy 132.793708 -251.498173) (xy 132.839724 -251.480721) (xy 132.887943 -251.470877) (xy 132.937118 -251.468896)
			(xy 132.985973 -251.474828) (xy 133.033244 -251.48852) (xy 133.077706 -251.509618) (xy 133.118209 -251.537574)
			(xy 133.153702 -251.571666) (xy 133.183267 -251.61101) (xy 133.206138 -251.654587) (xy 133.221722 -251.701268)
			(xy 133.229617 -251.749845) (xy 133.230112 -251.774452) (xy 133.559054 -251.774452) (xy 133.563014 -251.725398)
			(xy 133.574791 -251.677614) (xy 133.594082 -251.632338) (xy 133.620385 -251.590742) (xy 133.65302 -251.553905)
			(xy 133.691141 -251.52278) (xy 133.733762 -251.498173) (xy 133.779778 -251.480721) (xy 133.827997 -251.470877)
			(xy 133.877172 -251.468896) (xy 133.926027 -251.474828) (xy 133.973298 -251.48852) (xy 134.01776 -251.509618)
			(xy 134.058263 -251.537574) (xy 134.093756 -251.571666) (xy 134.123321 -251.61101) (xy 134.146192 -251.654587)
			(xy 134.161776 -251.701268) (xy 134.169671 -251.749845) (xy 134.170166 -251.774452) (xy 134.488423 -251.774452)
			(xy 134.492518 -251.723724) (xy 134.504697 -251.67431) (xy 134.524645 -251.62749) (xy 134.551846 -251.584476)
			(xy 134.585594 -251.546382) (xy 134.625016 -251.514195) (xy 134.66909 -251.488749) (xy 134.716676 -251.470702)
			(xy 134.76654 -251.460522) (xy 134.817392 -251.458473) (xy 134.867913 -251.464607) (xy 134.916797 -251.478767)
			(xy 134.962776 -251.500584) (xy 135.00466 -251.529494) (xy 135.041364 -251.564749) (xy 135.071937 -251.605435)
			(xy 135.095588 -251.650498) (xy 135.111704 -251.698772) (xy 135.119868 -251.749006) (xy 135.12038 -251.774452)
			(xy 135.438908 -251.774452) (xy 135.442868 -251.725398) (xy 135.454645 -251.677614) (xy 135.473936 -251.632338)
			(xy 135.500239 -251.590742) (xy 135.532874 -251.553905) (xy 135.570995 -251.52278) (xy 135.613616 -251.498173)
			(xy 135.659632 -251.480721) (xy 135.707851 -251.470877) (xy 135.757026 -251.468896) (xy 135.805881 -251.474828)
			(xy 135.853152 -251.48852) (xy 135.897614 -251.509618) (xy 135.938117 -251.537574) (xy 135.97361 -251.571666)
			(xy 136.003175 -251.61101) (xy 136.026046 -251.654587) (xy 136.04163 -251.701268) (xy 136.049525 -251.749845)
			(xy 136.05002 -251.774452) (xy 137.308585 -251.774452) (xy 137.31268 -251.723724) (xy 137.324859 -251.67431)
			(xy 137.344807 -251.62749) (xy 137.372008 -251.584476) (xy 137.405756 -251.546382) (xy 137.445178 -251.514195)
			(xy 137.489252 -251.488749) (xy 137.536838 -251.470702) (xy 137.586702 -251.460522) (xy 137.637554 -251.458473)
			(xy 137.688075 -251.464607) (xy 137.736959 -251.478767) (xy 137.782938 -251.500584) (xy 137.824822 -251.529494)
			(xy 137.861526 -251.564749) (xy 137.892099 -251.605435) (xy 137.91575 -251.650498) (xy 137.931866 -251.698772)
			(xy 137.94003 -251.749006) (xy 137.940542 -251.774452) (xy 138.25907 -251.774452) (xy 138.26303 -251.725398)
			(xy 138.274807 -251.677614) (xy 138.294098 -251.632338) (xy 138.320401 -251.590742) (xy 138.353036 -251.553905)
			(xy 138.391157 -251.52278) (xy 138.433778 -251.498173) (xy 138.479794 -251.480721) (xy 138.528013 -251.470877)
			(xy 138.577188 -251.468896) (xy 138.626043 -251.474828) (xy 138.673314 -251.48852) (xy 138.717776 -251.509618)
			(xy 138.758279 -251.537574) (xy 138.793772 -251.571666) (xy 138.823337 -251.61101) (xy 138.846208 -251.654587)
			(xy 138.861792 -251.701268) (xy 138.869687 -251.749845) (xy 138.870182 -251.774452) (xy 139.19887 -251.774452)
			(xy 139.20283 -251.725398) (xy 139.214607 -251.677614) (xy 139.233898 -251.632338) (xy 139.260201 -251.590742)
			(xy 139.292836 -251.553905) (xy 139.330957 -251.52278) (xy 139.373578 -251.498173) (xy 139.419594 -251.480721)
			(xy 139.467813 -251.470877) (xy 139.516988 -251.468896) (xy 139.565843 -251.474828) (xy 139.613114 -251.48852)
			(xy 139.657576 -251.509618) (xy 139.698079 -251.537574) (xy 139.733572 -251.571666) (xy 139.763137 -251.61101)
			(xy 139.786008 -251.654587) (xy 139.801592 -251.701268) (xy 139.809487 -251.749845) (xy 139.809982 -251.774452)
			(xy 140.138924 -251.774452) (xy 140.142884 -251.725398) (xy 140.154661 -251.677614) (xy 140.173952 -251.632338)
			(xy 140.200255 -251.590742) (xy 140.23289 -251.553905) (xy 140.271011 -251.52278) (xy 140.313632 -251.498173)
			(xy 140.359648 -251.480721) (xy 140.407867 -251.470877) (xy 140.457042 -251.468896) (xy 140.505897 -251.474828)
			(xy 140.553168 -251.48852) (xy 140.59763 -251.509618) (xy 140.638133 -251.537574) (xy 140.673626 -251.571666)
			(xy 140.703191 -251.61101) (xy 140.726062 -251.654587) (xy 140.741646 -251.701268) (xy 140.749541 -251.749845)
			(xy 140.750036 -251.774452) (xy 141.068547 -251.774452) (xy 141.072642 -251.723724) (xy 141.084821 -251.67431)
			(xy 141.104769 -251.62749) (xy 141.13197 -251.584476) (xy 141.165718 -251.546382) (xy 141.20514 -251.514195)
			(xy 141.249214 -251.488749) (xy 141.2968 -251.470702) (xy 141.346664 -251.460522) (xy 141.397516 -251.458473)
			(xy 141.448037 -251.464607) (xy 141.496921 -251.478767) (xy 141.5429 -251.500584) (xy 141.584784 -251.529494)
			(xy 141.621488 -251.564749) (xy 141.652061 -251.605435) (xy 141.675712 -251.650498) (xy 141.691828 -251.698772)
			(xy 141.699992 -251.749006) (xy 141.700504 -251.774452) (xy 142.019032 -251.774452) (xy 142.022992 -251.725398)
			(xy 142.034769 -251.677614) (xy 142.05406 -251.632338) (xy 142.080363 -251.590742) (xy 142.112998 -251.553905)
			(xy 142.151119 -251.52278) (xy 142.19374 -251.498173) (xy 142.239756 -251.480721) (xy 142.287975 -251.470877)
			(xy 142.33715 -251.468896) (xy 142.386005 -251.474828) (xy 142.433276 -251.48852) (xy 142.477738 -251.509618)
			(xy 142.518241 -251.537574) (xy 142.553734 -251.571666) (xy 142.583299 -251.61101) (xy 142.60617 -251.654587)
			(xy 142.621754 -251.701268) (xy 142.629649 -251.749845) (xy 142.630144 -251.774452) (xy 144.83894 -251.774452)
			(xy 144.8429 -251.725398) (xy 144.854677 -251.677614) (xy 144.873968 -251.632338) (xy 144.900271 -251.590742)
			(xy 144.932906 -251.553905) (xy 144.971027 -251.52278) (xy 145.013648 -251.498173) (xy 145.059664 -251.480721)
			(xy 145.107883 -251.470877) (xy 145.157058 -251.468896) (xy 145.205913 -251.474828) (xy 145.253184 -251.48852)
			(xy 145.297646 -251.509618) (xy 145.338149 -251.537574) (xy 145.373642 -251.571666) (xy 145.403207 -251.61101)
			(xy 145.426078 -251.654587) (xy 145.441662 -251.701268) (xy 145.449557 -251.749845) (xy 145.450052 -251.774452)
			(xy 145.449557 -251.799059) (xy 145.441662 -251.847636) (xy 145.426078 -251.894317) (xy 145.403207 -251.937894)
			(xy 145.373642 -251.977238) (xy 145.338149 -252.01133) (xy 145.297646 -252.039286) (xy 145.253184 -252.060384)
			(xy 145.205913 -252.074076) (xy 145.157058 -252.080008) (xy 145.107883 -252.078027) (xy 145.059664 -252.068183)
			(xy 145.013648 -252.050731) (xy 144.971027 -252.026124) (xy 144.932906 -251.994999) (xy 144.900271 -251.958162)
			(xy 144.873968 -251.916566) (xy 144.854677 -251.87129) (xy 144.8429 -251.823506) (xy 144.83894 -251.774452)
			(xy 142.630144 -251.774452) (xy 142.629649 -251.799059) (xy 142.621754 -251.847636) (xy 142.60617 -251.894317)
			(xy 142.583299 -251.937894) (xy 142.553734 -251.977238) (xy 142.518241 -252.01133) (xy 142.477738 -252.039286)
			(xy 142.433276 -252.060384) (xy 142.386005 -252.074076) (xy 142.33715 -252.080008) (xy 142.287975 -252.078027)
			(xy 142.239756 -252.068183) (xy 142.19374 -252.050731) (xy 142.151119 -252.026124) (xy 142.112998 -251.994999)
			(xy 142.080363 -251.958162) (xy 142.05406 -251.916566) (xy 142.034769 -251.87129) (xy 142.022992 -251.823506)
			(xy 142.019032 -251.774452) (xy 141.700504 -251.774452) (xy 141.699992 -251.799898) (xy 141.691828 -251.850132)
			(xy 141.675712 -251.898406) (xy 141.652061 -251.943469) (xy 141.621488 -251.984155) (xy 141.584784 -252.01941)
			(xy 141.5429 -252.04832) (xy 141.496921 -252.070137) (xy 141.448037 -252.084297) (xy 141.397516 -252.090431)
			(xy 141.346664 -252.088382) (xy 141.2968 -252.078202) (xy 141.249214 -252.060155) (xy 141.20514 -252.034709)
			(xy 141.165718 -252.002522) (xy 141.13197 -251.964428) (xy 141.104769 -251.921414) (xy 141.084821 -251.874594)
			(xy 141.072642 -251.82518) (xy 141.068547 -251.774452) (xy 140.750036 -251.774452) (xy 140.749541 -251.799059)
			(xy 140.741646 -251.847636) (xy 140.726062 -251.894317) (xy 140.703191 -251.937894) (xy 140.673626 -251.977238)
			(xy 140.638133 -252.01133) (xy 140.59763 -252.039286) (xy 140.553168 -252.060384) (xy 140.505897 -252.074076)
			(xy 140.457042 -252.080008) (xy 140.407867 -252.078027) (xy 140.359648 -252.068183) (xy 140.313632 -252.050731)
			(xy 140.271011 -252.026124) (xy 140.23289 -251.994999) (xy 140.200255 -251.958162) (xy 140.173952 -251.916566)
			(xy 140.154661 -251.87129) (xy 140.142884 -251.823506) (xy 140.138924 -251.774452) (xy 139.809982 -251.774452)
			(xy 139.809487 -251.799059) (xy 139.801592 -251.847636) (xy 139.786008 -251.894317) (xy 139.763137 -251.937894)
			(xy 139.733572 -251.977238) (xy 139.698079 -252.01133) (xy 139.657576 -252.039286) (xy 139.613114 -252.060384)
			(xy 139.565843 -252.074076) (xy 139.516988 -252.080008) (xy 139.467813 -252.078027) (xy 139.419594 -252.068183)
			(xy 139.373578 -252.050731) (xy 139.330957 -252.026124) (xy 139.292836 -251.994999) (xy 139.260201 -251.958162)
			(xy 139.233898 -251.916566) (xy 139.214607 -251.87129) (xy 139.20283 -251.823506) (xy 139.19887 -251.774452)
			(xy 138.870182 -251.774452) (xy 138.869687 -251.799059) (xy 138.861792 -251.847636) (xy 138.846208 -251.894317)
			(xy 138.823337 -251.937894) (xy 138.793772 -251.977238) (xy 138.758279 -252.01133) (xy 138.717776 -252.039286)
			(xy 138.673314 -252.060384) (xy 138.626043 -252.074076) (xy 138.577188 -252.080008) (xy 138.528013 -252.078027)
			(xy 138.479794 -252.068183) (xy 138.433778 -252.050731) (xy 138.391157 -252.026124) (xy 138.353036 -251.994999)
			(xy 138.320401 -251.958162) (xy 138.294098 -251.916566) (xy 138.274807 -251.87129) (xy 138.26303 -251.823506)
			(xy 138.25907 -251.774452) (xy 137.940542 -251.774452) (xy 137.94003 -251.799898) (xy 137.931866 -251.850132)
			(xy 137.91575 -251.898406) (xy 137.892099 -251.943469) (xy 137.861526 -251.984155) (xy 137.824822 -252.01941)
			(xy 137.782938 -252.04832) (xy 137.736959 -252.070137) (xy 137.688075 -252.084297) (xy 137.637554 -252.090431)
			(xy 137.586702 -252.088382) (xy 137.536838 -252.078202) (xy 137.489252 -252.060155) (xy 137.445178 -252.034709)
			(xy 137.405756 -252.002522) (xy 137.372008 -251.964428) (xy 137.344807 -251.921414) (xy 137.324859 -251.874594)
			(xy 137.31268 -251.82518) (xy 137.308585 -251.774452) (xy 136.05002 -251.774452) (xy 136.049525 -251.799059)
			(xy 136.04163 -251.847636) (xy 136.026046 -251.894317) (xy 136.003175 -251.937894) (xy 135.97361 -251.977238)
			(xy 135.938117 -252.01133) (xy 135.897614 -252.039286) (xy 135.853152 -252.060384) (xy 135.805881 -252.074076)
			(xy 135.757026 -252.080008) (xy 135.707851 -252.078027) (xy 135.659632 -252.068183) (xy 135.613616 -252.050731)
			(xy 135.570995 -252.026124) (xy 135.532874 -251.994999) (xy 135.500239 -251.958162) (xy 135.473936 -251.916566)
			(xy 135.454645 -251.87129) (xy 135.442868 -251.823506) (xy 135.438908 -251.774452) (xy 135.12038 -251.774452)
			(xy 135.119868 -251.799898) (xy 135.111704 -251.850132) (xy 135.095588 -251.898406) (xy 135.071937 -251.943469)
			(xy 135.041364 -251.984155) (xy 135.00466 -252.01941) (xy 134.962776 -252.04832) (xy 134.916797 -252.070137)
			(xy 134.867913 -252.084297) (xy 134.817392 -252.090431) (xy 134.76654 -252.088382) (xy 134.716676 -252.078202)
			(xy 134.66909 -252.060155) (xy 134.625016 -252.034709) (xy 134.585594 -252.002522) (xy 134.551846 -251.964428)
			(xy 134.524645 -251.921414) (xy 134.504697 -251.874594) (xy 134.492518 -251.82518) (xy 134.488423 -251.774452)
			(xy 134.170166 -251.774452) (xy 134.169671 -251.799059) (xy 134.161776 -251.847636) (xy 134.146192 -251.894317)
			(xy 134.123321 -251.937894) (xy 134.093756 -251.977238) (xy 134.058263 -252.01133) (xy 134.01776 -252.039286)
			(xy 133.973298 -252.060384) (xy 133.926027 -252.074076) (xy 133.877172 -252.080008) (xy 133.827997 -252.078027)
			(xy 133.779778 -252.068183) (xy 133.733762 -252.050731) (xy 133.691141 -252.026124) (xy 133.65302 -251.994999)
			(xy 133.620385 -251.958162) (xy 133.594082 -251.916566) (xy 133.574791 -251.87129) (xy 133.563014 -251.823506)
			(xy 133.559054 -251.774452) (xy 133.230112 -251.774452) (xy 133.229617 -251.799059) (xy 133.221722 -251.847636)
			(xy 133.206138 -251.894317) (xy 133.183267 -251.937894) (xy 133.153702 -251.977238) (xy 133.118209 -252.01133)
			(xy 133.077706 -252.039286) (xy 133.033244 -252.060384) (xy 132.985973 -252.074076) (xy 132.937118 -252.080008)
			(xy 132.887943 -252.078027) (xy 132.839724 -252.068183) (xy 132.793708 -252.050731) (xy 132.751087 -252.026124)
			(xy 132.712966 -251.994999) (xy 132.680331 -251.958162) (xy 132.654028 -251.916566) (xy 132.634737 -251.87129)
			(xy 132.62296 -251.823506) (xy 132.619 -251.774452) (xy 132.290058 -251.774452) (xy 132.289563 -251.799059)
			(xy 132.281668 -251.847636) (xy 132.266084 -251.894317) (xy 132.243213 -251.937894) (xy 132.213648 -251.977238)
			(xy 132.178155 -252.01133) (xy 132.137652 -252.039286) (xy 132.09319 -252.060384) (xy 132.045919 -252.074076)
			(xy 131.997064 -252.080008) (xy 131.947889 -252.078027) (xy 131.89967 -252.068183) (xy 131.853654 -252.050731)
			(xy 131.811033 -252.026124) (xy 131.772912 -251.994999) (xy 131.740277 -251.958162) (xy 131.713974 -251.916566)
			(xy 131.694683 -251.87129) (xy 131.682906 -251.823506) (xy 131.678946 -251.774452) (xy 131.360418 -251.774452)
			(xy 131.359906 -251.799898) (xy 131.351742 -251.850132) (xy 131.335626 -251.898406) (xy 131.311975 -251.943469)
			(xy 131.281402 -251.984155) (xy 131.244698 -252.01941) (xy 131.202814 -252.04832) (xy 131.156835 -252.070137)
			(xy 131.107951 -252.084297) (xy 131.05743 -252.090431) (xy 131.006578 -252.088382) (xy 130.956714 -252.078202)
			(xy 130.909128 -252.060155) (xy 130.865054 -252.034709) (xy 130.825632 -252.002522) (xy 130.791884 -251.964428)
			(xy 130.764683 -251.921414) (xy 130.744735 -251.874594) (xy 130.732556 -251.82518) (xy 130.728461 -251.774452)
			(xy 129.47015 -251.774452) (xy 129.469655 -251.799059) (xy 129.46176 -251.847636) (xy 129.446176 -251.894317)
			(xy 129.423305 -251.937894) (xy 129.39374 -251.977238) (xy 129.358247 -252.01133) (xy 129.317744 -252.039286)
			(xy 129.273282 -252.060384) (xy 129.226011 -252.074076) (xy 129.177156 -252.080008) (xy 129.127981 -252.078027)
			(xy 129.079762 -252.068183) (xy 129.033746 -252.050731) (xy 128.991125 -252.026124) (xy 128.953004 -251.994999)
			(xy 128.920369 -251.958162) (xy 128.894066 -251.916566) (xy 128.874775 -251.87129) (xy 128.862998 -251.823506)
			(xy 128.859038 -251.774452) (xy 128.54051 -251.774452) (xy 128.539998 -251.799898) (xy 128.531834 -251.850132)
			(xy 128.515718 -251.898406) (xy 128.492067 -251.943469) (xy 128.461494 -251.984155) (xy 128.42479 -252.01941)
			(xy 128.382906 -252.04832) (xy 128.336927 -252.070137) (xy 128.288043 -252.084297) (xy 128.237522 -252.090431)
			(xy 128.18667 -252.088382) (xy 128.136806 -252.078202) (xy 128.08922 -252.060155) (xy 128.045146 -252.034709)
			(xy 128.005724 -252.002522) (xy 127.971976 -251.964428) (xy 127.944775 -251.921414) (xy 127.924827 -251.874594)
			(xy 127.912648 -251.82518) (xy 127.908553 -251.774452) (xy 126.649988 -251.774452) (xy 126.649466 -251.799707)
			(xy 126.641153 -251.849529) (xy 126.624752 -251.897303) (xy 126.600711 -251.941726) (xy 126.569687 -251.981586)
			(xy 126.532525 -252.015796) (xy 126.490239 -252.043422) (xy 126.443983 -252.063712) (xy 126.395018 -252.076112)
			(xy 126.34468 -252.080283) (xy 126.294342 -252.076112) (xy 126.245377 -252.063712) (xy 126.199121 -252.043422)
			(xy 126.156835 -252.015796) (xy 126.119673 -251.981586) (xy 126.088649 -251.941726) (xy 126.064608 -251.897303)
			(xy 126.048207 -251.849529) (xy 126.039894 -251.799707) (xy 126.039372 -251.774452) (xy 126.039501 -251.761625)
			(xy 126.041659 -251.736063) (xy 126.04369 -251.723398) (xy 126.045722 -251.711968) (xy 126.03988 -251.690632)
			(xy 125.982222 -251.622814) (xy 125.974633 -251.614678) (xy 125.954473 -251.605329) (xy 125.94336 -251.60478)
			(xy 124.866146 -251.60478) (xy 124.855041 -251.605347) (xy 124.834899 -251.614709) (xy 124.827284 -251.622814)
			(xy 124.769626 -251.690632) (xy 124.763784 -251.711968) (xy 124.765816 -251.723398) (xy 124.767826 -251.736066)
			(xy 124.769988 -251.761626) (xy 124.770134 -251.774452) (xy 124.769612 -251.799707) (xy 124.761299 -251.849529)
			(xy 124.744898 -251.897303) (xy 124.720857 -251.941726) (xy 124.689833 -251.981586) (xy 124.652671 -252.015796)
			(xy 124.610385 -252.043422) (xy 124.564129 -252.063712) (xy 124.515164 -252.076112) (xy 124.464826 -252.080283)
			(xy 124.414488 -252.076112) (xy 124.365523 -252.063712) (xy 124.319267 -252.043422) (xy 124.276981 -252.015796)
			(xy 124.239819 -251.981586) (xy 124.208795 -251.941726) (xy 124.184754 -251.897303) (xy 124.168353 -251.849529)
			(xy 124.16004 -251.799707) (xy 124.159518 -251.774452) (xy 124.159647 -251.761625) (xy 124.161805 -251.736063)
			(xy 124.163836 -251.723398) (xy 124.165868 -251.711968) (xy 124.160026 -251.690632) (xy 124.102368 -251.622814)
			(xy 124.094782 -251.614671) (xy 124.074622 -251.605303) (xy 124.063506 -251.60478) (xy 122.986038 -251.60478)
			(xy 122.974934 -251.605348) (xy 122.954794 -251.614713) (xy 122.947176 -251.622814) (xy 122.889518 -251.690632)
			(xy 122.883676 -251.711968) (xy 122.885708 -251.723398) (xy 122.887718 -251.736066) (xy 122.88988 -251.761626)
			(xy 122.890026 -251.774452) (xy 122.889504 -251.799707) (xy 122.881191 -251.849529) (xy 122.86479 -251.897303)
			(xy 122.840749 -251.941726) (xy 122.809725 -251.981586) (xy 122.772563 -252.015796) (xy 122.730277 -252.043422)
			(xy 122.684021 -252.063712) (xy 122.635056 -252.076112) (xy 122.584718 -252.080283) (xy 122.53438 -252.076112)
			(xy 122.485415 -252.063712) (xy 122.439159 -252.043422) (xy 122.396873 -252.015796) (xy 122.359711 -251.981586)
			(xy 122.328687 -251.941726) (xy 122.304646 -251.897303) (xy 122.288245 -251.849529) (xy 122.279932 -251.799707)
			(xy 122.27941 -251.774452) (xy 122.279539 -251.761625) (xy 122.281697 -251.736063) (xy 122.283728 -251.723398)
			(xy 122.28576 -251.711968) (xy 122.279918 -251.690632) (xy 122.22226 -251.622814) (xy 122.214673 -251.614672)
			(xy 122.194513 -251.605308) (xy 122.183398 -251.60478) (xy 121.10593 -251.60478) (xy 121.094826 -251.60535)
			(xy 121.07469 -251.614716) (xy 121.067068 -251.622814) (xy 121.00941 -251.690632) (xy 121.003568 -251.711968)
			(xy 121.0056 -251.723398) (xy 121.00761 -251.736066) (xy 121.009772 -251.761626) (xy 121.009918 -251.774452)
			(xy 121.009396 -251.799707) (xy 121.001083 -251.849529) (xy 120.984682 -251.897303) (xy 120.960641 -251.941726)
			(xy 120.929617 -251.981586) (xy 120.892455 -252.015796) (xy 120.850169 -252.043422) (xy 120.803913 -252.063712)
			(xy 120.754948 -252.076112) (xy 120.70461 -252.080283) (xy 120.654272 -252.076112) (xy 120.605307 -252.063712)
			(xy 120.559051 -252.043422) (xy 120.516765 -252.015796) (xy 120.479603 -251.981586) (xy 120.448579 -251.941726)
			(xy 120.424538 -251.897303) (xy 120.408137 -251.849529) (xy 120.399824 -251.799707) (xy 120.399302 -251.774452)
			(xy 120.399431 -251.761625) (xy 120.401589 -251.736063) (xy 120.40362 -251.723398) (xy 120.405652 -251.711968)
			(xy 120.39981 -251.690632) (xy 120.342152 -251.622814) (xy 120.334565 -251.614673) (xy 120.314405 -251.605312)
			(xy 120.30329 -251.60478) (xy 119.226076 -251.60478) (xy 119.214968 -251.605341) (xy 119.194817 -251.614696)
			(xy 119.187214 -251.622814) (xy 119.129556 -251.690632) (xy 119.123714 -251.711968) (xy 119.125746 -251.723398)
			(xy 119.127756 -251.736066) (xy 119.129917 -251.761626) (xy 119.130064 -251.774452) (xy 119.129542 -251.799707)
			(xy 119.121229 -251.849529) (xy 119.104828 -251.897303) (xy 119.080787 -251.941726) (xy 119.049763 -251.981586)
			(xy 119.012601 -252.015796) (xy 118.970315 -252.043422) (xy 118.924059 -252.063712) (xy 118.875094 -252.076112)
			(xy 118.824756 -252.080283) (xy 118.774418 -252.076112) (xy 118.725453 -252.063712) (xy 118.679197 -252.043422)
			(xy 118.636911 -252.015796) (xy 118.599749 -251.981586) (xy 118.568725 -251.941726) (xy 118.544684 -251.897303)
			(xy 118.528283 -251.849529) (xy 118.51997 -251.799707) (xy 118.519448 -251.774452) (xy 118.519577 -251.761625)
			(xy 118.521735 -251.736063) (xy 118.523766 -251.723398) (xy 118.525798 -251.711968) (xy 118.519956 -251.690632)
			(xy 118.462298 -251.622814) (xy 118.454714 -251.614666) (xy 118.434554 -251.605286) (xy 118.423436 -251.60478)
			(xy 117.345968 -251.60478) (xy 117.334861 -251.605342) (xy 117.314712 -251.614699) (xy 117.307106 -251.622814)
			(xy 117.249448 -251.690632) (xy 117.243606 -251.711968) (xy 117.245638 -251.723398) (xy 117.247648 -251.736066)
			(xy 117.249809 -251.761626) (xy 117.249956 -251.774452) (xy 117.249434 -251.799707) (xy 117.241121 -251.849529)
			(xy 117.22472 -251.897303) (xy 117.200679 -251.941726) (xy 117.169655 -251.981586) (xy 117.132493 -252.015796)
			(xy 117.090207 -252.043422) (xy 117.043951 -252.063712) (xy 116.994986 -252.076112) (xy 116.944648 -252.080283)
			(xy 116.89431 -252.076112) (xy 116.845345 -252.063712) (xy 116.799089 -252.043422) (xy 116.756803 -252.015796)
			(xy 116.719641 -251.981586) (xy 116.688617 -251.941726) (xy 116.664576 -251.897303) (xy 116.648175 -251.849529)
			(xy 116.639862 -251.799707) (xy 116.63934 -251.774452) (xy 116.639469 -251.761625) (xy 116.641627 -251.736063)
			(xy 116.643658 -251.723398) (xy 116.64569 -251.711968) (xy 116.639848 -251.690632) (xy 116.58219 -251.622814)
			(xy 116.574605 -251.614667) (xy 116.554445 -251.605291) (xy 116.543328 -251.60478) (xy 115.466114 -251.60478)
			(xy 115.455012 -251.605353) (xy 115.43488 -251.614724) (xy 115.427252 -251.622814) (xy 115.369594 -251.690632)
			(xy 115.363752 -251.711968) (xy 115.365784 -251.723398) (xy 115.367794 -251.736066) (xy 115.369955 -251.761626)
			(xy 115.370102 -251.774452) (xy 115.36958 -251.799707) (xy 115.361267 -251.849529) (xy 115.344866 -251.897303)
			(xy 115.320825 -251.941726) (xy 115.289801 -251.981586) (xy 115.252639 -252.015796) (xy 115.210353 -252.043422)
			(xy 115.164097 -252.063712) (xy 115.115132 -252.076112) (xy 115.064794 -252.080283) (xy 115.014456 -252.076112)
			(xy 114.965491 -252.063712) (xy 114.919235 -252.043422) (xy 114.876949 -252.015796) (xy 114.839787 -251.981586)
			(xy 114.808763 -251.941726) (xy 114.784722 -251.897303) (xy 114.768321 -251.849529) (xy 114.760008 -251.799707)
			(xy 114.759486 -251.774452) (xy 114.759615 -251.761625) (xy 114.761773 -251.736063) (xy 114.763804 -251.723398)
			(xy 114.765836 -251.711968) (xy 114.759994 -251.690632) (xy 114.702336 -251.622814) (xy 114.694748 -251.614676)
			(xy 114.674588 -251.605321) (xy 114.663474 -251.60478) (xy 113.586006 -251.60478) (xy 113.574895 -251.605335)
			(xy 113.554735 -251.614682) (xy 113.547144 -251.622814) (xy 113.489486 -251.690632) (xy 113.483644 -251.711968)
			(xy 113.485676 -251.723398) (xy 113.487686 -251.736066) (xy 113.489848 -251.761626) (xy 113.489994 -251.774452)
			(xy 113.489472 -251.799707) (xy 113.481159 -251.849529) (xy 113.464758 -251.897303) (xy 113.440717 -251.941726)
			(xy 113.409693 -251.981586) (xy 113.372531 -252.015796) (xy 113.330245 -252.043422) (xy 113.283989 -252.063712)
			(xy 113.235024 -252.076112) (xy 113.184686 -252.080283) (xy 113.134348 -252.076112) (xy 113.085383 -252.063712)
			(xy 113.039127 -252.043422) (xy 112.996841 -252.015796) (xy 112.959679 -251.981586) (xy 112.928655 -251.941726)
			(xy 112.904614 -251.897303) (xy 112.888213 -251.849529) (xy 112.8799 -251.799707) (xy 112.879378 -251.774452)
			(xy 112.879507 -251.761625) (xy 112.881665 -251.736063) (xy 112.883696 -251.723398) (xy 112.885728 -251.711968)
			(xy 112.879886 -251.690632) (xy 112.822228 -251.622814) (xy 112.81464 -251.614677) (xy 112.794479 -251.605325)
			(xy 112.783366 -251.60478) (xy 112.588548 -251.60478) (xy 112.582965 -251.604923) (xy 112.572067 -251.607352)
			(xy 112.566958 -251.609606) (xy 112.539018 -251.62256) (xy 112.53216 -251.63018) (xy 112.512461 -251.651252)
			(xy 112.467311 -251.687145) (xy 112.416798 -251.714988) (xy 112.362342 -251.733999) (xy 112.305475 -251.743643)
			(xy 112.276636 -251.744226) (xy 112.247802 -251.743609) (xy 112.190951 -251.733933) (xy 112.136509 -251.714913)
			(xy 112.086 -251.687082) (xy 112.040839 -251.651219) (xy 112.021112 -251.63018) (xy 112.014254 -251.62256)
			(xy 111.986314 -251.609606) (xy 111.981199 -251.607371) (xy 111.970304 -251.604946) (xy 111.964724 -251.60478)
			(xy 111.695484 -251.60478) (xy 111.68377 -251.605373) (xy 111.662734 -251.61569) (xy 111.655098 -251.624592)
			(xy 111.637537 -251.646689) (xy 111.596834 -251.685787) (xy 111.550645 -251.718222) (xy 111.500051 -251.743236)
			(xy 111.446236 -251.760245) (xy 111.390456 -251.768849) (xy 111.334016 -251.768849) (xy 111.278236 -251.760245)
			(xy 111.224421 -251.743236) (xy 111.173827 -251.718222) (xy 111.127638 -251.685787) (xy 111.086935 -251.646689)
			(xy 111.069374 -251.624592) (xy 111.061774 -251.615641) (xy 111.040718 -251.60531) (xy 111.028988 -251.60478)
			(xy 109.832394 -251.60478) (xy 109.821284 -251.605337) (xy 109.801128 -251.614688) (xy 109.793532 -251.622814)
			(xy 109.735874 -251.690632) (xy 109.730032 -251.711968) (xy 109.732064 -251.723398) (xy 109.734074 -251.736066)
			(xy 109.736236 -251.761626) (xy 109.736382 -251.774452) (xy 109.73586 -251.799707) (xy 109.727547 -251.849529)
			(xy 109.711146 -251.897303) (xy 109.687105 -251.941726) (xy 109.656081 -251.981586) (xy 109.618919 -252.015796)
			(xy 109.576633 -252.043422) (xy 109.530377 -252.063712) (xy 109.481412 -252.076112) (xy 109.431074 -252.080283)
			(xy 109.380736 -252.076112) (xy 109.331771 -252.063712) (xy 109.285515 -252.043422) (xy 109.243229 -252.015796)
			(xy 109.206067 -251.981586) (xy 109.175043 -251.941726) (xy 109.151002 -251.897303) (xy 109.134601 -251.849529)
			(xy 109.126288 -251.799707) (xy 109.125766 -251.774452) (xy 109.125895 -251.761625) (xy 109.128053 -251.736063)
			(xy 109.130084 -251.723398) (xy 109.132116 -251.711968) (xy 109.126274 -251.690632) (xy 109.068616 -251.622814)
			(xy 109.061027 -251.614679) (xy 109.040866 -251.605332) (xy 109.029754 -251.60478) (xy 107.952286 -251.60478)
			(xy 107.941177 -251.605339) (xy 107.921023 -251.614691) (xy 107.913424 -251.622814) (xy 107.855766 -251.690632)
			(xy 107.849924 -251.711968) (xy 107.851956 -251.723398) (xy 107.853966 -251.736066) (xy 107.856127 -251.761626)
			(xy 107.856274 -251.774452) (xy 107.855752 -251.799707) (xy 107.847439 -251.849529) (xy 107.831038 -251.897303)
			(xy 107.806997 -251.941726) (xy 107.775973 -251.981586) (xy 107.738811 -252.015796) (xy 107.696525 -252.043422)
			(xy 107.650269 -252.063712) (xy 107.601304 -252.076112) (xy 107.550966 -252.080283) (xy 107.500628 -252.076112)
			(xy 107.451663 -252.063712) (xy 107.405407 -252.043422) (xy 107.363121 -252.015796) (xy 107.325959 -251.981586)
			(xy 107.294935 -251.941726) (xy 107.270894 -251.897303) (xy 107.254493 -251.849529) (xy 107.24618 -251.799707)
			(xy 107.245658 -251.774452) (xy 107.245787 -251.761625) (xy 107.247945 -251.736063) (xy 107.249976 -251.723398)
			(xy 107.252008 -251.711968) (xy 107.246166 -251.690632) (xy 107.188508 -251.622814) (xy 107.180918 -251.614681)
			(xy 107.160758 -251.605337) (xy 107.149646 -251.60478) (xy 106.072432 -251.60478) (xy 106.061328 -251.605349)
			(xy 106.041191 -251.614716) (xy 106.03357 -251.622814) (xy 105.975912 -251.690632) (xy 105.97007 -251.711968)
			(xy 105.972102 -251.723398) (xy 105.974112 -251.736066) (xy 105.976274 -251.761626) (xy 105.97642 -251.774452)
			(xy 105.975898 -251.799707) (xy 105.967585 -251.849529) (xy 105.951184 -251.897303) (xy 105.927143 -251.941726)
			(xy 105.896119 -251.981586) (xy 105.858957 -252.015796) (xy 105.816671 -252.043422) (xy 105.770415 -252.063712)
			(xy 105.72145 -252.076112) (xy 105.671112 -252.080283) (xy 105.620774 -252.076112) (xy 105.571809 -252.063712)
			(xy 105.525553 -252.043422) (xy 105.483267 -252.015796) (xy 105.446105 -251.981586) (xy 105.415081 -251.941726)
			(xy 105.39104 -251.897303) (xy 105.374639 -251.849529) (xy 105.366326 -251.799707) (xy 105.365804 -251.774452)
			(xy 105.365933 -251.761625) (xy 105.368091 -251.736063) (xy 105.370122 -251.723398) (xy 105.372154 -251.711968)
			(xy 105.366312 -251.690632) (xy 105.308654 -251.622814) (xy 105.301067 -251.614673) (xy 105.280907 -251.605311)
			(xy 105.269792 -251.60478) (xy 104.192324 -251.60478) (xy 104.181221 -251.605351) (xy 104.161086 -251.614719)
			(xy 104.153462 -251.622814) (xy 104.095804 -251.690632) (xy 104.089962 -251.711968) (xy 104.091994 -251.723398)
			(xy 104.094004 -251.736066) (xy 104.096166 -251.761626) (xy 104.096312 -251.774452) (xy 104.09579 -251.799707)
			(xy 104.087477 -251.849529) (xy 104.071076 -251.897303) (xy 104.047035 -251.941726) (xy 104.016011 -251.981586)
			(xy 103.978849 -252.015796) (xy 103.936563 -252.043422) (xy 103.890307 -252.063712) (xy 103.841342 -252.076112)
			(xy 103.791004 -252.080283) (xy 103.740666 -252.076112) (xy 103.691701 -252.063712) (xy 103.645445 -252.043422)
			(xy 103.603159 -252.015796) (xy 103.565997 -251.981586) (xy 103.534973 -251.941726) (xy 103.510932 -251.897303)
			(xy 103.494531 -251.849529) (xy 103.486218 -251.799707) (xy 103.485696 -251.774452) (xy 103.485825 -251.761625)
			(xy 103.487983 -251.736063) (xy 103.490014 -251.723398) (xy 103.492046 -251.711968) (xy 103.486204 -251.690632)
			(xy 103.428546 -251.622814) (xy 103.420958 -251.614674) (xy 103.400798 -251.605315) (xy 103.389684 -251.60478)
			(xy 102.31247 -251.60478) (xy 102.301363 -251.605342) (xy 102.281213 -251.614698) (xy 102.273608 -251.622814)
			(xy 102.21595 -251.690632) (xy 102.210108 -251.711968) (xy 102.21214 -251.723398) (xy 102.21415 -251.736066)
			(xy 102.216311 -251.761626) (xy 102.216458 -251.774452) (xy 102.215991 -251.798447) (xy 102.208491 -251.845848)
			(xy 102.193669 -251.891491) (xy 102.171888 -251.934254) (xy 102.143687 -251.973083) (xy 102.109758 -252.007023)
			(xy 102.070938 -252.035237) (xy 102.028182 -252.057031) (xy 101.982543 -252.071868) (xy 101.935145 -252.079383)
			(xy 101.91115 -252.07976) (xy 101.887871 -252.079346) (xy 101.841847 -252.07232) (xy 101.797426 -252.058378)
			(xy 101.755642 -252.037843) (xy 101.717465 -252.011195) (xy 101.70033 -251.995432) (xy 101.693218 -251.988574)
			(xy 101.674676 -251.981208) (xy 101.593904 -251.98197) (xy 101.584838 -251.982419) (xy 101.567903 -251.988916)
			(xy 101.560884 -251.99467) (xy 101.559614 -251.995686) (xy 101.442774 -252.112526) (xy 101.436548 -252.119357)
			(xy 101.429013 -252.136218) (xy 101.427929 -252.154655) (xy 101.430328 -252.16358) (xy 101.461316 -252.262894)
			(xy 101.482398 -252.28169) (xy 101.496368 -252.28423) (xy 101.519461 -252.288933) (xy 101.563942 -252.304497)
			(xy 101.605503 -252.326712) (xy 101.643158 -252.355048) (xy 101.676012 -252.388833) (xy 101.695691 -252.416564)
			(xy 111.913673 -252.416564) (xy 111.917703 -252.364066) (xy 111.9297 -252.312798) (xy 111.949383 -252.263963)
			(xy 111.976289 -252.218704) (xy 112.009789 -252.178083) (xy 112.049097 -252.143052) (xy 112.093292 -252.114432)
			(xy 112.141337 -252.092893) (xy 112.192108 -252.078941) (xy 112.244413 -252.072903) (xy 112.297027 -252.07492)
			(xy 112.348717 -252.084944) (xy 112.39827 -252.102742) (xy 112.444526 -252.127895) (xy 112.4864 -252.159814)
			(xy 112.522912 -252.197752) (xy 112.553204 -252.240818) (xy 112.576567 -252.288003) (xy 112.592453 -252.338202)
			(xy 112.60049 -252.390238) (xy 112.600994 -252.416564) (xy 112.60049 -252.44289) (xy 112.592453 -252.494926)
			(xy 112.576567 -252.545125) (xy 112.557092 -252.584458) (xy 120.86896 -252.584458) (xy 120.87292 -252.535404)
			(xy 120.884697 -252.48762) (xy 120.903988 -252.442344) (xy 120.930291 -252.400748) (xy 120.962926 -252.363911)
			(xy 121.001047 -252.332786) (xy 121.043668 -252.308179) (xy 121.089684 -252.290727) (xy 121.137903 -252.280883)
			(xy 121.187078 -252.278902) (xy 121.235933 -252.284834) (xy 121.283204 -252.298526) (xy 121.327666 -252.319624)
			(xy 121.368169 -252.34758) (xy 121.403662 -252.381672) (xy 121.433227 -252.421016) (xy 121.456098 -252.464593)
			(xy 121.471682 -252.511274) (xy 121.479577 -252.559851) (xy 121.480072 -252.584458) (xy 122.748814 -252.584458)
			(xy 122.752774 -252.535404) (xy 122.764551 -252.48762) (xy 122.783842 -252.442344) (xy 122.810145 -252.400748)
			(xy 122.84278 -252.363911) (xy 122.880901 -252.332786) (xy 122.923522 -252.308179) (xy 122.969538 -252.290727)
			(xy 123.017757 -252.280883) (xy 123.066932 -252.278902) (xy 123.115787 -252.284834) (xy 123.163058 -252.298526)
			(xy 123.20752 -252.319624) (xy 123.248023 -252.34758) (xy 123.283516 -252.381672) (xy 123.313081 -252.421016)
			(xy 123.335952 -252.464593) (xy 123.351536 -252.511274) (xy 123.359431 -252.559851) (xy 123.359926 -252.584458)
			(xy 124.628922 -252.584458) (xy 124.632882 -252.535404) (xy 124.644659 -252.48762) (xy 124.66395 -252.442344)
			(xy 124.690253 -252.400748) (xy 124.722888 -252.363911) (xy 124.761009 -252.332786) (xy 124.80363 -252.308179)
			(xy 124.849646 -252.290727) (xy 124.897865 -252.280883) (xy 124.94704 -252.278902) (xy 124.995895 -252.284834)
			(xy 125.043166 -252.298526) (xy 125.087628 -252.319624) (xy 125.128131 -252.34758) (xy 125.163624 -252.381672)
			(xy 125.193189 -252.421016) (xy 125.21606 -252.464593) (xy 125.231644 -252.511274) (xy 125.239539 -252.559851)
			(xy 125.240034 -252.584458) (xy 126.50903 -252.584458) (xy 126.51299 -252.535404) (xy 126.524767 -252.48762)
			(xy 126.544058 -252.442344) (xy 126.570361 -252.400748) (xy 126.602996 -252.363911) (xy 126.641117 -252.332786)
			(xy 126.683738 -252.308179) (xy 126.729754 -252.290727) (xy 126.777973 -252.280883) (xy 126.827148 -252.278902)
			(xy 126.876003 -252.284834) (xy 126.923274 -252.298526) (xy 126.967736 -252.319624) (xy 127.008239 -252.34758)
			(xy 127.043732 -252.381672) (xy 127.073297 -252.421016) (xy 127.096168 -252.464593) (xy 127.111752 -252.511274)
			(xy 127.119647 -252.559851) (xy 127.120142 -252.584458) (xy 127.44883 -252.584458) (xy 127.45279 -252.535404)
			(xy 127.464567 -252.48762) (xy 127.483858 -252.442344) (xy 127.510161 -252.400748) (xy 127.542796 -252.363911)
			(xy 127.580917 -252.332786) (xy 127.623538 -252.308179) (xy 127.669554 -252.290727) (xy 127.717773 -252.280883)
			(xy 127.766948 -252.278902) (xy 127.815803 -252.284834) (xy 127.863074 -252.298526) (xy 127.907536 -252.319624)
			(xy 127.948039 -252.34758) (xy 127.983532 -252.381672) (xy 128.013097 -252.421016) (xy 128.035968 -252.464593)
			(xy 128.051552 -252.511274) (xy 128.059447 -252.559851) (xy 128.059942 -252.584458) (xy 128.388884 -252.584458)
			(xy 128.392844 -252.535404) (xy 128.404621 -252.48762) (xy 128.423912 -252.442344) (xy 128.450215 -252.400748)
			(xy 128.48285 -252.363911) (xy 128.520971 -252.332786) (xy 128.563592 -252.308179) (xy 128.609608 -252.290727)
			(xy 128.657827 -252.280883) (xy 128.707002 -252.278902) (xy 128.755857 -252.284834) (xy 128.803128 -252.298526)
			(xy 128.84759 -252.319624) (xy 128.888093 -252.34758) (xy 128.923586 -252.381672) (xy 128.953151 -252.421016)
			(xy 128.976022 -252.464593) (xy 128.991606 -252.511274) (xy 128.999501 -252.559851) (xy 128.999996 -252.584458)
			(xy 129.318507 -252.584458) (xy 129.322602 -252.53373) (xy 129.334781 -252.484316) (xy 129.354729 -252.437496)
			(xy 129.38193 -252.394482) (xy 129.415678 -252.356388) (xy 129.4551 -252.324201) (xy 129.499174 -252.298755)
			(xy 129.54676 -252.280708) (xy 129.596624 -252.270528) (xy 129.647476 -252.268479) (xy 129.697997 -252.274613)
			(xy 129.746881 -252.288773) (xy 129.79286 -252.31059) (xy 129.834744 -252.3395) (xy 129.871448 -252.374755)
			(xy 129.902021 -252.415441) (xy 129.925672 -252.460504) (xy 129.941788 -252.508778) (xy 129.949952 -252.559012)
			(xy 129.950464 -252.584458) (xy 130.268992 -252.584458) (xy 130.272952 -252.535404) (xy 130.284729 -252.48762)
			(xy 130.30402 -252.442344) (xy 130.330323 -252.400748) (xy 130.362958 -252.363911) (xy 130.401079 -252.332786)
			(xy 130.4437 -252.308179) (xy 130.489716 -252.290727) (xy 130.537935 -252.280883) (xy 130.58711 -252.278902)
			(xy 130.635965 -252.284834) (xy 130.683236 -252.298526) (xy 130.727698 -252.319624) (xy 130.768201 -252.34758)
			(xy 130.803694 -252.381672) (xy 130.833259 -252.421016) (xy 130.85613 -252.464593) (xy 130.871714 -252.511274)
			(xy 130.879609 -252.559851) (xy 130.880104 -252.584458) (xy 131.209046 -252.584458) (xy 131.213006 -252.535404)
			(xy 131.224783 -252.48762) (xy 131.244074 -252.442344) (xy 131.270377 -252.400748) (xy 131.303012 -252.363911)
			(xy 131.341133 -252.332786) (xy 131.383754 -252.308179) (xy 131.42977 -252.290727) (xy 131.477989 -252.280883)
			(xy 131.527164 -252.278902) (xy 131.576019 -252.284834) (xy 131.62329 -252.298526) (xy 131.667752 -252.319624)
			(xy 131.708255 -252.34758) (xy 131.743748 -252.381672) (xy 131.773313 -252.421016) (xy 131.796184 -252.464593)
			(xy 131.811768 -252.511274) (xy 131.819663 -252.559851) (xy 131.820158 -252.584458) (xy 132.138415 -252.584458)
			(xy 132.14251 -252.53373) (xy 132.154689 -252.484316) (xy 132.174637 -252.437496) (xy 132.201838 -252.394482)
			(xy 132.235586 -252.356388) (xy 132.275008 -252.324201) (xy 132.319082 -252.298755) (xy 132.366668 -252.280708)
			(xy 132.416532 -252.270528) (xy 132.467384 -252.268479) (xy 132.517905 -252.274613) (xy 132.566789 -252.288773)
			(xy 132.612768 -252.31059) (xy 132.654652 -252.3395) (xy 132.691356 -252.374755) (xy 132.721929 -252.415441)
			(xy 132.74558 -252.460504) (xy 132.761696 -252.508778) (xy 132.76986 -252.559012) (xy 132.770372 -252.584458)
			(xy 133.0889 -252.584458) (xy 133.09286 -252.535404) (xy 133.104637 -252.48762) (xy 133.123928 -252.442344)
			(xy 133.150231 -252.400748) (xy 133.182866 -252.363911) (xy 133.220987 -252.332786) (xy 133.263608 -252.308179)
			(xy 133.309624 -252.290727) (xy 133.357843 -252.280883) (xy 133.407018 -252.278902) (xy 133.455873 -252.284834)
			(xy 133.503144 -252.298526) (xy 133.547606 -252.319624) (xy 133.588109 -252.34758) (xy 133.623602 -252.381672)
			(xy 133.653167 -252.421016) (xy 133.676038 -252.464593) (xy 133.691622 -252.511274) (xy 133.699517 -252.559851)
			(xy 133.700012 -252.584458) (xy 134.028954 -252.584458) (xy 134.032914 -252.535404) (xy 134.044691 -252.48762)
			(xy 134.063982 -252.442344) (xy 134.090285 -252.400748) (xy 134.12292 -252.363911) (xy 134.161041 -252.332786)
			(xy 134.203662 -252.308179) (xy 134.249678 -252.290727) (xy 134.297897 -252.280883) (xy 134.347072 -252.278902)
			(xy 134.395927 -252.284834) (xy 134.443198 -252.298526) (xy 134.48766 -252.319624) (xy 134.528163 -252.34758)
			(xy 134.563656 -252.381672) (xy 134.593221 -252.421016) (xy 134.616092 -252.464593) (xy 134.631676 -252.511274)
			(xy 134.639571 -252.559851) (xy 134.640066 -252.584458) (xy 134.969008 -252.584458) (xy 134.972968 -252.535404)
			(xy 134.984745 -252.48762) (xy 135.004036 -252.442344) (xy 135.030339 -252.400748) (xy 135.062974 -252.363911)
			(xy 135.101095 -252.332786) (xy 135.143716 -252.308179) (xy 135.189732 -252.290727) (xy 135.237951 -252.280883)
			(xy 135.287126 -252.278902) (xy 135.335981 -252.284834) (xy 135.383252 -252.298526) (xy 135.427714 -252.319624)
			(xy 135.468217 -252.34758) (xy 135.50371 -252.381672) (xy 135.533275 -252.421016) (xy 135.556146 -252.464593)
			(xy 135.57173 -252.511274) (xy 135.579625 -252.559851) (xy 135.58012 -252.584458) (xy 135.898631 -252.584458)
			(xy 135.902726 -252.53373) (xy 135.914905 -252.484316) (xy 135.934853 -252.437496) (xy 135.962054 -252.394482)
			(xy 135.995802 -252.356388) (xy 136.035224 -252.324201) (xy 136.079298 -252.298755) (xy 136.126884 -252.280708)
			(xy 136.176748 -252.270528) (xy 136.2276 -252.268479) (xy 136.278121 -252.274613) (xy 136.327005 -252.288773)
			(xy 136.372984 -252.31059) (xy 136.414868 -252.3395) (xy 136.451572 -252.374755) (xy 136.482145 -252.415441)
			(xy 136.505796 -252.460504) (xy 136.521912 -252.508778) (xy 136.530076 -252.559012) (xy 136.530588 -252.584458)
			(xy 136.848862 -252.584458) (xy 136.852822 -252.535404) (xy 136.864599 -252.48762) (xy 136.88389 -252.442344)
			(xy 136.910193 -252.400748) (xy 136.942828 -252.363911) (xy 136.980949 -252.332786) (xy 137.02357 -252.308179)
			(xy 137.069586 -252.290727) (xy 137.117805 -252.280883) (xy 137.16698 -252.278902) (xy 137.215835 -252.284834)
			(xy 137.263106 -252.298526) (xy 137.307568 -252.319624) (xy 137.348071 -252.34758) (xy 137.383564 -252.381672)
			(xy 137.413129 -252.421016) (xy 137.436 -252.464593) (xy 137.451584 -252.511274) (xy 137.459479 -252.559851)
			(xy 137.459974 -252.584458) (xy 137.788916 -252.584458) (xy 137.792876 -252.535404) (xy 137.804653 -252.48762)
			(xy 137.823944 -252.442344) (xy 137.850247 -252.400748) (xy 137.882882 -252.363911) (xy 137.921003 -252.332786)
			(xy 137.963624 -252.308179) (xy 138.00964 -252.290727) (xy 138.057859 -252.280883) (xy 138.107034 -252.278902)
			(xy 138.155889 -252.284834) (xy 138.20316 -252.298526) (xy 138.247622 -252.319624) (xy 138.288125 -252.34758)
			(xy 138.323618 -252.381672) (xy 138.353183 -252.421016) (xy 138.376054 -252.464593) (xy 138.391638 -252.511274)
			(xy 138.399533 -252.559851) (xy 138.400028 -252.584458) (xy 138.718539 -252.584458) (xy 138.722634 -252.53373)
			(xy 138.734813 -252.484316) (xy 138.754761 -252.437496) (xy 138.781962 -252.394482) (xy 138.81571 -252.356388)
			(xy 138.855132 -252.324201) (xy 138.899206 -252.298755) (xy 138.946792 -252.280708) (xy 138.996656 -252.270528)
			(xy 139.047508 -252.268479) (xy 139.098029 -252.274613) (xy 139.146913 -252.288773) (xy 139.192892 -252.31059)
			(xy 139.234776 -252.3395) (xy 139.27148 -252.374755) (xy 139.302053 -252.415441) (xy 139.325704 -252.460504)
			(xy 139.34182 -252.508778) (xy 139.349984 -252.559012) (xy 139.350496 -252.584458) (xy 139.669024 -252.584458)
			(xy 139.672984 -252.535404) (xy 139.684761 -252.48762) (xy 139.704052 -252.442344) (xy 139.730355 -252.400748)
			(xy 139.76299 -252.363911) (xy 139.801111 -252.332786) (xy 139.843732 -252.308179) (xy 139.889748 -252.290727)
			(xy 139.937967 -252.280883) (xy 139.987142 -252.278902) (xy 140.035997 -252.284834) (xy 140.083268 -252.298526)
			(xy 140.12773 -252.319624) (xy 140.168233 -252.34758) (xy 140.203726 -252.381672) (xy 140.233291 -252.421016)
			(xy 140.256162 -252.464593) (xy 140.271746 -252.511274) (xy 140.279641 -252.559851) (xy 140.280136 -252.584458)
			(xy 140.608824 -252.584458) (xy 140.612784 -252.535404) (xy 140.624561 -252.48762) (xy 140.643852 -252.442344)
			(xy 140.670155 -252.400748) (xy 140.70279 -252.363911) (xy 140.740911 -252.332786) (xy 140.783532 -252.308179)
			(xy 140.829548 -252.290727) (xy 140.877767 -252.280883) (xy 140.926942 -252.278902) (xy 140.975797 -252.284834)
			(xy 141.023068 -252.298526) (xy 141.06753 -252.319624) (xy 141.108033 -252.34758) (xy 141.143526 -252.381672)
			(xy 141.173091 -252.421016) (xy 141.195962 -252.464593) (xy 141.211546 -252.511274) (xy 141.219441 -252.559851)
			(xy 141.219936 -252.584458) (xy 141.548878 -252.584458) (xy 141.552838 -252.535404) (xy 141.564615 -252.48762)
			(xy 141.583906 -252.442344) (xy 141.610209 -252.400748) (xy 141.642844 -252.363911) (xy 141.680965 -252.332786)
			(xy 141.723586 -252.308179) (xy 141.769602 -252.290727) (xy 141.817821 -252.280883) (xy 141.866996 -252.278902)
			(xy 141.915851 -252.284834) (xy 141.963122 -252.298526) (xy 142.007584 -252.319624) (xy 142.048087 -252.34758)
			(xy 142.08358 -252.381672) (xy 142.113145 -252.421016) (xy 142.136016 -252.464593) (xy 142.1516 -252.511274)
			(xy 142.159495 -252.559851) (xy 142.15999 -252.584458) (xy 142.478501 -252.584458) (xy 142.482596 -252.53373)
			(xy 142.494775 -252.484316) (xy 142.514723 -252.437496) (xy 142.541924 -252.394482) (xy 142.575672 -252.356388)
			(xy 142.615094 -252.324201) (xy 142.659168 -252.298755) (xy 142.706754 -252.280708) (xy 142.756618 -252.270528)
			(xy 142.80747 -252.268479) (xy 142.857991 -252.274613) (xy 142.906875 -252.288773) (xy 142.952854 -252.31059)
			(xy 142.994738 -252.3395) (xy 143.031442 -252.374755) (xy 143.062015 -252.415441) (xy 143.085666 -252.460504)
			(xy 143.101782 -252.508778) (xy 143.109946 -252.559012) (xy 143.110458 -252.584458) (xy 143.428986 -252.584458)
			(xy 143.432946 -252.535404) (xy 143.444723 -252.48762) (xy 143.464014 -252.442344) (xy 143.490317 -252.400748)
			(xy 143.522952 -252.363911) (xy 143.561073 -252.332786) (xy 143.603694 -252.308179) (xy 143.64971 -252.290727)
			(xy 143.697929 -252.280883) (xy 143.747104 -252.278902) (xy 143.795959 -252.284834) (xy 143.84323 -252.298526)
			(xy 143.887692 -252.319624) (xy 143.928195 -252.34758) (xy 143.963688 -252.381672) (xy 143.993253 -252.421016)
			(xy 144.016124 -252.464593) (xy 144.031708 -252.511274) (xy 144.039603 -252.559851) (xy 144.040098 -252.584458)
			(xy 144.039603 -252.609065) (xy 144.031708 -252.657642) (xy 144.016124 -252.704323) (xy 143.993253 -252.7479)
			(xy 143.963688 -252.787244) (xy 143.928195 -252.821336) (xy 143.887692 -252.849292) (xy 143.84323 -252.87039)
			(xy 143.795959 -252.884082) (xy 143.747104 -252.890014) (xy 143.697929 -252.888033) (xy 143.64971 -252.878189)
			(xy 143.603694 -252.860737) (xy 143.561073 -252.83613) (xy 143.522952 -252.805005) (xy 143.490317 -252.768168)
			(xy 143.464014 -252.726572) (xy 143.444723 -252.681296) (xy 143.432946 -252.633512) (xy 143.428986 -252.584458)
			(xy 143.110458 -252.584458) (xy 143.109946 -252.609904) (xy 143.101782 -252.660138) (xy 143.085666 -252.708412)
			(xy 143.062015 -252.753475) (xy 143.031442 -252.794161) (xy 142.994738 -252.829416) (xy 142.952854 -252.858326)
			(xy 142.906875 -252.880143) (xy 142.857991 -252.894303) (xy 142.80747 -252.900437) (xy 142.756618 -252.898388)
			(xy 142.706754 -252.888208) (xy 142.659168 -252.870161) (xy 142.615094 -252.844715) (xy 142.575672 -252.812528)
			(xy 142.541924 -252.774434) (xy 142.514723 -252.73142) (xy 142.494775 -252.6846) (xy 142.482596 -252.635186)
			(xy 142.478501 -252.584458) (xy 142.15999 -252.584458) (xy 142.159495 -252.609065) (xy 142.1516 -252.657642)
			(xy 142.136016 -252.704323) (xy 142.113145 -252.7479) (xy 142.08358 -252.787244) (xy 142.048087 -252.821336)
			(xy 142.007584 -252.849292) (xy 141.963122 -252.87039) (xy 141.915851 -252.884082) (xy 141.866996 -252.890014)
			(xy 141.817821 -252.888033) (xy 141.769602 -252.878189) (xy 141.723586 -252.860737) (xy 141.680965 -252.83613)
			(xy 141.642844 -252.805005) (xy 141.610209 -252.768168) (xy 141.583906 -252.726572) (xy 141.564615 -252.681296)
			(xy 141.552838 -252.633512) (xy 141.548878 -252.584458) (xy 141.219936 -252.584458) (xy 141.219441 -252.609065)
			(xy 141.211546 -252.657642) (xy 141.195962 -252.704323) (xy 141.173091 -252.7479) (xy 141.143526 -252.787244)
			(xy 141.108033 -252.821336) (xy 141.06753 -252.849292) (xy 141.023068 -252.87039) (xy 140.975797 -252.884082)
			(xy 140.926942 -252.890014) (xy 140.877767 -252.888033) (xy 140.829548 -252.878189) (xy 140.783532 -252.860737)
			(xy 140.740911 -252.83613) (xy 140.70279 -252.805005) (xy 140.670155 -252.768168) (xy 140.643852 -252.726572)
			(xy 140.624561 -252.681296) (xy 140.612784 -252.633512) (xy 140.608824 -252.584458) (xy 140.280136 -252.584458)
			(xy 140.279641 -252.609065) (xy 140.271746 -252.657642) (xy 140.256162 -252.704323) (xy 140.233291 -252.7479)
			(xy 140.203726 -252.787244) (xy 140.168233 -252.821336) (xy 140.12773 -252.849292) (xy 140.083268 -252.87039)
			(xy 140.035997 -252.884082) (xy 139.987142 -252.890014) (xy 139.937967 -252.888033) (xy 139.889748 -252.878189)
			(xy 139.843732 -252.860737) (xy 139.801111 -252.83613) (xy 139.76299 -252.805005) (xy 139.730355 -252.768168)
			(xy 139.704052 -252.726572) (xy 139.684761 -252.681296) (xy 139.672984 -252.633512) (xy 139.669024 -252.584458)
			(xy 139.350496 -252.584458) (xy 139.349984 -252.609904) (xy 139.34182 -252.660138) (xy 139.325704 -252.708412)
			(xy 139.302053 -252.753475) (xy 139.27148 -252.794161) (xy 139.234776 -252.829416) (xy 139.192892 -252.858326)
			(xy 139.146913 -252.880143) (xy 139.098029 -252.894303) (xy 139.047508 -252.900437) (xy 138.996656 -252.898388)
			(xy 138.946792 -252.888208) (xy 138.899206 -252.870161) (xy 138.855132 -252.844715) (xy 138.81571 -252.812528)
			(xy 138.781962 -252.774434) (xy 138.754761 -252.73142) (xy 138.734813 -252.6846) (xy 138.722634 -252.635186)
			(xy 138.718539 -252.584458) (xy 138.400028 -252.584458) (xy 138.399533 -252.609065) (xy 138.391638 -252.657642)
			(xy 138.376054 -252.704323) (xy 138.353183 -252.7479) (xy 138.323618 -252.787244) (xy 138.288125 -252.821336)
			(xy 138.247622 -252.849292) (xy 138.20316 -252.87039) (xy 138.155889 -252.884082) (xy 138.107034 -252.890014)
			(xy 138.057859 -252.888033) (xy 138.00964 -252.878189) (xy 137.963624 -252.860737) (xy 137.921003 -252.83613)
			(xy 137.882882 -252.805005) (xy 137.850247 -252.768168) (xy 137.823944 -252.726572) (xy 137.804653 -252.681296)
			(xy 137.792876 -252.633512) (xy 137.788916 -252.584458) (xy 137.459974 -252.584458) (xy 137.459479 -252.609065)
			(xy 137.451584 -252.657642) (xy 137.436 -252.704323) (xy 137.413129 -252.7479) (xy 137.383564 -252.787244)
			(xy 137.348071 -252.821336) (xy 137.307568 -252.849292) (xy 137.263106 -252.87039) (xy 137.215835 -252.884082)
			(xy 137.16698 -252.890014) (xy 137.117805 -252.888033) (xy 137.069586 -252.878189) (xy 137.02357 -252.860737)
			(xy 136.980949 -252.83613) (xy 136.942828 -252.805005) (xy 136.910193 -252.768168) (xy 136.88389 -252.726572)
			(xy 136.864599 -252.681296) (xy 136.852822 -252.633512) (xy 136.848862 -252.584458) (xy 136.530588 -252.584458)
			(xy 136.530076 -252.609904) (xy 136.521912 -252.660138) (xy 136.505796 -252.708412) (xy 136.482145 -252.753475)
			(xy 136.451572 -252.794161) (xy 136.414868 -252.829416) (xy 136.372984 -252.858326) (xy 136.327005 -252.880143)
			(xy 136.278121 -252.894303) (xy 136.2276 -252.900437) (xy 136.176748 -252.898388) (xy 136.126884 -252.888208)
			(xy 136.079298 -252.870161) (xy 136.035224 -252.844715) (xy 135.995802 -252.812528) (xy 135.962054 -252.774434)
			(xy 135.934853 -252.73142) (xy 135.914905 -252.6846) (xy 135.902726 -252.635186) (xy 135.898631 -252.584458)
			(xy 135.58012 -252.584458) (xy 135.579625 -252.609065) (xy 135.57173 -252.657642) (xy 135.556146 -252.704323)
			(xy 135.533275 -252.7479) (xy 135.50371 -252.787244) (xy 135.468217 -252.821336) (xy 135.427714 -252.849292)
			(xy 135.383252 -252.87039) (xy 135.335981 -252.884082) (xy 135.287126 -252.890014) (xy 135.237951 -252.888033)
			(xy 135.189732 -252.878189) (xy 135.143716 -252.860737) (xy 135.101095 -252.83613) (xy 135.062974 -252.805005)
			(xy 135.030339 -252.768168) (xy 135.004036 -252.726572) (xy 134.984745 -252.681296) (xy 134.972968 -252.633512)
			(xy 134.969008 -252.584458) (xy 134.640066 -252.584458) (xy 134.639571 -252.609065) (xy 134.631676 -252.657642)
			(xy 134.616092 -252.704323) (xy 134.593221 -252.7479) (xy 134.563656 -252.787244) (xy 134.528163 -252.821336)
			(xy 134.48766 -252.849292) (xy 134.443198 -252.87039) (xy 134.395927 -252.884082) (xy 134.347072 -252.890014)
			(xy 134.297897 -252.888033) (xy 134.249678 -252.878189) (xy 134.203662 -252.860737) (xy 134.161041 -252.83613)
			(xy 134.12292 -252.805005) (xy 134.090285 -252.768168) (xy 134.063982 -252.726572) (xy 134.044691 -252.681296)
			(xy 134.032914 -252.633512) (xy 134.028954 -252.584458) (xy 133.700012 -252.584458) (xy 133.699517 -252.609065)
			(xy 133.691622 -252.657642) (xy 133.676038 -252.704323) (xy 133.653167 -252.7479) (xy 133.623602 -252.787244)
			(xy 133.588109 -252.821336) (xy 133.547606 -252.849292) (xy 133.503144 -252.87039) (xy 133.455873 -252.884082)
			(xy 133.407018 -252.890014) (xy 133.357843 -252.888033) (xy 133.309624 -252.878189) (xy 133.263608 -252.860737)
			(xy 133.220987 -252.83613) (xy 133.182866 -252.805005) (xy 133.150231 -252.768168) (xy 133.123928 -252.726572)
			(xy 133.104637 -252.681296) (xy 133.09286 -252.633512) (xy 133.0889 -252.584458) (xy 132.770372 -252.584458)
			(xy 132.76986 -252.609904) (xy 132.761696 -252.660138) (xy 132.74558 -252.708412) (xy 132.721929 -252.753475)
			(xy 132.691356 -252.794161) (xy 132.654652 -252.829416) (xy 132.612768 -252.858326) (xy 132.566789 -252.880143)
			(xy 132.517905 -252.894303) (xy 132.467384 -252.900437) (xy 132.416532 -252.898388) (xy 132.366668 -252.888208)
			(xy 132.319082 -252.870161) (xy 132.275008 -252.844715) (xy 132.235586 -252.812528) (xy 132.201838 -252.774434)
			(xy 132.174637 -252.73142) (xy 132.154689 -252.6846) (xy 132.14251 -252.635186) (xy 132.138415 -252.584458)
			(xy 131.820158 -252.584458) (xy 131.819663 -252.609065) (xy 131.811768 -252.657642) (xy 131.796184 -252.704323)
			(xy 131.773313 -252.7479) (xy 131.743748 -252.787244) (xy 131.708255 -252.821336) (xy 131.667752 -252.849292)
			(xy 131.62329 -252.87039) (xy 131.576019 -252.884082) (xy 131.527164 -252.890014) (xy 131.477989 -252.888033)
			(xy 131.42977 -252.878189) (xy 131.383754 -252.860737) (xy 131.341133 -252.83613) (xy 131.303012 -252.805005)
			(xy 131.270377 -252.768168) (xy 131.244074 -252.726572) (xy 131.224783 -252.681296) (xy 131.213006 -252.633512)
			(xy 131.209046 -252.584458) (xy 130.880104 -252.584458) (xy 130.879609 -252.609065) (xy 130.871714 -252.657642)
			(xy 130.85613 -252.704323) (xy 130.833259 -252.7479) (xy 130.803694 -252.787244) (xy 130.768201 -252.821336)
			(xy 130.727698 -252.849292) (xy 130.683236 -252.87039) (xy 130.635965 -252.884082) (xy 130.58711 -252.890014)
			(xy 130.537935 -252.888033) (xy 130.489716 -252.878189) (xy 130.4437 -252.860737) (xy 130.401079 -252.83613)
			(xy 130.362958 -252.805005) (xy 130.330323 -252.768168) (xy 130.30402 -252.726572) (xy 130.284729 -252.681296)
			(xy 130.272952 -252.633512) (xy 130.268992 -252.584458) (xy 129.950464 -252.584458) (xy 129.949952 -252.609904)
			(xy 129.941788 -252.660138) (xy 129.925672 -252.708412) (xy 129.902021 -252.753475) (xy 129.871448 -252.794161)
			(xy 129.834744 -252.829416) (xy 129.79286 -252.858326) (xy 129.746881 -252.880143) (xy 129.697997 -252.894303)
			(xy 129.647476 -252.900437) (xy 129.596624 -252.898388) (xy 129.54676 -252.888208) (xy 129.499174 -252.870161)
			(xy 129.4551 -252.844715) (xy 129.415678 -252.812528) (xy 129.38193 -252.774434) (xy 129.354729 -252.73142)
			(xy 129.334781 -252.6846) (xy 129.322602 -252.635186) (xy 129.318507 -252.584458) (xy 128.999996 -252.584458)
			(xy 128.999501 -252.609065) (xy 128.991606 -252.657642) (xy 128.976022 -252.704323) (xy 128.953151 -252.7479)
			(xy 128.923586 -252.787244) (xy 128.888093 -252.821336) (xy 128.84759 -252.849292) (xy 128.803128 -252.87039)
			(xy 128.755857 -252.884082) (xy 128.707002 -252.890014) (xy 128.657827 -252.888033) (xy 128.609608 -252.878189)
			(xy 128.563592 -252.860737) (xy 128.520971 -252.83613) (xy 128.48285 -252.805005) (xy 128.450215 -252.768168)
			(xy 128.423912 -252.726572) (xy 128.404621 -252.681296) (xy 128.392844 -252.633512) (xy 128.388884 -252.584458)
			(xy 128.059942 -252.584458) (xy 128.059447 -252.609065) (xy 128.051552 -252.657642) (xy 128.035968 -252.704323)
			(xy 128.013097 -252.7479) (xy 127.983532 -252.787244) (xy 127.948039 -252.821336) (xy 127.907536 -252.849292)
			(xy 127.863074 -252.87039) (xy 127.815803 -252.884082) (xy 127.766948 -252.890014) (xy 127.717773 -252.888033)
			(xy 127.669554 -252.878189) (xy 127.623538 -252.860737) (xy 127.580917 -252.83613) (xy 127.542796 -252.805005)
			(xy 127.510161 -252.768168) (xy 127.483858 -252.726572) (xy 127.464567 -252.681296) (xy 127.45279 -252.633512)
			(xy 127.44883 -252.584458) (xy 127.120142 -252.584458) (xy 127.119647 -252.609065) (xy 127.111752 -252.657642)
			(xy 127.096168 -252.704323) (xy 127.073297 -252.7479) (xy 127.043732 -252.787244) (xy 127.008239 -252.821336)
			(xy 126.967736 -252.849292) (xy 126.923274 -252.87039) (xy 126.876003 -252.884082) (xy 126.827148 -252.890014)
			(xy 126.777973 -252.888033) (xy 126.729754 -252.878189) (xy 126.683738 -252.860737) (xy 126.641117 -252.83613)
			(xy 126.602996 -252.805005) (xy 126.570361 -252.768168) (xy 126.544058 -252.726572) (xy 126.524767 -252.681296)
			(xy 126.51299 -252.633512) (xy 126.50903 -252.584458) (xy 125.240034 -252.584458) (xy 125.239539 -252.609065)
			(xy 125.231644 -252.657642) (xy 125.21606 -252.704323) (xy 125.193189 -252.7479) (xy 125.163624 -252.787244)
			(xy 125.128131 -252.821336) (xy 125.087628 -252.849292) (xy 125.043166 -252.87039) (xy 124.995895 -252.884082)
			(xy 124.94704 -252.890014) (xy 124.897865 -252.888033) (xy 124.849646 -252.878189) (xy 124.80363 -252.860737)
			(xy 124.761009 -252.83613) (xy 124.722888 -252.805005) (xy 124.690253 -252.768168) (xy 124.66395 -252.726572)
			(xy 124.644659 -252.681296) (xy 124.632882 -252.633512) (xy 124.628922 -252.584458) (xy 123.359926 -252.584458)
			(xy 123.359431 -252.609065) (xy 123.351536 -252.657642) (xy 123.335952 -252.704323) (xy 123.313081 -252.7479)
			(xy 123.283516 -252.787244) (xy 123.248023 -252.821336) (xy 123.20752 -252.849292) (xy 123.163058 -252.87039)
			(xy 123.115787 -252.884082) (xy 123.066932 -252.890014) (xy 123.017757 -252.888033) (xy 122.969538 -252.878189)
			(xy 122.923522 -252.860737) (xy 122.880901 -252.83613) (xy 122.84278 -252.805005) (xy 122.810145 -252.768168)
			(xy 122.783842 -252.726572) (xy 122.764551 -252.681296) (xy 122.752774 -252.633512) (xy 122.748814 -252.584458)
			(xy 121.480072 -252.584458) (xy 121.479577 -252.609065) (xy 121.471682 -252.657642) (xy 121.456098 -252.704323)
			(xy 121.433227 -252.7479) (xy 121.403662 -252.787244) (xy 121.368169 -252.821336) (xy 121.327666 -252.849292)
			(xy 121.283204 -252.87039) (xy 121.235933 -252.884082) (xy 121.187078 -252.890014) (xy 121.137903 -252.888033)
			(xy 121.089684 -252.878189) (xy 121.043668 -252.860737) (xy 121.001047 -252.83613) (xy 120.962926 -252.805005)
			(xy 120.930291 -252.768168) (xy 120.903988 -252.726572) (xy 120.884697 -252.681296) (xy 120.87292 -252.633512)
			(xy 120.86896 -252.584458) (xy 112.557092 -252.584458) (xy 112.553204 -252.59231) (xy 112.522912 -252.635376)
			(xy 112.4864 -252.673314) (xy 112.444526 -252.705233) (xy 112.39827 -252.730386) (xy 112.348717 -252.748184)
			(xy 112.297027 -252.758208) (xy 112.244413 -252.760225) (xy 112.192108 -252.754187) (xy 112.141337 -252.740235)
			(xy 112.093292 -252.718696) (xy 112.049097 -252.690076) (xy 112.009789 -252.655045) (xy 111.976289 -252.614424)
			(xy 111.949383 -252.569165) (xy 111.9297 -252.52033) (xy 111.917703 -252.469062) (xy 111.913673 -252.416564)
			(xy 101.695691 -252.416564) (xy 101.703285 -252.427265) (xy 101.724329 -252.469431) (xy 101.738645 -252.51433)
			(xy 101.745892 -252.560895) (xy 101.746304 -252.584458) (xy 101.745861 -252.608453) (xy 101.738359 -252.655854)
			(xy 101.723535 -252.701497) (xy 101.701751 -252.744258) (xy 101.673546 -252.783085) (xy 101.639614 -252.817022)
			(xy 101.600791 -252.845231) (xy 101.558032 -252.86702) (xy 101.512391 -252.881851) (xy 101.464991 -252.889358)
			(xy 101.440996 -252.889766) (xy 101.417434 -252.889328) (xy 101.370871 -252.882086) (xy 101.325974 -252.867775)
			(xy 101.283809 -252.846734) (xy 101.245379 -252.819464) (xy 101.211595 -252.786612) (xy 101.183261 -252.748958)
			(xy 101.16105 -252.707398) (xy 101.14549 -252.662918) (xy 101.140768 -252.63983) (xy 101.138228 -252.62586)
			(xy 101.119432 -252.604778) (xy 101.020118 -252.57379) (xy 101.011191 -252.571403) (xy 100.992757 -252.572476)
			(xy 100.975904 -252.58002) (xy 100.969064 -252.586236) (xy 100.634546 -252.920754) (xy 100.62718 -252.927866)
			(xy 100.61956 -252.946662) (xy 100.61956 -253.394464) (xy 101.605346 -253.394464) (xy 101.609306 -253.34541)
			(xy 101.621083 -253.297626) (xy 101.640374 -253.25235) (xy 101.666677 -253.210754) (xy 101.699312 -253.173917)
			(xy 101.737433 -253.142792) (xy 101.780054 -253.118185) (xy 101.82607 -253.100733) (xy 101.874289 -253.090889)
			(xy 101.923464 -253.088908) (xy 101.972319 -253.09484) (xy 102.01959 -253.108532) (xy 102.064052 -253.12963)
			(xy 102.104555 -253.157586) (xy 102.140048 -253.191678) (xy 102.169613 -253.231022) (xy 102.192484 -253.274599)
			(xy 102.208068 -253.32128) (xy 102.215963 -253.369857) (xy 102.216417 -253.392432) (xy 103.482152 -253.392432)
			(xy 103.486112 -253.343378) (xy 103.497889 -253.295594) (xy 103.51718 -253.250318) (xy 103.543483 -253.208722)
			(xy 103.576118 -253.171885) (xy 103.614239 -253.14076) (xy 103.65686 -253.116153) (xy 103.702876 -253.098701)
			(xy 103.751095 -253.088857) (xy 103.80027 -253.086876) (xy 103.849125 -253.092808) (xy 103.896396 -253.1065)
			(xy 103.940858 -253.127598) (xy 103.981361 -253.155554) (xy 104.016854 -253.189646) (xy 104.046419 -253.22899)
			(xy 104.06929 -253.272567) (xy 104.084874 -253.319248) (xy 104.092769 -253.367825) (xy 104.093264 -253.392432)
			(xy 105.362006 -253.392432) (xy 105.365966 -253.343378) (xy 105.377743 -253.295594) (xy 105.397034 -253.250318)
			(xy 105.423337 -253.208722) (xy 105.455972 -253.171885) (xy 105.494093 -253.14076) (xy 105.536714 -253.116153)
			(xy 105.58273 -253.098701) (xy 105.630949 -253.088857) (xy 105.680124 -253.086876) (xy 105.728979 -253.092808)
			(xy 105.77625 -253.1065) (xy 105.820712 -253.127598) (xy 105.861215 -253.155554) (xy 105.896708 -253.189646)
			(xy 105.926273 -253.22899) (xy 105.949144 -253.272567) (xy 105.964728 -253.319248) (xy 105.972623 -253.367825)
			(xy 105.973118 -253.392432) (xy 107.242114 -253.392432) (xy 107.246074 -253.343378) (xy 107.257851 -253.295594)
			(xy 107.277142 -253.250318) (xy 107.303445 -253.208722) (xy 107.33608 -253.171885) (xy 107.374201 -253.14076)
			(xy 107.416822 -253.116153) (xy 107.462838 -253.098701) (xy 107.511057 -253.088857) (xy 107.560232 -253.086876)
			(xy 107.609087 -253.092808) (xy 107.656358 -253.1065) (xy 107.70082 -253.127598) (xy 107.741323 -253.155554)
			(xy 107.776816 -253.189646) (xy 107.806381 -253.22899) (xy 107.829252 -253.272567) (xy 107.844836 -253.319248)
			(xy 107.852731 -253.367825) (xy 107.853226 -253.392432) (xy 109.122222 -253.392432) (xy 109.126182 -253.343378)
			(xy 109.137959 -253.295594) (xy 109.15725 -253.250318) (xy 109.183553 -253.208722) (xy 109.216188 -253.171885)
			(xy 109.254309 -253.14076) (xy 109.29693 -253.116153) (xy 109.342946 -253.098701) (xy 109.391165 -253.088857)
			(xy 109.44034 -253.086876) (xy 109.489195 -253.092808) (xy 109.536466 -253.1065) (xy 109.580928 -253.127598)
			(xy 109.621431 -253.155554) (xy 109.656924 -253.189646) (xy 109.686489 -253.22899) (xy 109.70936 -253.272567)
			(xy 109.724944 -253.319248) (xy 109.732839 -253.367825) (xy 109.733334 -253.392432) (xy 109.732839 -253.417039)
			(xy 109.730316 -253.432564) (xy 111.913673 -253.432564) (xy 111.917703 -253.380066) (xy 111.9297 -253.328798)
			(xy 111.949383 -253.279963) (xy 111.976289 -253.234704) (xy 112.009789 -253.194083) (xy 112.049097 -253.159052)
			(xy 112.093292 -253.130432) (xy 112.141337 -253.108893) (xy 112.192108 -253.094941) (xy 112.244413 -253.088903)
			(xy 112.297027 -253.09092) (xy 112.348717 -253.100944) (xy 112.39827 -253.118742) (xy 112.444526 -253.143895)
			(xy 112.4864 -253.175814) (xy 112.522912 -253.213752) (xy 112.553204 -253.256818) (xy 112.576567 -253.304003)
			(xy 112.592453 -253.354202) (xy 112.598358 -253.392432) (xy 112.882184 -253.392432) (xy 112.886144 -253.343378)
			(xy 112.897921 -253.295594) (xy 112.917212 -253.250318) (xy 112.943515 -253.208722) (xy 112.97615 -253.171885)
			(xy 113.014271 -253.14076) (xy 113.056892 -253.116153) (xy 113.102908 -253.098701) (xy 113.151127 -253.088857)
			(xy 113.200302 -253.086876) (xy 113.249157 -253.092808) (xy 113.296428 -253.1065) (xy 113.34089 -253.127598)
			(xy 113.381393 -253.155554) (xy 113.416886 -253.189646) (xy 113.446451 -253.22899) (xy 113.469322 -253.272567)
			(xy 113.484906 -253.319248) (xy 113.492801 -253.367825) (xy 113.493296 -253.392432) (xy 114.762038 -253.392432)
			(xy 114.765998 -253.343378) (xy 114.777775 -253.295594) (xy 114.797066 -253.250318) (xy 114.823369 -253.208722)
			(xy 114.856004 -253.171885) (xy 114.894125 -253.14076) (xy 114.936746 -253.116153) (xy 114.982762 -253.098701)
			(xy 115.030981 -253.088857) (xy 115.080156 -253.086876) (xy 115.129011 -253.092808) (xy 115.176282 -253.1065)
			(xy 115.220744 -253.127598) (xy 115.261247 -253.155554) (xy 115.29674 -253.189646) (xy 115.326305 -253.22899)
			(xy 115.349176 -253.272567) (xy 115.36476 -253.319248) (xy 115.372655 -253.367825) (xy 115.37315 -253.392432)
			(xy 116.642146 -253.392432) (xy 116.646106 -253.343378) (xy 116.657883 -253.295594) (xy 116.677174 -253.250318)
			(xy 116.703477 -253.208722) (xy 116.736112 -253.171885) (xy 116.774233 -253.14076) (xy 116.816854 -253.116153)
			(xy 116.86287 -253.098701) (xy 116.911089 -253.088857) (xy 116.960264 -253.086876) (xy 117.009119 -253.092808)
			(xy 117.05639 -253.1065) (xy 117.100852 -253.127598) (xy 117.141355 -253.155554) (xy 117.176848 -253.189646)
			(xy 117.206413 -253.22899) (xy 117.229284 -253.272567) (xy 117.244868 -253.319248) (xy 117.252763 -253.367825)
			(xy 117.253258 -253.392432) (xy 118.522 -253.392432) (xy 118.52596 -253.343378) (xy 118.537737 -253.295594)
			(xy 118.557028 -253.250318) (xy 118.583331 -253.208722) (xy 118.615966 -253.171885) (xy 118.654087 -253.14076)
			(xy 118.696708 -253.116153) (xy 118.742724 -253.098701) (xy 118.790943 -253.088857) (xy 118.840118 -253.086876)
			(xy 118.888973 -253.092808) (xy 118.936244 -253.1065) (xy 118.980706 -253.127598) (xy 119.021209 -253.155554)
			(xy 119.056702 -253.189646) (xy 119.086267 -253.22899) (xy 119.109138 -253.272567) (xy 119.124722 -253.319248)
			(xy 119.132617 -253.367825) (xy 119.133112 -253.392432) (xy 119.133071 -253.394464) (xy 122.278914 -253.394464)
			(xy 122.282874 -253.34541) (xy 122.294651 -253.297626) (xy 122.313942 -253.25235) (xy 122.340245 -253.210754)
			(xy 122.37288 -253.173917) (xy 122.411001 -253.142792) (xy 122.453622 -253.118185) (xy 122.499638 -253.100733)
			(xy 122.547857 -253.090889) (xy 122.597032 -253.088908) (xy 122.645887 -253.09484) (xy 122.693158 -253.108532)
			(xy 122.73762 -253.12963) (xy 122.778123 -253.157586) (xy 122.813616 -253.191678) (xy 122.843181 -253.231022)
			(xy 122.866052 -253.274599) (xy 122.881636 -253.32128) (xy 122.889531 -253.369857) (xy 122.890026 -253.394464)
			(xy 124.159022 -253.394464) (xy 124.162982 -253.34541) (xy 124.174759 -253.297626) (xy 124.19405 -253.25235)
			(xy 124.220353 -253.210754) (xy 124.252988 -253.173917) (xy 124.291109 -253.142792) (xy 124.33373 -253.118185)
			(xy 124.379746 -253.100733) (xy 124.427965 -253.090889) (xy 124.47714 -253.088908) (xy 124.525995 -253.09484)
			(xy 124.573266 -253.108532) (xy 124.617728 -253.12963) (xy 124.658231 -253.157586) (xy 124.693724 -253.191678)
			(xy 124.723289 -253.231022) (xy 124.74616 -253.274599) (xy 124.761744 -253.32128) (xy 124.769639 -253.369857)
			(xy 124.770134 -253.394464) (xy 126.038876 -253.394464) (xy 126.042836 -253.34541) (xy 126.054613 -253.297626)
			(xy 126.073904 -253.25235) (xy 126.100207 -253.210754) (xy 126.132842 -253.173917) (xy 126.170963 -253.142792)
			(xy 126.213584 -253.118185) (xy 126.2596 -253.100733) (xy 126.307819 -253.090889) (xy 126.356994 -253.088908)
			(xy 126.405849 -253.09484) (xy 126.45312 -253.108532) (xy 126.497582 -253.12963) (xy 126.538085 -253.157586)
			(xy 126.573578 -253.191678) (xy 126.603143 -253.231022) (xy 126.626014 -253.274599) (xy 126.641598 -253.32128)
			(xy 126.649493 -253.369857) (xy 126.649988 -253.394464) (xy 127.908553 -253.394464) (xy 127.912648 -253.343736)
			(xy 127.924827 -253.294322) (xy 127.944775 -253.247502) (xy 127.971976 -253.204488) (xy 128.005724 -253.166394)
			(xy 128.045146 -253.134207) (xy 128.08922 -253.108761) (xy 128.136806 -253.090714) (xy 128.18667 -253.080534)
			(xy 128.237522 -253.078485) (xy 128.288043 -253.084619) (xy 128.336927 -253.098779) (xy 128.382906 -253.120596)
			(xy 128.42479 -253.149506) (xy 128.461494 -253.184761) (xy 128.492067 -253.225447) (xy 128.515718 -253.27051)
			(xy 128.531834 -253.318784) (xy 128.539998 -253.369018) (xy 128.54051 -253.394464) (xy 128.848607 -253.394464)
			(xy 128.852702 -253.343736) (xy 128.864881 -253.294322) (xy 128.884829 -253.247502) (xy 128.91203 -253.204488)
			(xy 128.945778 -253.166394) (xy 128.9852 -253.134207) (xy 129.029274 -253.108761) (xy 129.07686 -253.090714)
			(xy 129.126724 -253.080534) (xy 129.177576 -253.078485) (xy 129.228097 -253.084619) (xy 129.276981 -253.098779)
			(xy 129.32296 -253.120596) (xy 129.364844 -253.149506) (xy 129.401548 -253.184761) (xy 129.432121 -253.225447)
			(xy 129.455772 -253.27051) (xy 129.471888 -253.318784) (xy 129.480052 -253.369018) (xy 129.480564 -253.394464)
			(xy 129.798838 -253.394464) (xy 129.802798 -253.34541) (xy 129.814575 -253.297626) (xy 129.833866 -253.25235)
			(xy 129.860169 -253.210754) (xy 129.892804 -253.173917) (xy 129.930925 -253.142792) (xy 129.973546 -253.118185)
			(xy 130.019562 -253.100733) (xy 130.067781 -253.090889) (xy 130.116956 -253.088908) (xy 130.165811 -253.09484)
			(xy 130.213082 -253.108532) (xy 130.257544 -253.12963) (xy 130.298047 -253.157586) (xy 130.33354 -253.191678)
			(xy 130.363105 -253.231022) (xy 130.385976 -253.274599) (xy 130.40156 -253.32128) (xy 130.409455 -253.369857)
			(xy 130.40995 -253.394464) (xy 130.728461 -253.394464) (xy 130.732556 -253.343736) (xy 130.744735 -253.294322)
			(xy 130.764683 -253.247502) (xy 130.791884 -253.204488) (xy 130.825632 -253.166394) (xy 130.865054 -253.134207)
			(xy 130.909128 -253.108761) (xy 130.956714 -253.090714) (xy 131.006578 -253.080534) (xy 131.05743 -253.078485)
			(xy 131.107951 -253.084619) (xy 131.156835 -253.098779) (xy 131.202814 -253.120596) (xy 131.244698 -253.149506)
			(xy 131.281402 -253.184761) (xy 131.311975 -253.225447) (xy 131.335626 -253.27051) (xy 131.351742 -253.318784)
			(xy 131.359906 -253.369018) (xy 131.360418 -253.394464) (xy 131.678946 -253.394464) (xy 131.682906 -253.34541)
			(xy 131.694683 -253.297626) (xy 131.713974 -253.25235) (xy 131.740277 -253.210754) (xy 131.772912 -253.173917)
			(xy 131.811033 -253.142792) (xy 131.853654 -253.118185) (xy 131.89967 -253.100733) (xy 131.947889 -253.090889)
			(xy 131.997064 -253.088908) (xy 132.045919 -253.09484) (xy 132.09319 -253.108532) (xy 132.137652 -253.12963)
			(xy 132.178155 -253.157586) (xy 132.213648 -253.191678) (xy 132.243213 -253.231022) (xy 132.266084 -253.274599)
			(xy 132.281668 -253.32128) (xy 132.289563 -253.369857) (xy 132.290058 -253.394464) (xy 132.608569 -253.394464)
			(xy 132.612664 -253.343736) (xy 132.624843 -253.294322) (xy 132.644791 -253.247502) (xy 132.671992 -253.204488)
			(xy 132.70574 -253.166394) (xy 132.745162 -253.134207) (xy 132.789236 -253.108761) (xy 132.836822 -253.090714)
			(xy 132.886686 -253.080534) (xy 132.937538 -253.078485) (xy 132.988059 -253.084619) (xy 133.036943 -253.098779)
			(xy 133.082922 -253.120596) (xy 133.124806 -253.149506) (xy 133.16151 -253.184761) (xy 133.192083 -253.225447)
			(xy 133.215734 -253.27051) (xy 133.23185 -253.318784) (xy 133.240014 -253.369018) (xy 133.240526 -253.394464)
			(xy 133.559054 -253.394464) (xy 133.563014 -253.34541) (xy 133.574791 -253.297626) (xy 133.594082 -253.25235)
			(xy 133.620385 -253.210754) (xy 133.65302 -253.173917) (xy 133.691141 -253.142792) (xy 133.733762 -253.118185)
			(xy 133.779778 -253.100733) (xy 133.827997 -253.090889) (xy 133.877172 -253.088908) (xy 133.926027 -253.09484)
			(xy 133.973298 -253.108532) (xy 134.01776 -253.12963) (xy 134.058263 -253.157586) (xy 134.093756 -253.191678)
			(xy 134.123321 -253.231022) (xy 134.146192 -253.274599) (xy 134.161776 -253.32128) (xy 134.169671 -253.369857)
			(xy 134.170166 -253.394464) (xy 134.488423 -253.394464) (xy 134.492518 -253.343736) (xy 134.504697 -253.294322)
			(xy 134.524645 -253.247502) (xy 134.551846 -253.204488) (xy 134.585594 -253.166394) (xy 134.625016 -253.134207)
			(xy 134.66909 -253.108761) (xy 134.716676 -253.090714) (xy 134.76654 -253.080534) (xy 134.817392 -253.078485)
			(xy 134.867913 -253.084619) (xy 134.916797 -253.098779) (xy 134.962776 -253.120596) (xy 135.00466 -253.149506)
			(xy 135.041364 -253.184761) (xy 135.071937 -253.225447) (xy 135.095588 -253.27051) (xy 135.111704 -253.318784)
			(xy 135.119868 -253.369018) (xy 135.12038 -253.394464) (xy 135.428477 -253.394464) (xy 135.432572 -253.343736)
			(xy 135.444751 -253.294322) (xy 135.464699 -253.247502) (xy 135.4919 -253.204488) (xy 135.525648 -253.166394)
			(xy 135.56507 -253.134207) (xy 135.609144 -253.108761) (xy 135.65673 -253.090714) (xy 135.706594 -253.080534)
			(xy 135.757446 -253.078485) (xy 135.807967 -253.084619) (xy 135.856851 -253.098779) (xy 135.90283 -253.120596)
			(xy 135.944714 -253.149506) (xy 135.981418 -253.184761) (xy 136.011991 -253.225447) (xy 136.035642 -253.27051)
			(xy 136.051758 -253.318784) (xy 136.059922 -253.369018) (xy 136.060434 -253.394464) (xy 136.378962 -253.394464)
			(xy 136.382922 -253.34541) (xy 136.394699 -253.297626) (xy 136.41399 -253.25235) (xy 136.440293 -253.210754)
			(xy 136.472928 -253.173917) (xy 136.511049 -253.142792) (xy 136.55367 -253.118185) (xy 136.599686 -253.100733)
			(xy 136.647905 -253.090889) (xy 136.69708 -253.088908) (xy 136.745935 -253.09484) (xy 136.793206 -253.108532)
			(xy 136.837668 -253.12963) (xy 136.878171 -253.157586) (xy 136.913664 -253.191678) (xy 136.943229 -253.231022)
			(xy 136.9661 -253.274599) (xy 136.981684 -253.32128) (xy 136.989579 -253.369857) (xy 136.990074 -253.394464)
			(xy 137.308585 -253.394464) (xy 137.31268 -253.343736) (xy 137.324859 -253.294322) (xy 137.344807 -253.247502)
			(xy 137.372008 -253.204488) (xy 137.405756 -253.166394) (xy 137.445178 -253.134207) (xy 137.489252 -253.108761)
			(xy 137.536838 -253.090714) (xy 137.586702 -253.080534) (xy 137.637554 -253.078485) (xy 137.688075 -253.084619)
			(xy 137.736959 -253.098779) (xy 137.782938 -253.120596) (xy 137.824822 -253.149506) (xy 137.861526 -253.184761)
			(xy 137.892099 -253.225447) (xy 137.91575 -253.27051) (xy 137.931866 -253.318784) (xy 137.94003 -253.369018)
			(xy 137.940542 -253.394464) (xy 138.25907 -253.394464) (xy 138.26303 -253.34541) (xy 138.274807 -253.297626)
			(xy 138.294098 -253.25235) (xy 138.320401 -253.210754) (xy 138.353036 -253.173917) (xy 138.391157 -253.142792)
			(xy 138.433778 -253.118185) (xy 138.479794 -253.100733) (xy 138.528013 -253.090889) (xy 138.577188 -253.088908)
			(xy 138.626043 -253.09484) (xy 138.673314 -253.108532) (xy 138.717776 -253.12963) (xy 138.758279 -253.157586)
			(xy 138.793772 -253.191678) (xy 138.823337 -253.231022) (xy 138.846208 -253.274599) (xy 138.861792 -253.32128)
			(xy 138.869687 -253.369857) (xy 138.870182 -253.394464) (xy 139.188439 -253.394464) (xy 139.192534 -253.343736)
			(xy 139.204713 -253.294322) (xy 139.224661 -253.247502) (xy 139.251862 -253.204488) (xy 139.28561 -253.166394)
			(xy 139.325032 -253.134207) (xy 139.369106 -253.108761) (xy 139.416692 -253.090714) (xy 139.466556 -253.080534)
			(xy 139.517408 -253.078485) (xy 139.567929 -253.084619) (xy 139.616813 -253.098779) (xy 139.662792 -253.120596)
			(xy 139.704676 -253.149506) (xy 139.74138 -253.184761) (xy 139.771953 -253.225447) (xy 139.795604 -253.27051)
			(xy 139.81172 -253.318784) (xy 139.819884 -253.369018) (xy 139.820396 -253.394464) (xy 140.138924 -253.394464)
			(xy 140.142884 -253.34541) (xy 140.154661 -253.297626) (xy 140.173952 -253.25235) (xy 140.200255 -253.210754)
			(xy 140.23289 -253.173917) (xy 140.271011 -253.142792) (xy 140.313632 -253.118185) (xy 140.359648 -253.100733)
			(xy 140.407867 -253.090889) (xy 140.457042 -253.088908) (xy 140.505897 -253.09484) (xy 140.553168 -253.108532)
			(xy 140.59763 -253.12963) (xy 140.638133 -253.157586) (xy 140.673626 -253.191678) (xy 140.703191 -253.231022)
			(xy 140.726062 -253.274599) (xy 140.741646 -253.32128) (xy 140.749541 -253.369857) (xy 140.750036 -253.394464)
			(xy 141.068547 -253.394464) (xy 141.072642 -253.343736) (xy 141.084821 -253.294322) (xy 141.104769 -253.247502)
			(xy 141.13197 -253.204488) (xy 141.165718 -253.166394) (xy 141.20514 -253.134207) (xy 141.249214 -253.108761)
			(xy 141.2968 -253.090714) (xy 141.346664 -253.080534) (xy 141.397516 -253.078485) (xy 141.448037 -253.084619)
			(xy 141.496921 -253.098779) (xy 141.5429 -253.120596) (xy 141.584784 -253.149506) (xy 141.621488 -253.184761)
			(xy 141.652061 -253.225447) (xy 141.675712 -253.27051) (xy 141.691828 -253.318784) (xy 141.699992 -253.369018)
			(xy 141.700504 -253.394464) (xy 142.008601 -253.394464) (xy 142.012696 -253.343736) (xy 142.024875 -253.294322)
			(xy 142.044823 -253.247502) (xy 142.072024 -253.204488) (xy 142.105772 -253.166394) (xy 142.145194 -253.134207)
			(xy 142.189268 -253.108761) (xy 142.236854 -253.090714) (xy 142.286718 -253.080534) (xy 142.33757 -253.078485)
			(xy 142.388091 -253.084619) (xy 142.436975 -253.098779) (xy 142.482954 -253.120596) (xy 142.524838 -253.149506)
			(xy 142.561542 -253.184761) (xy 142.592115 -253.225447) (xy 142.615766 -253.27051) (xy 142.631882 -253.318784)
			(xy 142.640046 -253.369018) (xy 142.640558 -253.394464) (xy 142.958832 -253.394464) (xy 142.962792 -253.34541)
			(xy 142.974569 -253.297626) (xy 142.99386 -253.25235) (xy 143.020163 -253.210754) (xy 143.052798 -253.173917)
			(xy 143.090919 -253.142792) (xy 143.13354 -253.118185) (xy 143.179556 -253.100733) (xy 143.227775 -253.090889)
			(xy 143.27695 -253.088908) (xy 143.325805 -253.09484) (xy 143.373076 -253.108532) (xy 143.417538 -253.12963)
			(xy 143.458041 -253.157586) (xy 143.493534 -253.191678) (xy 143.523099 -253.231022) (xy 143.54597 -253.274599)
			(xy 143.561554 -253.32128) (xy 143.569449 -253.369857) (xy 143.569944 -253.394464) (xy 144.83894 -253.394464)
			(xy 144.8429 -253.34541) (xy 144.854677 -253.297626) (xy 144.873968 -253.25235) (xy 144.900271 -253.210754)
			(xy 144.932906 -253.173917) (xy 144.971027 -253.142792) (xy 145.013648 -253.118185) (xy 145.059664 -253.100733)
			(xy 145.107883 -253.090889) (xy 145.157058 -253.088908) (xy 145.205913 -253.09484) (xy 145.253184 -253.108532)
			(xy 145.297646 -253.12963) (xy 145.338149 -253.157586) (xy 145.373642 -253.191678) (xy 145.403207 -253.231022)
			(xy 145.426078 -253.274599) (xy 145.441662 -253.32128) (xy 145.449557 -253.369857) (xy 145.450052 -253.394464)
			(xy 145.449557 -253.419071) (xy 145.441662 -253.467648) (xy 145.426078 -253.514329) (xy 145.403207 -253.557906)
			(xy 145.373642 -253.59725) (xy 145.338149 -253.631342) (xy 145.297646 -253.659298) (xy 145.253184 -253.680396)
			(xy 145.205913 -253.694088) (xy 145.157058 -253.70002) (xy 145.107883 -253.698039) (xy 145.059664 -253.688195)
			(xy 145.013648 -253.670743) (xy 144.971027 -253.646136) (xy 144.932906 -253.615011) (xy 144.900271 -253.578174)
			(xy 144.873968 -253.536578) (xy 144.854677 -253.491302) (xy 144.8429 -253.443518) (xy 144.83894 -253.394464)
			(xy 143.569944 -253.394464) (xy 143.569449 -253.419071) (xy 143.561554 -253.467648) (xy 143.54597 -253.514329)
			(xy 143.523099 -253.557906) (xy 143.493534 -253.59725) (xy 143.458041 -253.631342) (xy 143.417538 -253.659298)
			(xy 143.373076 -253.680396) (xy 143.325805 -253.694088) (xy 143.27695 -253.70002) (xy 143.227775 -253.698039)
			(xy 143.179556 -253.688195) (xy 143.13354 -253.670743) (xy 143.090919 -253.646136) (xy 143.052798 -253.615011)
			(xy 143.020163 -253.578174) (xy 142.99386 -253.536578) (xy 142.974569 -253.491302) (xy 142.962792 -253.443518)
			(xy 142.958832 -253.394464) (xy 142.640558 -253.394464) (xy 142.640046 -253.41991) (xy 142.631882 -253.470144)
			(xy 142.615766 -253.518418) (xy 142.592115 -253.563481) (xy 142.561542 -253.604167) (xy 142.524838 -253.639422)
			(xy 142.482954 -253.668332) (xy 142.436975 -253.690149) (xy 142.388091 -253.704309) (xy 142.33757 -253.710443)
			(xy 142.286718 -253.708394) (xy 142.236854 -253.698214) (xy 142.189268 -253.680167) (xy 142.145194 -253.654721)
			(xy 142.105772 -253.622534) (xy 142.072024 -253.58444) (xy 142.044823 -253.541426) (xy 142.024875 -253.494606)
			(xy 142.012696 -253.445192) (xy 142.008601 -253.394464) (xy 141.700504 -253.394464) (xy 141.699992 -253.41991)
			(xy 141.691828 -253.470144) (xy 141.675712 -253.518418) (xy 141.652061 -253.563481) (xy 141.621488 -253.604167)
			(xy 141.584784 -253.639422) (xy 141.5429 -253.668332) (xy 141.496921 -253.690149) (xy 141.448037 -253.704309)
			(xy 141.397516 -253.710443) (xy 141.346664 -253.708394) (xy 141.2968 -253.698214) (xy 141.249214 -253.680167)
			(xy 141.20514 -253.654721) (xy 141.165718 -253.622534) (xy 141.13197 -253.58444) (xy 141.104769 -253.541426)
			(xy 141.084821 -253.494606) (xy 141.072642 -253.445192) (xy 141.068547 -253.394464) (xy 140.750036 -253.394464)
			(xy 140.749541 -253.419071) (xy 140.741646 -253.467648) (xy 140.726062 -253.514329) (xy 140.703191 -253.557906)
			(xy 140.673626 -253.59725) (xy 140.638133 -253.631342) (xy 140.59763 -253.659298) (xy 140.553168 -253.680396)
			(xy 140.505897 -253.694088) (xy 140.457042 -253.70002) (xy 140.407867 -253.698039) (xy 140.359648 -253.688195)
			(xy 140.313632 -253.670743) (xy 140.271011 -253.646136) (xy 140.23289 -253.615011) (xy 140.200255 -253.578174)
			(xy 140.173952 -253.536578) (xy 140.154661 -253.491302) (xy 140.142884 -253.443518) (xy 140.138924 -253.394464)
			(xy 139.820396 -253.394464) (xy 139.819884 -253.41991) (xy 139.81172 -253.470144) (xy 139.795604 -253.518418)
			(xy 139.771953 -253.563481) (xy 139.74138 -253.604167) (xy 139.704676 -253.639422) (xy 139.662792 -253.668332)
			(xy 139.616813 -253.690149) (xy 139.567929 -253.704309) (xy 139.517408 -253.710443) (xy 139.466556 -253.708394)
			(xy 139.416692 -253.698214) (xy 139.369106 -253.680167) (xy 139.325032 -253.654721) (xy 139.28561 -253.622534)
			(xy 139.251862 -253.58444) (xy 139.224661 -253.541426) (xy 139.204713 -253.494606) (xy 139.192534 -253.445192)
			(xy 139.188439 -253.394464) (xy 138.870182 -253.394464) (xy 138.869687 -253.419071) (xy 138.861792 -253.467648)
			(xy 138.846208 -253.514329) (xy 138.823337 -253.557906) (xy 138.793772 -253.59725) (xy 138.758279 -253.631342)
			(xy 138.717776 -253.659298) (xy 138.673314 -253.680396) (xy 138.626043 -253.694088) (xy 138.577188 -253.70002)
			(xy 138.528013 -253.698039) (xy 138.479794 -253.688195) (xy 138.433778 -253.670743) (xy 138.391157 -253.646136)
			(xy 138.353036 -253.615011) (xy 138.320401 -253.578174) (xy 138.294098 -253.536578) (xy 138.274807 -253.491302)
			(xy 138.26303 -253.443518) (xy 138.25907 -253.394464) (xy 137.940542 -253.394464) (xy 137.94003 -253.41991)
			(xy 137.931866 -253.470144) (xy 137.91575 -253.518418) (xy 137.892099 -253.563481) (xy 137.861526 -253.604167)
			(xy 137.824822 -253.639422) (xy 137.782938 -253.668332) (xy 137.736959 -253.690149) (xy 137.688075 -253.704309)
			(xy 137.637554 -253.710443) (xy 137.586702 -253.708394) (xy 137.536838 -253.698214) (xy 137.489252 -253.680167)
			(xy 137.445178 -253.654721) (xy 137.405756 -253.622534) (xy 137.372008 -253.58444) (xy 137.344807 -253.541426)
			(xy 137.324859 -253.494606) (xy 137.31268 -253.445192) (xy 137.308585 -253.394464) (xy 136.990074 -253.394464)
			(xy 136.989579 -253.419071) (xy 136.981684 -253.467648) (xy 136.9661 -253.514329) (xy 136.943229 -253.557906)
			(xy 136.913664 -253.59725) (xy 136.878171 -253.631342) (xy 136.837668 -253.659298) (xy 136.793206 -253.680396)
			(xy 136.745935 -253.694088) (xy 136.69708 -253.70002) (xy 136.647905 -253.698039) (xy 136.599686 -253.688195)
			(xy 136.55367 -253.670743) (xy 136.511049 -253.646136) (xy 136.472928 -253.615011) (xy 136.440293 -253.578174)
			(xy 136.41399 -253.536578) (xy 136.394699 -253.491302) (xy 136.382922 -253.443518) (xy 136.378962 -253.394464)
			(xy 136.060434 -253.394464) (xy 136.059922 -253.41991) (xy 136.051758 -253.470144) (xy 136.035642 -253.518418)
			(xy 136.011991 -253.563481) (xy 135.981418 -253.604167) (xy 135.944714 -253.639422) (xy 135.90283 -253.668332)
			(xy 135.856851 -253.690149) (xy 135.807967 -253.704309) (xy 135.757446 -253.710443) (xy 135.706594 -253.708394)
			(xy 135.65673 -253.698214) (xy 135.609144 -253.680167) (xy 135.56507 -253.654721) (xy 135.525648 -253.622534)
			(xy 135.4919 -253.58444) (xy 135.464699 -253.541426) (xy 135.444751 -253.494606) (xy 135.432572 -253.445192)
			(xy 135.428477 -253.394464) (xy 135.12038 -253.394464) (xy 135.119868 -253.41991) (xy 135.111704 -253.470144)
			(xy 135.095588 -253.518418) (xy 135.071937 -253.563481) (xy 135.041364 -253.604167) (xy 135.00466 -253.639422)
			(xy 134.962776 -253.668332) (xy 134.916797 -253.690149) (xy 134.867913 -253.704309) (xy 134.817392 -253.710443)
			(xy 134.76654 -253.708394) (xy 134.716676 -253.698214) (xy 134.66909 -253.680167) (xy 134.625016 -253.654721)
			(xy 134.585594 -253.622534) (xy 134.551846 -253.58444) (xy 134.524645 -253.541426) (xy 134.504697 -253.494606)
			(xy 134.492518 -253.445192) (xy 134.488423 -253.394464) (xy 134.170166 -253.394464) (xy 134.169671 -253.419071)
			(xy 134.161776 -253.467648) (xy 134.146192 -253.514329) (xy 134.123321 -253.557906) (xy 134.093756 -253.59725)
			(xy 134.058263 -253.631342) (xy 134.01776 -253.659298) (xy 133.973298 -253.680396) (xy 133.926027 -253.694088)
			(xy 133.877172 -253.70002) (xy 133.827997 -253.698039) (xy 133.779778 -253.688195) (xy 133.733762 -253.670743)
			(xy 133.691141 -253.646136) (xy 133.65302 -253.615011) (xy 133.620385 -253.578174) (xy 133.594082 -253.536578)
			(xy 133.574791 -253.491302) (xy 133.563014 -253.443518) (xy 133.559054 -253.394464) (xy 133.240526 -253.394464)
			(xy 133.240014 -253.41991) (xy 133.23185 -253.470144) (xy 133.215734 -253.518418) (xy 133.192083 -253.563481)
			(xy 133.16151 -253.604167) (xy 133.124806 -253.639422) (xy 133.082922 -253.668332) (xy 133.036943 -253.690149)
			(xy 132.988059 -253.704309) (xy 132.937538 -253.710443) (xy 132.886686 -253.708394) (xy 132.836822 -253.698214)
			(xy 132.789236 -253.680167) (xy 132.745162 -253.654721) (xy 132.70574 -253.622534) (xy 132.671992 -253.58444)
			(xy 132.644791 -253.541426) (xy 132.624843 -253.494606) (xy 132.612664 -253.445192) (xy 132.608569 -253.394464)
			(xy 132.290058 -253.394464) (xy 132.289563 -253.419071) (xy 132.281668 -253.467648) (xy 132.266084 -253.514329)
			(xy 132.243213 -253.557906) (xy 132.213648 -253.59725) (xy 132.178155 -253.631342) (xy 132.137652 -253.659298)
			(xy 132.09319 -253.680396) (xy 132.045919 -253.694088) (xy 131.997064 -253.70002) (xy 131.947889 -253.698039)
			(xy 131.89967 -253.688195) (xy 131.853654 -253.670743) (xy 131.811033 -253.646136) (xy 131.772912 -253.615011)
			(xy 131.740277 -253.578174) (xy 131.713974 -253.536578) (xy 131.694683 -253.491302) (xy 131.682906 -253.443518)
			(xy 131.678946 -253.394464) (xy 131.360418 -253.394464) (xy 131.359906 -253.41991) (xy 131.351742 -253.470144)
			(xy 131.335626 -253.518418) (xy 131.311975 -253.563481) (xy 131.281402 -253.604167) (xy 131.244698 -253.639422)
			(xy 131.202814 -253.668332) (xy 131.156835 -253.690149) (xy 131.107951 -253.704309) (xy 131.05743 -253.710443)
			(xy 131.006578 -253.708394) (xy 130.956714 -253.698214) (xy 130.909128 -253.680167) (xy 130.865054 -253.654721)
			(xy 130.825632 -253.622534) (xy 130.791884 -253.58444) (xy 130.764683 -253.541426) (xy 130.744735 -253.494606)
			(xy 130.732556 -253.445192) (xy 130.728461 -253.394464) (xy 130.40995 -253.394464) (xy 130.409455 -253.419071)
			(xy 130.40156 -253.467648) (xy 130.385976 -253.514329) (xy 130.363105 -253.557906) (xy 130.33354 -253.59725)
			(xy 130.298047 -253.631342) (xy 130.257544 -253.659298) (xy 130.213082 -253.680396) (xy 130.165811 -253.694088)
			(xy 130.116956 -253.70002) (xy 130.067781 -253.698039) (xy 130.019562 -253.688195) (xy 129.973546 -253.670743)
			(xy 129.930925 -253.646136) (xy 129.892804 -253.615011) (xy 129.860169 -253.578174) (xy 129.833866 -253.536578)
			(xy 129.814575 -253.491302) (xy 129.802798 -253.443518) (xy 129.798838 -253.394464) (xy 129.480564 -253.394464)
			(xy 129.480052 -253.41991) (xy 129.471888 -253.470144) (xy 129.455772 -253.518418) (xy 129.432121 -253.563481)
			(xy 129.401548 -253.604167) (xy 129.364844 -253.639422) (xy 129.32296 -253.668332) (xy 129.276981 -253.690149)
			(xy 129.228097 -253.704309) (xy 129.177576 -253.710443) (xy 129.126724 -253.708394) (xy 129.07686 -253.698214)
			(xy 129.029274 -253.680167) (xy 128.9852 -253.654721) (xy 128.945778 -253.622534) (xy 128.91203 -253.58444)
			(xy 128.884829 -253.541426) (xy 128.864881 -253.494606) (xy 128.852702 -253.445192) (xy 128.848607 -253.394464)
			(xy 128.54051 -253.394464) (xy 128.539998 -253.41991) (xy 128.531834 -253.470144) (xy 128.515718 -253.518418)
			(xy 128.492067 -253.563481) (xy 128.461494 -253.604167) (xy 128.42479 -253.639422) (xy 128.382906 -253.668332)
			(xy 128.336927 -253.690149) (xy 128.288043 -253.704309) (xy 128.237522 -253.710443) (xy 128.18667 -253.708394)
			(xy 128.136806 -253.698214) (xy 128.08922 -253.680167) (xy 128.045146 -253.654721) (xy 128.005724 -253.622534)
			(xy 127.971976 -253.58444) (xy 127.944775 -253.541426) (xy 127.924827 -253.494606) (xy 127.912648 -253.445192)
			(xy 127.908553 -253.394464) (xy 126.649988 -253.394464) (xy 126.649493 -253.419071) (xy 126.641598 -253.467648)
			(xy 126.626014 -253.514329) (xy 126.603143 -253.557906) (xy 126.573578 -253.59725) (xy 126.538085 -253.631342)
			(xy 126.497582 -253.659298) (xy 126.45312 -253.680396) (xy 126.405849 -253.694088) (xy 126.356994 -253.70002)
			(xy 126.307819 -253.698039) (xy 126.2596 -253.688195) (xy 126.213584 -253.670743) (xy 126.170963 -253.646136)
			(xy 126.132842 -253.615011) (xy 126.100207 -253.578174) (xy 126.073904 -253.536578) (xy 126.054613 -253.491302)
			(xy 126.042836 -253.443518) (xy 126.038876 -253.394464) (xy 124.770134 -253.394464) (xy 124.769639 -253.419071)
			(xy 124.761744 -253.467648) (xy 124.74616 -253.514329) (xy 124.723289 -253.557906) (xy 124.693724 -253.59725)
			(xy 124.658231 -253.631342) (xy 124.617728 -253.659298) (xy 124.573266 -253.680396) (xy 124.525995 -253.694088)
			(xy 124.47714 -253.70002) (xy 124.427965 -253.698039) (xy 124.379746 -253.688195) (xy 124.33373 -253.670743)
			(xy 124.291109 -253.646136) (xy 124.252988 -253.615011) (xy 124.220353 -253.578174) (xy 124.19405 -253.536578)
			(xy 124.174759 -253.491302) (xy 124.162982 -253.443518) (xy 124.159022 -253.394464) (xy 122.890026 -253.394464)
			(xy 122.889531 -253.419071) (xy 122.881636 -253.467648) (xy 122.866052 -253.514329) (xy 122.843181 -253.557906)
			(xy 122.813616 -253.59725) (xy 122.778123 -253.631342) (xy 122.73762 -253.659298) (xy 122.693158 -253.680396)
			(xy 122.645887 -253.694088) (xy 122.597032 -253.70002) (xy 122.547857 -253.698039) (xy 122.499638 -253.688195)
			(xy 122.453622 -253.670743) (xy 122.411001 -253.646136) (xy 122.37288 -253.615011) (xy 122.340245 -253.578174)
			(xy 122.313942 -253.536578) (xy 122.294651 -253.491302) (xy 122.282874 -253.443518) (xy 122.278914 -253.394464)
			(xy 119.133071 -253.394464) (xy 119.132617 -253.417039) (xy 119.124722 -253.465616) (xy 119.109138 -253.512297)
			(xy 119.086267 -253.555874) (xy 119.056702 -253.595218) (xy 119.021209 -253.62931) (xy 118.980706 -253.657266)
			(xy 118.936244 -253.678364) (xy 118.888973 -253.692056) (xy 118.840118 -253.697988) (xy 118.790943 -253.696007)
			(xy 118.742724 -253.686163) (xy 118.696708 -253.668711) (xy 118.654087 -253.644104) (xy 118.615966 -253.612979)
			(xy 118.583331 -253.576142) (xy 118.557028 -253.534546) (xy 118.537737 -253.48927) (xy 118.52596 -253.441486)
			(xy 118.522 -253.392432) (xy 117.253258 -253.392432) (xy 117.252763 -253.417039) (xy 117.244868 -253.465616)
			(xy 117.229284 -253.512297) (xy 117.206413 -253.555874) (xy 117.176848 -253.595218) (xy 117.141355 -253.62931)
			(xy 117.100852 -253.657266) (xy 117.05639 -253.678364) (xy 117.009119 -253.692056) (xy 116.960264 -253.697988)
			(xy 116.911089 -253.696007) (xy 116.86287 -253.686163) (xy 116.816854 -253.668711) (xy 116.774233 -253.644104)
			(xy 116.736112 -253.612979) (xy 116.703477 -253.576142) (xy 116.677174 -253.534546) (xy 116.657883 -253.48927)
			(xy 116.646106 -253.441486) (xy 116.642146 -253.392432) (xy 115.37315 -253.392432) (xy 115.372655 -253.417039)
			(xy 115.36476 -253.465616) (xy 115.349176 -253.512297) (xy 115.326305 -253.555874) (xy 115.29674 -253.595218)
			(xy 115.261247 -253.62931) (xy 115.220744 -253.657266) (xy 115.176282 -253.678364) (xy 115.129011 -253.692056)
			(xy 115.080156 -253.697988) (xy 115.030981 -253.696007) (xy 114.982762 -253.686163) (xy 114.936746 -253.668711)
			(xy 114.894125 -253.644104) (xy 114.856004 -253.612979) (xy 114.823369 -253.576142) (xy 114.797066 -253.534546)
			(xy 114.777775 -253.48927) (xy 114.765998 -253.441486) (xy 114.762038 -253.392432) (xy 113.493296 -253.392432)
			(xy 113.492801 -253.417039) (xy 113.484906 -253.465616) (xy 113.469322 -253.512297) (xy 113.446451 -253.555874)
			(xy 113.416886 -253.595218) (xy 113.381393 -253.62931) (xy 113.34089 -253.657266) (xy 113.296428 -253.678364)
			(xy 113.249157 -253.692056) (xy 113.200302 -253.697988) (xy 113.151127 -253.696007) (xy 113.102908 -253.686163)
			(xy 113.056892 -253.668711) (xy 113.014271 -253.644104) (xy 112.97615 -253.612979) (xy 112.943515 -253.576142)
			(xy 112.917212 -253.534546) (xy 112.897921 -253.48927) (xy 112.886144 -253.441486) (xy 112.882184 -253.392432)
			(xy 112.598358 -253.392432) (xy 112.60049 -253.406238) (xy 112.600994 -253.432564) (xy 112.60049 -253.45889)
			(xy 112.592453 -253.510926) (xy 112.576567 -253.561125) (xy 112.553204 -253.60831) (xy 112.522912 -253.651376)
			(xy 112.4864 -253.689314) (xy 112.444526 -253.721233) (xy 112.39827 -253.746386) (xy 112.348717 -253.764184)
			(xy 112.297027 -253.774208) (xy 112.244413 -253.776225) (xy 112.192108 -253.770187) (xy 112.141337 -253.756235)
			(xy 112.093292 -253.734696) (xy 112.049097 -253.706076) (xy 112.009789 -253.671045) (xy 111.976289 -253.630424)
			(xy 111.949383 -253.585165) (xy 111.9297 -253.53633) (xy 111.917703 -253.485062) (xy 111.913673 -253.432564)
			(xy 109.730316 -253.432564) (xy 109.724944 -253.465616) (xy 109.70936 -253.512297) (xy 109.686489 -253.555874)
			(xy 109.656924 -253.595218) (xy 109.621431 -253.62931) (xy 109.580928 -253.657266) (xy 109.536466 -253.678364)
			(xy 109.489195 -253.692056) (xy 109.44034 -253.697988) (xy 109.391165 -253.696007) (xy 109.342946 -253.686163)
			(xy 109.29693 -253.668711) (xy 109.254309 -253.644104) (xy 109.216188 -253.612979) (xy 109.183553 -253.576142)
			(xy 109.15725 -253.534546) (xy 109.137959 -253.48927) (xy 109.126182 -253.441486) (xy 109.122222 -253.392432)
			(xy 107.853226 -253.392432) (xy 107.852731 -253.417039) (xy 107.844836 -253.465616) (xy 107.829252 -253.512297)
			(xy 107.806381 -253.555874) (xy 107.776816 -253.595218) (xy 107.741323 -253.62931) (xy 107.70082 -253.657266)
			(xy 107.656358 -253.678364) (xy 107.609087 -253.692056) (xy 107.560232 -253.697988) (xy 107.511057 -253.696007)
			(xy 107.462838 -253.686163) (xy 107.416822 -253.668711) (xy 107.374201 -253.644104) (xy 107.33608 -253.612979)
			(xy 107.303445 -253.576142) (xy 107.277142 -253.534546) (xy 107.257851 -253.48927) (xy 107.246074 -253.441486)
			(xy 107.242114 -253.392432) (xy 105.973118 -253.392432) (xy 105.972623 -253.417039) (xy 105.964728 -253.465616)
			(xy 105.949144 -253.512297) (xy 105.926273 -253.555874) (xy 105.896708 -253.595218) (xy 105.861215 -253.62931)
			(xy 105.820712 -253.657266) (xy 105.77625 -253.678364) (xy 105.728979 -253.692056) (xy 105.680124 -253.697988)
			(xy 105.630949 -253.696007) (xy 105.58273 -253.686163) (xy 105.536714 -253.668711) (xy 105.494093 -253.644104)
			(xy 105.455972 -253.612979) (xy 105.423337 -253.576142) (xy 105.397034 -253.534546) (xy 105.377743 -253.48927)
			(xy 105.365966 -253.441486) (xy 105.362006 -253.392432) (xy 104.093264 -253.392432) (xy 104.092769 -253.417039)
			(xy 104.084874 -253.465616) (xy 104.06929 -253.512297) (xy 104.046419 -253.555874) (xy 104.016854 -253.595218)
			(xy 103.981361 -253.62931) (xy 103.940858 -253.657266) (xy 103.896396 -253.678364) (xy 103.849125 -253.692056)
			(xy 103.80027 -253.697988) (xy 103.751095 -253.696007) (xy 103.702876 -253.686163) (xy 103.65686 -253.668711)
			(xy 103.614239 -253.644104) (xy 103.576118 -253.612979) (xy 103.543483 -253.576142) (xy 103.51718 -253.534546)
			(xy 103.497889 -253.48927) (xy 103.486112 -253.441486) (xy 103.482152 -253.392432) (xy 102.216417 -253.392432)
			(xy 102.216458 -253.394464) (xy 102.215963 -253.419071) (xy 102.208068 -253.467648) (xy 102.192484 -253.514329)
			(xy 102.169613 -253.557906) (xy 102.140048 -253.59725) (xy 102.104555 -253.631342) (xy 102.064052 -253.659298)
			(xy 102.01959 -253.680396) (xy 101.972319 -253.694088) (xy 101.923464 -253.70002) (xy 101.874289 -253.698039)
			(xy 101.82607 -253.688195) (xy 101.780054 -253.670743) (xy 101.737433 -253.646136) (xy 101.699312 -253.615011)
			(xy 101.666677 -253.578174) (xy 101.640374 -253.536578) (xy 101.621083 -253.491302) (xy 101.609306 -253.443518)
			(xy 101.605346 -253.394464) (xy 100.61956 -253.394464) (xy 100.61956 -253.905258) (xy 100.633784 -253.929134)
			(xy 100.64623 -253.935992) (xy 100.668191 -253.948471) (xy 100.708046 -253.979495) (xy 100.742253 -254.016655)
			(xy 100.769877 -254.058938) (xy 100.790166 -254.10519) (xy 100.802565 -254.154152) (xy 100.806737 -254.20447)
			(xy 101.135192 -254.20447) (xy 101.139152 -254.155416) (xy 101.150929 -254.107632) (xy 101.17022 -254.062356)
			(xy 101.196523 -254.02076) (xy 101.229158 -253.983923) (xy 101.267279 -253.952798) (xy 101.3099 -253.928191)
			(xy 101.355916 -253.910739) (xy 101.404135 -253.900895) (xy 101.45331 -253.898914) (xy 101.502165 -253.904846)
			(xy 101.549436 -253.918538) (xy 101.593898 -253.939636) (xy 101.634401 -253.967592) (xy 101.669894 -254.001684)
			(xy 101.699459 -254.041028) (xy 101.72233 -254.084605) (xy 101.737914 -254.131286) (xy 101.745809 -254.179863)
			(xy 101.746304 -254.20447) (xy 101.745809 -254.229077) (xy 101.737914 -254.277654) (xy 101.72233 -254.324335)
			(xy 101.699459 -254.367912) (xy 101.669894 -254.407256) (xy 101.634401 -254.441348) (xy 101.623946 -254.448564)
			(xy 111.913673 -254.448564) (xy 111.917703 -254.396066) (xy 111.9297 -254.344798) (xy 111.949383 -254.295963)
			(xy 111.976289 -254.250704) (xy 112.009789 -254.210083) (xy 112.049097 -254.175052) (xy 112.093292 -254.146432)
			(xy 112.141337 -254.124893) (xy 112.192108 -254.110941) (xy 112.244413 -254.104903) (xy 112.297027 -254.10692)
			(xy 112.348717 -254.116944) (xy 112.39827 -254.134742) (xy 112.444526 -254.159895) (xy 112.4864 -254.191814)
			(xy 112.49858 -254.20447) (xy 120.86896 -254.20447) (xy 120.87292 -254.155416) (xy 120.884697 -254.107632)
			(xy 120.903988 -254.062356) (xy 120.930291 -254.02076) (xy 120.962926 -253.983923) (xy 121.001047 -253.952798)
			(xy 121.043668 -253.928191) (xy 121.089684 -253.910739) (xy 121.137903 -253.900895) (xy 121.187078 -253.898914)
			(xy 121.235933 -253.904846) (xy 121.283204 -253.918538) (xy 121.327666 -253.939636) (xy 121.368169 -253.967592)
			(xy 121.403662 -254.001684) (xy 121.433227 -254.041028) (xy 121.456098 -254.084605) (xy 121.471682 -254.131286)
			(xy 121.479577 -254.179863) (xy 121.480072 -254.20447) (xy 122.748814 -254.20447) (xy 122.752774 -254.155416)
			(xy 122.764551 -254.107632) (xy 122.783842 -254.062356) (xy 122.810145 -254.02076) (xy 122.84278 -253.983923)
			(xy 122.880901 -253.952798) (xy 122.923522 -253.928191) (xy 122.969538 -253.910739) (xy 123.017757 -253.900895)
			(xy 123.066932 -253.898914) (xy 123.115787 -253.904846) (xy 123.163058 -253.918538) (xy 123.20752 -253.939636)
			(xy 123.248023 -253.967592) (xy 123.283516 -254.001684) (xy 123.313081 -254.041028) (xy 123.335952 -254.084605)
			(xy 123.351536 -254.131286) (xy 123.359431 -254.179863) (xy 123.359926 -254.20447) (xy 124.628922 -254.20447)
			(xy 124.632882 -254.155416) (xy 124.644659 -254.107632) (xy 124.66395 -254.062356) (xy 124.690253 -254.02076)
			(xy 124.722888 -253.983923) (xy 124.761009 -253.952798) (xy 124.80363 -253.928191) (xy 124.849646 -253.910739)
			(xy 124.897865 -253.900895) (xy 124.94704 -253.898914) (xy 124.995895 -253.904846) (xy 125.043166 -253.918538)
			(xy 125.087628 -253.939636) (xy 125.128131 -253.967592) (xy 125.163624 -254.001684) (xy 125.193189 -254.041028)
			(xy 125.21606 -254.084605) (xy 125.231644 -254.131286) (xy 125.239539 -254.179863) (xy 125.240034 -254.20447)
			(xy 126.50903 -254.20447) (xy 126.51299 -254.155416) (xy 126.524767 -254.107632) (xy 126.544058 -254.062356)
			(xy 126.570361 -254.02076) (xy 126.602996 -253.983923) (xy 126.641117 -253.952798) (xy 126.683738 -253.928191)
			(xy 126.729754 -253.910739) (xy 126.777973 -253.900895) (xy 126.827148 -253.898914) (xy 126.876003 -253.904846)
			(xy 126.923274 -253.918538) (xy 126.967736 -253.939636) (xy 127.008239 -253.967592) (xy 127.043732 -254.001684)
			(xy 127.073297 -254.041028) (xy 127.096168 -254.084605) (xy 127.111752 -254.131286) (xy 127.119647 -254.179863)
			(xy 127.120142 -254.20447) (xy 127.438399 -254.20447) (xy 127.442494 -254.153742) (xy 127.454673 -254.104328)
			(xy 127.474621 -254.057508) (xy 127.501822 -254.014494) (xy 127.53557 -253.9764) (xy 127.574992 -253.944213)
			(xy 127.619066 -253.918767) (xy 127.666652 -253.90072) (xy 127.716516 -253.89054) (xy 127.767368 -253.888491)
			(xy 127.817889 -253.894625) (xy 127.866773 -253.908785) (xy 127.912752 -253.930602) (xy 127.954636 -253.959512)
			(xy 127.99134 -253.994767) (xy 128.021913 -254.035453) (xy 128.045564 -254.080516) (xy 128.06168 -254.12879)
			(xy 128.069844 -254.179024) (xy 128.070356 -254.20447) (xy 128.388884 -254.20447) (xy 128.392844 -254.155416)
			(xy 128.404621 -254.107632) (xy 128.423912 -254.062356) (xy 128.450215 -254.02076) (xy 128.48285 -253.983923)
			(xy 128.520971 -253.952798) (xy 128.563592 -253.928191) (xy 128.609608 -253.910739) (xy 128.657827 -253.900895)
			(xy 128.707002 -253.898914) (xy 128.755857 -253.904846) (xy 128.803128 -253.918538) (xy 128.84759 -253.939636)
			(xy 128.888093 -253.967592) (xy 128.923586 -254.001684) (xy 128.953151 -254.041028) (xy 128.976022 -254.084605)
			(xy 128.991606 -254.131286) (xy 128.999501 -254.179863) (xy 128.999996 -254.20447) (xy 129.318507 -254.20447)
			(xy 129.322602 -254.153742) (xy 129.334781 -254.104328) (xy 129.354729 -254.057508) (xy 129.38193 -254.014494)
			(xy 129.415678 -253.9764) (xy 129.4551 -253.944213) (xy 129.499174 -253.918767) (xy 129.54676 -253.90072)
			(xy 129.596624 -253.89054) (xy 129.647476 -253.888491) (xy 129.697997 -253.894625) (xy 129.746881 -253.908785)
			(xy 129.79286 -253.930602) (xy 129.834744 -253.959512) (xy 129.871448 -253.994767) (xy 129.902021 -254.035453)
			(xy 129.925672 -254.080516) (xy 129.941788 -254.12879) (xy 129.949952 -254.179024) (xy 129.950464 -254.20447)
			(xy 131.198615 -254.20447) (xy 131.20271 -254.153742) (xy 131.214889 -254.104328) (xy 131.234837 -254.057508)
			(xy 131.262038 -254.014494) (xy 131.295786 -253.9764) (xy 131.335208 -253.944213) (xy 131.379282 -253.918767)
			(xy 131.426868 -253.90072) (xy 131.476732 -253.89054) (xy 131.527584 -253.888491) (xy 131.578105 -253.894625)
			(xy 131.626989 -253.908785) (xy 131.672968 -253.930602) (xy 131.714852 -253.959512) (xy 131.751556 -253.994767)
			(xy 131.782129 -254.035453) (xy 131.80578 -254.080516) (xy 131.821896 -254.12879) (xy 131.83006 -254.179024)
			(xy 131.830572 -254.20447) (xy 132.138415 -254.20447) (xy 132.14251 -254.153742) (xy 132.154689 -254.104328)
			(xy 132.174637 -254.057508) (xy 132.201838 -254.014494) (xy 132.235586 -253.9764) (xy 132.275008 -253.944213)
			(xy 132.319082 -253.918767) (xy 132.366668 -253.90072) (xy 132.416532 -253.89054) (xy 132.467384 -253.888491)
			(xy 132.517905 -253.894625) (xy 132.566789 -253.908785) (xy 132.612768 -253.930602) (xy 132.654652 -253.959512)
			(xy 132.691356 -253.994767) (xy 132.721929 -254.035453) (xy 132.74558 -254.080516) (xy 132.761696 -254.12879)
			(xy 132.76986 -254.179024) (xy 132.770372 -254.20447) (xy 133.0889 -254.20447) (xy 133.09286 -254.155416)
			(xy 133.104637 -254.107632) (xy 133.123928 -254.062356) (xy 133.150231 -254.02076) (xy 133.182866 -253.983923)
			(xy 133.220987 -253.952798) (xy 133.263608 -253.928191) (xy 133.309624 -253.910739) (xy 133.357843 -253.900895)
			(xy 133.407018 -253.898914) (xy 133.455873 -253.904846) (xy 133.503144 -253.918538) (xy 133.547606 -253.939636)
			(xy 133.588109 -253.967592) (xy 133.623602 -254.001684) (xy 133.653167 -254.041028) (xy 133.676038 -254.084605)
			(xy 133.691622 -254.131286) (xy 133.699517 -254.179863) (xy 133.700012 -254.20447) (xy 134.018523 -254.20447)
			(xy 134.022618 -254.153742) (xy 134.034797 -254.104328) (xy 134.054745 -254.057508) (xy 134.081946 -254.014494)
			(xy 134.115694 -253.9764) (xy 134.155116 -253.944213) (xy 134.19919 -253.918767) (xy 134.246776 -253.90072)
			(xy 134.29664 -253.89054) (xy 134.347492 -253.888491) (xy 134.398013 -253.894625) (xy 134.446897 -253.908785)
			(xy 134.492876 -253.930602) (xy 134.53476 -253.959512) (xy 134.571464 -253.994767) (xy 134.602037 -254.035453)
			(xy 134.625688 -254.080516) (xy 134.641804 -254.12879) (xy 134.649968 -254.179024) (xy 134.65048 -254.20447)
			(xy 134.969008 -254.20447) (xy 134.972968 -254.155416) (xy 134.984745 -254.107632) (xy 135.004036 -254.062356)
			(xy 135.030339 -254.02076) (xy 135.062974 -253.983923) (xy 135.101095 -253.952798) (xy 135.143716 -253.928191)
			(xy 135.189732 -253.910739) (xy 135.237951 -253.900895) (xy 135.287126 -253.898914) (xy 135.335981 -253.904846)
			(xy 135.383252 -253.918538) (xy 135.427714 -253.939636) (xy 135.468217 -253.967592) (xy 135.50371 -254.001684)
			(xy 135.533275 -254.041028) (xy 135.556146 -254.084605) (xy 135.57173 -254.131286) (xy 135.579625 -254.179863)
			(xy 135.58012 -254.20447) (xy 135.898631 -254.20447) (xy 135.902726 -254.153742) (xy 135.914905 -254.104328)
			(xy 135.934853 -254.057508) (xy 135.962054 -254.014494) (xy 135.995802 -253.9764) (xy 136.035224 -253.944213)
			(xy 136.079298 -253.918767) (xy 136.126884 -253.90072) (xy 136.176748 -253.89054) (xy 136.2276 -253.888491)
			(xy 136.278121 -253.894625) (xy 136.327005 -253.908785) (xy 136.372984 -253.930602) (xy 136.414868 -253.959512)
			(xy 136.451572 -253.994767) (xy 136.482145 -254.035453) (xy 136.505796 -254.080516) (xy 136.521912 -254.12879)
			(xy 136.530076 -254.179024) (xy 136.530588 -254.20447) (xy 137.778485 -254.20447) (xy 137.78258 -254.153742)
			(xy 137.794759 -254.104328) (xy 137.814707 -254.057508) (xy 137.841908 -254.014494) (xy 137.875656 -253.9764)
			(xy 137.915078 -253.944213) (xy 137.959152 -253.918767) (xy 138.006738 -253.90072) (xy 138.056602 -253.89054)
			(xy 138.107454 -253.888491) (xy 138.157975 -253.894625) (xy 138.206859 -253.908785) (xy 138.252838 -253.930602)
			(xy 138.294722 -253.959512) (xy 138.331426 -253.994767) (xy 138.361999 -254.035453) (xy 138.38565 -254.080516)
			(xy 138.401766 -254.12879) (xy 138.40993 -254.179024) (xy 138.410442 -254.20447) (xy 138.718539 -254.20447)
			(xy 138.722634 -254.153742) (xy 138.734813 -254.104328) (xy 138.754761 -254.057508) (xy 138.781962 -254.014494)
			(xy 138.81571 -253.9764) (xy 138.855132 -253.944213) (xy 138.899206 -253.918767) (xy 138.946792 -253.90072)
			(xy 138.996656 -253.89054) (xy 139.047508 -253.888491) (xy 139.098029 -253.894625) (xy 139.146913 -253.908785)
			(xy 139.192892 -253.930602) (xy 139.234776 -253.959512) (xy 139.27148 -253.994767) (xy 139.302053 -254.035453)
			(xy 139.325704 -254.080516) (xy 139.34182 -254.12879) (xy 139.349984 -254.179024) (xy 139.350496 -254.20447)
			(xy 139.669024 -254.20447) (xy 139.672984 -254.155416) (xy 139.684761 -254.107632) (xy 139.704052 -254.062356)
			(xy 139.730355 -254.02076) (xy 139.76299 -253.983923) (xy 139.801111 -253.952798) (xy 139.843732 -253.928191)
			(xy 139.889748 -253.910739) (xy 139.937967 -253.900895) (xy 139.987142 -253.898914) (xy 140.035997 -253.904846)
			(xy 140.083268 -253.918538) (xy 140.12773 -253.939636) (xy 140.168233 -253.967592) (xy 140.203726 -254.001684)
			(xy 140.233291 -254.041028) (xy 140.256162 -254.084605) (xy 140.271746 -254.131286) (xy 140.279641 -254.179863)
			(xy 140.280136 -254.20447) (xy 140.598647 -254.20447) (xy 140.602742 -254.153742) (xy 140.614921 -254.104328)
			(xy 140.634869 -254.057508) (xy 140.66207 -254.014494) (xy 140.695818 -253.9764) (xy 140.73524 -253.944213)
			(xy 140.779314 -253.918767) (xy 140.8269 -253.90072) (xy 140.876764 -253.89054) (xy 140.927616 -253.888491)
			(xy 140.978137 -253.894625) (xy 141.027021 -253.908785) (xy 141.073 -253.930602) (xy 141.114884 -253.959512)
			(xy 141.151588 -253.994767) (xy 141.182161 -254.035453) (xy 141.205812 -254.080516) (xy 141.221928 -254.12879)
			(xy 141.230092 -254.179024) (xy 141.230604 -254.20447) (xy 141.548878 -254.20447) (xy 141.552838 -254.155416)
			(xy 141.564615 -254.107632) (xy 141.583906 -254.062356) (xy 141.610209 -254.02076) (xy 141.642844 -253.983923)
			(xy 141.680965 -253.952798) (xy 141.723586 -253.928191) (xy 141.769602 -253.910739) (xy 141.817821 -253.900895)
			(xy 141.866996 -253.898914) (xy 141.915851 -253.904846) (xy 141.963122 -253.918538) (xy 142.007584 -253.939636)
			(xy 142.048087 -253.967592) (xy 142.08358 -254.001684) (xy 142.113145 -254.041028) (xy 142.136016 -254.084605)
			(xy 142.1516 -254.131286) (xy 142.159495 -254.179863) (xy 142.15999 -254.20447) (xy 142.478501 -254.20447)
			(xy 142.482596 -254.153742) (xy 142.494775 -254.104328) (xy 142.514723 -254.057508) (xy 142.541924 -254.014494)
			(xy 142.575672 -253.9764) (xy 142.615094 -253.944213) (xy 142.659168 -253.918767) (xy 142.706754 -253.90072)
			(xy 142.756618 -253.89054) (xy 142.80747 -253.888491) (xy 142.857991 -253.894625) (xy 142.906875 -253.908785)
			(xy 142.952854 -253.930602) (xy 142.994738 -253.959512) (xy 143.031442 -253.994767) (xy 143.062015 -254.035453)
			(xy 143.085666 -254.080516) (xy 143.101782 -254.12879) (xy 143.109946 -254.179024) (xy 143.110458 -254.20447)
			(xy 143.109946 -254.229916) (xy 143.101782 -254.28015) (xy 143.085666 -254.328424) (xy 143.062015 -254.373487)
			(xy 143.031442 -254.414173) (xy 142.994738 -254.449428) (xy 142.952854 -254.478338) (xy 142.906875 -254.500155)
			(xy 142.857991 -254.514315) (xy 142.80747 -254.520449) (xy 142.756618 -254.5184) (xy 142.706754 -254.50822)
			(xy 142.659168 -254.490173) (xy 142.615094 -254.464727) (xy 142.575672 -254.43254) (xy 142.541924 -254.394446)
			(xy 142.514723 -254.351432) (xy 142.494775 -254.304612) (xy 142.482596 -254.255198) (xy 142.478501 -254.20447)
			(xy 142.15999 -254.20447) (xy 142.159495 -254.229077) (xy 142.1516 -254.277654) (xy 142.136016 -254.324335)
			(xy 142.113145 -254.367912) (xy 142.08358 -254.407256) (xy 142.048087 -254.441348) (xy 142.007584 -254.469304)
			(xy 141.963122 -254.490402) (xy 141.915851 -254.504094) (xy 141.866996 -254.510026) (xy 141.817821 -254.508045)
			(xy 141.769602 -254.498201) (xy 141.723586 -254.480749) (xy 141.680965 -254.456142) (xy 141.642844 -254.425017)
			(xy 141.610209 -254.38818) (xy 141.583906 -254.346584) (xy 141.564615 -254.301308) (xy 141.552838 -254.253524)
			(xy 141.548878 -254.20447) (xy 141.230604 -254.20447) (xy 141.230092 -254.229916) (xy 141.221928 -254.28015)
			(xy 141.205812 -254.328424) (xy 141.182161 -254.373487) (xy 141.151588 -254.414173) (xy 141.114884 -254.449428)
			(xy 141.073 -254.478338) (xy 141.027021 -254.500155) (xy 140.978137 -254.514315) (xy 140.927616 -254.520449)
			(xy 140.876764 -254.5184) (xy 140.8269 -254.50822) (xy 140.779314 -254.490173) (xy 140.73524 -254.464727)
			(xy 140.695818 -254.43254) (xy 140.66207 -254.394446) (xy 140.634869 -254.351432) (xy 140.614921 -254.304612)
			(xy 140.602742 -254.255198) (xy 140.598647 -254.20447) (xy 140.280136 -254.20447) (xy 140.279641 -254.229077)
			(xy 140.271746 -254.277654) (xy 140.256162 -254.324335) (xy 140.233291 -254.367912) (xy 140.203726 -254.407256)
			(xy 140.168233 -254.441348) (xy 140.12773 -254.469304) (xy 140.083268 -254.490402) (xy 140.035997 -254.504094)
			(xy 139.987142 -254.510026) (xy 139.937967 -254.508045) (xy 139.889748 -254.498201) (xy 139.843732 -254.480749)
			(xy 139.801111 -254.456142) (xy 139.76299 -254.425017) (xy 139.730355 -254.38818) (xy 139.704052 -254.346584)
			(xy 139.684761 -254.301308) (xy 139.672984 -254.253524) (xy 139.669024 -254.20447) (xy 139.350496 -254.20447)
			(xy 139.349984 -254.229916) (xy 139.34182 -254.28015) (xy 139.325704 -254.328424) (xy 139.302053 -254.373487)
			(xy 139.27148 -254.414173) (xy 139.234776 -254.449428) (xy 139.192892 -254.478338) (xy 139.146913 -254.500155)
			(xy 139.098029 -254.514315) (xy 139.047508 -254.520449) (xy 138.996656 -254.5184) (xy 138.946792 -254.50822)
			(xy 138.899206 -254.490173) (xy 138.855132 -254.464727) (xy 138.81571 -254.43254) (xy 138.781962 -254.394446)
			(xy 138.754761 -254.351432) (xy 138.734813 -254.304612) (xy 138.722634 -254.255198) (xy 138.718539 -254.20447)
			(xy 138.410442 -254.20447) (xy 138.40993 -254.229916) (xy 138.401766 -254.28015) (xy 138.38565 -254.328424)
			(xy 138.361999 -254.373487) (xy 138.331426 -254.414173) (xy 138.294722 -254.449428) (xy 138.252838 -254.478338)
			(xy 138.206859 -254.500155) (xy 138.157975 -254.514315) (xy 138.107454 -254.520449) (xy 138.056602 -254.5184)
			(xy 138.006738 -254.50822) (xy 137.959152 -254.490173) (xy 137.915078 -254.464727) (xy 137.875656 -254.43254)
			(xy 137.841908 -254.394446) (xy 137.814707 -254.351432) (xy 137.794759 -254.304612) (xy 137.78258 -254.255198)
			(xy 137.778485 -254.20447) (xy 136.530588 -254.20447) (xy 136.530076 -254.229916) (xy 136.521912 -254.28015)
			(xy 136.505796 -254.328424) (xy 136.482145 -254.373487) (xy 136.451572 -254.414173) (xy 136.414868 -254.449428)
			(xy 136.372984 -254.478338) (xy 136.327005 -254.500155) (xy 136.278121 -254.514315) (xy 136.2276 -254.520449)
			(xy 136.176748 -254.5184) (xy 136.126884 -254.50822) (xy 136.079298 -254.490173) (xy 136.035224 -254.464727)
			(xy 135.995802 -254.43254) (xy 135.962054 -254.394446) (xy 135.934853 -254.351432) (xy 135.914905 -254.304612)
			(xy 135.902726 -254.255198) (xy 135.898631 -254.20447) (xy 135.58012 -254.20447) (xy 135.579625 -254.229077)
			(xy 135.57173 -254.277654) (xy 135.556146 -254.324335) (xy 135.533275 -254.367912) (xy 135.50371 -254.407256)
			(xy 135.468217 -254.441348) (xy 135.427714 -254.469304) (xy 135.383252 -254.490402) (xy 135.335981 -254.504094)
			(xy 135.287126 -254.510026) (xy 135.237951 -254.508045) (xy 135.189732 -254.498201) (xy 135.143716 -254.480749)
			(xy 135.101095 -254.456142) (xy 135.062974 -254.425017) (xy 135.030339 -254.38818) (xy 135.004036 -254.346584)
			(xy 134.984745 -254.301308) (xy 134.972968 -254.253524) (xy 134.969008 -254.20447) (xy 134.65048 -254.20447)
			(xy 134.649968 -254.229916) (xy 134.641804 -254.28015) (xy 134.625688 -254.328424) (xy 134.602037 -254.373487)
			(xy 134.571464 -254.414173) (xy 134.53476 -254.449428) (xy 134.492876 -254.478338) (xy 134.446897 -254.500155)
			(xy 134.398013 -254.514315) (xy 134.347492 -254.520449) (xy 134.29664 -254.5184) (xy 134.246776 -254.50822)
			(xy 134.19919 -254.490173) (xy 134.155116 -254.464727) (xy 134.115694 -254.43254) (xy 134.081946 -254.394446)
			(xy 134.054745 -254.351432) (xy 134.034797 -254.304612) (xy 134.022618 -254.255198) (xy 134.018523 -254.20447)
			(xy 133.700012 -254.20447) (xy 133.699517 -254.229077) (xy 133.691622 -254.277654) (xy 133.676038 -254.324335)
			(xy 133.653167 -254.367912) (xy 133.623602 -254.407256) (xy 133.588109 -254.441348) (xy 133.547606 -254.469304)
			(xy 133.503144 -254.490402) (xy 133.455873 -254.504094) (xy 133.407018 -254.510026) (xy 133.357843 -254.508045)
			(xy 133.309624 -254.498201) (xy 133.263608 -254.480749) (xy 133.220987 -254.456142) (xy 133.182866 -254.425017)
			(xy 133.150231 -254.38818) (xy 133.123928 -254.346584) (xy 133.104637 -254.301308) (xy 133.09286 -254.253524)
			(xy 133.0889 -254.20447) (xy 132.770372 -254.20447) (xy 132.76986 -254.229916) (xy 132.761696 -254.28015)
			(xy 132.74558 -254.328424) (xy 132.721929 -254.373487) (xy 132.691356 -254.414173) (xy 132.654652 -254.449428)
			(xy 132.612768 -254.478338) (xy 132.566789 -254.500155) (xy 132.517905 -254.514315) (xy 132.467384 -254.520449)
			(xy 132.416532 -254.5184) (xy 132.366668 -254.50822) (xy 132.319082 -254.490173) (xy 132.275008 -254.464727)
			(xy 132.235586 -254.43254) (xy 132.201838 -254.394446) (xy 132.174637 -254.351432) (xy 132.154689 -254.304612)
			(xy 132.14251 -254.255198) (xy 132.138415 -254.20447) (xy 131.830572 -254.20447) (xy 131.83006 -254.229916)
			(xy 131.821896 -254.28015) (xy 131.80578 -254.328424) (xy 131.782129 -254.373487) (xy 131.751556 -254.414173)
			(xy 131.714852 -254.449428) (xy 131.672968 -254.478338) (xy 131.626989 -254.500155) (xy 131.578105 -254.514315)
			(xy 131.527584 -254.520449) (xy 131.476732 -254.5184) (xy 131.426868 -254.50822) (xy 131.379282 -254.490173)
			(xy 131.335208 -254.464727) (xy 131.295786 -254.43254) (xy 131.262038 -254.394446) (xy 131.234837 -254.351432)
			(xy 131.214889 -254.304612) (xy 131.20271 -254.255198) (xy 131.198615 -254.20447) (xy 129.950464 -254.20447)
			(xy 129.949952 -254.229916) (xy 129.941788 -254.28015) (xy 129.925672 -254.328424) (xy 129.902021 -254.373487)
			(xy 129.871448 -254.414173) (xy 129.834744 -254.449428) (xy 129.79286 -254.478338) (xy 129.746881 -254.500155)
			(xy 129.697997 -254.514315) (xy 129.647476 -254.520449) (xy 129.596624 -254.5184) (xy 129.54676 -254.50822)
			(xy 129.499174 -254.490173) (xy 129.4551 -254.464727) (xy 129.415678 -254.43254) (xy 129.38193 -254.394446)
			(xy 129.354729 -254.351432) (xy 129.334781 -254.304612) (xy 129.322602 -254.255198) (xy 129.318507 -254.20447)
			(xy 128.999996 -254.20447) (xy 128.999501 -254.229077) (xy 128.991606 -254.277654) (xy 128.976022 -254.324335)
			(xy 128.953151 -254.367912) (xy 128.923586 -254.407256) (xy 128.888093 -254.441348) (xy 128.84759 -254.469304)
			(xy 128.803128 -254.490402) (xy 128.755857 -254.504094) (xy 128.707002 -254.510026) (xy 128.657827 -254.508045)
			(xy 128.609608 -254.498201) (xy 128.563592 -254.480749) (xy 128.520971 -254.456142) (xy 128.48285 -254.425017)
			(xy 128.450215 -254.38818) (xy 128.423912 -254.346584) (xy 128.404621 -254.301308) (xy 128.392844 -254.253524)
			(xy 128.388884 -254.20447) (xy 128.070356 -254.20447) (xy 128.069844 -254.229916) (xy 128.06168 -254.28015)
			(xy 128.045564 -254.328424) (xy 128.021913 -254.373487) (xy 127.99134 -254.414173) (xy 127.954636 -254.449428)
			(xy 127.912752 -254.478338) (xy 127.866773 -254.500155) (xy 127.817889 -254.514315) (xy 127.767368 -254.520449)
			(xy 127.716516 -254.5184) (xy 127.666652 -254.50822) (xy 127.619066 -254.490173) (xy 127.574992 -254.464727)
			(xy 127.53557 -254.43254) (xy 127.501822 -254.394446) (xy 127.474621 -254.351432) (xy 127.454673 -254.304612)
			(xy 127.442494 -254.255198) (xy 127.438399 -254.20447) (xy 127.120142 -254.20447) (xy 127.119647 -254.229077)
			(xy 127.111752 -254.277654) (xy 127.096168 -254.324335) (xy 127.073297 -254.367912) (xy 127.043732 -254.407256)
			(xy 127.008239 -254.441348) (xy 126.967736 -254.469304) (xy 126.923274 -254.490402) (xy 126.876003 -254.504094)
			(xy 126.827148 -254.510026) (xy 126.777973 -254.508045) (xy 126.729754 -254.498201) (xy 126.683738 -254.480749)
			(xy 126.641117 -254.456142) (xy 126.602996 -254.425017) (xy 126.570361 -254.38818) (xy 126.544058 -254.346584)
			(xy 126.524767 -254.301308) (xy 126.51299 -254.253524) (xy 126.50903 -254.20447) (xy 125.240034 -254.20447)
			(xy 125.239539 -254.229077) (xy 125.231644 -254.277654) (xy 125.21606 -254.324335) (xy 125.193189 -254.367912)
			(xy 125.163624 -254.407256) (xy 125.128131 -254.441348) (xy 125.087628 -254.469304) (xy 125.043166 -254.490402)
			(xy 124.995895 -254.504094) (xy 124.94704 -254.510026) (xy 124.897865 -254.508045) (xy 124.849646 -254.498201)
			(xy 124.80363 -254.480749) (xy 124.761009 -254.456142) (xy 124.722888 -254.425017) (xy 124.690253 -254.38818)
			(xy 124.66395 -254.346584) (xy 124.644659 -254.301308) (xy 124.632882 -254.253524) (xy 124.628922 -254.20447)
			(xy 123.359926 -254.20447) (xy 123.359431 -254.229077) (xy 123.351536 -254.277654) (xy 123.335952 -254.324335)
			(xy 123.313081 -254.367912) (xy 123.283516 -254.407256) (xy 123.248023 -254.441348) (xy 123.20752 -254.469304)
			(xy 123.163058 -254.490402) (xy 123.115787 -254.504094) (xy 123.066932 -254.510026) (xy 123.017757 -254.508045)
			(xy 122.969538 -254.498201) (xy 122.923522 -254.480749) (xy 122.880901 -254.456142) (xy 122.84278 -254.425017)
			(xy 122.810145 -254.38818) (xy 122.783842 -254.346584) (xy 122.764551 -254.301308) (xy 122.752774 -254.253524)
			(xy 122.748814 -254.20447) (xy 121.480072 -254.20447) (xy 121.479577 -254.229077) (xy 121.471682 -254.277654)
			(xy 121.456098 -254.324335) (xy 121.433227 -254.367912) (xy 121.403662 -254.407256) (xy 121.368169 -254.441348)
			(xy 121.327666 -254.469304) (xy 121.283204 -254.490402) (xy 121.235933 -254.504094) (xy 121.187078 -254.510026)
			(xy 121.137903 -254.508045) (xy 121.089684 -254.498201) (xy 121.043668 -254.480749) (xy 121.001047 -254.456142)
			(xy 120.962926 -254.425017) (xy 120.930291 -254.38818) (xy 120.903988 -254.346584) (xy 120.884697 -254.301308)
			(xy 120.87292 -254.253524) (xy 120.86896 -254.20447) (xy 112.49858 -254.20447) (xy 112.522912 -254.229752)
			(xy 112.553204 -254.272818) (xy 112.576567 -254.320003) (xy 112.592453 -254.370202) (xy 112.60049 -254.422238)
			(xy 112.600994 -254.448564) (xy 112.60049 -254.47489) (xy 112.592453 -254.526926) (xy 112.576567 -254.577125)
			(xy 112.553204 -254.62431) (xy 112.522912 -254.667376) (xy 112.4864 -254.705314) (xy 112.444526 -254.737233)
			(xy 112.39827 -254.762386) (xy 112.348717 -254.780184) (xy 112.297027 -254.790208) (xy 112.244413 -254.792225)
			(xy 112.192108 -254.786187) (xy 112.141337 -254.772235) (xy 112.093292 -254.750696) (xy 112.049097 -254.722076)
			(xy 112.009789 -254.687045) (xy 111.976289 -254.646424) (xy 111.949383 -254.601165) (xy 111.9297 -254.55233)
			(xy 111.917703 -254.501062) (xy 111.913673 -254.448564) (xy 101.623946 -254.448564) (xy 101.593898 -254.469304)
			(xy 101.549436 -254.490402) (xy 101.502165 -254.504094) (xy 101.45331 -254.510026) (xy 101.404135 -254.508045)
			(xy 101.355916 -254.498201) (xy 101.3099 -254.480749) (xy 101.267279 -254.456142) (xy 101.229158 -254.425017)
			(xy 101.196523 -254.38818) (xy 101.17022 -254.346584) (xy 101.150929 -254.301308) (xy 101.139152 -254.253524)
			(xy 101.135192 -254.20447) (xy 100.806737 -254.20447) (xy 100.806738 -254.204486) (xy 100.80257 -254.25482)
			(xy 100.790175 -254.303782) (xy 100.769891 -254.350037) (xy 100.74227 -254.392323) (xy 100.708068 -254.429486)
			(xy 100.668215 -254.460513) (xy 100.64623 -254.472948) (xy 100.633784 -254.479806) (xy 100.61956 -254.503682)
			(xy 100.61956 -255.014476) (xy 101.605346 -255.014476) (xy 101.609306 -254.965422) (xy 101.621083 -254.917638)
			(xy 101.640374 -254.872362) (xy 101.666677 -254.830766) (xy 101.699312 -254.793929) (xy 101.737433 -254.762804)
			(xy 101.780054 -254.738197) (xy 101.82607 -254.720745) (xy 101.874289 -254.710901) (xy 101.923464 -254.70892)
			(xy 101.972319 -254.714852) (xy 102.01959 -254.728544) (xy 102.064052 -254.749642) (xy 102.104555 -254.777598)
			(xy 102.140048 -254.81169) (xy 102.169613 -254.851034) (xy 102.192484 -254.894611) (xy 102.208068 -254.941292)
			(xy 102.215963 -254.989869) (xy 102.216458 -255.014476) (xy 122.278914 -255.014476) (xy 122.282874 -254.965422)
			(xy 122.294651 -254.917638) (xy 122.313942 -254.872362) (xy 122.340245 -254.830766) (xy 122.37288 -254.793929)
			(xy 122.411001 -254.762804) (xy 122.453622 -254.738197) (xy 122.499638 -254.720745) (xy 122.547857 -254.710901)
			(xy 122.597032 -254.70892) (xy 122.645887 -254.714852) (xy 122.693158 -254.728544) (xy 122.73762 -254.749642)
			(xy 122.778123 -254.777598) (xy 122.813616 -254.81169) (xy 122.843181 -254.851034) (xy 122.866052 -254.894611)
			(xy 122.881636 -254.941292) (xy 122.889531 -254.989869) (xy 122.890026 -255.014476) (xy 124.159022 -255.014476)
			(xy 124.162982 -254.965422) (xy 124.174759 -254.917638) (xy 124.19405 -254.872362) (xy 124.220353 -254.830766)
			(xy 124.252988 -254.793929) (xy 124.291109 -254.762804) (xy 124.33373 -254.738197) (xy 124.379746 -254.720745)
			(xy 124.427965 -254.710901) (xy 124.47714 -254.70892) (xy 124.525995 -254.714852) (xy 124.573266 -254.728544)
			(xy 124.617728 -254.749642) (xy 124.658231 -254.777598) (xy 124.693724 -254.81169) (xy 124.723289 -254.851034)
			(xy 124.74616 -254.894611) (xy 124.761744 -254.941292) (xy 124.769639 -254.989869) (xy 124.770134 -255.014476)
			(xy 126.038876 -255.014476) (xy 126.042836 -254.965422) (xy 126.054613 -254.917638) (xy 126.073904 -254.872362)
			(xy 126.100207 -254.830766) (xy 126.132842 -254.793929) (xy 126.170963 -254.762804) (xy 126.213584 -254.738197)
			(xy 126.2596 -254.720745) (xy 126.307819 -254.710901) (xy 126.356994 -254.70892) (xy 126.405849 -254.714852)
			(xy 126.45312 -254.728544) (xy 126.497582 -254.749642) (xy 126.538085 -254.777598) (xy 126.573578 -254.81169)
			(xy 126.603143 -254.851034) (xy 126.626014 -254.894611) (xy 126.641598 -254.941292) (xy 126.649493 -254.989869)
			(xy 126.649988 -255.014476) (xy 127.908553 -255.014476) (xy 127.912648 -254.963748) (xy 127.924827 -254.914334)
			(xy 127.944775 -254.867514) (xy 127.971976 -254.8245) (xy 128.005724 -254.786406) (xy 128.045146 -254.754219)
			(xy 128.08922 -254.728773) (xy 128.136806 -254.710726) (xy 128.18667 -254.700546) (xy 128.237522 -254.698497)
			(xy 128.288043 -254.704631) (xy 128.336927 -254.718791) (xy 128.382906 -254.740608) (xy 128.42479 -254.769518)
			(xy 128.461494 -254.804773) (xy 128.492067 -254.845459) (xy 128.515718 -254.890522) (xy 128.531834 -254.938796)
			(xy 128.539998 -254.98903) (xy 128.54051 -255.014476) (xy 128.848607 -255.014476) (xy 128.852702 -254.963748)
			(xy 128.864881 -254.914334) (xy 128.884829 -254.867514) (xy 128.91203 -254.8245) (xy 128.945778 -254.786406)
			(xy 128.9852 -254.754219) (xy 129.029274 -254.728773) (xy 129.07686 -254.710726) (xy 129.126724 -254.700546)
			(xy 129.177576 -254.698497) (xy 129.228097 -254.704631) (xy 129.276981 -254.718791) (xy 129.32296 -254.740608)
			(xy 129.364844 -254.769518) (xy 129.401548 -254.804773) (xy 129.432121 -254.845459) (xy 129.455772 -254.890522)
			(xy 129.471888 -254.938796) (xy 129.480052 -254.98903) (xy 129.480564 -255.014476) (xy 129.798838 -255.014476)
			(xy 129.802798 -254.965422) (xy 129.814575 -254.917638) (xy 129.833866 -254.872362) (xy 129.860169 -254.830766)
			(xy 129.892804 -254.793929) (xy 129.930925 -254.762804) (xy 129.973546 -254.738197) (xy 130.019562 -254.720745)
			(xy 130.067781 -254.710901) (xy 130.116956 -254.70892) (xy 130.165811 -254.714852) (xy 130.213082 -254.728544)
			(xy 130.257544 -254.749642) (xy 130.298047 -254.777598) (xy 130.33354 -254.81169) (xy 130.363105 -254.851034)
			(xy 130.385976 -254.894611) (xy 130.40156 -254.941292) (xy 130.409455 -254.989869) (xy 130.40995 -255.014476)
			(xy 130.728461 -255.014476) (xy 130.732556 -254.963748) (xy 130.744735 -254.914334) (xy 130.764683 -254.867514)
			(xy 130.791884 -254.8245) (xy 130.825632 -254.786406) (xy 130.865054 -254.754219) (xy 130.909128 -254.728773)
			(xy 130.956714 -254.710726) (xy 131.006578 -254.700546) (xy 131.05743 -254.698497) (xy 131.107951 -254.704631)
			(xy 131.156835 -254.718791) (xy 131.202814 -254.740608) (xy 131.244698 -254.769518) (xy 131.281402 -254.804773)
			(xy 131.311975 -254.845459) (xy 131.335626 -254.890522) (xy 131.351742 -254.938796) (xy 131.359906 -254.98903)
			(xy 131.360418 -255.014476) (xy 131.678946 -255.014476) (xy 131.682906 -254.965422) (xy 131.694683 -254.917638)
			(xy 131.713974 -254.872362) (xy 131.740277 -254.830766) (xy 131.772912 -254.793929) (xy 131.811033 -254.762804)
			(xy 131.853654 -254.738197) (xy 131.89967 -254.720745) (xy 131.947889 -254.710901) (xy 131.997064 -254.70892)
			(xy 132.045919 -254.714852) (xy 132.09319 -254.728544) (xy 132.137652 -254.749642) (xy 132.178155 -254.777598)
			(xy 132.213648 -254.81169) (xy 132.243213 -254.851034) (xy 132.266084 -254.894611) (xy 132.281668 -254.941292)
			(xy 132.289563 -254.989869) (xy 132.290058 -255.014476) (xy 132.608569 -255.014476) (xy 132.612664 -254.963748)
			(xy 132.624843 -254.914334) (xy 132.644791 -254.867514) (xy 132.671992 -254.8245) (xy 132.70574 -254.786406)
			(xy 132.745162 -254.754219) (xy 132.789236 -254.728773) (xy 132.836822 -254.710726) (xy 132.886686 -254.700546)
			(xy 132.937538 -254.698497) (xy 132.988059 -254.704631) (xy 133.036943 -254.718791) (xy 133.082922 -254.740608)
			(xy 133.124806 -254.769518) (xy 133.16151 -254.804773) (xy 133.192083 -254.845459) (xy 133.215734 -254.890522)
			(xy 133.23185 -254.938796) (xy 133.240014 -254.98903) (xy 133.240526 -255.014476) (xy 133.559054 -255.014476)
			(xy 133.563014 -254.965422) (xy 133.574791 -254.917638) (xy 133.594082 -254.872362) (xy 133.620385 -254.830766)
			(xy 133.65302 -254.793929) (xy 133.691141 -254.762804) (xy 133.733762 -254.738197) (xy 133.779778 -254.720745)
			(xy 133.827997 -254.710901) (xy 133.877172 -254.70892) (xy 133.926027 -254.714852) (xy 133.973298 -254.728544)
			(xy 134.01776 -254.749642) (xy 134.058263 -254.777598) (xy 134.093756 -254.81169) (xy 134.123321 -254.851034)
			(xy 134.146192 -254.894611) (xy 134.161776 -254.941292) (xy 134.169671 -254.989869) (xy 134.170166 -255.014476)
			(xy 134.488423 -255.014476) (xy 134.492518 -254.963748) (xy 134.504697 -254.914334) (xy 134.524645 -254.867514)
			(xy 134.551846 -254.8245) (xy 134.585594 -254.786406) (xy 134.625016 -254.754219) (xy 134.66909 -254.728773)
			(xy 134.716676 -254.710726) (xy 134.76654 -254.700546) (xy 134.817392 -254.698497) (xy 134.867913 -254.704631)
			(xy 134.916797 -254.718791) (xy 134.962776 -254.740608) (xy 135.00466 -254.769518) (xy 135.041364 -254.804773)
			(xy 135.071937 -254.845459) (xy 135.095588 -254.890522) (xy 135.111704 -254.938796) (xy 135.119868 -254.98903)
			(xy 135.12038 -255.014476) (xy 135.428477 -255.014476) (xy 135.432572 -254.963748) (xy 135.444751 -254.914334)
			(xy 135.464699 -254.867514) (xy 135.4919 -254.8245) (xy 135.525648 -254.786406) (xy 135.56507 -254.754219)
			(xy 135.609144 -254.728773) (xy 135.65673 -254.710726) (xy 135.706594 -254.700546) (xy 135.757446 -254.698497)
			(xy 135.807967 -254.704631) (xy 135.856851 -254.718791) (xy 135.90283 -254.740608) (xy 135.944714 -254.769518)
			(xy 135.981418 -254.804773) (xy 136.011991 -254.845459) (xy 136.035642 -254.890522) (xy 136.051758 -254.938796)
			(xy 136.059922 -254.98903) (xy 136.060434 -255.014476) (xy 136.378962 -255.014476) (xy 136.382922 -254.965422)
			(xy 136.394699 -254.917638) (xy 136.41399 -254.872362) (xy 136.440293 -254.830766) (xy 136.472928 -254.793929)
			(xy 136.511049 -254.762804) (xy 136.55367 -254.738197) (xy 136.599686 -254.720745) (xy 136.647905 -254.710901)
			(xy 136.69708 -254.70892) (xy 136.745935 -254.714852) (xy 136.793206 -254.728544) (xy 136.837668 -254.749642)
			(xy 136.878171 -254.777598) (xy 136.913664 -254.81169) (xy 136.943229 -254.851034) (xy 136.9661 -254.894611)
			(xy 136.981684 -254.941292) (xy 136.989579 -254.989869) (xy 136.990074 -255.014476) (xy 137.308585 -255.014476)
			(xy 137.31268 -254.963748) (xy 137.324859 -254.914334) (xy 137.344807 -254.867514) (xy 137.372008 -254.8245)
			(xy 137.405756 -254.786406) (xy 137.445178 -254.754219) (xy 137.489252 -254.728773) (xy 137.536838 -254.710726)
			(xy 137.586702 -254.700546) (xy 137.637554 -254.698497) (xy 137.688075 -254.704631) (xy 137.736959 -254.718791)
			(xy 137.782938 -254.740608) (xy 137.824822 -254.769518) (xy 137.861526 -254.804773) (xy 137.892099 -254.845459)
			(xy 137.91575 -254.890522) (xy 137.931866 -254.938796) (xy 137.94003 -254.98903) (xy 137.940542 -255.014476)
			(xy 138.25907 -255.014476) (xy 138.26303 -254.965422) (xy 138.274807 -254.917638) (xy 138.294098 -254.872362)
			(xy 138.320401 -254.830766) (xy 138.353036 -254.793929) (xy 138.391157 -254.762804) (xy 138.433778 -254.738197)
			(xy 138.479794 -254.720745) (xy 138.528013 -254.710901) (xy 138.577188 -254.70892) (xy 138.626043 -254.714852)
			(xy 138.673314 -254.728544) (xy 138.717776 -254.749642) (xy 138.758279 -254.777598) (xy 138.793772 -254.81169)
			(xy 138.823337 -254.851034) (xy 138.846208 -254.894611) (xy 138.861792 -254.941292) (xy 138.869687 -254.989869)
			(xy 138.870182 -255.014476) (xy 139.188439 -255.014476) (xy 139.192534 -254.963748) (xy 139.204713 -254.914334)
			(xy 139.224661 -254.867514) (xy 139.251862 -254.8245) (xy 139.28561 -254.786406) (xy 139.325032 -254.754219)
			(xy 139.369106 -254.728773) (xy 139.416692 -254.710726) (xy 139.466556 -254.700546) (xy 139.517408 -254.698497)
			(xy 139.567929 -254.704631) (xy 139.616813 -254.718791) (xy 139.662792 -254.740608) (xy 139.704676 -254.769518)
			(xy 139.74138 -254.804773) (xy 139.771953 -254.845459) (xy 139.795604 -254.890522) (xy 139.81172 -254.938796)
			(xy 139.819884 -254.98903) (xy 139.820396 -255.014476) (xy 140.138924 -255.014476) (xy 140.142884 -254.965422)
			(xy 140.154661 -254.917638) (xy 140.173952 -254.872362) (xy 140.200255 -254.830766) (xy 140.23289 -254.793929)
			(xy 140.271011 -254.762804) (xy 140.313632 -254.738197) (xy 140.359648 -254.720745) (xy 140.407867 -254.710901)
			(xy 140.457042 -254.70892) (xy 140.505897 -254.714852) (xy 140.553168 -254.728544) (xy 140.59763 -254.749642)
			(xy 140.638133 -254.777598) (xy 140.673626 -254.81169) (xy 140.703191 -254.851034) (xy 140.726062 -254.894611)
			(xy 140.741646 -254.941292) (xy 140.749541 -254.989869) (xy 140.750036 -255.014476) (xy 141.068547 -255.014476)
			(xy 141.072642 -254.963748) (xy 141.084821 -254.914334) (xy 141.104769 -254.867514) (xy 141.13197 -254.8245)
			(xy 141.165718 -254.786406) (xy 141.20514 -254.754219) (xy 141.249214 -254.728773) (xy 141.2968 -254.710726)
			(xy 141.346664 -254.700546) (xy 141.397516 -254.698497) (xy 141.448037 -254.704631) (xy 141.496921 -254.718791)
			(xy 141.5429 -254.740608) (xy 141.584784 -254.769518) (xy 141.621488 -254.804773) (xy 141.652061 -254.845459)
			(xy 141.675712 -254.890522) (xy 141.691828 -254.938796) (xy 141.699992 -254.98903) (xy 141.700504 -255.014476)
			(xy 142.008601 -255.014476) (xy 142.012696 -254.963748) (xy 142.024875 -254.914334) (xy 142.044823 -254.867514)
			(xy 142.072024 -254.8245) (xy 142.105772 -254.786406) (xy 142.145194 -254.754219) (xy 142.189268 -254.728773)
			(xy 142.236854 -254.710726) (xy 142.286718 -254.700546) (xy 142.33757 -254.698497) (xy 142.388091 -254.704631)
			(xy 142.436975 -254.718791) (xy 142.482954 -254.740608) (xy 142.524838 -254.769518) (xy 142.561542 -254.804773)
			(xy 142.592115 -254.845459) (xy 142.615766 -254.890522) (xy 142.631882 -254.938796) (xy 142.640046 -254.98903)
			(xy 142.640558 -255.014476) (xy 142.958832 -255.014476) (xy 142.962792 -254.965422) (xy 142.974569 -254.917638)
			(xy 142.99386 -254.872362) (xy 143.020163 -254.830766) (xy 143.052798 -254.793929) (xy 143.090919 -254.762804)
			(xy 143.13354 -254.738197) (xy 143.179556 -254.720745) (xy 143.227775 -254.710901) (xy 143.27695 -254.70892)
			(xy 143.325805 -254.714852) (xy 143.373076 -254.728544) (xy 143.417538 -254.749642) (xy 143.458041 -254.777598)
			(xy 143.493534 -254.81169) (xy 143.523099 -254.851034) (xy 143.54597 -254.894611) (xy 143.561554 -254.941292)
			(xy 143.569449 -254.989869) (xy 143.569944 -255.014476) (xy 144.83894 -255.014476) (xy 144.8429 -254.965422)
			(xy 144.854677 -254.917638) (xy 144.873968 -254.872362) (xy 144.900271 -254.830766) (xy 144.932906 -254.793929)
			(xy 144.971027 -254.762804) (xy 145.013648 -254.738197) (xy 145.059664 -254.720745) (xy 145.107883 -254.710901)
			(xy 145.157058 -254.70892) (xy 145.205913 -254.714852) (xy 145.253184 -254.728544) (xy 145.297646 -254.749642)
			(xy 145.338149 -254.777598) (xy 145.373642 -254.81169) (xy 145.403207 -254.851034) (xy 145.426078 -254.894611)
			(xy 145.441662 -254.941292) (xy 145.449557 -254.989869) (xy 145.450052 -255.014476) (xy 145.449557 -255.039083)
			(xy 145.441662 -255.08766) (xy 145.426078 -255.134341) (xy 145.403207 -255.177918) (xy 145.373642 -255.217262)
			(xy 145.338149 -255.251354) (xy 145.297646 -255.27931) (xy 145.253184 -255.300408) (xy 145.205913 -255.3141)
			(xy 145.157058 -255.320032) (xy 145.107883 -255.318051) (xy 145.059664 -255.308207) (xy 145.013648 -255.290755)
			(xy 144.971027 -255.266148) (xy 144.932906 -255.235023) (xy 144.900271 -255.198186) (xy 144.873968 -255.15659)
			(xy 144.854677 -255.111314) (xy 144.8429 -255.06353) (xy 144.83894 -255.014476) (xy 143.569944 -255.014476)
			(xy 143.569449 -255.039083) (xy 143.561554 -255.08766) (xy 143.54597 -255.134341) (xy 143.523099 -255.177918)
			(xy 143.493534 -255.217262) (xy 143.458041 -255.251354) (xy 143.417538 -255.27931) (xy 143.373076 -255.300408)
			(xy 143.325805 -255.3141) (xy 143.27695 -255.320032) (xy 143.227775 -255.318051) (xy 143.179556 -255.308207)
			(xy 143.13354 -255.290755) (xy 143.090919 -255.266148) (xy 143.052798 -255.235023) (xy 143.020163 -255.198186)
			(xy 142.99386 -255.15659) (xy 142.974569 -255.111314) (xy 142.962792 -255.06353) (xy 142.958832 -255.014476)
			(xy 142.640558 -255.014476) (xy 142.640046 -255.039922) (xy 142.631882 -255.090156) (xy 142.615766 -255.13843)
			(xy 142.592115 -255.183493) (xy 142.561542 -255.224179) (xy 142.524838 -255.259434) (xy 142.482954 -255.288344)
			(xy 142.436975 -255.310161) (xy 142.388091 -255.324321) (xy 142.33757 -255.330455) (xy 142.286718 -255.328406)
			(xy 142.236854 -255.318226) (xy 142.189268 -255.300179) (xy 142.145194 -255.274733) (xy 142.105772 -255.242546)
			(xy 142.072024 -255.204452) (xy 142.044823 -255.161438) (xy 142.024875 -255.114618) (xy 142.012696 -255.065204)
			(xy 142.008601 -255.014476) (xy 141.700504 -255.014476) (xy 141.699992 -255.039922) (xy 141.691828 -255.090156)
			(xy 141.675712 -255.13843) (xy 141.652061 -255.183493) (xy 141.621488 -255.224179) (xy 141.584784 -255.259434)
			(xy 141.5429 -255.288344) (xy 141.496921 -255.310161) (xy 141.448037 -255.324321) (xy 141.397516 -255.330455)
			(xy 141.346664 -255.328406) (xy 141.2968 -255.318226) (xy 141.249214 -255.300179) (xy 141.20514 -255.274733)
			(xy 141.165718 -255.242546) (xy 141.13197 -255.204452) (xy 141.104769 -255.161438) (xy 141.084821 -255.114618)
			(xy 141.072642 -255.065204) (xy 141.068547 -255.014476) (xy 140.750036 -255.014476) (xy 140.749541 -255.039083)
			(xy 140.741646 -255.08766) (xy 140.726062 -255.134341) (xy 140.703191 -255.177918) (xy 140.673626 -255.217262)
			(xy 140.638133 -255.251354) (xy 140.59763 -255.27931) (xy 140.553168 -255.300408) (xy 140.505897 -255.3141)
			(xy 140.457042 -255.320032) (xy 140.407867 -255.318051) (xy 140.359648 -255.308207) (xy 140.313632 -255.290755)
			(xy 140.271011 -255.266148) (xy 140.23289 -255.235023) (xy 140.200255 -255.198186) (xy 140.173952 -255.15659)
			(xy 140.154661 -255.111314) (xy 140.142884 -255.06353) (xy 140.138924 -255.014476) (xy 139.820396 -255.014476)
			(xy 139.819884 -255.039922) (xy 139.81172 -255.090156) (xy 139.795604 -255.13843) (xy 139.771953 -255.183493)
			(xy 139.74138 -255.224179) (xy 139.704676 -255.259434) (xy 139.662792 -255.288344) (xy 139.616813 -255.310161)
			(xy 139.567929 -255.324321) (xy 139.517408 -255.330455) (xy 139.466556 -255.328406) (xy 139.416692 -255.318226)
			(xy 139.369106 -255.300179) (xy 139.325032 -255.274733) (xy 139.28561 -255.242546) (xy 139.251862 -255.204452)
			(xy 139.224661 -255.161438) (xy 139.204713 -255.114618) (xy 139.192534 -255.065204) (xy 139.188439 -255.014476)
			(xy 138.870182 -255.014476) (xy 138.869687 -255.039083) (xy 138.861792 -255.08766) (xy 138.846208 -255.134341)
			(xy 138.823337 -255.177918) (xy 138.793772 -255.217262) (xy 138.758279 -255.251354) (xy 138.717776 -255.27931)
			(xy 138.673314 -255.300408) (xy 138.626043 -255.3141) (xy 138.577188 -255.320032) (xy 138.528013 -255.318051)
			(xy 138.479794 -255.308207) (xy 138.433778 -255.290755) (xy 138.391157 -255.266148) (xy 138.353036 -255.235023)
			(xy 138.320401 -255.198186) (xy 138.294098 -255.15659) (xy 138.274807 -255.111314) (xy 138.26303 -255.06353)
			(xy 138.25907 -255.014476) (xy 137.940542 -255.014476) (xy 137.94003 -255.039922) (xy 137.931866 -255.090156)
			(xy 137.91575 -255.13843) (xy 137.892099 -255.183493) (xy 137.861526 -255.224179) (xy 137.824822 -255.259434)
			(xy 137.782938 -255.288344) (xy 137.736959 -255.310161) (xy 137.688075 -255.324321) (xy 137.637554 -255.330455)
			(xy 137.586702 -255.328406) (xy 137.536838 -255.318226) (xy 137.489252 -255.300179) (xy 137.445178 -255.274733)
			(xy 137.405756 -255.242546) (xy 137.372008 -255.204452) (xy 137.344807 -255.161438) (xy 137.324859 -255.114618)
			(xy 137.31268 -255.065204) (xy 137.308585 -255.014476) (xy 136.990074 -255.014476) (xy 136.989579 -255.039083)
			(xy 136.981684 -255.08766) (xy 136.9661 -255.134341) (xy 136.943229 -255.177918) (xy 136.913664 -255.217262)
			(xy 136.878171 -255.251354) (xy 136.837668 -255.27931) (xy 136.793206 -255.300408) (xy 136.745935 -255.3141)
			(xy 136.69708 -255.320032) (xy 136.647905 -255.318051) (xy 136.599686 -255.308207) (xy 136.55367 -255.290755)
			(xy 136.511049 -255.266148) (xy 136.472928 -255.235023) (xy 136.440293 -255.198186) (xy 136.41399 -255.15659)
			(xy 136.394699 -255.111314) (xy 136.382922 -255.06353) (xy 136.378962 -255.014476) (xy 136.060434 -255.014476)
			(xy 136.059922 -255.039922) (xy 136.051758 -255.090156) (xy 136.035642 -255.13843) (xy 136.011991 -255.183493)
			(xy 135.981418 -255.224179) (xy 135.944714 -255.259434) (xy 135.90283 -255.288344) (xy 135.856851 -255.310161)
			(xy 135.807967 -255.324321) (xy 135.757446 -255.330455) (xy 135.706594 -255.328406) (xy 135.65673 -255.318226)
			(xy 135.609144 -255.300179) (xy 135.56507 -255.274733) (xy 135.525648 -255.242546) (xy 135.4919 -255.204452)
			(xy 135.464699 -255.161438) (xy 135.444751 -255.114618) (xy 135.432572 -255.065204) (xy 135.428477 -255.014476)
			(xy 135.12038 -255.014476) (xy 135.119868 -255.039922) (xy 135.111704 -255.090156) (xy 135.095588 -255.13843)
			(xy 135.071937 -255.183493) (xy 135.041364 -255.224179) (xy 135.00466 -255.259434) (xy 134.962776 -255.288344)
			(xy 134.916797 -255.310161) (xy 134.867913 -255.324321) (xy 134.817392 -255.330455) (xy 134.76654 -255.328406)
			(xy 134.716676 -255.318226) (xy 134.66909 -255.300179) (xy 134.625016 -255.274733) (xy 134.585594 -255.242546)
			(xy 134.551846 -255.204452) (xy 134.524645 -255.161438) (xy 134.504697 -255.114618) (xy 134.492518 -255.065204)
			(xy 134.488423 -255.014476) (xy 134.170166 -255.014476) (xy 134.169671 -255.039083) (xy 134.161776 -255.08766)
			(xy 134.146192 -255.134341) (xy 134.123321 -255.177918) (xy 134.093756 -255.217262) (xy 134.058263 -255.251354)
			(xy 134.01776 -255.27931) (xy 133.973298 -255.300408) (xy 133.926027 -255.3141) (xy 133.877172 -255.320032)
			(xy 133.827997 -255.318051) (xy 133.779778 -255.308207) (xy 133.733762 -255.290755) (xy 133.691141 -255.266148)
			(xy 133.65302 -255.235023) (xy 133.620385 -255.198186) (xy 133.594082 -255.15659) (xy 133.574791 -255.111314)
			(xy 133.563014 -255.06353) (xy 133.559054 -255.014476) (xy 133.240526 -255.014476) (xy 133.240014 -255.039922)
			(xy 133.23185 -255.090156) (xy 133.215734 -255.13843) (xy 133.192083 -255.183493) (xy 133.16151 -255.224179)
			(xy 133.124806 -255.259434) (xy 133.082922 -255.288344) (xy 133.036943 -255.310161) (xy 132.988059 -255.324321)
			(xy 132.937538 -255.330455) (xy 132.886686 -255.328406) (xy 132.836822 -255.318226) (xy 132.789236 -255.300179)
			(xy 132.745162 -255.274733) (xy 132.70574 -255.242546) (xy 132.671992 -255.204452) (xy 132.644791 -255.161438)
			(xy 132.624843 -255.114618) (xy 132.612664 -255.065204) (xy 132.608569 -255.014476) (xy 132.290058 -255.014476)
			(xy 132.289563 -255.039083) (xy 132.281668 -255.08766) (xy 132.266084 -255.134341) (xy 132.243213 -255.177918)
			(xy 132.213648 -255.217262) (xy 132.178155 -255.251354) (xy 132.137652 -255.27931) (xy 132.09319 -255.300408)
			(xy 132.045919 -255.3141) (xy 131.997064 -255.320032) (xy 131.947889 -255.318051) (xy 131.89967 -255.308207)
			(xy 131.853654 -255.290755) (xy 131.811033 -255.266148) (xy 131.772912 -255.235023) (xy 131.740277 -255.198186)
			(xy 131.713974 -255.15659) (xy 131.694683 -255.111314) (xy 131.682906 -255.06353) (xy 131.678946 -255.014476)
			(xy 131.360418 -255.014476) (xy 131.359906 -255.039922) (xy 131.351742 -255.090156) (xy 131.335626 -255.13843)
			(xy 131.311975 -255.183493) (xy 131.281402 -255.224179) (xy 131.244698 -255.259434) (xy 131.202814 -255.288344)
			(xy 131.156835 -255.310161) (xy 131.107951 -255.324321) (xy 131.05743 -255.330455) (xy 131.006578 -255.328406)
			(xy 130.956714 -255.318226) (xy 130.909128 -255.300179) (xy 130.865054 -255.274733) (xy 130.825632 -255.242546)
			(xy 130.791884 -255.204452) (xy 130.764683 -255.161438) (xy 130.744735 -255.114618) (xy 130.732556 -255.065204)
			(xy 130.728461 -255.014476) (xy 130.40995 -255.014476) (xy 130.409455 -255.039083) (xy 130.40156 -255.08766)
			(xy 130.385976 -255.134341) (xy 130.363105 -255.177918) (xy 130.33354 -255.217262) (xy 130.298047 -255.251354)
			(xy 130.257544 -255.27931) (xy 130.213082 -255.300408) (xy 130.165811 -255.3141) (xy 130.116956 -255.320032)
			(xy 130.067781 -255.318051) (xy 130.019562 -255.308207) (xy 129.973546 -255.290755) (xy 129.930925 -255.266148)
			(xy 129.892804 -255.235023) (xy 129.860169 -255.198186) (xy 129.833866 -255.15659) (xy 129.814575 -255.111314)
			(xy 129.802798 -255.06353) (xy 129.798838 -255.014476) (xy 129.480564 -255.014476) (xy 129.480052 -255.039922)
			(xy 129.471888 -255.090156) (xy 129.455772 -255.13843) (xy 129.432121 -255.183493) (xy 129.401548 -255.224179)
			(xy 129.364844 -255.259434) (xy 129.32296 -255.288344) (xy 129.276981 -255.310161) (xy 129.228097 -255.324321)
			(xy 129.177576 -255.330455) (xy 129.126724 -255.328406) (xy 129.07686 -255.318226) (xy 129.029274 -255.300179)
			(xy 128.9852 -255.274733) (xy 128.945778 -255.242546) (xy 128.91203 -255.204452) (xy 128.884829 -255.161438)
			(xy 128.864881 -255.114618) (xy 128.852702 -255.065204) (xy 128.848607 -255.014476) (xy 128.54051 -255.014476)
			(xy 128.539998 -255.039922) (xy 128.531834 -255.090156) (xy 128.515718 -255.13843) (xy 128.492067 -255.183493)
			(xy 128.461494 -255.224179) (xy 128.42479 -255.259434) (xy 128.382906 -255.288344) (xy 128.336927 -255.310161)
			(xy 128.288043 -255.324321) (xy 128.237522 -255.330455) (xy 128.18667 -255.328406) (xy 128.136806 -255.318226)
			(xy 128.08922 -255.300179) (xy 128.045146 -255.274733) (xy 128.005724 -255.242546) (xy 127.971976 -255.204452)
			(xy 127.944775 -255.161438) (xy 127.924827 -255.114618) (xy 127.912648 -255.065204) (xy 127.908553 -255.014476)
			(xy 126.649988 -255.014476) (xy 126.649493 -255.039083) (xy 126.641598 -255.08766) (xy 126.626014 -255.134341)
			(xy 126.603143 -255.177918) (xy 126.573578 -255.217262) (xy 126.538085 -255.251354) (xy 126.497582 -255.27931)
			(xy 126.45312 -255.300408) (xy 126.405849 -255.3141) (xy 126.356994 -255.320032) (xy 126.307819 -255.318051)
			(xy 126.2596 -255.308207) (xy 126.213584 -255.290755) (xy 126.170963 -255.266148) (xy 126.132842 -255.235023)
			(xy 126.100207 -255.198186) (xy 126.073904 -255.15659) (xy 126.054613 -255.111314) (xy 126.042836 -255.06353)
			(xy 126.038876 -255.014476) (xy 124.770134 -255.014476) (xy 124.769639 -255.039083) (xy 124.761744 -255.08766)
			(xy 124.74616 -255.134341) (xy 124.723289 -255.177918) (xy 124.693724 -255.217262) (xy 124.658231 -255.251354)
			(xy 124.617728 -255.27931) (xy 124.573266 -255.300408) (xy 124.525995 -255.3141) (xy 124.47714 -255.320032)
			(xy 124.427965 -255.318051) (xy 124.379746 -255.308207) (xy 124.33373 -255.290755) (xy 124.291109 -255.266148)
			(xy 124.252988 -255.235023) (xy 124.220353 -255.198186) (xy 124.19405 -255.15659) (xy 124.174759 -255.111314)
			(xy 124.162982 -255.06353) (xy 124.159022 -255.014476) (xy 122.890026 -255.014476) (xy 122.889531 -255.039083)
			(xy 122.881636 -255.08766) (xy 122.866052 -255.134341) (xy 122.843181 -255.177918) (xy 122.813616 -255.217262)
			(xy 122.778123 -255.251354) (xy 122.73762 -255.27931) (xy 122.693158 -255.300408) (xy 122.645887 -255.3141)
			(xy 122.597032 -255.320032) (xy 122.547857 -255.318051) (xy 122.499638 -255.308207) (xy 122.453622 -255.290755)
			(xy 122.411001 -255.266148) (xy 122.37288 -255.235023) (xy 122.340245 -255.198186) (xy 122.313942 -255.15659)
			(xy 122.294651 -255.111314) (xy 122.282874 -255.06353) (xy 122.278914 -255.014476) (xy 102.216458 -255.014476)
			(xy 102.215963 -255.039083) (xy 102.208068 -255.08766) (xy 102.192484 -255.134341) (xy 102.169613 -255.177918)
			(xy 102.140048 -255.217262) (xy 102.104555 -255.251354) (xy 102.064052 -255.27931) (xy 102.01959 -255.300408)
			(xy 101.972319 -255.3141) (xy 101.923464 -255.320032) (xy 101.874289 -255.318051) (xy 101.82607 -255.308207)
			(xy 101.780054 -255.290755) (xy 101.737433 -255.266148) (xy 101.699312 -255.235023) (xy 101.666677 -255.198186)
			(xy 101.640374 -255.15659) (xy 101.621083 -255.111314) (xy 101.609306 -255.06353) (xy 101.605346 -255.014476)
			(xy 100.61956 -255.014476) (xy 100.61956 -255.52527) (xy 100.633784 -255.549146) (xy 100.64623 -255.556004)
			(xy 100.66819 -255.568483) (xy 100.708044 -255.599506) (xy 100.742248 -255.636666) (xy 100.76987 -255.678948)
			(xy 100.790158 -255.725199) (xy 100.802556 -255.774159) (xy 100.806727 -255.824482) (xy 101.135192 -255.824482)
			(xy 101.139152 -255.775428) (xy 101.150929 -255.727644) (xy 101.17022 -255.682368) (xy 101.196523 -255.640772)
			(xy 101.229158 -255.603935) (xy 101.267279 -255.57281) (xy 101.3099 -255.548203) (xy 101.355916 -255.530751)
			(xy 101.404135 -255.520907) (xy 101.45331 -255.518926) (xy 101.502165 -255.524858) (xy 101.549436 -255.53855)
			(xy 101.593898 -255.559648) (xy 101.634401 -255.587604) (xy 101.669894 -255.621696) (xy 101.699459 -255.66104)
			(xy 101.72233 -255.704617) (xy 101.737914 -255.751298) (xy 101.745809 -255.799875) (xy 101.746263 -255.82245)
			(xy 103.952052 -255.82245) (xy 103.956012 -255.773396) (xy 103.967789 -255.725612) (xy 103.98708 -255.680336)
			(xy 104.013383 -255.63874) (xy 104.046018 -255.601903) (xy 104.084139 -255.570778) (xy 104.12676 -255.546171)
			(xy 104.172776 -255.528719) (xy 104.220995 -255.518875) (xy 104.27017 -255.516894) (xy 104.319025 -255.522826)
			(xy 104.345001 -255.53035) (xy 105.146859 -255.53035) (xy 105.150889 -255.477852) (xy 105.162886 -255.426584)
			(xy 105.182569 -255.377749) (xy 105.209475 -255.33249) (xy 105.242975 -255.291869) (xy 105.282283 -255.256838)
			(xy 105.326478 -255.228218) (xy 105.374523 -255.206679) (xy 105.425294 -255.192727) (xy 105.477599 -255.186689)
			(xy 105.530213 -255.188706) (xy 105.581903 -255.19873) (xy 105.631456 -255.216528) (xy 105.677712 -255.241681)
			(xy 105.719586 -255.2736) (xy 105.756098 -255.311538) (xy 105.78639 -255.354604) (xy 105.809753 -255.401789)
			(xy 105.825639 -255.451988) (xy 105.833676 -255.504024) (xy 105.83418 -255.53035) (xy 106.061259 -255.53035)
			(xy 106.065289 -255.477852) (xy 106.077286 -255.426584) (xy 106.096969 -255.377749) (xy 106.123875 -255.33249)
			(xy 106.157375 -255.291869) (xy 106.196683 -255.256838) (xy 106.240878 -255.228218) (xy 106.288923 -255.206679)
			(xy 106.339694 -255.192727) (xy 106.391999 -255.186689) (xy 106.444613 -255.188706) (xy 106.496303 -255.19873)
			(xy 106.545856 -255.216528) (xy 106.592112 -255.241681) (xy 106.633986 -255.2736) (xy 106.670498 -255.311538)
			(xy 106.70079 -255.354604) (xy 106.724153 -255.401789) (xy 106.740039 -255.451988) (xy 106.748076 -255.504024)
			(xy 106.74858 -255.53035) (xy 117.096797 -255.53035) (xy 117.100827 -255.477852) (xy 117.112824 -255.426584)
			(xy 117.132507 -255.377749) (xy 117.159413 -255.33249) (xy 117.192913 -255.291869) (xy 117.232221 -255.256838)
			(xy 117.276416 -255.228218) (xy 117.324461 -255.206679) (xy 117.375232 -255.192727) (xy 117.427537 -255.186689)
			(xy 117.480151 -255.188706) (xy 117.531841 -255.19873) (xy 117.581394 -255.216528) (xy 117.62765 -255.241681)
			(xy 117.669524 -255.2736) (xy 117.706036 -255.311538) (xy 117.736328 -255.354604) (xy 117.759691 -255.401789)
			(xy 117.775577 -255.451988) (xy 117.783614 -255.504024) (xy 117.784118 -255.53035) (xy 117.783614 -255.556676)
			(xy 117.775577 -255.608712) (xy 117.759691 -255.658911) (xy 117.736328 -255.706096) (xy 117.706036 -255.749162)
			(xy 117.669524 -255.7871) (xy 117.62765 -255.819019) (xy 117.617604 -255.824482) (xy 120.86896 -255.824482)
			(xy 120.87292 -255.775428) (xy 120.884697 -255.727644) (xy 120.903988 -255.682368) (xy 120.930291 -255.640772)
			(xy 120.962926 -255.603935) (xy 121.001047 -255.57281) (xy 121.043668 -255.548203) (xy 121.089684 -255.530751)
			(xy 121.137903 -255.520907) (xy 121.187078 -255.518926) (xy 121.235933 -255.524858) (xy 121.283204 -255.53855)
			(xy 121.327666 -255.559648) (xy 121.368169 -255.587604) (xy 121.403662 -255.621696) (xy 121.433227 -255.66104)
			(xy 121.456098 -255.704617) (xy 121.471682 -255.751298) (xy 121.479577 -255.799875) (xy 121.480072 -255.824482)
			(xy 122.748814 -255.824482) (xy 122.752774 -255.775428) (xy 122.764551 -255.727644) (xy 122.783842 -255.682368)
			(xy 122.810145 -255.640772) (xy 122.84278 -255.603935) (xy 122.880901 -255.57281) (xy 122.923522 -255.548203)
			(xy 122.969538 -255.530751) (xy 123.017757 -255.520907) (xy 123.066932 -255.518926) (xy 123.115787 -255.524858)
			(xy 123.163058 -255.53855) (xy 123.20752 -255.559648) (xy 123.248023 -255.587604) (xy 123.283516 -255.621696)
			(xy 123.313081 -255.66104) (xy 123.335952 -255.704617) (xy 123.351536 -255.751298) (xy 123.359431 -255.799875)
			(xy 123.359926 -255.824482) (xy 124.628922 -255.824482) (xy 124.632882 -255.775428) (xy 124.644659 -255.727644)
			(xy 124.66395 -255.682368) (xy 124.690253 -255.640772) (xy 124.722888 -255.603935) (xy 124.761009 -255.57281)
			(xy 124.80363 -255.548203) (xy 124.849646 -255.530751) (xy 124.897865 -255.520907) (xy 124.94704 -255.518926)
			(xy 124.995895 -255.524858) (xy 125.043166 -255.53855) (xy 125.087628 -255.559648) (xy 125.128131 -255.587604)
			(xy 125.163624 -255.621696) (xy 125.193189 -255.66104) (xy 125.21606 -255.704617) (xy 125.231644 -255.751298)
			(xy 125.239539 -255.799875) (xy 125.240034 -255.824482) (xy 126.50903 -255.824482) (xy 126.51299 -255.775428)
			(xy 126.524767 -255.727644) (xy 126.544058 -255.682368) (xy 126.570361 -255.640772) (xy 126.602996 -255.603935)
			(xy 126.641117 -255.57281) (xy 126.683738 -255.548203) (xy 126.729754 -255.530751) (xy 126.777973 -255.520907)
			(xy 126.827148 -255.518926) (xy 126.876003 -255.524858) (xy 126.923274 -255.53855) (xy 126.967736 -255.559648)
			(xy 127.008239 -255.587604) (xy 127.043732 -255.621696) (xy 127.073297 -255.66104) (xy 127.096168 -255.704617)
			(xy 127.111752 -255.751298) (xy 127.119647 -255.799875) (xy 127.120142 -255.824482) (xy 127.438399 -255.824482)
			(xy 127.442494 -255.773754) (xy 127.454673 -255.72434) (xy 127.474621 -255.67752) (xy 127.501822 -255.634506)
			(xy 127.53557 -255.596412) (xy 127.574992 -255.564225) (xy 127.619066 -255.538779) (xy 127.666652 -255.520732)
			(xy 127.716516 -255.510552) (xy 127.767368 -255.508503) (xy 127.817889 -255.514637) (xy 127.866773 -255.528797)
			(xy 127.912752 -255.550614) (xy 127.954636 -255.579524) (xy 127.99134 -255.614779) (xy 128.021913 -255.655465)
			(xy 128.045564 -255.700528) (xy 128.06168 -255.748802) (xy 128.069844 -255.799036) (xy 128.070356 -255.824482)
			(xy 128.388884 -255.824482) (xy 128.392844 -255.775428) (xy 128.404621 -255.727644) (xy 128.423912 -255.682368)
			(xy 128.450215 -255.640772) (xy 128.48285 -255.603935) (xy 128.520971 -255.57281) (xy 128.563592 -255.548203)
			(xy 128.609608 -255.530751) (xy 128.657827 -255.520907) (xy 128.707002 -255.518926) (xy 128.755857 -255.524858)
			(xy 128.803128 -255.53855) (xy 128.84759 -255.559648) (xy 128.888093 -255.587604) (xy 128.923586 -255.621696)
			(xy 128.953151 -255.66104) (xy 128.976022 -255.704617) (xy 128.991606 -255.751298) (xy 128.999501 -255.799875)
			(xy 128.999996 -255.824482) (xy 129.318507 -255.824482) (xy 129.322602 -255.773754) (xy 129.334781 -255.72434)
			(xy 129.354729 -255.67752) (xy 129.38193 -255.634506) (xy 129.415678 -255.596412) (xy 129.4551 -255.564225)
			(xy 129.499174 -255.538779) (xy 129.54676 -255.520732) (xy 129.596624 -255.510552) (xy 129.647476 -255.508503)
			(xy 129.697997 -255.514637) (xy 129.746881 -255.528797) (xy 129.79286 -255.550614) (xy 129.834744 -255.579524)
			(xy 129.871448 -255.614779) (xy 129.902021 -255.655465) (xy 129.925672 -255.700528) (xy 129.941788 -255.748802)
			(xy 129.949952 -255.799036) (xy 129.950464 -255.824482) (xy 130.268992 -255.824482) (xy 130.272952 -255.775428)
			(xy 130.284729 -255.727644) (xy 130.30402 -255.682368) (xy 130.330323 -255.640772) (xy 130.362958 -255.603935)
			(xy 130.401079 -255.57281) (xy 130.4437 -255.548203) (xy 130.489716 -255.530751) (xy 130.537935 -255.520907)
			(xy 130.58711 -255.518926) (xy 130.635965 -255.524858) (xy 130.683236 -255.53855) (xy 130.727698 -255.559648)
			(xy 130.768201 -255.587604) (xy 130.803694 -255.621696) (xy 130.833259 -255.66104) (xy 130.85613 -255.704617)
			(xy 130.871714 -255.751298) (xy 130.879609 -255.799875) (xy 130.880104 -255.824482) (xy 131.198615 -255.824482)
			(xy 131.20271 -255.773754) (xy 131.214889 -255.72434) (xy 131.234837 -255.67752) (xy 131.262038 -255.634506)
			(xy 131.295786 -255.596412) (xy 131.335208 -255.564225) (xy 131.379282 -255.538779) (xy 131.426868 -255.520732)
			(xy 131.476732 -255.510552) (xy 131.527584 -255.508503) (xy 131.578105 -255.514637) (xy 131.626989 -255.528797)
			(xy 131.672968 -255.550614) (xy 131.714852 -255.579524) (xy 131.751556 -255.614779) (xy 131.782129 -255.655465)
			(xy 131.80578 -255.700528) (xy 131.821896 -255.748802) (xy 131.83006 -255.799036) (xy 131.830572 -255.824482)
			(xy 132.138415 -255.824482) (xy 132.14251 -255.773754) (xy 132.154689 -255.72434) (xy 132.174637 -255.67752)
			(xy 132.201838 -255.634506) (xy 132.235586 -255.596412) (xy 132.275008 -255.564225) (xy 132.319082 -255.538779)
			(xy 132.366668 -255.520732) (xy 132.416532 -255.510552) (xy 132.467384 -255.508503) (xy 132.517905 -255.514637)
			(xy 132.566789 -255.528797) (xy 132.612768 -255.550614) (xy 132.654652 -255.579524) (xy 132.691356 -255.614779)
			(xy 132.721929 -255.655465) (xy 132.74558 -255.700528) (xy 132.761696 -255.748802) (xy 132.76986 -255.799036)
			(xy 132.770372 -255.824482) (xy 133.0889 -255.824482) (xy 133.09286 -255.775428) (xy 133.104637 -255.727644)
			(xy 133.123928 -255.682368) (xy 133.150231 -255.640772) (xy 133.182866 -255.603935) (xy 133.220987 -255.57281)
			(xy 133.263608 -255.548203) (xy 133.309624 -255.530751) (xy 133.357843 -255.520907) (xy 133.407018 -255.518926)
			(xy 133.455873 -255.524858) (xy 133.503144 -255.53855) (xy 133.547606 -255.559648) (xy 133.588109 -255.587604)
			(xy 133.623602 -255.621696) (xy 133.653167 -255.66104) (xy 133.676038 -255.704617) (xy 133.691622 -255.751298)
			(xy 133.699517 -255.799875) (xy 133.700012 -255.824482) (xy 134.018523 -255.824482) (xy 134.022618 -255.773754)
			(xy 134.034797 -255.72434) (xy 134.054745 -255.67752) (xy 134.081946 -255.634506) (xy 134.115694 -255.596412)
			(xy 134.155116 -255.564225) (xy 134.19919 -255.538779) (xy 134.246776 -255.520732) (xy 134.29664 -255.510552)
			(xy 134.347492 -255.508503) (xy 134.398013 -255.514637) (xy 134.446897 -255.528797) (xy 134.492876 -255.550614)
			(xy 134.53476 -255.579524) (xy 134.571464 -255.614779) (xy 134.602037 -255.655465) (xy 134.625688 -255.700528)
			(xy 134.641804 -255.748802) (xy 134.649968 -255.799036) (xy 134.65048 -255.824482) (xy 134.969008 -255.824482)
			(xy 134.972968 -255.775428) (xy 134.984745 -255.727644) (xy 135.004036 -255.682368) (xy 135.030339 -255.640772)
			(xy 135.062974 -255.603935) (xy 135.101095 -255.57281) (xy 135.143716 -255.548203) (xy 135.189732 -255.530751)
			(xy 135.237951 -255.520907) (xy 135.287126 -255.518926) (xy 135.335981 -255.524858) (xy 135.383252 -255.53855)
			(xy 135.427714 -255.559648) (xy 135.468217 -255.587604) (xy 135.50371 -255.621696) (xy 135.533275 -255.66104)
			(xy 135.556146 -255.704617) (xy 135.57173 -255.751298) (xy 135.579625 -255.799875) (xy 135.58012 -255.824482)
			(xy 135.898631 -255.824482) (xy 135.902726 -255.773754) (xy 135.914905 -255.72434) (xy 135.934853 -255.67752)
			(xy 135.962054 -255.634506) (xy 135.995802 -255.596412) (xy 136.035224 -255.564225) (xy 136.079298 -255.538779)
			(xy 136.126884 -255.520732) (xy 136.176748 -255.510552) (xy 136.2276 -255.508503) (xy 136.278121 -255.514637)
			(xy 136.327005 -255.528797) (xy 136.372984 -255.550614) (xy 136.414868 -255.579524) (xy 136.451572 -255.614779)
			(xy 136.482145 -255.655465) (xy 136.505796 -255.700528) (xy 136.521912 -255.748802) (xy 136.530076 -255.799036)
			(xy 136.530588 -255.824482) (xy 136.530583 -255.824736) (xy 136.848608 -255.824736) (xy 136.852568 -255.775682)
			(xy 136.864345 -255.727898) (xy 136.883636 -255.682622) (xy 136.909939 -255.641026) (xy 136.942574 -255.604189)
			(xy 136.980695 -255.573064) (xy 137.023316 -255.548457) (xy 137.069332 -255.531005) (xy 137.117551 -255.521161)
			(xy 137.166726 -255.51918) (xy 137.215581 -255.525112) (xy 137.262852 -255.538804) (xy 137.307314 -255.559902)
			(xy 137.347817 -255.587858) (xy 137.38331 -255.62195) (xy 137.412875 -255.661294) (xy 137.435746 -255.704871)
			(xy 137.45133 -255.751552) (xy 137.459225 -255.800129) (xy 137.459715 -255.824482) (xy 137.778485 -255.824482)
			(xy 137.78258 -255.773754) (xy 137.794759 -255.72434) (xy 137.814707 -255.67752) (xy 137.841908 -255.634506)
			(xy 137.875656 -255.596412) (xy 137.915078 -255.564225) (xy 137.959152 -255.538779) (xy 138.006738 -255.520732)
			(xy 138.056602 -255.510552) (xy 138.107454 -255.508503) (xy 138.157975 -255.514637) (xy 138.206859 -255.528797)
			(xy 138.252838 -255.550614) (xy 138.294722 -255.579524) (xy 138.331426 -255.614779) (xy 138.361999 -255.655465)
			(xy 138.38565 -255.700528) (xy 138.401766 -255.748802) (xy 138.40993 -255.799036) (xy 138.410442 -255.824482)
			(xy 138.718539 -255.824482) (xy 138.722634 -255.773754) (xy 138.734813 -255.72434) (xy 138.754761 -255.67752)
			(xy 138.781962 -255.634506) (xy 138.81571 -255.596412) (xy 138.855132 -255.564225) (xy 138.899206 -255.538779)
			(xy 138.946792 -255.520732) (xy 138.996656 -255.510552) (xy 139.047508 -255.508503) (xy 139.098029 -255.514637)
			(xy 139.146913 -255.528797) (xy 139.192892 -255.550614) (xy 139.234776 -255.579524) (xy 139.27148 -255.614779)
			(xy 139.302053 -255.655465) (xy 139.325704 -255.700528) (xy 139.34182 -255.748802) (xy 139.349984 -255.799036)
			(xy 139.350496 -255.824482) (xy 139.669024 -255.824482) (xy 139.672984 -255.775428) (xy 139.684761 -255.727644)
			(xy 139.704052 -255.682368) (xy 139.730355 -255.640772) (xy 139.76299 -255.603935) (xy 139.801111 -255.57281)
			(xy 139.843732 -255.548203) (xy 139.889748 -255.530751) (xy 139.937967 -255.520907) (xy 139.987142 -255.518926)
			(xy 140.035997 -255.524858) (xy 140.083268 -255.53855) (xy 140.12773 -255.559648) (xy 140.168233 -255.587604)
			(xy 140.203726 -255.621696) (xy 140.233291 -255.66104) (xy 140.256162 -255.704617) (xy 140.271746 -255.751298)
			(xy 140.279641 -255.799875) (xy 140.280136 -255.824482) (xy 140.598647 -255.824482) (xy 140.602742 -255.773754)
			(xy 140.614921 -255.72434) (xy 140.634869 -255.67752) (xy 140.66207 -255.634506) (xy 140.695818 -255.596412)
			(xy 140.73524 -255.564225) (xy 140.779314 -255.538779) (xy 140.8269 -255.520732) (xy 140.876764 -255.510552)
			(xy 140.927616 -255.508503) (xy 140.978137 -255.514637) (xy 141.027021 -255.528797) (xy 141.073 -255.550614)
			(xy 141.114884 -255.579524) (xy 141.151588 -255.614779) (xy 141.182161 -255.655465) (xy 141.205812 -255.700528)
			(xy 141.221928 -255.748802) (xy 141.230092 -255.799036) (xy 141.230604 -255.824482) (xy 141.548878 -255.824482)
			(xy 141.552838 -255.775428) (xy 141.564615 -255.727644) (xy 141.583906 -255.682368) (xy 141.610209 -255.640772)
			(xy 141.642844 -255.603935) (xy 141.680965 -255.57281) (xy 141.723586 -255.548203) (xy 141.769602 -255.530751)
			(xy 141.817821 -255.520907) (xy 141.866996 -255.518926) (xy 141.915851 -255.524858) (xy 141.963122 -255.53855)
			(xy 142.007584 -255.559648) (xy 142.048087 -255.587604) (xy 142.08358 -255.621696) (xy 142.113145 -255.66104)
			(xy 142.136016 -255.704617) (xy 142.1516 -255.751298) (xy 142.159495 -255.799875) (xy 142.15999 -255.824482)
			(xy 142.478501 -255.824482) (xy 142.482596 -255.773754) (xy 142.494775 -255.72434) (xy 142.514723 -255.67752)
			(xy 142.541924 -255.634506) (xy 142.575672 -255.596412) (xy 142.615094 -255.564225) (xy 142.659168 -255.538779)
			(xy 142.706754 -255.520732) (xy 142.756618 -255.510552) (xy 142.80747 -255.508503) (xy 142.857991 -255.514637)
			(xy 142.906875 -255.528797) (xy 142.952854 -255.550614) (xy 142.994738 -255.579524) (xy 143.031442 -255.614779)
			(xy 143.062015 -255.655465) (xy 143.085666 -255.700528) (xy 143.101782 -255.748802) (xy 143.109946 -255.799036)
			(xy 143.110458 -255.824482) (xy 143.428986 -255.824482) (xy 143.432946 -255.775428) (xy 143.444723 -255.727644)
			(xy 143.464014 -255.682368) (xy 143.490317 -255.640772) (xy 143.522952 -255.603935) (xy 143.561073 -255.57281)
			(xy 143.603694 -255.548203) (xy 143.64971 -255.530751) (xy 143.697929 -255.520907) (xy 143.747104 -255.518926)
			(xy 143.795959 -255.524858) (xy 143.84323 -255.53855) (xy 143.887692 -255.559648) (xy 143.928195 -255.587604)
			(xy 143.963688 -255.621696) (xy 143.993253 -255.66104) (xy 144.016124 -255.704617) (xy 144.031708 -255.751298)
			(xy 144.039603 -255.799875) (xy 144.040098 -255.824482) (xy 144.039603 -255.849089) (xy 144.031708 -255.897666)
			(xy 144.016124 -255.944347) (xy 143.993253 -255.987924) (xy 143.963688 -256.027268) (xy 143.928195 -256.06136)
			(xy 143.887692 -256.089316) (xy 143.84323 -256.110414) (xy 143.795959 -256.124106) (xy 143.747104 -256.130038)
			(xy 143.697929 -256.128057) (xy 143.64971 -256.118213) (xy 143.603694 -256.100761) (xy 143.561073 -256.076154)
			(xy 143.522952 -256.045029) (xy 143.490317 -256.008192) (xy 143.464014 -255.966596) (xy 143.444723 -255.92132)
			(xy 143.432946 -255.873536) (xy 143.428986 -255.824482) (xy 143.110458 -255.824482) (xy 143.109946 -255.849928)
			(xy 143.101782 -255.900162) (xy 143.085666 -255.948436) (xy 143.062015 -255.993499) (xy 143.031442 -256.034185)
			(xy 142.994738 -256.06944) (xy 142.952854 -256.09835) (xy 142.906875 -256.120167) (xy 142.857991 -256.134327)
			(xy 142.80747 -256.140461) (xy 142.756618 -256.138412) (xy 142.706754 -256.128232) (xy 142.659168 -256.110185)
			(xy 142.615094 -256.084739) (xy 142.575672 -256.052552) (xy 142.541924 -256.014458) (xy 142.514723 -255.971444)
			(xy 142.494775 -255.924624) (xy 142.482596 -255.87521) (xy 142.478501 -255.824482) (xy 142.15999 -255.824482)
			(xy 142.159495 -255.849089) (xy 142.1516 -255.897666) (xy 142.136016 -255.944347) (xy 142.113145 -255.987924)
			(xy 142.08358 -256.027268) (xy 142.048087 -256.06136) (xy 142.007584 -256.089316) (xy 141.963122 -256.110414)
			(xy 141.915851 -256.124106) (xy 141.866996 -256.130038) (xy 141.817821 -256.128057) (xy 141.769602 -256.118213)
			(xy 141.723586 -256.100761) (xy 141.680965 -256.076154) (xy 141.642844 -256.045029) (xy 141.610209 -256.008192)
			(xy 141.583906 -255.966596) (xy 141.564615 -255.92132) (xy 141.552838 -255.873536) (xy 141.548878 -255.824482)
			(xy 141.230604 -255.824482) (xy 141.230092 -255.849928) (xy 141.221928 -255.900162) (xy 141.205812 -255.948436)
			(xy 141.182161 -255.993499) (xy 141.151588 -256.034185) (xy 141.114884 -256.06944) (xy 141.073 -256.09835)
			(xy 141.027021 -256.120167) (xy 140.978137 -256.134327) (xy 140.927616 -256.140461) (xy 140.876764 -256.138412)
			(xy 140.8269 -256.128232) (xy 140.779314 -256.110185) (xy 140.73524 -256.084739) (xy 140.695818 -256.052552)
			(xy 140.66207 -256.014458) (xy 140.634869 -255.971444) (xy 140.614921 -255.924624) (xy 140.602742 -255.87521)
			(xy 140.598647 -255.824482) (xy 140.280136 -255.824482) (xy 140.279641 -255.849089) (xy 140.271746 -255.897666)
			(xy 140.256162 -255.944347) (xy 140.233291 -255.987924) (xy 140.203726 -256.027268) (xy 140.168233 -256.06136)
			(xy 140.12773 -256.089316) (xy 140.083268 -256.110414) (xy 140.035997 -256.124106) (xy 139.987142 -256.130038)
			(xy 139.937967 -256.128057) (xy 139.889748 -256.118213) (xy 139.843732 -256.100761) (xy 139.801111 -256.076154)
			(xy 139.76299 -256.045029) (xy 139.730355 -256.008192) (xy 139.704052 -255.966596) (xy 139.684761 -255.92132)
			(xy 139.672984 -255.873536) (xy 139.669024 -255.824482) (xy 139.350496 -255.824482) (xy 139.349984 -255.849928)
			(xy 139.34182 -255.900162) (xy 139.325704 -255.948436) (xy 139.302053 -255.993499) (xy 139.27148 -256.034185)
			(xy 139.234776 -256.06944) (xy 139.192892 -256.09835) (xy 139.146913 -256.120167) (xy 139.098029 -256.134327)
			(xy 139.047508 -256.140461) (xy 138.996656 -256.138412) (xy 138.946792 -256.128232) (xy 138.899206 -256.110185)
			(xy 138.855132 -256.084739) (xy 138.81571 -256.052552) (xy 138.781962 -256.014458) (xy 138.754761 -255.971444)
			(xy 138.734813 -255.924624) (xy 138.722634 -255.87521) (xy 138.718539 -255.824482) (xy 138.410442 -255.824482)
			(xy 138.40993 -255.849928) (xy 138.401766 -255.900162) (xy 138.38565 -255.948436) (xy 138.361999 -255.993499)
			(xy 138.331426 -256.034185) (xy 138.294722 -256.06944) (xy 138.252838 -256.09835) (xy 138.206859 -256.120167)
			(xy 138.157975 -256.134327) (xy 138.107454 -256.140461) (xy 138.056602 -256.138412) (xy 138.006738 -256.128232)
			(xy 137.959152 -256.110185) (xy 137.915078 -256.084739) (xy 137.875656 -256.052552) (xy 137.841908 -256.014458)
			(xy 137.814707 -255.971444) (xy 137.794759 -255.924624) (xy 137.78258 -255.87521) (xy 137.778485 -255.824482)
			(xy 137.459715 -255.824482) (xy 137.45972 -255.824736) (xy 137.459225 -255.849343) (xy 137.45133 -255.89792)
			(xy 137.435746 -255.944601) (xy 137.412875 -255.988178) (xy 137.38331 -256.027522) (xy 137.347817 -256.061614)
			(xy 137.307314 -256.08957) (xy 137.262852 -256.110668) (xy 137.215581 -256.12436) (xy 137.166726 -256.130292)
			(xy 137.117551 -256.128311) (xy 137.069332 -256.118467) (xy 137.023316 -256.101015) (xy 136.980695 -256.076408)
			(xy 136.942574 -256.045283) (xy 136.909939 -256.008446) (xy 136.883636 -255.96685) (xy 136.864345 -255.921574)
			(xy 136.852568 -255.87379) (xy 136.848608 -255.824736) (xy 136.530583 -255.824736) (xy 136.530076 -255.849928)
			(xy 136.521912 -255.900162) (xy 136.505796 -255.948436) (xy 136.482145 -255.993499) (xy 136.451572 -256.034185)
			(xy 136.414868 -256.06944) (xy 136.372984 -256.09835) (xy 136.327005 -256.120167) (xy 136.278121 -256.134327)
			(xy 136.2276 -256.140461) (xy 136.176748 -256.138412) (xy 136.126884 -256.128232) (xy 136.079298 -256.110185)
			(xy 136.035224 -256.084739) (xy 135.995802 -256.052552) (xy 135.962054 -256.014458) (xy 135.934853 -255.971444)
			(xy 135.914905 -255.924624) (xy 135.902726 -255.87521) (xy 135.898631 -255.824482) (xy 135.58012 -255.824482)
			(xy 135.579625 -255.849089) (xy 135.57173 -255.897666) (xy 135.556146 -255.944347) (xy 135.533275 -255.987924)
			(xy 135.50371 -256.027268) (xy 135.468217 -256.06136) (xy 135.427714 -256.089316) (xy 135.383252 -256.110414)
			(xy 135.335981 -256.124106) (xy 135.287126 -256.130038) (xy 135.237951 -256.128057) (xy 135.189732 -256.118213)
			(xy 135.143716 -256.100761) (xy 135.101095 -256.076154) (xy 135.062974 -256.045029) (xy 135.030339 -256.008192)
			(xy 135.004036 -255.966596) (xy 134.984745 -255.92132) (xy 134.972968 -255.873536) (xy 134.969008 -255.824482)
			(xy 134.65048 -255.824482) (xy 134.649968 -255.849928) (xy 134.641804 -255.900162) (xy 134.625688 -255.948436)
			(xy 134.602037 -255.993499) (xy 134.571464 -256.034185) (xy 134.53476 -256.06944) (xy 134.492876 -256.09835)
			(xy 134.446897 -256.120167) (xy 134.398013 -256.134327) (xy 134.347492 -256.140461) (xy 134.29664 -256.138412)
			(xy 134.246776 -256.128232) (xy 134.19919 -256.110185) (xy 134.155116 -256.084739) (xy 134.115694 -256.052552)
			(xy 134.081946 -256.014458) (xy 134.054745 -255.971444) (xy 134.034797 -255.924624) (xy 134.022618 -255.87521)
			(xy 134.018523 -255.824482) (xy 133.700012 -255.824482) (xy 133.699517 -255.849089) (xy 133.691622 -255.897666)
			(xy 133.676038 -255.944347) (xy 133.653167 -255.987924) (xy 133.623602 -256.027268) (xy 133.588109 -256.06136)
			(xy 133.547606 -256.089316) (xy 133.503144 -256.110414) (xy 133.455873 -256.124106) (xy 133.407018 -256.130038)
			(xy 133.357843 -256.128057) (xy 133.309624 -256.118213) (xy 133.263608 -256.100761) (xy 133.220987 -256.076154)
			(xy 133.182866 -256.045029) (xy 133.150231 -256.008192) (xy 133.123928 -255.966596) (xy 133.104637 -255.92132)
			(xy 133.09286 -255.873536) (xy 133.0889 -255.824482) (xy 132.770372 -255.824482) (xy 132.76986 -255.849928)
			(xy 132.761696 -255.900162) (xy 132.74558 -255.948436) (xy 132.721929 -255.993499) (xy 132.691356 -256.034185)
			(xy 132.654652 -256.06944) (xy 132.612768 -256.09835) (xy 132.566789 -256.120167) (xy 132.517905 -256.134327)
			(xy 132.467384 -256.140461) (xy 132.416532 -256.138412) (xy 132.366668 -256.128232) (xy 132.319082 -256.110185)
			(xy 132.275008 -256.084739) (xy 132.235586 -256.052552) (xy 132.201838 -256.014458) (xy 132.174637 -255.971444)
			(xy 132.154689 -255.924624) (xy 132.14251 -255.87521) (xy 132.138415 -255.824482) (xy 131.830572 -255.824482)
			(xy 131.83006 -255.849928) (xy 131.821896 -255.900162) (xy 131.80578 -255.948436) (xy 131.782129 -255.993499)
			(xy 131.751556 -256.034185) (xy 131.714852 -256.06944) (xy 131.672968 -256.09835) (xy 131.626989 -256.120167)
			(xy 131.578105 -256.134327) (xy 131.527584 -256.140461) (xy 131.476732 -256.138412) (xy 131.426868 -256.128232)
			(xy 131.379282 -256.110185) (xy 131.335208 -256.084739) (xy 131.295786 -256.052552) (xy 131.262038 -256.014458)
			(xy 131.234837 -255.971444) (xy 131.214889 -255.924624) (xy 131.20271 -255.87521) (xy 131.198615 -255.824482)
			(xy 130.880104 -255.824482) (xy 130.879609 -255.849089) (xy 130.871714 -255.897666) (xy 130.85613 -255.944347)
			(xy 130.833259 -255.987924) (xy 130.803694 -256.027268) (xy 130.768201 -256.06136) (xy 130.727698 -256.089316)
			(xy 130.683236 -256.110414) (xy 130.635965 -256.124106) (xy 130.58711 -256.130038) (xy 130.537935 -256.128057)
			(xy 130.489716 -256.118213) (xy 130.4437 -256.100761) (xy 130.401079 -256.076154) (xy 130.362958 -256.045029)
			(xy 130.330323 -256.008192) (xy 130.30402 -255.966596) (xy 130.284729 -255.92132) (xy 130.272952 -255.873536)
			(xy 130.268992 -255.824482) (xy 129.950464 -255.824482) (xy 129.949952 -255.849928) (xy 129.941788 -255.900162)
			(xy 129.925672 -255.948436) (xy 129.902021 -255.993499) (xy 129.871448 -256.034185) (xy 129.834744 -256.06944)
			(xy 129.79286 -256.09835) (xy 129.746881 -256.120167) (xy 129.697997 -256.134327) (xy 129.647476 -256.140461)
			(xy 129.596624 -256.138412) (xy 129.54676 -256.128232) (xy 129.499174 -256.110185) (xy 129.4551 -256.084739)
			(xy 129.415678 -256.052552) (xy 129.38193 -256.014458) (xy 129.354729 -255.971444) (xy 129.334781 -255.924624)
			(xy 129.322602 -255.87521) (xy 129.318507 -255.824482) (xy 128.999996 -255.824482) (xy 128.999501 -255.849089)
			(xy 128.991606 -255.897666) (xy 128.976022 -255.944347) (xy 128.953151 -255.987924) (xy 128.923586 -256.027268)
			(xy 128.888093 -256.06136) (xy 128.84759 -256.089316) (xy 128.803128 -256.110414) (xy 128.755857 -256.124106)
			(xy 128.707002 -256.130038) (xy 128.657827 -256.128057) (xy 128.609608 -256.118213) (xy 128.563592 -256.100761)
			(xy 128.520971 -256.076154) (xy 128.48285 -256.045029) (xy 128.450215 -256.008192) (xy 128.423912 -255.966596)
			(xy 128.404621 -255.92132) (xy 128.392844 -255.873536) (xy 128.388884 -255.824482) (xy 128.070356 -255.824482)
			(xy 128.069844 -255.849928) (xy 128.06168 -255.900162) (xy 128.045564 -255.948436) (xy 128.021913 -255.993499)
			(xy 127.99134 -256.034185) (xy 127.954636 -256.06944) (xy 127.912752 -256.09835) (xy 127.866773 -256.120167)
			(xy 127.817889 -256.134327) (xy 127.767368 -256.140461) (xy 127.716516 -256.138412) (xy 127.666652 -256.128232)
			(xy 127.619066 -256.110185) (xy 127.574992 -256.084739) (xy 127.53557 -256.052552) (xy 127.501822 -256.014458)
			(xy 127.474621 -255.971444) (xy 127.454673 -255.924624) (xy 127.442494 -255.87521) (xy 127.438399 -255.824482)
			(xy 127.120142 -255.824482) (xy 127.119647 -255.849089) (xy 127.111752 -255.897666) (xy 127.096168 -255.944347)
			(xy 127.073297 -255.987924) (xy 127.043732 -256.027268) (xy 127.008239 -256.06136) (xy 126.967736 -256.089316)
			(xy 126.923274 -256.110414) (xy 126.876003 -256.124106) (xy 126.827148 -256.130038) (xy 126.777973 -256.128057)
			(xy 126.729754 -256.118213) (xy 126.683738 -256.100761) (xy 126.641117 -256.076154) (xy 126.602996 -256.045029)
			(xy 126.570361 -256.008192) (xy 126.544058 -255.966596) (xy 126.524767 -255.92132) (xy 126.51299 -255.873536)
			(xy 126.50903 -255.824482) (xy 125.240034 -255.824482) (xy 125.239539 -255.849089) (xy 125.231644 -255.897666)
			(xy 125.21606 -255.944347) (xy 125.193189 -255.987924) (xy 125.163624 -256.027268) (xy 125.128131 -256.06136)
			(xy 125.087628 -256.089316) (xy 125.043166 -256.110414) (xy 124.995895 -256.124106) (xy 124.94704 -256.130038)
			(xy 124.897865 -256.128057) (xy 124.849646 -256.118213) (xy 124.80363 -256.100761) (xy 124.761009 -256.076154)
			(xy 124.722888 -256.045029) (xy 124.690253 -256.008192) (xy 124.66395 -255.966596) (xy 124.644659 -255.92132)
			(xy 124.632882 -255.873536) (xy 124.628922 -255.824482) (xy 123.359926 -255.824482) (xy 123.359431 -255.849089)
			(xy 123.351536 -255.897666) (xy 123.335952 -255.944347) (xy 123.313081 -255.987924) (xy 123.283516 -256.027268)
			(xy 123.248023 -256.06136) (xy 123.20752 -256.089316) (xy 123.163058 -256.110414) (xy 123.115787 -256.124106)
			(xy 123.066932 -256.130038) (xy 123.017757 -256.128057) (xy 122.969538 -256.118213) (xy 122.923522 -256.100761)
			(xy 122.880901 -256.076154) (xy 122.84278 -256.045029) (xy 122.810145 -256.008192) (xy 122.783842 -255.966596)
			(xy 122.764551 -255.92132) (xy 122.752774 -255.873536) (xy 122.748814 -255.824482) (xy 121.480072 -255.824482)
			(xy 121.479577 -255.849089) (xy 121.471682 -255.897666) (xy 121.456098 -255.944347) (xy 121.433227 -255.987924)
			(xy 121.403662 -256.027268) (xy 121.368169 -256.06136) (xy 121.327666 -256.089316) (xy 121.283204 -256.110414)
			(xy 121.235933 -256.124106) (xy 121.187078 -256.130038) (xy 121.137903 -256.128057) (xy 121.089684 -256.118213)
			(xy 121.043668 -256.100761) (xy 121.001047 -256.076154) (xy 120.962926 -256.045029) (xy 120.930291 -256.008192)
			(xy 120.903988 -255.966596) (xy 120.884697 -255.92132) (xy 120.87292 -255.873536) (xy 120.86896 -255.824482)
			(xy 117.617604 -255.824482) (xy 117.581394 -255.844172) (xy 117.531841 -255.86197) (xy 117.480151 -255.871994)
			(xy 117.427537 -255.874011) (xy 117.375232 -255.867973) (xy 117.324461 -255.854021) (xy 117.276416 -255.832482)
			(xy 117.232221 -255.803862) (xy 117.192913 -255.768831) (xy 117.159413 -255.72821) (xy 117.132507 -255.682951)
			(xy 117.112824 -255.634116) (xy 117.100827 -255.582848) (xy 117.096797 -255.53035) (xy 106.74858 -255.53035)
			(xy 106.748076 -255.556676) (xy 106.740039 -255.608712) (xy 106.724153 -255.658911) (xy 106.70079 -255.706096)
			(xy 106.670498 -255.749162) (xy 106.633986 -255.7871) (xy 106.592112 -255.819019) (xy 106.545856 -255.844172)
			(xy 106.496303 -255.86197) (xy 106.444613 -255.871994) (xy 106.391999 -255.874011) (xy 106.339694 -255.867973)
			(xy 106.288923 -255.854021) (xy 106.240878 -255.832482) (xy 106.196683 -255.803862) (xy 106.157375 -255.768831)
			(xy 106.123875 -255.72821) (xy 106.096969 -255.682951) (xy 106.077286 -255.634116) (xy 106.065289 -255.582848)
			(xy 106.061259 -255.53035) (xy 105.83418 -255.53035) (xy 105.833676 -255.556676) (xy 105.825639 -255.608712)
			(xy 105.809753 -255.658911) (xy 105.78639 -255.706096) (xy 105.756098 -255.749162) (xy 105.719586 -255.7871)
			(xy 105.677712 -255.819019) (xy 105.631456 -255.844172) (xy 105.581903 -255.86197) (xy 105.530213 -255.871994)
			(xy 105.477599 -255.874011) (xy 105.425294 -255.867973) (xy 105.374523 -255.854021) (xy 105.326478 -255.832482)
			(xy 105.282283 -255.803862) (xy 105.242975 -255.768831) (xy 105.209475 -255.72821) (xy 105.182569 -255.682951)
			(xy 105.162886 -255.634116) (xy 105.150889 -255.582848) (xy 105.146859 -255.53035) (xy 104.345001 -255.53035)
			(xy 104.366296 -255.536518) (xy 104.410758 -255.557616) (xy 104.451261 -255.585572) (xy 104.486754 -255.619664)
			(xy 104.516319 -255.659008) (xy 104.53919 -255.702585) (xy 104.554774 -255.749266) (xy 104.562669 -255.797843)
			(xy 104.563164 -255.82245) (xy 104.562669 -255.847057) (xy 104.554774 -255.895634) (xy 104.53919 -255.942315)
			(xy 104.516319 -255.985892) (xy 104.486754 -256.025236) (xy 104.451261 -256.059328) (xy 104.410758 -256.087284)
			(xy 104.366296 -256.108382) (xy 104.319025 -256.122074) (xy 104.27017 -256.128006) (xy 104.220995 -256.126025)
			(xy 104.172776 -256.116181) (xy 104.12676 -256.098729) (xy 104.084139 -256.074122) (xy 104.046018 -256.042997)
			(xy 104.013383 -256.00616) (xy 103.98708 -255.964564) (xy 103.967789 -255.919288) (xy 103.956012 -255.871504)
			(xy 103.952052 -255.82245) (xy 101.746263 -255.82245) (xy 101.746304 -255.824482) (xy 101.745809 -255.849089)
			(xy 101.737914 -255.897666) (xy 101.72233 -255.944347) (xy 101.699459 -255.987924) (xy 101.669894 -256.027268)
			(xy 101.634401 -256.06136) (xy 101.593898 -256.089316) (xy 101.549436 -256.110414) (xy 101.502165 -256.124106)
			(xy 101.45331 -256.130038) (xy 101.404135 -256.128057) (xy 101.355916 -256.118213) (xy 101.3099 -256.100761)
			(xy 101.267279 -256.076154) (xy 101.229158 -256.045029) (xy 101.196523 -256.008192) (xy 101.17022 -255.966596)
			(xy 101.150929 -255.92132) (xy 101.139152 -255.873536) (xy 101.135192 -255.824482) (xy 100.806727 -255.824482)
			(xy 100.806728 -255.824491) (xy 100.802559 -255.874824) (xy 100.790163 -255.923784) (xy 100.769879 -255.970037)
			(xy 100.742259 -256.012321) (xy 100.708056 -256.049482) (xy 100.668204 -256.080507) (xy 100.64623 -256.09296)
			(xy 100.633784 -256.099818) (xy 100.61956 -256.123694) (xy 100.61956 -256.313432) (xy 100.61956 -256.316226)
			(xy 100.620931 -256.328819) (xy 100.634128 -256.350404) (xy 100.644706 -256.357374) (xy 100.648008 -256.359152)
			(xy 100.743258 -256.405634) (xy 100.77196 -256.402586) (xy 100.78339 -256.393696) (xy 100.803637 -256.37854)
			(xy 100.848102 -256.354446) (xy 100.895928 -256.338007) (xy 100.94581 -256.329673) (xy 100.971096 -256.32918)
			(xy 100.996355 -256.329672) (xy 101.046184 -256.337987) (xy 101.093965 -256.354389) (xy 101.138394 -256.378433)
			(xy 101.17826 -256.409461) (xy 101.212475 -256.446628) (xy 101.240106 -256.48892) (xy 101.260399 -256.535183)
			(xy 101.2728 -256.584155) (xy 101.276845 -256.632964) (xy 102.544638 -256.632964) (xy 102.548598 -256.58391)
			(xy 102.560375 -256.536126) (xy 102.579666 -256.49085) (xy 102.605969 -256.449254) (xy 102.638604 -256.412417)
			(xy 102.676725 -256.381292) (xy 102.719346 -256.356685) (xy 102.765362 -256.339233) (xy 102.813581 -256.329389)
			(xy 102.862756 -256.327408) (xy 102.911611 -256.33334) (xy 102.958882 -256.347032) (xy 103.003344 -256.36813)
			(xy 103.043847 -256.396086) (xy 103.07934 -256.430178) (xy 103.108905 -256.469522) (xy 103.114567 -256.48031)
			(xy 105.146859 -256.48031) (xy 105.150889 -256.427812) (xy 105.162886 -256.376544) (xy 105.182569 -256.327709)
			(xy 105.209475 -256.28245) (xy 105.242975 -256.241829) (xy 105.282283 -256.206798) (xy 105.326478 -256.178178)
			(xy 105.374523 -256.156639) (xy 105.425294 -256.142687) (xy 105.477599 -256.136649) (xy 105.530213 -256.138666)
			(xy 105.581903 -256.14869) (xy 105.631456 -256.166488) (xy 105.677712 -256.191641) (xy 105.719586 -256.22356)
			(xy 105.756098 -256.261498) (xy 105.78639 -256.304564) (xy 105.809753 -256.351749) (xy 105.825639 -256.401948)
			(xy 105.833676 -256.453984) (xy 105.83418 -256.48031) (xy 106.061259 -256.48031) (xy 106.065289 -256.427812)
			(xy 106.077286 -256.376544) (xy 106.096969 -256.327709) (xy 106.123875 -256.28245) (xy 106.157375 -256.241829)
			(xy 106.196683 -256.206798) (xy 106.240878 -256.178178) (xy 106.288923 -256.156639) (xy 106.339694 -256.142687)
			(xy 106.391999 -256.136649) (xy 106.444613 -256.138666) (xy 106.496303 -256.14869) (xy 106.545856 -256.166488)
			(xy 106.592112 -256.191641) (xy 106.633986 -256.22356) (xy 106.670498 -256.261498) (xy 106.70079 -256.304564)
			(xy 106.724153 -256.351749) (xy 106.735498 -256.3876) (xy 107.304081 -256.3876) (xy 107.308111 -256.335102)
			(xy 107.320108 -256.283834) (xy 107.339791 -256.234999) (xy 107.366697 -256.18974) (xy 107.400197 -256.149119)
			(xy 107.439505 -256.114088) (xy 107.4837 -256.085468) (xy 107.531745 -256.063929) (xy 107.582516 -256.049977)
			(xy 107.634821 -256.043939) (xy 107.687435 -256.045956) (xy 107.739125 -256.05598) (xy 107.788678 -256.073778)
			(xy 107.834934 -256.098931) (xy 107.876808 -256.13085) (xy 107.91332 -256.168788) (xy 107.943612 -256.211854)
			(xy 107.966975 -256.259039) (xy 107.982861 -256.309238) (xy 107.990898 -256.361274) (xy 107.991402 -256.3876)
			(xy 108.254041 -256.3876) (xy 108.258071 -256.335102) (xy 108.270068 -256.283834) (xy 108.289751 -256.234999)
			(xy 108.316657 -256.18974) (xy 108.350157 -256.149119) (xy 108.389465 -256.114088) (xy 108.43366 -256.085468)
			(xy 108.481705 -256.063929) (xy 108.532476 -256.049977) (xy 108.584781 -256.043939) (xy 108.637395 -256.045956)
			(xy 108.689085 -256.05598) (xy 108.738638 -256.073778) (xy 108.784894 -256.098931) (xy 108.826768 -256.13085)
			(xy 108.86328 -256.168788) (xy 108.893572 -256.211854) (xy 108.916935 -256.259039) (xy 108.932821 -256.309238)
			(xy 108.940858 -256.361274) (xy 108.941362 -256.3876) (xy 109.204001 -256.3876) (xy 109.208031 -256.335102)
			(xy 109.220028 -256.283834) (xy 109.239711 -256.234999) (xy 109.266617 -256.18974) (xy 109.300117 -256.149119)
			(xy 109.339425 -256.114088) (xy 109.38362 -256.085468) (xy 109.431665 -256.063929) (xy 109.482436 -256.049977)
			(xy 109.534741 -256.043939) (xy 109.587355 -256.045956) (xy 109.639045 -256.05598) (xy 109.688598 -256.073778)
			(xy 109.734854 -256.098931) (xy 109.776728 -256.13085) (xy 109.81324 -256.168788) (xy 109.843532 -256.211854)
			(xy 109.866895 -256.259039) (xy 109.882781 -256.309238) (xy 109.890818 -256.361274) (xy 109.891322 -256.3876)
			(xy 110.153961 -256.3876) (xy 110.157991 -256.335102) (xy 110.169988 -256.283834) (xy 110.189671 -256.234999)
			(xy 110.216577 -256.18974) (xy 110.250077 -256.149119) (xy 110.289385 -256.114088) (xy 110.33358 -256.085468)
			(xy 110.381625 -256.063929) (xy 110.432396 -256.049977) (xy 110.484701 -256.043939) (xy 110.537315 -256.045956)
			(xy 110.589005 -256.05598) (xy 110.638558 -256.073778) (xy 110.684814 -256.098931) (xy 110.726688 -256.13085)
			(xy 110.7632 -256.168788) (xy 110.793492 -256.211854) (xy 110.816855 -256.259039) (xy 110.832741 -256.309238)
			(xy 110.840778 -256.361274) (xy 110.841282 -256.3876) (xy 111.103921 -256.3876) (xy 111.107951 -256.335102)
			(xy 111.119948 -256.283834) (xy 111.139631 -256.234999) (xy 111.166537 -256.18974) (xy 111.200037 -256.149119)
			(xy 111.239345 -256.114088) (xy 111.28354 -256.085468) (xy 111.331585 -256.063929) (xy 111.382356 -256.049977)
			(xy 111.434661 -256.043939) (xy 111.487275 -256.045956) (xy 111.538965 -256.05598) (xy 111.588518 -256.073778)
			(xy 111.634774 -256.098931) (xy 111.676648 -256.13085) (xy 111.71316 -256.168788) (xy 111.743452 -256.211854)
			(xy 111.766815 -256.259039) (xy 111.782701 -256.309238) (xy 111.790738 -256.361274) (xy 111.791242 -256.3876)
			(xy 112.053881 -256.3876) (xy 112.057911 -256.335102) (xy 112.069908 -256.283834) (xy 112.089591 -256.234999)
			(xy 112.116497 -256.18974) (xy 112.149997 -256.149119) (xy 112.189305 -256.114088) (xy 112.2335 -256.085468)
			(xy 112.281545 -256.063929) (xy 112.332316 -256.049977) (xy 112.384621 -256.043939) (xy 112.437235 -256.045956)
			(xy 112.488925 -256.05598) (xy 112.538478 -256.073778) (xy 112.584734 -256.098931) (xy 112.626608 -256.13085)
			(xy 112.66312 -256.168788) (xy 112.693412 -256.211854) (xy 112.716775 -256.259039) (xy 112.732661 -256.309238)
			(xy 112.740698 -256.361274) (xy 112.741202 -256.3876) (xy 113.004095 -256.3876) (xy 113.008125 -256.335102)
			(xy 113.020122 -256.283834) (xy 113.039805 -256.234999) (xy 113.066711 -256.18974) (xy 113.100211 -256.149119)
			(xy 113.139519 -256.114088) (xy 113.183714 -256.085468) (xy 113.231759 -256.063929) (xy 113.28253 -256.049977)
			(xy 113.334835 -256.043939) (xy 113.387449 -256.045956) (xy 113.439139 -256.05598) (xy 113.488692 -256.073778)
			(xy 113.534948 -256.098931) (xy 113.576822 -256.13085) (xy 113.613334 -256.168788) (xy 113.643626 -256.211854)
			(xy 113.666989 -256.259039) (xy 113.682875 -256.309238) (xy 113.690912 -256.361274) (xy 113.691416 -256.3876)
			(xy 113.954055 -256.3876) (xy 113.958085 -256.335102) (xy 113.970082 -256.283834) (xy 113.989765 -256.234999)
			(xy 114.016671 -256.18974) (xy 114.050171 -256.149119) (xy 114.089479 -256.114088) (xy 114.133674 -256.085468)
			(xy 114.181719 -256.063929) (xy 114.23249 -256.049977) (xy 114.284795 -256.043939) (xy 114.337409 -256.045956)
			(xy 114.389099 -256.05598) (xy 114.438652 -256.073778) (xy 114.484908 -256.098931) (xy 114.526782 -256.13085)
			(xy 114.563294 -256.168788) (xy 114.593586 -256.211854) (xy 114.616949 -256.259039) (xy 114.632835 -256.309238)
			(xy 114.640872 -256.361274) (xy 114.641376 -256.3876) (xy 114.904015 -256.3876) (xy 114.908045 -256.335102)
			(xy 114.920042 -256.283834) (xy 114.939725 -256.234999) (xy 114.966631 -256.18974) (xy 115.000131 -256.149119)
			(xy 115.039439 -256.114088) (xy 115.083634 -256.085468) (xy 115.131679 -256.063929) (xy 115.18245 -256.049977)
			(xy 115.234755 -256.043939) (xy 115.287369 -256.045956) (xy 115.339059 -256.05598) (xy 115.388612 -256.073778)
			(xy 115.434868 -256.098931) (xy 115.476742 -256.13085) (xy 115.513254 -256.168788) (xy 115.543546 -256.211854)
			(xy 115.566909 -256.259039) (xy 115.582795 -256.309238) (xy 115.590832 -256.361274) (xy 115.591336 -256.3876)
			(xy 115.853975 -256.3876) (xy 115.858005 -256.335102) (xy 115.870002 -256.283834) (xy 115.889685 -256.234999)
			(xy 115.916591 -256.18974) (xy 115.950091 -256.149119) (xy 115.989399 -256.114088) (xy 116.033594 -256.085468)
			(xy 116.081639 -256.063929) (xy 116.13241 -256.049977) (xy 116.184715 -256.043939) (xy 116.237329 -256.045956)
			(xy 116.289019 -256.05598) (xy 116.338572 -256.073778) (xy 116.384828 -256.098931) (xy 116.426702 -256.13085)
			(xy 116.463214 -256.168788) (xy 116.493506 -256.211854) (xy 116.516869 -256.259039) (xy 116.532755 -256.309238)
			(xy 116.540792 -256.361274) (xy 116.541296 -256.3876) (xy 116.540792 -256.413926) (xy 116.532755 -256.465962)
			(xy 116.528214 -256.48031) (xy 117.096797 -256.48031) (xy 117.100827 -256.427812) (xy 117.112824 -256.376544)
			(xy 117.132507 -256.327709) (xy 117.159413 -256.28245) (xy 117.192913 -256.241829) (xy 117.232221 -256.206798)
			(xy 117.276416 -256.178178) (xy 117.324461 -256.156639) (xy 117.375232 -256.142687) (xy 117.427537 -256.136649)
			(xy 117.480151 -256.138666) (xy 117.531841 -256.14869) (xy 117.581394 -256.166488) (xy 117.62765 -256.191641)
			(xy 117.669524 -256.22356) (xy 117.706036 -256.261498) (xy 117.736328 -256.304564) (xy 117.759691 -256.351749)
			(xy 117.775577 -256.401948) (xy 117.783614 -256.453984) (xy 117.784118 -256.48031) (xy 117.783614 -256.506636)
			(xy 117.775577 -256.558672) (xy 117.759691 -256.608871) (xy 117.747007 -256.634488) (xy 122.278914 -256.634488)
			(xy 122.282874 -256.585434) (xy 122.294651 -256.53765) (xy 122.313942 -256.492374) (xy 122.340245 -256.450778)
			(xy 122.37288 -256.413941) (xy 122.411001 -256.382816) (xy 122.453622 -256.358209) (xy 122.499638 -256.340757)
			(xy 122.547857 -256.330913) (xy 122.597032 -256.328932) (xy 122.645887 -256.334864) (xy 122.693158 -256.348556)
			(xy 122.73762 -256.369654) (xy 122.778123 -256.39761) (xy 122.813616 -256.431702) (xy 122.843181 -256.471046)
			(xy 122.866052 -256.514623) (xy 122.881636 -256.561304) (xy 122.889531 -256.609881) (xy 122.890026 -256.634488)
			(xy 124.159022 -256.634488) (xy 124.162982 -256.585434) (xy 124.174759 -256.53765) (xy 124.19405 -256.492374)
			(xy 124.220353 -256.450778) (xy 124.252988 -256.413941) (xy 124.291109 -256.382816) (xy 124.33373 -256.358209)
			(xy 124.379746 -256.340757) (xy 124.427965 -256.330913) (xy 124.47714 -256.328932) (xy 124.525995 -256.334864)
			(xy 124.573266 -256.348556) (xy 124.617728 -256.369654) (xy 124.658231 -256.39761) (xy 124.693724 -256.431702)
			(xy 124.723289 -256.471046) (xy 124.74616 -256.514623) (xy 124.761744 -256.561304) (xy 124.769639 -256.609881)
			(xy 124.770134 -256.634488) (xy 126.038876 -256.634488) (xy 126.042836 -256.585434) (xy 126.054613 -256.53765)
			(xy 126.073904 -256.492374) (xy 126.100207 -256.450778) (xy 126.132842 -256.413941) (xy 126.170963 -256.382816)
			(xy 126.213584 -256.358209) (xy 126.2596 -256.340757) (xy 126.307819 -256.330913) (xy 126.356994 -256.328932)
			(xy 126.405849 -256.334864) (xy 126.45312 -256.348556) (xy 126.497582 -256.369654) (xy 126.538085 -256.39761)
			(xy 126.573578 -256.431702) (xy 126.603143 -256.471046) (xy 126.626014 -256.514623) (xy 126.641598 -256.561304)
			(xy 126.649493 -256.609881) (xy 126.649988 -256.634488) (xy 127.918984 -256.634488) (xy 127.922944 -256.585434)
			(xy 127.934721 -256.53765) (xy 127.954012 -256.492374) (xy 127.980315 -256.450778) (xy 128.01295 -256.413941)
			(xy 128.051071 -256.382816) (xy 128.093692 -256.358209) (xy 128.139708 -256.340757) (xy 128.187927 -256.330913)
			(xy 128.237102 -256.328932) (xy 128.285957 -256.334864) (xy 128.333228 -256.348556) (xy 128.37769 -256.369654)
			(xy 128.418193 -256.39761) (xy 128.453686 -256.431702) (xy 128.483251 -256.471046) (xy 128.506122 -256.514623)
			(xy 128.521706 -256.561304) (xy 128.529601 -256.609881) (xy 128.530096 -256.634488) (xy 128.848607 -256.634488)
			(xy 128.852702 -256.58376) (xy 128.864881 -256.534346) (xy 128.884829 -256.487526) (xy 128.91203 -256.444512)
			(xy 128.945778 -256.406418) (xy 128.9852 -256.374231) (xy 129.029274 -256.348785) (xy 129.07686 -256.330738)
			(xy 129.126724 -256.320558) (xy 129.177576 -256.318509) (xy 129.228097 -256.324643) (xy 129.276981 -256.338803)
			(xy 129.32296 -256.36062) (xy 129.364844 -256.38953) (xy 129.401548 -256.424785) (xy 129.432121 -256.465471)
			(xy 129.455772 -256.510534) (xy 129.471888 -256.558808) (xy 129.480052 -256.609042) (xy 129.480564 -256.634488)
			(xy 130.738892 -256.634488) (xy 130.742852 -256.585434) (xy 130.754629 -256.53765) (xy 130.77392 -256.492374)
			(xy 130.800223 -256.450778) (xy 130.832858 -256.413941) (xy 130.870979 -256.382816) (xy 130.9136 -256.358209)
			(xy 130.959616 -256.340757) (xy 131.007835 -256.330913) (xy 131.05701 -256.328932) (xy 131.105865 -256.334864)
			(xy 131.153136 -256.348556) (xy 131.197598 -256.369654) (xy 131.238101 -256.39761) (xy 131.273594 -256.431702)
			(xy 131.303159 -256.471046) (xy 131.32603 -256.514623) (xy 131.341614 -256.561304) (xy 131.349509 -256.609881)
			(xy 131.350004 -256.634488) (xy 131.678946 -256.634488) (xy 131.682906 -256.585434) (xy 131.694683 -256.53765)
			(xy 131.713974 -256.492374) (xy 131.740277 -256.450778) (xy 131.772912 -256.413941) (xy 131.811033 -256.382816)
			(xy 131.853654 -256.358209) (xy 131.89967 -256.340757) (xy 131.947889 -256.330913) (xy 131.997064 -256.328932)
			(xy 132.045919 -256.334864) (xy 132.09319 -256.348556) (xy 132.137652 -256.369654) (xy 132.178155 -256.39761)
			(xy 132.213648 -256.431702) (xy 132.243213 -256.471046) (xy 132.266084 -256.514623) (xy 132.281668 -256.561304)
			(xy 132.289563 -256.609881) (xy 132.290058 -256.634488) (xy 132.608569 -256.634488) (xy 132.612664 -256.58376)
			(xy 132.624843 -256.534346) (xy 132.644791 -256.487526) (xy 132.671992 -256.444512) (xy 132.70574 -256.406418)
			(xy 132.745162 -256.374231) (xy 132.789236 -256.348785) (xy 132.836822 -256.330738) (xy 132.886686 -256.320558)
			(xy 132.937538 -256.318509) (xy 132.988059 -256.324643) (xy 133.036943 -256.338803) (xy 133.082922 -256.36062)
			(xy 133.124806 -256.38953) (xy 133.16151 -256.424785) (xy 133.192083 -256.465471) (xy 133.215734 -256.510534)
			(xy 133.23185 -256.558808) (xy 133.240014 -256.609042) (xy 133.240526 -256.634488) (xy 133.559054 -256.634488)
			(xy 133.563014 -256.585434) (xy 133.574791 -256.53765) (xy 133.594082 -256.492374) (xy 133.620385 -256.450778)
			(xy 133.65302 -256.413941) (xy 133.691141 -256.382816) (xy 133.733762 -256.358209) (xy 133.779778 -256.340757)
			(xy 133.827997 -256.330913) (xy 133.877172 -256.328932) (xy 133.926027 -256.334864) (xy 133.973298 -256.348556)
			(xy 134.01776 -256.369654) (xy 134.058263 -256.39761) (xy 134.093756 -256.431702) (xy 134.123321 -256.471046)
			(xy 134.146192 -256.514623) (xy 134.161776 -256.561304) (xy 134.169671 -256.609881) (xy 134.170166 -256.634488)
			(xy 134.498854 -256.634488) (xy 134.502814 -256.585434) (xy 134.514591 -256.53765) (xy 134.533882 -256.492374)
			(xy 134.560185 -256.450778) (xy 134.59282 -256.413941) (xy 134.630941 -256.382816) (xy 134.673562 -256.358209)
			(xy 134.719578 -256.340757) (xy 134.767797 -256.330913) (xy 134.816972 -256.328932) (xy 134.865827 -256.334864)
			(xy 134.913098 -256.348556) (xy 134.95756 -256.369654) (xy 134.998063 -256.39761) (xy 135.033556 -256.431702)
			(xy 135.063121 -256.471046) (xy 135.085992 -256.514623) (xy 135.101576 -256.561304) (xy 135.109471 -256.609881)
			(xy 135.109966 -256.634488) (xy 135.428477 -256.634488) (xy 135.432572 -256.58376) (xy 135.444751 -256.534346)
			(xy 135.464699 -256.487526) (xy 135.4919 -256.444512) (xy 135.525648 -256.406418) (xy 135.56507 -256.374231)
			(xy 135.609144 -256.348785) (xy 135.65673 -256.330738) (xy 135.706594 -256.320558) (xy 135.757446 -256.318509)
			(xy 135.807967 -256.324643) (xy 135.856851 -256.338803) (xy 135.90283 -256.36062) (xy 135.944714 -256.38953)
			(xy 135.981418 -256.424785) (xy 136.011991 -256.465471) (xy 136.035642 -256.510534) (xy 136.051758 -256.558808)
			(xy 136.059922 -256.609042) (xy 136.060434 -256.634488) (xy 137.319016 -256.634488) (xy 137.322976 -256.585434)
			(xy 137.334753 -256.53765) (xy 137.354044 -256.492374) (xy 137.380347 -256.450778) (xy 137.412982 -256.413941)
			(xy 137.451103 -256.382816) (xy 137.493724 -256.358209) (xy 137.53974 -256.340757) (xy 137.587959 -256.330913)
			(xy 137.637134 -256.328932) (xy 137.685989 -256.334864) (xy 137.73326 -256.348556) (xy 137.777722 -256.369654)
			(xy 137.818225 -256.39761) (xy 137.853718 -256.431702) (xy 137.883283 -256.471046) (xy 137.906154 -256.514623)
			(xy 137.921738 -256.561304) (xy 137.929633 -256.609881) (xy 137.930128 -256.634488) (xy 138.25907 -256.634488)
			(xy 138.26303 -256.585434) (xy 138.274807 -256.53765) (xy 138.294098 -256.492374) (xy 138.320401 -256.450778)
			(xy 138.353036 -256.413941) (xy 138.391157 -256.382816) (xy 138.433778 -256.358209) (xy 138.479794 -256.340757)
			(xy 138.528013 -256.330913) (xy 138.577188 -256.328932) (xy 138.626043 -256.334864) (xy 138.673314 -256.348556)
			(xy 138.717776 -256.369654) (xy 138.758279 -256.39761) (xy 138.793772 -256.431702) (xy 138.823337 -256.471046)
			(xy 138.846208 -256.514623) (xy 138.861792 -256.561304) (xy 138.869687 -256.609881) (xy 138.870182 -256.634488)
			(xy 139.188439 -256.634488) (xy 139.192534 -256.58376) (xy 139.204713 -256.534346) (xy 139.224661 -256.487526)
			(xy 139.251862 -256.444512) (xy 139.28561 -256.406418) (xy 139.325032 -256.374231) (xy 139.369106 -256.348785)
			(xy 139.416692 -256.330738) (xy 139.466556 -256.320558) (xy 139.517408 -256.318509) (xy 139.567929 -256.324643)
			(xy 139.616813 -256.338803) (xy 139.662792 -256.36062) (xy 139.704676 -256.38953) (xy 139.74138 -256.424785)
			(xy 139.771953 -256.465471) (xy 139.795604 -256.510534) (xy 139.81172 -256.558808) (xy 139.819884 -256.609042)
			(xy 139.820396 -256.634488) (xy 140.138924 -256.634488) (xy 140.142884 -256.585434) (xy 140.154661 -256.53765)
			(xy 140.173952 -256.492374) (xy 140.200255 -256.450778) (xy 140.23289 -256.413941) (xy 140.271011 -256.382816)
			(xy 140.313632 -256.358209) (xy 140.359648 -256.340757) (xy 140.407867 -256.330913) (xy 140.457042 -256.328932)
			(xy 140.505897 -256.334864) (xy 140.553168 -256.348556) (xy 140.59763 -256.369654) (xy 140.638133 -256.39761)
			(xy 140.673626 -256.431702) (xy 140.703191 -256.471046) (xy 140.726062 -256.514623) (xy 140.741646 -256.561304)
			(xy 140.749541 -256.609881) (xy 140.750036 -256.634488) (xy 141.078978 -256.634488) (xy 141.082938 -256.585434)
			(xy 141.094715 -256.53765) (xy 141.114006 -256.492374) (xy 141.140309 -256.450778) (xy 141.172944 -256.413941)
			(xy 141.211065 -256.382816) (xy 141.253686 -256.358209) (xy 141.299702 -256.340757) (xy 141.347921 -256.330913)
			(xy 141.397096 -256.328932) (xy 141.445951 -256.334864) (xy 141.493222 -256.348556) (xy 141.537684 -256.369654)
			(xy 141.578187 -256.39761) (xy 141.61368 -256.431702) (xy 141.643245 -256.471046) (xy 141.666116 -256.514623)
			(xy 141.6817 -256.561304) (xy 141.689595 -256.609881) (xy 141.69009 -256.634488) (xy 142.008601 -256.634488)
			(xy 142.012696 -256.58376) (xy 142.024875 -256.534346) (xy 142.044823 -256.487526) (xy 142.072024 -256.444512)
			(xy 142.105772 -256.406418) (xy 142.145194 -256.374231) (xy 142.189268 -256.348785) (xy 142.236854 -256.330738)
			(xy 142.286718 -256.320558) (xy 142.33757 -256.318509) (xy 142.388091 -256.324643) (xy 142.436975 -256.338803)
			(xy 142.482954 -256.36062) (xy 142.524838 -256.38953) (xy 142.561542 -256.424785) (xy 142.592115 -256.465471)
			(xy 142.615766 -256.510534) (xy 142.631882 -256.558808) (xy 142.640046 -256.609042) (xy 142.640558 -256.634488)
			(xy 143.898886 -256.634488) (xy 143.902846 -256.585434) (xy 143.914623 -256.53765) (xy 143.933914 -256.492374)
			(xy 143.960217 -256.450778) (xy 143.992852 -256.413941) (xy 144.030973 -256.382816) (xy 144.073594 -256.358209)
			(xy 144.11961 -256.340757) (xy 144.167829 -256.330913) (xy 144.217004 -256.328932) (xy 144.265859 -256.334864)
			(xy 144.31313 -256.348556) (xy 144.357592 -256.369654) (xy 144.398095 -256.39761) (xy 144.433588 -256.431702)
			(xy 144.463153 -256.471046) (xy 144.486024 -256.514623) (xy 144.501608 -256.561304) (xy 144.509503 -256.609881)
			(xy 144.509998 -256.634488) (xy 144.83894 -256.634488) (xy 144.8429 -256.585434) (xy 144.854677 -256.53765)
			(xy 144.873968 -256.492374) (xy 144.900271 -256.450778) (xy 144.932906 -256.413941) (xy 144.971027 -256.382816)
			(xy 145.013648 -256.358209) (xy 145.059664 -256.340757) (xy 145.107883 -256.330913) (xy 145.157058 -256.328932)
			(xy 145.205913 -256.334864) (xy 145.253184 -256.348556) (xy 145.297646 -256.369654) (xy 145.338149 -256.39761)
			(xy 145.373642 -256.431702) (xy 145.403207 -256.471046) (xy 145.426078 -256.514623) (xy 145.441662 -256.561304)
			(xy 145.449557 -256.609881) (xy 145.450052 -256.634488) (xy 145.449557 -256.659095) (xy 145.441662 -256.707672)
			(xy 145.426078 -256.754353) (xy 145.403207 -256.79793) (xy 145.373642 -256.837274) (xy 145.338149 -256.871366)
			(xy 145.297646 -256.899322) (xy 145.253184 -256.92042) (xy 145.205913 -256.934112) (xy 145.157058 -256.940044)
			(xy 145.107883 -256.938063) (xy 145.059664 -256.928219) (xy 145.013648 -256.910767) (xy 144.971027 -256.88616)
			(xy 144.932906 -256.855035) (xy 144.900271 -256.818198) (xy 144.873968 -256.776602) (xy 144.854677 -256.731326)
			(xy 144.8429 -256.683542) (xy 144.83894 -256.634488) (xy 144.509998 -256.634488) (xy 144.509503 -256.659095)
			(xy 144.501608 -256.707672) (xy 144.486024 -256.754353) (xy 144.463153 -256.79793) (xy 144.433588 -256.837274)
			(xy 144.398095 -256.871366) (xy 144.357592 -256.899322) (xy 144.31313 -256.92042) (xy 144.265859 -256.934112)
			(xy 144.217004 -256.940044) (xy 144.167829 -256.938063) (xy 144.11961 -256.928219) (xy 144.073594 -256.910767)
			(xy 144.030973 -256.88616) (xy 143.992852 -256.855035) (xy 143.960217 -256.818198) (xy 143.933914 -256.776602)
			(xy 143.914623 -256.731326) (xy 143.902846 -256.683542) (xy 143.898886 -256.634488) (xy 142.640558 -256.634488)
			(xy 142.640046 -256.659934) (xy 142.631882 -256.710168) (xy 142.615766 -256.758442) (xy 142.592115 -256.803505)
			(xy 142.561542 -256.844191) (xy 142.524838 -256.879446) (xy 142.482954 -256.908356) (xy 142.436975 -256.930173)
			(xy 142.388091 -256.944333) (xy 142.33757 -256.950467) (xy 142.286718 -256.948418) (xy 142.236854 -256.938238)
			(xy 142.189268 -256.920191) (xy 142.145194 -256.894745) (xy 142.105772 -256.862558) (xy 142.072024 -256.824464)
			(xy 142.044823 -256.78145) (xy 142.024875 -256.73463) (xy 142.012696 -256.685216) (xy 142.008601 -256.634488)
			(xy 141.69009 -256.634488) (xy 141.689595 -256.659095) (xy 141.6817 -256.707672) (xy 141.666116 -256.754353)
			(xy 141.643245 -256.79793) (xy 141.61368 -256.837274) (xy 141.578187 -256.871366) (xy 141.537684 -256.899322)
			(xy 141.493222 -256.92042) (xy 141.445951 -256.934112) (xy 141.397096 -256.940044) (xy 141.347921 -256.938063)
			(xy 141.299702 -256.928219) (xy 141.253686 -256.910767) (xy 141.211065 -256.88616) (xy 141.172944 -256.855035)
			(xy 141.140309 -256.818198) (xy 141.114006 -256.776602) (xy 141.094715 -256.731326) (xy 141.082938 -256.683542)
			(xy 141.078978 -256.634488) (xy 140.750036 -256.634488) (xy 140.749541 -256.659095) (xy 140.741646 -256.707672)
			(xy 140.726062 -256.754353) (xy 140.703191 -256.79793) (xy 140.673626 -256.837274) (xy 140.638133 -256.871366)
			(xy 140.59763 -256.899322) (xy 140.553168 -256.92042) (xy 140.505897 -256.934112) (xy 140.457042 -256.940044)
			(xy 140.407867 -256.938063) (xy 140.359648 -256.928219) (xy 140.313632 -256.910767) (xy 140.271011 -256.88616)
			(xy 140.23289 -256.855035) (xy 140.200255 -256.818198) (xy 140.173952 -256.776602) (xy 140.154661 -256.731326)
			(xy 140.142884 -256.683542) (xy 140.138924 -256.634488) (xy 139.820396 -256.634488) (xy 139.819884 -256.659934)
			(xy 139.81172 -256.710168) (xy 139.795604 -256.758442) (xy 139.771953 -256.803505) (xy 139.74138 -256.844191)
			(xy 139.704676 -256.879446) (xy 139.662792 -256.908356) (xy 139.616813 -256.930173) (xy 139.567929 -256.944333)
			(xy 139.517408 -256.950467) (xy 139.466556 -256.948418) (xy 139.416692 -256.938238) (xy 139.369106 -256.920191)
			(xy 139.325032 -256.894745) (xy 139.28561 -256.862558) (xy 139.251862 -256.824464) (xy 139.224661 -256.78145)
			(xy 139.204713 -256.73463) (xy 139.192534 -256.685216) (xy 139.188439 -256.634488) (xy 138.870182 -256.634488)
			(xy 138.869687 -256.659095) (xy 138.861792 -256.707672) (xy 138.846208 -256.754353) (xy 138.823337 -256.79793)
			(xy 138.793772 -256.837274) (xy 138.758279 -256.871366) (xy 138.717776 -256.899322) (xy 138.673314 -256.92042)
			(xy 138.626043 -256.934112) (xy 138.577188 -256.940044) (xy 138.528013 -256.938063) (xy 138.479794 -256.928219)
			(xy 138.433778 -256.910767) (xy 138.391157 -256.88616) (xy 138.353036 -256.855035) (xy 138.320401 -256.818198)
			(xy 138.294098 -256.776602) (xy 138.274807 -256.731326) (xy 138.26303 -256.683542) (xy 138.25907 -256.634488)
			(xy 137.930128 -256.634488) (xy 137.929633 -256.659095) (xy 137.921738 -256.707672) (xy 137.906154 -256.754353)
			(xy 137.883283 -256.79793) (xy 137.853718 -256.837274) (xy 137.818225 -256.871366) (xy 137.777722 -256.899322)
			(xy 137.73326 -256.92042) (xy 137.685989 -256.934112) (xy 137.637134 -256.940044) (xy 137.587959 -256.938063)
			(xy 137.53974 -256.928219) (xy 137.493724 -256.910767) (xy 137.451103 -256.88616) (xy 137.412982 -256.855035)
			(xy 137.380347 -256.818198) (xy 137.354044 -256.776602) (xy 137.334753 -256.731326) (xy 137.322976 -256.683542)
			(xy 137.319016 -256.634488) (xy 136.060434 -256.634488) (xy 136.059922 -256.659934) (xy 136.051758 -256.710168)
			(xy 136.035642 -256.758442) (xy 136.011991 -256.803505) (xy 135.981418 -256.844191) (xy 135.944714 -256.879446)
			(xy 135.90283 -256.908356) (xy 135.856851 -256.930173) (xy 135.807967 -256.944333) (xy 135.757446 -256.950467)
			(xy 135.706594 -256.948418) (xy 135.65673 -256.938238) (xy 135.609144 -256.920191) (xy 135.56507 -256.894745)
			(xy 135.525648 -256.862558) (xy 135.4919 -256.824464) (xy 135.464699 -256.78145) (xy 135.444751 -256.73463)
			(xy 135.432572 -256.685216) (xy 135.428477 -256.634488) (xy 135.109966 -256.634488) (xy 135.109471 -256.659095)
			(xy 135.101576 -256.707672) (xy 135.085992 -256.754353) (xy 135.063121 -256.79793) (xy 135.033556 -256.837274)
			(xy 134.998063 -256.871366) (xy 134.95756 -256.899322) (xy 134.913098 -256.92042) (xy 134.865827 -256.934112)
			(xy 134.816972 -256.940044) (xy 134.767797 -256.938063) (xy 134.719578 -256.928219) (xy 134.673562 -256.910767)
			(xy 134.630941 -256.88616) (xy 134.59282 -256.855035) (xy 134.560185 -256.818198) (xy 134.533882 -256.776602)
			(xy 134.514591 -256.731326) (xy 134.502814 -256.683542) (xy 134.498854 -256.634488) (xy 134.170166 -256.634488)
			(xy 134.169671 -256.659095) (xy 134.161776 -256.707672) (xy 134.146192 -256.754353) (xy 134.123321 -256.79793)
			(xy 134.093756 -256.837274) (xy 134.058263 -256.871366) (xy 134.01776 -256.899322) (xy 133.973298 -256.92042)
			(xy 133.926027 -256.934112) (xy 133.877172 -256.940044) (xy 133.827997 -256.938063) (xy 133.779778 -256.928219)
			(xy 133.733762 -256.910767) (xy 133.691141 -256.88616) (xy 133.65302 -256.855035) (xy 133.620385 -256.818198)
			(xy 133.594082 -256.776602) (xy 133.574791 -256.731326) (xy 133.563014 -256.683542) (xy 133.559054 -256.634488)
			(xy 133.240526 -256.634488) (xy 133.240014 -256.659934) (xy 133.23185 -256.710168) (xy 133.215734 -256.758442)
			(xy 133.192083 -256.803505) (xy 133.16151 -256.844191) (xy 133.124806 -256.879446) (xy 133.082922 -256.908356)
			(xy 133.036943 -256.930173) (xy 132.988059 -256.944333) (xy 132.937538 -256.950467) (xy 132.886686 -256.948418)
			(xy 132.836822 -256.938238) (xy 132.789236 -256.920191) (xy 132.745162 -256.894745) (xy 132.70574 -256.862558)
			(xy 132.671992 -256.824464) (xy 132.644791 -256.78145) (xy 132.624843 -256.73463) (xy 132.612664 -256.685216)
			(xy 132.608569 -256.634488) (xy 132.290058 -256.634488) (xy 132.289563 -256.659095) (xy 132.281668 -256.707672)
			(xy 132.266084 -256.754353) (xy 132.243213 -256.79793) (xy 132.213648 -256.837274) (xy 132.178155 -256.871366)
			(xy 132.137652 -256.899322) (xy 132.09319 -256.92042) (xy 132.045919 -256.934112) (xy 131.997064 -256.940044)
			(xy 131.947889 -256.938063) (xy 131.89967 -256.928219) (xy 131.853654 -256.910767) (xy 131.811033 -256.88616)
			(xy 131.772912 -256.855035) (xy 131.740277 -256.818198) (xy 131.713974 -256.776602) (xy 131.694683 -256.731326)
			(xy 131.682906 -256.683542) (xy 131.678946 -256.634488) (xy 131.350004 -256.634488) (xy 131.349509 -256.659095)
			(xy 131.341614 -256.707672) (xy 131.32603 -256.754353) (xy 131.303159 -256.79793) (xy 131.273594 -256.837274)
			(xy 131.238101 -256.871366) (xy 131.197598 -256.899322) (xy 131.153136 -256.92042) (xy 131.105865 -256.934112)
			(xy 131.05701 -256.940044) (xy 131.007835 -256.938063) (xy 130.959616 -256.928219) (xy 130.9136 -256.910767)
			(xy 130.870979 -256.88616) (xy 130.832858 -256.855035) (xy 130.800223 -256.818198) (xy 130.77392 -256.776602)
			(xy 130.754629 -256.731326) (xy 130.742852 -256.683542) (xy 130.738892 -256.634488) (xy 129.480564 -256.634488)
			(xy 129.480052 -256.659934) (xy 129.471888 -256.710168) (xy 129.455772 -256.758442) (xy 129.432121 -256.803505)
			(xy 129.401548 -256.844191) (xy 129.364844 -256.879446) (xy 129.32296 -256.908356) (xy 129.276981 -256.930173)
			(xy 129.228097 -256.944333) (xy 129.177576 -256.950467) (xy 129.126724 -256.948418) (xy 129.07686 -256.938238)
			(xy 129.029274 -256.920191) (xy 128.9852 -256.894745) (xy 128.945778 -256.862558) (xy 128.91203 -256.824464)
			(xy 128.884829 -256.78145) (xy 128.864881 -256.73463) (xy 128.852702 -256.685216) (xy 128.848607 -256.634488)
			(xy 128.530096 -256.634488) (xy 128.529601 -256.659095) (xy 128.521706 -256.707672) (xy 128.506122 -256.754353)
			(xy 128.483251 -256.79793) (xy 128.453686 -256.837274) (xy 128.418193 -256.871366) (xy 128.37769 -256.899322)
			(xy 128.333228 -256.92042) (xy 128.285957 -256.934112) (xy 128.237102 -256.940044) (xy 128.187927 -256.938063)
			(xy 128.139708 -256.928219) (xy 128.093692 -256.910767) (xy 128.051071 -256.88616) (xy 128.01295 -256.855035)
			(xy 127.980315 -256.818198) (xy 127.954012 -256.776602) (xy 127.934721 -256.731326) (xy 127.922944 -256.683542)
			(xy 127.918984 -256.634488) (xy 126.649988 -256.634488) (xy 126.649493 -256.659095) (xy 126.641598 -256.707672)
			(xy 126.626014 -256.754353) (xy 126.603143 -256.79793) (xy 126.573578 -256.837274) (xy 126.538085 -256.871366)
			(xy 126.497582 -256.899322) (xy 126.45312 -256.92042) (xy 126.405849 -256.934112) (xy 126.356994 -256.940044)
			(xy 126.307819 -256.938063) (xy 126.2596 -256.928219) (xy 126.213584 -256.910767) (xy 126.170963 -256.88616)
			(xy 126.132842 -256.855035) (xy 126.100207 -256.818198) (xy 126.073904 -256.776602) (xy 126.054613 -256.731326)
			(xy 126.042836 -256.683542) (xy 126.038876 -256.634488) (xy 124.770134 -256.634488) (xy 124.769639 -256.659095)
			(xy 124.761744 -256.707672) (xy 124.74616 -256.754353) (xy 124.723289 -256.79793) (xy 124.693724 -256.837274)
			(xy 124.658231 -256.871366) (xy 124.617728 -256.899322) (xy 124.573266 -256.92042) (xy 124.525995 -256.934112)
			(xy 124.47714 -256.940044) (xy 124.427965 -256.938063) (xy 124.379746 -256.928219) (xy 124.33373 -256.910767)
			(xy 124.291109 -256.88616) (xy 124.252988 -256.855035) (xy 124.220353 -256.818198) (xy 124.19405 -256.776602)
			(xy 124.174759 -256.731326) (xy 124.162982 -256.683542) (xy 124.159022 -256.634488) (xy 122.890026 -256.634488)
			(xy 122.889531 -256.659095) (xy 122.881636 -256.707672) (xy 122.866052 -256.754353) (xy 122.843181 -256.79793)
			(xy 122.813616 -256.837274) (xy 122.778123 -256.871366) (xy 122.73762 -256.899322) (xy 122.693158 -256.92042)
			(xy 122.645887 -256.934112) (xy 122.597032 -256.940044) (xy 122.547857 -256.938063) (xy 122.499638 -256.928219)
			(xy 122.453622 -256.910767) (xy 122.411001 -256.88616) (xy 122.37288 -256.855035) (xy 122.340245 -256.818198)
			(xy 122.313942 -256.776602) (xy 122.294651 -256.731326) (xy 122.282874 -256.683542) (xy 122.278914 -256.634488)
			(xy 117.747007 -256.634488) (xy 117.736328 -256.656056) (xy 117.706036 -256.699122) (xy 117.669524 -256.73706)
			(xy 117.62765 -256.768979) (xy 117.581394 -256.794132) (xy 117.531841 -256.81193) (xy 117.480151 -256.821954)
			(xy 117.427537 -256.823971) (xy 117.375232 -256.817933) (xy 117.324461 -256.803981) (xy 117.276416 -256.782442)
			(xy 117.232221 -256.753822) (xy 117.192913 -256.718791) (xy 117.159413 -256.67817) (xy 117.132507 -256.632911)
			(xy 117.112824 -256.584076) (xy 117.100827 -256.532808) (xy 117.096797 -256.48031) (xy 116.528214 -256.48031)
			(xy 116.516869 -256.516161) (xy 116.493506 -256.563346) (xy 116.463214 -256.606412) (xy 116.426702 -256.64435)
			(xy 116.384828 -256.676269) (xy 116.338572 -256.701422) (xy 116.289019 -256.71922) (xy 116.237329 -256.729244)
			(xy 116.184715 -256.731261) (xy 116.13241 -256.725223) (xy 116.081639 -256.711271) (xy 116.033594 -256.689732)
			(xy 115.989399 -256.661112) (xy 115.950091 -256.626081) (xy 115.916591 -256.58546) (xy 115.889685 -256.540201)
			(xy 115.870002 -256.491366) (xy 115.858005 -256.440098) (xy 115.853975 -256.3876) (xy 115.591336 -256.3876)
			(xy 115.590832 -256.413926) (xy 115.582795 -256.465962) (xy 115.566909 -256.516161) (xy 115.543546 -256.563346)
			(xy 115.513254 -256.606412) (xy 115.476742 -256.64435) (xy 115.434868 -256.676269) (xy 115.388612 -256.701422)
			(xy 115.339059 -256.71922) (xy 115.287369 -256.729244) (xy 115.234755 -256.731261) (xy 115.18245 -256.725223)
			(xy 115.131679 -256.711271) (xy 115.083634 -256.689732) (xy 115.039439 -256.661112) (xy 115.000131 -256.626081)
			(xy 114.966631 -256.58546) (xy 114.939725 -256.540201) (xy 114.920042 -256.491366) (xy 114.908045 -256.440098)
			(xy 114.904015 -256.3876) (xy 114.641376 -256.3876) (xy 114.640872 -256.413926) (xy 114.632835 -256.465962)
			(xy 114.616949 -256.516161) (xy 114.593586 -256.563346) (xy 114.563294 -256.606412) (xy 114.526782 -256.64435)
			(xy 114.484908 -256.676269) (xy 114.438652 -256.701422) (xy 114.389099 -256.71922) (xy 114.337409 -256.729244)
			(xy 114.284795 -256.731261) (xy 114.23249 -256.725223) (xy 114.181719 -256.711271) (xy 114.133674 -256.689732)
			(xy 114.089479 -256.661112) (xy 114.050171 -256.626081) (xy 114.016671 -256.58546) (xy 113.989765 -256.540201)
			(xy 113.970082 -256.491366) (xy 113.958085 -256.440098) (xy 113.954055 -256.3876) (xy 113.691416 -256.3876)
			(xy 113.690912 -256.413926) (xy 113.682875 -256.465962) (xy 113.666989 -256.516161) (xy 113.643626 -256.563346)
			(xy 113.613334 -256.606412) (xy 113.576822 -256.64435) (xy 113.534948 -256.676269) (xy 113.488692 -256.701422)
			(xy 113.439139 -256.71922) (xy 113.387449 -256.729244) (xy 113.334835 -256.731261) (xy 113.28253 -256.725223)
			(xy 113.231759 -256.711271) (xy 113.183714 -256.689732) (xy 113.139519 -256.661112) (xy 113.100211 -256.626081)
			(xy 113.066711 -256.58546) (xy 113.039805 -256.540201) (xy 113.020122 -256.491366) (xy 113.008125 -256.440098)
			(xy 113.004095 -256.3876) (xy 112.741202 -256.3876) (xy 112.740698 -256.413926) (xy 112.732661 -256.465962)
			(xy 112.716775 -256.516161) (xy 112.693412 -256.563346) (xy 112.66312 -256.606412) (xy 112.626608 -256.64435)
			(xy 112.584734 -256.676269) (xy 112.538478 -256.701422) (xy 112.488925 -256.71922) (xy 112.437235 -256.729244)
			(xy 112.384621 -256.731261) (xy 112.332316 -256.725223) (xy 112.281545 -256.711271) (xy 112.2335 -256.689732)
			(xy 112.189305 -256.661112) (xy 112.149997 -256.626081) (xy 112.116497 -256.58546) (xy 112.089591 -256.540201)
			(xy 112.069908 -256.491366) (xy 112.057911 -256.440098) (xy 112.053881 -256.3876) (xy 111.791242 -256.3876)
			(xy 111.790738 -256.413926) (xy 111.782701 -256.465962) (xy 111.766815 -256.516161) (xy 111.743452 -256.563346)
			(xy 111.71316 -256.606412) (xy 111.676648 -256.64435) (xy 111.634774 -256.676269) (xy 111.588518 -256.701422)
			(xy 111.538965 -256.71922) (xy 111.487275 -256.729244) (xy 111.434661 -256.731261) (xy 111.382356 -256.725223)
			(xy 111.331585 -256.711271) (xy 111.28354 -256.689732) (xy 111.239345 -256.661112) (xy 111.200037 -256.626081)
			(xy 111.166537 -256.58546) (xy 111.139631 -256.540201) (xy 111.119948 -256.491366) (xy 111.107951 -256.440098)
			(xy 111.103921 -256.3876) (xy 110.841282 -256.3876) (xy 110.840778 -256.413926) (xy 110.832741 -256.465962)
			(xy 110.816855 -256.516161) (xy 110.793492 -256.563346) (xy 110.7632 -256.606412) (xy 110.726688 -256.64435)
			(xy 110.684814 -256.676269) (xy 110.638558 -256.701422) (xy 110.589005 -256.71922) (xy 110.537315 -256.729244)
			(xy 110.484701 -256.731261) (xy 110.432396 -256.725223) (xy 110.381625 -256.711271) (xy 110.33358 -256.689732)
			(xy 110.289385 -256.661112) (xy 110.250077 -256.626081) (xy 110.216577 -256.58546) (xy 110.189671 -256.540201)
			(xy 110.169988 -256.491366) (xy 110.157991 -256.440098) (xy 110.153961 -256.3876) (xy 109.891322 -256.3876)
			(xy 109.890818 -256.413926) (xy 109.882781 -256.465962) (xy 109.866895 -256.516161) (xy 109.843532 -256.563346)
			(xy 109.81324 -256.606412) (xy 109.776728 -256.64435) (xy 109.734854 -256.676269) (xy 109.688598 -256.701422)
			(xy 109.639045 -256.71922) (xy 109.587355 -256.729244) (xy 109.534741 -256.731261) (xy 109.482436 -256.725223)
			(xy 109.431665 -256.711271) (xy 109.38362 -256.689732) (xy 109.339425 -256.661112) (xy 109.300117 -256.626081)
			(xy 109.266617 -256.58546) (xy 109.239711 -256.540201) (xy 109.220028 -256.491366) (xy 109.208031 -256.440098)
			(xy 109.204001 -256.3876) (xy 108.941362 -256.3876) (xy 108.940858 -256.413926) (xy 108.932821 -256.465962)
			(xy 108.916935 -256.516161) (xy 108.893572 -256.563346) (xy 108.86328 -256.606412) (xy 108.826768 -256.64435)
			(xy 108.784894 -256.676269) (xy 108.738638 -256.701422) (xy 108.689085 -256.71922) (xy 108.637395 -256.729244)
			(xy 108.584781 -256.731261) (xy 108.532476 -256.725223) (xy 108.481705 -256.711271) (xy 108.43366 -256.689732)
			(xy 108.389465 -256.661112) (xy 108.350157 -256.626081) (xy 108.316657 -256.58546) (xy 108.289751 -256.540201)
			(xy 108.270068 -256.491366) (xy 108.258071 -256.440098) (xy 108.254041 -256.3876) (xy 107.991402 -256.3876)
			(xy 107.990898 -256.413926) (xy 107.982861 -256.465962) (xy 107.966975 -256.516161) (xy 107.943612 -256.563346)
			(xy 107.91332 -256.606412) (xy 107.876808 -256.64435) (xy 107.834934 -256.676269) (xy 107.788678 -256.701422)
			(xy 107.739125 -256.71922) (xy 107.687435 -256.729244) (xy 107.634821 -256.731261) (xy 107.582516 -256.725223)
			(xy 107.531745 -256.711271) (xy 107.4837 -256.689732) (xy 107.439505 -256.661112) (xy 107.400197 -256.626081)
			(xy 107.366697 -256.58546) (xy 107.339791 -256.540201) (xy 107.320108 -256.491366) (xy 107.308111 -256.440098)
			(xy 107.304081 -256.3876) (xy 106.735498 -256.3876) (xy 106.740039 -256.401948) (xy 106.748076 -256.453984)
			(xy 106.74858 -256.48031) (xy 106.748076 -256.506636) (xy 106.740039 -256.558672) (xy 106.724153 -256.608871)
			(xy 106.70079 -256.656056) (xy 106.670498 -256.699122) (xy 106.633986 -256.73706) (xy 106.592112 -256.768979)
			(xy 106.545856 -256.794132) (xy 106.496303 -256.81193) (xy 106.444613 -256.821954) (xy 106.391999 -256.823971)
			(xy 106.339694 -256.817933) (xy 106.288923 -256.803981) (xy 106.240878 -256.782442) (xy 106.196683 -256.753822)
			(xy 106.157375 -256.718791) (xy 106.123875 -256.67817) (xy 106.096969 -256.632911) (xy 106.077286 -256.584076)
			(xy 106.065289 -256.532808) (xy 106.061259 -256.48031) (xy 105.83418 -256.48031) (xy 105.833676 -256.506636)
			(xy 105.825639 -256.558672) (xy 105.809753 -256.608871) (xy 105.78639 -256.656056) (xy 105.756098 -256.699122)
			(xy 105.719586 -256.73706) (xy 105.677712 -256.768979) (xy 105.631456 -256.794132) (xy 105.581903 -256.81193)
			(xy 105.530213 -256.821954) (xy 105.477599 -256.823971) (xy 105.425294 -256.817933) (xy 105.374523 -256.803981)
			(xy 105.326478 -256.782442) (xy 105.282283 -256.753822) (xy 105.242975 -256.718791) (xy 105.209475 -256.67817)
			(xy 105.182569 -256.632911) (xy 105.162886 -256.584076) (xy 105.150889 -256.532808) (xy 105.146859 -256.48031)
			(xy 103.114567 -256.48031) (xy 103.131776 -256.513099) (xy 103.14736 -256.55978) (xy 103.155255 -256.608357)
			(xy 103.15575 -256.632964) (xy 103.155255 -256.657571) (xy 103.14736 -256.706148) (xy 103.131776 -256.752829)
			(xy 103.108905 -256.796406) (xy 103.07934 -256.83575) (xy 103.043847 -256.869842) (xy 103.003344 -256.897798)
			(xy 102.958882 -256.918896) (xy 102.911611 -256.932588) (xy 102.862756 -256.93852) (xy 102.813581 -256.936539)
			(xy 102.765362 -256.926695) (xy 102.719346 -256.909243) (xy 102.676725 -256.884636) (xy 102.638604 -256.853511)
			(xy 102.605969 -256.816674) (xy 102.579666 -256.775078) (xy 102.560375 -256.729802) (xy 102.548598 -256.682018)
			(xy 102.544638 -256.632964) (xy 101.276845 -256.632964) (xy 101.276972 -256.6345) (xy 101.2728 -256.684845)
			(xy 101.260399 -256.733817) (xy 101.240106 -256.78008) (xy 101.212475 -256.822372) (xy 101.17826 -256.859539)
			(xy 101.138394 -256.890567) (xy 101.093965 -256.914611) (xy 101.046184 -256.931013) (xy 100.996355 -256.939328)
			(xy 100.971096 -256.939796) (xy 100.94581 -256.939301) (xy 100.895929 -256.930966) (xy 100.848104 -256.914527)
			(xy 100.803641 -256.890431) (xy 100.78339 -256.87528) (xy 100.77196 -256.86639) (xy 100.743258 -256.863342)
			(xy 100.648008 -256.909824) (xy 100.644706 -256.911602) (xy 100.634115 -256.918559) (xy 100.620919 -256.940152)
			(xy 100.61956 -256.95275) (xy 100.61956 -257.138678) (xy 100.62003 -257.148551) (xy 100.627484 -257.166838)
			(xy 100.634038 -257.174238) (xy 100.634292 -257.174492) (xy 100.880672 -257.420872) (xy 100.888073 -257.42771)
			(xy 100.894246 -257.43027) (xy 105.146859 -257.43027) (xy 105.150889 -257.377772) (xy 105.162886 -257.326504)
			(xy 105.182569 -257.277669) (xy 105.209475 -257.23241) (xy 105.242975 -257.191789) (xy 105.282283 -257.156758)
			(xy 105.326478 -257.128138) (xy 105.374523 -257.106599) (xy 105.425294 -257.092647) (xy 105.477599 -257.086609)
			(xy 105.530213 -257.088626) (xy 105.581903 -257.09865) (xy 105.631456 -257.116448) (xy 105.677712 -257.141601)
			(xy 105.719586 -257.17352) (xy 105.756098 -257.211458) (xy 105.78639 -257.254524) (xy 105.809753 -257.301709)
			(xy 105.825639 -257.351908) (xy 105.833676 -257.403944) (xy 105.83418 -257.43027) (xy 106.061259 -257.43027)
			(xy 106.065289 -257.377772) (xy 106.077286 -257.326504) (xy 106.096969 -257.277669) (xy 106.123875 -257.23241)
			(xy 106.157375 -257.191789) (xy 106.196683 -257.156758) (xy 106.240878 -257.128138) (xy 106.288923 -257.106599)
			(xy 106.339694 -257.092647) (xy 106.391999 -257.086609) (xy 106.444613 -257.088626) (xy 106.496303 -257.09865)
			(xy 106.545856 -257.116448) (xy 106.592112 -257.141601) (xy 106.633986 -257.17352) (xy 106.670498 -257.211458)
			(xy 106.70079 -257.254524) (xy 106.724153 -257.301709) (xy 106.740039 -257.351908) (xy 106.748076 -257.403944)
			(xy 106.74858 -257.43027) (xy 106.748076 -257.456596) (xy 106.740039 -257.508632) (xy 106.724153 -257.558831)
			(xy 106.70079 -257.606016) (xy 106.670498 -257.649082) (xy 106.633986 -257.68702) (xy 106.592112 -257.718939)
			(xy 106.545856 -257.744092) (xy 106.496303 -257.76189) (xy 106.444613 -257.771914) (xy 106.391999 -257.773931)
			(xy 106.339694 -257.767893) (xy 106.288923 -257.753941) (xy 106.240878 -257.732402) (xy 106.196683 -257.703782)
			(xy 106.157375 -257.668751) (xy 106.123875 -257.62813) (xy 106.096969 -257.582871) (xy 106.077286 -257.534036)
			(xy 106.065289 -257.482768) (xy 106.061259 -257.43027) (xy 105.83418 -257.43027) (xy 105.833676 -257.456596)
			(xy 105.825639 -257.508632) (xy 105.809753 -257.558831) (xy 105.78639 -257.606016) (xy 105.756098 -257.649082)
			(xy 105.719586 -257.68702) (xy 105.677712 -257.718939) (xy 105.631456 -257.744092) (xy 105.581903 -257.76189)
			(xy 105.530213 -257.771914) (xy 105.477599 -257.773931) (xy 105.425294 -257.767893) (xy 105.374523 -257.753941)
			(xy 105.326478 -257.732402) (xy 105.282283 -257.703782) (xy 105.242975 -257.668751) (xy 105.209475 -257.62813)
			(xy 105.182569 -257.582871) (xy 105.162886 -257.534036) (xy 105.150889 -257.482768) (xy 105.146859 -257.43027)
			(xy 100.894246 -257.43027) (xy 100.906672 -257.435423) (xy 100.91674 -257.435858) (xy 102.909878 -257.435858)
			(xy 102.919941 -257.436297) (xy 102.938519 -257.444038) (xy 102.945946 -257.450844) (xy 103.183436 -257.688334)
			(xy 103.190284 -257.695731) (xy 103.198016 -257.71433) (xy 103.198422 -257.724402) (xy 103.198422 -257.930396)
			(xy 103.196644 -257.96494) (xy 103.195628 -257.975608) (xy 103.202232 -257.995928) (xy 103.260144 -258.059936)
			(xy 103.267684 -258.067457) (xy 103.287103 -258.076142) (xy 103.297736 -258.0767) (xy 105.323894 -258.0767)
			(xy 105.33507 -258.07416) (xy 105.34015 -258.07162) (xy 105.363726 -258.060646) (xy 105.413364 -258.045144)
			(xy 105.464771 -258.037304) (xy 105.516773 -258.037304) (xy 105.56818 -258.045144) (xy 105.617818 -258.060646)
			(xy 105.641394 -258.07162) (xy 105.646474 -258.07416) (xy 105.65765 -258.0767) (xy 106.238294 -258.0767)
			(xy 106.24947 -258.07416) (xy 106.25455 -258.07162) (xy 106.278126 -258.060646) (xy 106.327764 -258.045144)
			(xy 106.379171 -258.037304) (xy 106.431173 -258.037304) (xy 106.48258 -258.045144) (xy 106.532218 -258.060646)
			(xy 106.555794 -258.07162) (xy 106.560874 -258.07416) (xy 106.57205 -258.0767) (xy 107.536742 -258.0767)
			(xy 107.545725 -258.07635) (xy 107.56258 -258.070132) (xy 107.576228 -258.05845) (xy 107.580938 -258.050792)
			(xy 107.63123 -257.961638) (xy 107.630722 -257.93446) (xy 107.62361 -257.922522) (xy 107.611926 -257.902366)
			(xy 107.593504 -257.859574) (xy 107.581031 -257.814686) (xy 107.574735 -257.768524) (xy 107.574334 -257.74523)
			(xy 107.574814 -257.719531) (xy 107.582475 -257.668707) (xy 107.597624 -257.619593) (xy 107.619925 -257.573285)
			(xy 107.648878 -257.530818) (xy 107.683838 -257.493141) (xy 107.724022 -257.461095) (xy 107.768534 -257.435396)
			(xy 107.816379 -257.416619) (xy 107.866488 -257.405181) (xy 107.917742 -257.401341) (xy 107.968996 -257.405181)
			(xy 108.019105 -257.416619) (xy 108.06695 -257.435396) (xy 108.111462 -257.461095) (xy 108.151646 -257.493141)
			(xy 108.186606 -257.530818) (xy 108.215559 -257.573285) (xy 108.23786 -257.619593) (xy 108.253009 -257.668707)
			(xy 108.26067 -257.719531) (xy 108.26115 -257.74523) (xy 108.261404 -257.74523) (xy 108.260992 -257.768564)
			(xy 108.254641 -257.814799) (xy 108.242098 -257.859751) (xy 108.223595 -257.902595) (xy 108.211874 -257.922776)
			(xy 108.204762 -257.934714) (xy 108.204254 -257.961892) (xy 108.254546 -258.050792) (xy 108.259267 -258.058431)
			(xy 108.272936 -258.070061) (xy 108.28977 -258.076284) (xy 108.298742 -258.0767) (xy 108.451142 -258.0767)
			(xy 108.460125 -258.07635) (xy 108.47698 -258.070132) (xy 108.490628 -258.05845) (xy 108.495338 -258.050792)
			(xy 108.54563 -257.961638) (xy 108.545122 -257.93446) (xy 108.53801 -257.922522) (xy 108.526326 -257.902366)
			(xy 108.507904 -257.859574) (xy 108.495431 -257.814686) (xy 108.489135 -257.768524) (xy 108.488734 -257.74523)
			(xy 108.489214 -257.719531) (xy 108.496875 -257.668707) (xy 108.512024 -257.619593) (xy 108.534325 -257.573285)
			(xy 108.563278 -257.530818) (xy 108.598238 -257.493141) (xy 108.638422 -257.461095) (xy 108.682934 -257.435396)
			(xy 108.730779 -257.416619) (xy 108.780888 -257.405181) (xy 108.832142 -257.401341) (xy 108.883396 -257.405181)
			(xy 108.933505 -257.416619) (xy 108.98135 -257.435396) (xy 109.025862 -257.461095) (xy 109.066046 -257.493141)
			(xy 109.101006 -257.530818) (xy 109.129959 -257.573285) (xy 109.15226 -257.619593) (xy 109.167409 -257.668707)
			(xy 109.17507 -257.719531) (xy 109.17555 -257.74523) (xy 109.175804 -257.74523) (xy 110.988351 -257.74523)
			(xy 110.992381 -257.692732) (xy 111.004378 -257.641464) (xy 111.024061 -257.592629) (xy 111.050967 -257.54737)
			(xy 111.084467 -257.506749) (xy 111.123775 -257.471718) (xy 111.16797 -257.443098) (xy 111.216015 -257.421559)
			(xy 111.266786 -257.407607) (xy 111.319091 -257.401569) (xy 111.371705 -257.403586) (xy 111.423395 -257.41361)
			(xy 111.472948 -257.431408) (xy 111.519204 -257.456561) (xy 111.561078 -257.48848) (xy 111.59759 -257.526418)
			(xy 111.627882 -257.569484) (xy 111.651245 -257.616669) (xy 111.667131 -257.666868) (xy 111.675168 -257.718904)
			(xy 111.675672 -257.74523) (xy 113.238283 -257.74523) (xy 113.242313 -257.692732) (xy 113.25431 -257.641464)
			(xy 113.273993 -257.592629) (xy 113.300899 -257.54737) (xy 113.334399 -257.506749) (xy 113.373707 -257.471718)
			(xy 113.417902 -257.443098) (xy 113.465947 -257.421559) (xy 113.516718 -257.407607) (xy 113.569023 -257.401569)
			(xy 113.621637 -257.403586) (xy 113.673327 -257.41361) (xy 113.72288 -257.431408) (xy 113.769136 -257.456561)
			(xy 113.81101 -257.48848) (xy 113.847522 -257.526418) (xy 113.877814 -257.569484) (xy 113.901177 -257.616669)
			(xy 113.917063 -257.666868) (xy 113.9251 -257.718904) (xy 113.925604 -257.74523) (xy 115.838227 -257.74523)
			(xy 115.842257 -257.692732) (xy 115.854254 -257.641464) (xy 115.873937 -257.592629) (xy 115.900843 -257.54737)
			(xy 115.934343 -257.506749) (xy 115.973651 -257.471718) (xy 116.017846 -257.443098) (xy 116.065891 -257.421559)
			(xy 116.116662 -257.407607) (xy 116.168967 -257.401569) (xy 116.221581 -257.403586) (xy 116.273271 -257.41361)
			(xy 116.319656 -257.43027) (xy 117.096797 -257.43027) (xy 117.100827 -257.377772) (xy 117.112824 -257.326504)
			(xy 117.132507 -257.277669) (xy 117.159413 -257.23241) (xy 117.192913 -257.191789) (xy 117.232221 -257.156758)
			(xy 117.276416 -257.128138) (xy 117.324461 -257.106599) (xy 117.375232 -257.092647) (xy 117.427537 -257.086609)
			(xy 117.480151 -257.088626) (xy 117.531841 -257.09865) (xy 117.581394 -257.116448) (xy 117.62765 -257.141601)
			(xy 117.669524 -257.17352) (xy 117.706036 -257.211458) (xy 117.736328 -257.254524) (xy 117.759691 -257.301709)
			(xy 117.775577 -257.351908) (xy 117.783614 -257.403944) (xy 117.784118 -257.43027) (xy 117.783614 -257.456596)
			(xy 117.775577 -257.508632) (xy 117.759691 -257.558831) (xy 117.736328 -257.606016) (xy 117.706036 -257.649082)
			(xy 117.669524 -257.68702) (xy 117.62765 -257.718939) (xy 117.581394 -257.744092) (xy 117.531841 -257.76189)
			(xy 117.480151 -257.771914) (xy 117.427537 -257.773931) (xy 117.375232 -257.767893) (xy 117.324461 -257.753941)
			(xy 117.276416 -257.732402) (xy 117.232221 -257.703782) (xy 117.192913 -257.668751) (xy 117.159413 -257.62813)
			(xy 117.132507 -257.582871) (xy 117.112824 -257.534036) (xy 117.100827 -257.482768) (xy 117.096797 -257.43027)
			(xy 116.319656 -257.43027) (xy 116.322824 -257.431408) (xy 116.36908 -257.456561) (xy 116.410954 -257.48848)
			(xy 116.447466 -257.526418) (xy 116.477758 -257.569484) (xy 116.501121 -257.616669) (xy 116.517007 -257.666868)
			(xy 116.525044 -257.718904) (xy 116.525548 -257.74523) (xy 116.525044 -257.771556) (xy 116.517007 -257.823592)
			(xy 116.501121 -257.873791) (xy 116.477758 -257.920976) (xy 116.471132 -257.930396) (xy 120.865649 -257.930396)
			(xy 120.869679 -257.877898) (xy 120.881676 -257.82663) (xy 120.901359 -257.777795) (xy 120.928265 -257.732536)
			(xy 120.961765 -257.691915) (xy 121.001073 -257.656884) (xy 121.045268 -257.628264) (xy 121.093313 -257.606725)
			(xy 121.144084 -257.592773) (xy 121.196389 -257.586735) (xy 121.249003 -257.588752) (xy 121.300693 -257.598776)
			(xy 121.350246 -257.616574) (xy 121.396502 -257.641727) (xy 121.438376 -257.673646) (xy 121.474888 -257.711584)
			(xy 121.50518 -257.75465) (xy 121.528543 -257.801835) (xy 121.544429 -257.852034) (xy 121.552466 -257.90407)
			(xy 121.55297 -257.930396) (xy 122.791223 -257.930396) (xy 122.795253 -257.877898) (xy 122.80725 -257.82663)
			(xy 122.826933 -257.777795) (xy 122.853839 -257.732536) (xy 122.887339 -257.691915) (xy 122.926647 -257.656884)
			(xy 122.970842 -257.628264) (xy 123.018887 -257.606725) (xy 123.069658 -257.592773) (xy 123.121963 -257.586735)
			(xy 123.174577 -257.588752) (xy 123.226267 -257.598776) (xy 123.27582 -257.616574) (xy 123.322076 -257.641727)
			(xy 123.36395 -257.673646) (xy 123.400462 -257.711584) (xy 123.430754 -257.75465) (xy 123.454117 -257.801835)
			(xy 123.470003 -257.852034) (xy 123.47804 -257.90407) (xy 123.478544 -257.930396) (xy 124.696223 -257.930396)
			(xy 124.700253 -257.877898) (xy 124.71225 -257.82663) (xy 124.731933 -257.777795) (xy 124.758839 -257.732536)
			(xy 124.792339 -257.691915) (xy 124.831647 -257.656884) (xy 124.875842 -257.628264) (xy 124.923887 -257.606725)
			(xy 124.974658 -257.592773) (xy 125.026963 -257.586735) (xy 125.079577 -257.588752) (xy 125.131267 -257.598776)
			(xy 125.18082 -257.616574) (xy 125.227076 -257.641727) (xy 125.26895 -257.673646) (xy 125.305462 -257.711584)
			(xy 125.335754 -257.75465) (xy 125.359117 -257.801835) (xy 125.375003 -257.852034) (xy 125.38304 -257.90407)
			(xy 125.383544 -257.930396) (xy 125.38304 -257.956722) (xy 125.375003 -258.008758) (xy 125.359117 -258.058957)
			(xy 125.335754 -258.106142) (xy 125.305462 -258.149208) (xy 125.26895 -258.187146) (xy 125.227076 -258.219065)
			(xy 125.18082 -258.244218) (xy 125.131267 -258.262016) (xy 125.079577 -258.27204) (xy 125.026963 -258.274057)
			(xy 124.974658 -258.268019) (xy 124.923887 -258.254067) (xy 124.875842 -258.232528) (xy 124.831647 -258.203908)
			(xy 124.792339 -258.168877) (xy 124.758839 -258.128256) (xy 124.731933 -258.082997) (xy 124.71225 -258.034162)
			(xy 124.700253 -257.982894) (xy 124.696223 -257.930396) (xy 123.478544 -257.930396) (xy 123.47804 -257.956722)
			(xy 123.470003 -258.008758) (xy 123.454117 -258.058957) (xy 123.430754 -258.106142) (xy 123.400462 -258.149208)
			(xy 123.36395 -258.187146) (xy 123.322076 -258.219065) (xy 123.27582 -258.244218) (xy 123.226267 -258.262016)
			(xy 123.174577 -258.27204) (xy 123.121963 -258.274057) (xy 123.069658 -258.268019) (xy 123.018887 -258.254067)
			(xy 122.970842 -258.232528) (xy 122.926647 -258.203908) (xy 122.887339 -258.168877) (xy 122.853839 -258.128256)
			(xy 122.826933 -258.082997) (xy 122.80725 -258.034162) (xy 122.795253 -257.982894) (xy 122.791223 -257.930396)
			(xy 121.55297 -257.930396) (xy 121.552466 -257.956722) (xy 121.544429 -258.008758) (xy 121.528543 -258.058957)
			(xy 121.50518 -258.106142) (xy 121.474888 -258.149208) (xy 121.438376 -258.187146) (xy 121.396502 -258.219065)
			(xy 121.350246 -258.244218) (xy 121.300693 -258.262016) (xy 121.249003 -258.27204) (xy 121.196389 -258.274057)
			(xy 121.144084 -258.268019) (xy 121.093313 -258.254067) (xy 121.045268 -258.232528) (xy 121.001073 -258.203908)
			(xy 120.961765 -258.168877) (xy 120.928265 -258.128256) (xy 120.901359 -258.082997) (xy 120.881676 -258.034162)
			(xy 120.869679 -257.982894) (xy 120.865649 -257.930396) (xy 116.471132 -257.930396) (xy 116.447466 -257.964042)
			(xy 116.410954 -258.00198) (xy 116.36908 -258.033899) (xy 116.322824 -258.059052) (xy 116.273271 -258.07685)
			(xy 116.221581 -258.086874) (xy 116.168967 -258.088891) (xy 116.116662 -258.082853) (xy 116.065891 -258.068901)
			(xy 116.017846 -258.047362) (xy 115.973651 -258.018742) (xy 115.934343 -257.983711) (xy 115.900843 -257.94309)
			(xy 115.873937 -257.897831) (xy 115.854254 -257.848996) (xy 115.842257 -257.797728) (xy 115.838227 -257.74523)
			(xy 113.925604 -257.74523) (xy 113.9251 -257.771556) (xy 113.917063 -257.823592) (xy 113.901177 -257.873791)
			(xy 113.877814 -257.920976) (xy 113.847522 -257.964042) (xy 113.81101 -258.00198) (xy 113.769136 -258.033899)
			(xy 113.72288 -258.059052) (xy 113.673327 -258.07685) (xy 113.621637 -258.086874) (xy 113.569023 -258.088891)
			(xy 113.516718 -258.082853) (xy 113.465947 -258.068901) (xy 113.417902 -258.047362) (xy 113.373707 -258.018742)
			(xy 113.334399 -257.983711) (xy 113.300899 -257.94309) (xy 113.273993 -257.897831) (xy 113.25431 -257.848996)
			(xy 113.242313 -257.797728) (xy 113.238283 -257.74523) (xy 111.675672 -257.74523) (xy 111.675168 -257.771556)
			(xy 111.667131 -257.823592) (xy 111.651245 -257.873791) (xy 111.627882 -257.920976) (xy 111.59759 -257.964042)
			(xy 111.561078 -258.00198) (xy 111.519204 -258.033899) (xy 111.472948 -258.059052) (xy 111.423395 -258.07685)
			(xy 111.371705 -258.086874) (xy 111.319091 -258.088891) (xy 111.266786 -258.082853) (xy 111.216015 -258.068901)
			(xy 111.16797 -258.047362) (xy 111.123775 -258.018742) (xy 111.084467 -257.983711) (xy 111.050967 -257.94309)
			(xy 111.024061 -257.897831) (xy 111.004378 -257.848996) (xy 110.992381 -257.797728) (xy 110.988351 -257.74523)
			(xy 109.175804 -257.74523) (xy 109.175392 -257.768564) (xy 109.169041 -257.814799) (xy 109.156498 -257.859751)
			(xy 109.137995 -257.902595) (xy 109.126274 -257.922776) (xy 109.119162 -257.934714) (xy 109.118654 -257.961892)
			(xy 109.168946 -258.050792) (xy 109.173667 -258.058431) (xy 109.187336 -258.070061) (xy 109.20417 -258.076284)
			(xy 109.213142 -258.0767) (xy 110.959138 -258.0767) (xy 110.969205 -258.07713) (xy 110.987799 -258.084854)
			(xy 110.995206 -258.091686) (xy 111.28375 -258.38023) (xy 117.096797 -258.38023) (xy 117.100827 -258.327732)
			(xy 117.112824 -258.276464) (xy 117.132507 -258.227629) (xy 117.159413 -258.18237) (xy 117.192913 -258.141749)
			(xy 117.232221 -258.106718) (xy 117.276416 -258.078098) (xy 117.324461 -258.056559) (xy 117.375232 -258.042607)
			(xy 117.427537 -258.036569) (xy 117.480151 -258.038586) (xy 117.531841 -258.04861) (xy 117.581394 -258.066408)
			(xy 117.62765 -258.091561) (xy 117.669524 -258.12348) (xy 117.706036 -258.161418) (xy 117.736328 -258.204484)
			(xy 117.759691 -258.251669) (xy 117.775577 -258.301868) (xy 117.783614 -258.353904) (xy 117.784118 -258.38023)
			(xy 117.783614 -258.406556) (xy 117.775577 -258.458592) (xy 117.759691 -258.508791) (xy 117.736328 -258.555976)
			(xy 117.706036 -258.599042) (xy 117.669524 -258.63698) (xy 117.62765 -258.668899) (xy 117.581394 -258.694052)
			(xy 117.531841 -258.71185) (xy 117.480151 -258.721874) (xy 117.427537 -258.723891) (xy 117.375232 -258.717853)
			(xy 117.324461 -258.703901) (xy 117.276416 -258.682362) (xy 117.232221 -258.653742) (xy 117.192913 -258.618711)
			(xy 117.159413 -258.57809) (xy 117.132507 -258.532831) (xy 117.112824 -258.483996) (xy 117.100827 -258.432728)
			(xy 117.096797 -258.38023) (xy 111.28375 -258.38023) (xy 111.349536 -258.446016) (xy 111.364522 -258.453382)
			(xy 111.373158 -258.454398) (xy 111.398342 -258.457879) (xy 111.447377 -258.471307) (xy 111.493895 -258.491818)
			(xy 111.53688 -258.518964) (xy 111.575392 -258.552153) (xy 111.608589 -258.590657) (xy 111.635746 -258.633636)
			(xy 111.656267 -258.68015) (xy 111.669706 -258.729181) (xy 111.673132 -258.754372) (xy 111.674148 -258.763008)
			(xy 111.681514 -258.777994) (xy 112.039654 -259.136134) (xy 112.040162 -259.136642) (xy 112.047543 -259.143224)
			(xy 112.065842 -259.150673) (xy 112.075722 -259.15112) (xy 113.216944 -259.15112) (xy 113.226179 -259.150729)
			(xy 113.243452 -259.14419) (xy 113.257277 -259.131944) (xy 113.261902 -259.123942) (xy 113.303812 -259.044186)
			(xy 113.307801 -259.035747) (xy 113.309999 -259.017227) (xy 113.305367 -258.999162) (xy 113.300256 -258.991354)
			(xy 113.285747 -258.969651) (xy 113.262762 -258.92278) (xy 113.24714 -258.87297) (xy 113.23924 -258.821368)
			(xy 113.238788 -258.795266) (xy 113.239268 -258.769567) (xy 113.246929 -258.718743) (xy 113.262078 -258.669629)
			(xy 113.284379 -258.623321) (xy 113.313332 -258.580854) (xy 113.348292 -258.543177) (xy 113.388476 -258.511131)
			(xy 113.432988 -258.485432) (xy 113.480833 -258.466655) (xy 113.530942 -258.455217) (xy 113.582196 -258.451377)
			(xy 113.63345 -258.455217) (xy 113.683559 -258.466655) (xy 113.731404 -258.485432) (xy 113.775916 -258.511131)
			(xy 113.8161 -258.543177) (xy 113.85106 -258.580854) (xy 113.880013 -258.623321) (xy 113.902314 -258.669629)
			(xy 113.917463 -258.718743) (xy 113.925124 -258.769567) (xy 113.925604 -258.795266) (xy 115.838227 -258.795266)
			(xy 115.842257 -258.742768) (xy 115.854254 -258.6915) (xy 115.873937 -258.642665) (xy 115.900843 -258.597406)
			(xy 115.934343 -258.556785) (xy 115.973651 -258.521754) (xy 116.017846 -258.493134) (xy 116.065891 -258.471595)
			(xy 116.116662 -258.457643) (xy 116.168967 -258.451605) (xy 116.221581 -258.453622) (xy 116.273271 -258.463646)
			(xy 116.322824 -258.481444) (xy 116.36908 -258.506597) (xy 116.410954 -258.538516) (xy 116.447466 -258.576454)
			(xy 116.477758 -258.61952) (xy 116.501121 -258.666705) (xy 116.517007 -258.716904) (xy 116.525044 -258.76894)
			(xy 116.525548 -258.795266) (xy 116.525044 -258.821592) (xy 116.523696 -258.830318) (xy 120.865649 -258.830318)
			(xy 120.869679 -258.77782) (xy 120.881676 -258.726552) (xy 120.901359 -258.677717) (xy 120.928265 -258.632458)
			(xy 120.961765 -258.591837) (xy 121.001073 -258.556806) (xy 121.045268 -258.528186) (xy 121.093313 -258.506647)
			(xy 121.144084 -258.492695) (xy 121.196389 -258.486657) (xy 121.249003 -258.488674) (xy 121.300693 -258.498698)
			(xy 121.350246 -258.516496) (xy 121.396502 -258.541649) (xy 121.438376 -258.573568) (xy 121.474888 -258.611506)
			(xy 121.50518 -258.654572) (xy 121.528543 -258.701757) (xy 121.544429 -258.751956) (xy 121.552466 -258.803992)
			(xy 121.55297 -258.830318) (xy 122.791223 -258.830318) (xy 122.795253 -258.77782) (xy 122.80725 -258.726552)
			(xy 122.826933 -258.677717) (xy 122.853839 -258.632458) (xy 122.887339 -258.591837) (xy 122.926647 -258.556806)
			(xy 122.970842 -258.528186) (xy 123.018887 -258.506647) (xy 123.069658 -258.492695) (xy 123.121963 -258.486657)
			(xy 123.174577 -258.488674) (xy 123.226267 -258.498698) (xy 123.27582 -258.516496) (xy 123.322076 -258.541649)
			(xy 123.36395 -258.573568) (xy 123.400462 -258.611506) (xy 123.430754 -258.654572) (xy 123.454117 -258.701757)
			(xy 123.470003 -258.751956) (xy 123.47804 -258.803992) (xy 123.478544 -258.830318) (xy 124.696223 -258.830318)
			(xy 124.700253 -258.77782) (xy 124.71225 -258.726552) (xy 124.731933 -258.677717) (xy 124.758839 -258.632458)
			(xy 124.792339 -258.591837) (xy 124.831647 -258.556806) (xy 124.875842 -258.528186) (xy 124.923887 -258.506647)
			(xy 124.974658 -258.492695) (xy 125.026963 -258.486657) (xy 125.079577 -258.488674) (xy 125.131267 -258.498698)
			(xy 125.18082 -258.516496) (xy 125.227076 -258.541649) (xy 125.26895 -258.573568) (xy 125.305462 -258.611506)
			(xy 125.335754 -258.654572) (xy 125.359117 -258.701757) (xy 125.375003 -258.751956) (xy 125.38304 -258.803992)
			(xy 125.383544 -258.830318) (xy 125.38304 -258.856644) (xy 125.375003 -258.90868) (xy 125.359117 -258.958879)
			(xy 125.335754 -259.006064) (xy 125.305462 -259.04913) (xy 125.26895 -259.087068) (xy 125.227076 -259.118987)
			(xy 125.18082 -259.14414) (xy 125.131267 -259.161938) (xy 125.079577 -259.171962) (xy 125.026963 -259.173979)
			(xy 124.974658 -259.167941) (xy 124.923887 -259.153989) (xy 124.875842 -259.13245) (xy 124.831647 -259.10383)
			(xy 124.792339 -259.068799) (xy 124.758839 -259.028178) (xy 124.731933 -258.982919) (xy 124.71225 -258.934084)
			(xy 124.700253 -258.882816) (xy 124.696223 -258.830318) (xy 123.478544 -258.830318) (xy 123.47804 -258.856644)
			(xy 123.470003 -258.90868) (xy 123.454117 -258.958879) (xy 123.430754 -259.006064) (xy 123.400462 -259.04913)
			(xy 123.36395 -259.087068) (xy 123.322076 -259.118987) (xy 123.27582 -259.14414) (xy 123.226267 -259.161938)
			(xy 123.174577 -259.171962) (xy 123.121963 -259.173979) (xy 123.069658 -259.167941) (xy 123.018887 -259.153989)
			(xy 122.970842 -259.13245) (xy 122.926647 -259.10383) (xy 122.887339 -259.068799) (xy 122.853839 -259.028178)
			(xy 122.826933 -258.982919) (xy 122.80725 -258.934084) (xy 122.795253 -258.882816) (xy 122.791223 -258.830318)
			(xy 121.55297 -258.830318) (xy 121.552466 -258.856644) (xy 121.544429 -258.90868) (xy 121.528543 -258.958879)
			(xy 121.50518 -259.006064) (xy 121.474888 -259.04913) (xy 121.438376 -259.087068) (xy 121.396502 -259.118987)
			(xy 121.350246 -259.14414) (xy 121.300693 -259.161938) (xy 121.249003 -259.171962) (xy 121.196389 -259.173979)
			(xy 121.144084 -259.167941) (xy 121.093313 -259.153989) (xy 121.045268 -259.13245) (xy 121.001073 -259.10383)
			(xy 120.961765 -259.068799) (xy 120.928265 -259.028178) (xy 120.901359 -258.982919) (xy 120.881676 -258.934084)
			(xy 120.869679 -258.882816) (xy 120.865649 -258.830318) (xy 116.523696 -258.830318) (xy 116.517007 -258.873628)
			(xy 116.501121 -258.923827) (xy 116.477758 -258.971012) (xy 116.447466 -259.014078) (xy 116.410954 -259.052016)
			(xy 116.36908 -259.083935) (xy 116.322824 -259.109088) (xy 116.273271 -259.126886) (xy 116.221581 -259.13691)
			(xy 116.168967 -259.138927) (xy 116.116662 -259.132889) (xy 116.065891 -259.118937) (xy 116.017846 -259.097398)
			(xy 115.973651 -259.068778) (xy 115.934343 -259.033747) (xy 115.900843 -258.993126) (xy 115.873937 -258.947867)
			(xy 115.854254 -258.899032) (xy 115.842257 -258.847764) (xy 115.838227 -258.795266) (xy 113.925604 -258.795266)
			(xy 113.925113 -258.821365) (xy 113.917209 -258.87296) (xy 113.901591 -258.922766) (xy 113.878619 -258.969637)
			(xy 113.864136 -258.991354) (xy 113.856008 -259.003038) (xy 113.853976 -259.031486) (xy 113.90249 -259.123942)
			(xy 113.907135 -259.131931) (xy 113.920955 -259.144177) (xy 113.938216 -259.150734) (xy 113.947448 -259.15112)
			(xy 115.810538 -259.15112) (xy 115.820605 -259.151551) (xy 115.839197 -259.159277) (xy 115.846606 -259.166106)
			(xy 116.010944 -259.330444) (xy 117.096797 -259.330444) (xy 117.100827 -259.277946) (xy 117.112824 -259.226678)
			(xy 117.132507 -259.177843) (xy 117.159413 -259.132584) (xy 117.192913 -259.091963) (xy 117.232221 -259.056932)
			(xy 117.276416 -259.028312) (xy 117.324461 -259.006773) (xy 117.375232 -258.992821) (xy 117.427537 -258.986783)
			(xy 117.480151 -258.9888) (xy 117.531841 -258.998824) (xy 117.581394 -259.016622) (xy 117.62765 -259.041775)
			(xy 117.669524 -259.073694) (xy 117.706036 -259.111632) (xy 117.736328 -259.154698) (xy 117.759691 -259.201883)
			(xy 117.775577 -259.252082) (xy 117.783614 -259.304118) (xy 117.784118 -259.330444) (xy 117.783614 -259.35677)
			(xy 117.775577 -259.408806) (xy 117.759691 -259.459005) (xy 117.736328 -259.50619) (xy 117.706036 -259.549256)
			(xy 117.669524 -259.587194) (xy 117.62765 -259.619113) (xy 117.581394 -259.644266) (xy 117.531841 -259.662064)
			(xy 117.480151 -259.672088) (xy 117.427537 -259.674105) (xy 117.375232 -259.668067) (xy 117.324461 -259.654115)
			(xy 117.276416 -259.632576) (xy 117.232221 -259.603956) (xy 117.192913 -259.568925) (xy 117.159413 -259.528304)
			(xy 117.132507 -259.483045) (xy 117.112824 -259.43421) (xy 117.100827 -259.382942) (xy 117.096797 -259.330444)
			(xy 116.010944 -259.330444) (xy 116.040408 -259.359908) (xy 116.043845 -259.363524) (xy 116.049352 -259.371839)
			(xy 116.05133 -259.376418) (xy 116.054378 -259.38353) (xy 116.056385 -259.388094) (xy 116.061884 -259.396408)
			(xy 116.0653 -259.40004) (xy 116.15928 -259.49402) (xy 116.177568 -259.50164) (xy 116.187474 -259.501894)
			(xy 116.213917 -259.502796) (xy 116.266065 -259.511726) (xy 116.316227 -259.528549) (xy 116.363216 -259.552864)
			(xy 116.40592 -259.584099) (xy 116.443329 -259.621512) (xy 116.474558 -259.66422) (xy 116.498868 -259.711212)
			(xy 116.505247 -259.73024) (xy 120.865649 -259.73024) (xy 120.869679 -259.677742) (xy 120.881676 -259.626474)
			(xy 120.901359 -259.577639) (xy 120.928265 -259.53238) (xy 120.961765 -259.491759) (xy 121.001073 -259.456728)
			(xy 121.045268 -259.428108) (xy 121.093313 -259.406569) (xy 121.144084 -259.392617) (xy 121.196389 -259.386579)
			(xy 121.249003 -259.388596) (xy 121.300693 -259.39862) (xy 121.350246 -259.416418) (xy 121.396502 -259.441571)
			(xy 121.438376 -259.47349) (xy 121.474888 -259.511428) (xy 121.50518 -259.554494) (xy 121.528543 -259.601679)
			(xy 121.544429 -259.651878) (xy 121.552466 -259.703914) (xy 121.55297 -259.73024) (xy 122.791223 -259.73024)
			(xy 122.795253 -259.677742) (xy 122.80725 -259.626474) (xy 122.826933 -259.577639) (xy 122.853839 -259.53238)
			(xy 122.887339 -259.491759) (xy 122.926647 -259.456728) (xy 122.970842 -259.428108) (xy 123.018887 -259.406569)
			(xy 123.069658 -259.392617) (xy 123.121963 -259.386579) (xy 123.174577 -259.388596) (xy 123.226267 -259.39862)
			(xy 123.27582 -259.416418) (xy 123.322076 -259.441571) (xy 123.36395 -259.47349) (xy 123.400462 -259.511428)
			(xy 123.430754 -259.554494) (xy 123.454117 -259.601679) (xy 123.470003 -259.651878) (xy 123.47804 -259.703914)
			(xy 123.478544 -259.73024) (xy 124.696223 -259.73024) (xy 124.700253 -259.677742) (xy 124.71225 -259.626474)
			(xy 124.731933 -259.577639) (xy 124.758839 -259.53238) (xy 124.792339 -259.491759) (xy 124.831647 -259.456728)
			(xy 124.875842 -259.428108) (xy 124.923887 -259.406569) (xy 124.974658 -259.392617) (xy 125.026963 -259.386579)
			(xy 125.079577 -259.388596) (xy 125.131267 -259.39862) (xy 125.18082 -259.416418) (xy 125.227076 -259.441571)
			(xy 125.26895 -259.47349) (xy 125.305462 -259.511428) (xy 125.335754 -259.554494) (xy 125.359117 -259.601679)
			(xy 125.375003 -259.651878) (xy 125.38304 -259.703914) (xy 125.383544 -259.73024) (xy 125.38304 -259.756566)
			(xy 125.375003 -259.808602) (xy 125.359117 -259.858801) (xy 125.335754 -259.905986) (xy 125.305462 -259.949052)
			(xy 125.26895 -259.98699) (xy 125.227076 -260.018909) (xy 125.18082 -260.044062) (xy 125.131267 -260.06186)
			(xy 125.079577 -260.071884) (xy 125.026963 -260.073901) (xy 124.974658 -260.067863) (xy 124.923887 -260.053911)
			(xy 124.875842 -260.032372) (xy 124.831647 -260.003752) (xy 124.792339 -259.968721) (xy 124.758839 -259.9281)
			(xy 124.731933 -259.882841) (xy 124.71225 -259.834006) (xy 124.700253 -259.782738) (xy 124.696223 -259.73024)
			(xy 123.478544 -259.73024) (xy 123.47804 -259.756566) (xy 123.470003 -259.808602) (xy 123.454117 -259.858801)
			(xy 123.430754 -259.905986) (xy 123.400462 -259.949052) (xy 123.36395 -259.98699) (xy 123.322076 -260.018909)
			(xy 123.27582 -260.044062) (xy 123.226267 -260.06186) (xy 123.174577 -260.071884) (xy 123.121963 -260.073901)
			(xy 123.069658 -260.067863) (xy 123.018887 -260.053911) (xy 122.970842 -260.032372) (xy 122.926647 -260.003752)
			(xy 122.887339 -259.968721) (xy 122.853839 -259.9281) (xy 122.826933 -259.882841) (xy 122.80725 -259.834006)
			(xy 122.795253 -259.782738) (xy 122.791223 -259.73024) (xy 121.55297 -259.73024) (xy 121.552466 -259.756566)
			(xy 121.544429 -259.808602) (xy 121.528543 -259.858801) (xy 121.50518 -259.905986) (xy 121.474888 -259.949052)
			(xy 121.438376 -259.98699) (xy 121.396502 -260.018909) (xy 121.350246 -260.044062) (xy 121.300693 -260.06186)
			(xy 121.249003 -260.071884) (xy 121.196389 -260.073901) (xy 121.144084 -260.067863) (xy 121.093313 -260.053911)
			(xy 121.045268 -260.032372) (xy 121.001073 -260.003752) (xy 120.961765 -259.968721) (xy 120.928265 -259.9281)
			(xy 120.901359 -259.882841) (xy 120.881676 -259.834006) (xy 120.869679 -259.782738) (xy 120.865649 -259.73024)
			(xy 116.505247 -259.73024) (xy 116.515684 -259.761376) (xy 116.524608 -259.813526) (xy 116.525548 -259.839968)
			(xy 116.525802 -259.849874) (xy 116.533422 -259.868162) (xy 116.932202 -260.266942) (xy 116.938591 -260.272799)
			(xy 116.954233 -260.280239) (xy 116.971455 -260.282093) (xy 116.979954 -260.280404) (xy 116.983002 -260.279642)
			(xy 117.0686 -260.253226) (xy 117.077253 -260.250198) (xy 117.091798 -260.239062) (xy 117.10151 -260.223529)
			(xy 117.103652 -260.214618) (xy 117.109183 -260.188897) (xy 117.127018 -260.139404) (xy 117.152193 -260.09321)
			(xy 117.184119 -260.051397) (xy 117.222049 -260.014942) (xy 117.265096 -259.984699) (xy 117.312251 -259.961375)
			(xy 117.362413 -259.945516) (xy 117.414406 -259.937494) (xy 117.44071 -259.936996) (xy 117.467695 -259.937526)
			(xy 117.520999 -259.94597) (xy 117.572326 -259.962649) (xy 117.620412 -259.987151) (xy 117.664073 -260.018875)
			(xy 117.702235 -260.057037) (xy 117.733956 -260.1007) (xy 117.758457 -260.148787) (xy 117.775133 -260.200115)
			(xy 117.783575 -260.253419) (xy 117.784118 -260.280404) (xy 117.783616 -260.306708) (xy 117.775592 -260.358699)
			(xy 117.759732 -260.408859) (xy 117.736408 -260.456013) (xy 117.706165 -260.499058) (xy 117.669711 -260.536988)
			(xy 117.627899 -260.568913) (xy 117.581707 -260.594089) (xy 117.532215 -260.611924) (xy 117.506496 -260.617462)
			(xy 117.49278 -260.620256) (xy 117.471952 -260.638798) (xy 117.441472 -260.738112) (xy 117.44071 -260.74116)
			(xy 117.439005 -260.749666) (xy 117.440798 -260.766909) (xy 117.448273 -260.782551) (xy 117.454172 -260.788912)
			(xy 117.58295 -260.91769) (xy 117.59057 -260.9215) (xy 117.6161 -260.934526) (xy 117.662793 -260.967757)
			(xy 117.70332 -261.00828) (xy 117.736556 -261.05497) (xy 117.749574 -261.080504) (xy 117.753384 -261.088124)
			(xy 117.791484 -261.126224) (xy 121.638834 -261.126224) (xy 121.642794 -261.07717) (xy 121.654571 -261.029386)
			(xy 121.673862 -260.98411) (xy 121.700165 -260.942514) (xy 121.7328 -260.905677) (xy 121.770921 -260.874552)
			(xy 121.813542 -260.849945) (xy 121.859558 -260.832493) (xy 121.907777 -260.822649) (xy 121.956952 -260.820668)
			(xy 122.005807 -260.8266) (xy 122.053078 -260.840292) (xy 122.09754 -260.86139) (xy 122.138043 -260.889346)
			(xy 122.173536 -260.923438) (xy 122.203101 -260.962782) (xy 122.225972 -261.006359) (xy 122.241556 -261.05304)
			(xy 122.249451 -261.101617) (xy 122.249946 -261.126224) (xy 123.518942 -261.126224) (xy 123.522902 -261.07717)
			(xy 123.534679 -261.029386) (xy 123.55397 -260.98411) (xy 123.580273 -260.942514) (xy 123.612908 -260.905677)
			(xy 123.651029 -260.874552) (xy 123.69365 -260.849945) (xy 123.739666 -260.832493) (xy 123.787885 -260.822649)
			(xy 123.83706 -260.820668) (xy 123.885915 -260.8266) (xy 123.933186 -260.840292) (xy 123.977648 -260.86139)
			(xy 124.018151 -260.889346) (xy 124.053644 -260.923438) (xy 124.083209 -260.962782) (xy 124.10608 -261.006359)
			(xy 124.121664 -261.05304) (xy 124.129559 -261.101617) (xy 124.130054 -261.126224) (xy 125.39905 -261.126224)
			(xy 125.40301 -261.07717) (xy 125.414787 -261.029386) (xy 125.434078 -260.98411) (xy 125.460381 -260.942514)
			(xy 125.493016 -260.905677) (xy 125.531137 -260.874552) (xy 125.573758 -260.849945) (xy 125.619774 -260.832493)
			(xy 125.667993 -260.822649) (xy 125.717168 -260.820668) (xy 125.766023 -260.8266) (xy 125.813294 -260.840292)
			(xy 125.857756 -260.86139) (xy 125.898259 -260.889346) (xy 125.933752 -260.923438) (xy 125.963317 -260.962782)
			(xy 125.986188 -261.006359) (xy 126.001772 -261.05304) (xy 126.009667 -261.101617) (xy 126.010162 -261.126224)
			(xy 127.278904 -261.126224) (xy 127.282864 -261.07717) (xy 127.294641 -261.029386) (xy 127.313932 -260.98411)
			(xy 127.340235 -260.942514) (xy 127.37287 -260.905677) (xy 127.410991 -260.874552) (xy 127.453612 -260.849945)
			(xy 127.499628 -260.832493) (xy 127.547847 -260.822649) (xy 127.597022 -260.820668) (xy 127.645877 -260.8266)
			(xy 127.693148 -260.840292) (xy 127.73761 -260.86139) (xy 127.778113 -260.889346) (xy 127.813606 -260.923438)
			(xy 127.843171 -260.962782) (xy 127.866042 -261.006359) (xy 127.881626 -261.05304) (xy 127.889521 -261.101617)
			(xy 127.890016 -261.126224) (xy 128.218958 -261.126224) (xy 128.222918 -261.07717) (xy 128.234695 -261.029386)
			(xy 128.253986 -260.98411) (xy 128.280289 -260.942514) (xy 128.312924 -260.905677) (xy 128.351045 -260.874552)
			(xy 128.393666 -260.849945) (xy 128.439682 -260.832493) (xy 128.487901 -260.822649) (xy 128.537076 -260.820668)
			(xy 128.585931 -260.8266) (xy 128.633202 -260.840292) (xy 128.677664 -260.86139) (xy 128.718167 -260.889346)
			(xy 128.75366 -260.923438) (xy 128.783225 -260.962782) (xy 128.806096 -261.006359) (xy 128.82168 -261.05304)
			(xy 128.829575 -261.101617) (xy 128.83007 -261.126224) (xy 129.159012 -261.126224) (xy 129.162972 -261.07717)
			(xy 129.174749 -261.029386) (xy 129.19404 -260.98411) (xy 129.220343 -260.942514) (xy 129.252978 -260.905677)
			(xy 129.291099 -260.874552) (xy 129.33372 -260.849945) (xy 129.379736 -260.832493) (xy 129.427955 -260.822649)
			(xy 129.47713 -260.820668) (xy 129.525985 -260.8266) (xy 129.573256 -260.840292) (xy 129.617718 -260.86139)
			(xy 129.658221 -260.889346) (xy 129.693714 -260.923438) (xy 129.723279 -260.962782) (xy 129.74615 -261.006359)
			(xy 129.761734 -261.05304) (xy 129.769629 -261.101617) (xy 129.770124 -261.126224) (xy 130.099066 -261.126224)
			(xy 130.103026 -261.07717) (xy 130.114803 -261.029386) (xy 130.134094 -260.98411) (xy 130.160397 -260.942514)
			(xy 130.193032 -260.905677) (xy 130.231153 -260.874552) (xy 130.273774 -260.849945) (xy 130.31979 -260.832493)
			(xy 130.368009 -260.822649) (xy 130.417184 -260.820668) (xy 130.466039 -260.8266) (xy 130.51331 -260.840292)
			(xy 130.557772 -260.86139) (xy 130.598275 -260.889346) (xy 130.633768 -260.923438) (xy 130.663333 -260.962782)
			(xy 130.686204 -261.006359) (xy 130.701788 -261.05304) (xy 130.709683 -261.101617) (xy 130.710178 -261.126224)
			(xy 131.038866 -261.126224) (xy 131.042826 -261.07717) (xy 131.054603 -261.029386) (xy 131.073894 -260.98411)
			(xy 131.100197 -260.942514) (xy 131.132832 -260.905677) (xy 131.170953 -260.874552) (xy 131.213574 -260.849945)
			(xy 131.25959 -260.832493) (xy 131.307809 -260.822649) (xy 131.356984 -260.820668) (xy 131.405839 -260.8266)
			(xy 131.45311 -260.840292) (xy 131.497572 -260.86139) (xy 131.538075 -260.889346) (xy 131.573568 -260.923438)
			(xy 131.603133 -260.962782) (xy 131.626004 -261.006359) (xy 131.641588 -261.05304) (xy 131.649483 -261.101617)
			(xy 131.649978 -261.126224) (xy 131.97892 -261.126224) (xy 131.98288 -261.07717) (xy 131.994657 -261.029386)
			(xy 132.013948 -260.98411) (xy 132.040251 -260.942514) (xy 132.072886 -260.905677) (xy 132.111007 -260.874552)
			(xy 132.153628 -260.849945) (xy 132.199644 -260.832493) (xy 132.247863 -260.822649) (xy 132.297038 -260.820668)
			(xy 132.345893 -260.8266) (xy 132.393164 -260.840292) (xy 132.437626 -260.86139) (xy 132.478129 -260.889346)
			(xy 132.513622 -260.923438) (xy 132.543187 -260.962782) (xy 132.566058 -261.006359) (xy 132.581642 -261.05304)
			(xy 132.589537 -261.101617) (xy 132.590032 -261.126224) (xy 132.918974 -261.126224) (xy 132.922934 -261.07717)
			(xy 132.934711 -261.029386) (xy 132.954002 -260.98411) (xy 132.980305 -260.942514) (xy 133.01294 -260.905677)
			(xy 133.051061 -260.874552) (xy 133.093682 -260.849945) (xy 133.139698 -260.832493) (xy 133.187917 -260.822649)
			(xy 133.237092 -260.820668) (xy 133.285947 -260.8266) (xy 133.333218 -260.840292) (xy 133.37768 -260.86139)
			(xy 133.418183 -260.889346) (xy 133.453676 -260.923438) (xy 133.483241 -260.962782) (xy 133.506112 -261.006359)
			(xy 133.521696 -261.05304) (xy 133.529591 -261.101617) (xy 133.530086 -261.126224) (xy 133.859028 -261.126224)
			(xy 133.862988 -261.07717) (xy 133.874765 -261.029386) (xy 133.894056 -260.98411) (xy 133.920359 -260.942514)
			(xy 133.952994 -260.905677) (xy 133.991115 -260.874552) (xy 134.033736 -260.849945) (xy 134.079752 -260.832493)
			(xy 134.127971 -260.822649) (xy 134.177146 -260.820668) (xy 134.226001 -260.8266) (xy 134.273272 -260.840292)
			(xy 134.317734 -260.86139) (xy 134.358237 -260.889346) (xy 134.39373 -260.923438) (xy 134.423295 -260.962782)
			(xy 134.446166 -261.006359) (xy 134.46175 -261.05304) (xy 134.469645 -261.101617) (xy 134.47014 -261.126224)
			(xy 134.798828 -261.126224) (xy 134.802788 -261.07717) (xy 134.814565 -261.029386) (xy 134.833856 -260.98411)
			(xy 134.860159 -260.942514) (xy 134.892794 -260.905677) (xy 134.930915 -260.874552) (xy 134.973536 -260.849945)
			(xy 135.019552 -260.832493) (xy 135.067771 -260.822649) (xy 135.116946 -260.820668) (xy 135.165801 -260.8266)
			(xy 135.213072 -260.840292) (xy 135.257534 -260.86139) (xy 135.298037 -260.889346) (xy 135.33353 -260.923438)
			(xy 135.363095 -260.962782) (xy 135.385966 -261.006359) (xy 135.40155 -261.05304) (xy 135.409445 -261.101617)
			(xy 135.40994 -261.126224) (xy 135.738882 -261.126224) (xy 135.742842 -261.07717) (xy 135.754619 -261.029386)
			(xy 135.77391 -260.98411) (xy 135.800213 -260.942514) (xy 135.832848 -260.905677) (xy 135.870969 -260.874552)
			(xy 135.91359 -260.849945) (xy 135.959606 -260.832493) (xy 136.007825 -260.822649) (xy 136.057 -260.820668)
			(xy 136.105855 -260.8266) (xy 136.153126 -260.840292) (xy 136.197588 -260.86139) (xy 136.238091 -260.889346)
			(xy 136.273584 -260.923438) (xy 136.303149 -260.962782) (xy 136.32602 -261.006359) (xy 136.341604 -261.05304)
			(xy 136.349499 -261.101617) (xy 136.349994 -261.126224) (xy 136.678936 -261.126224) (xy 136.682896 -261.07717)
			(xy 136.694673 -261.029386) (xy 136.713964 -260.98411) (xy 136.740267 -260.942514) (xy 136.772902 -260.905677)
			(xy 136.811023 -260.874552) (xy 136.853644 -260.849945) (xy 136.89966 -260.832493) (xy 136.947879 -260.822649)
			(xy 136.997054 -260.820668) (xy 137.045909 -260.8266) (xy 137.09318 -260.840292) (xy 137.137642 -260.86139)
			(xy 137.178145 -260.889346) (xy 137.213638 -260.923438) (xy 137.243203 -260.962782) (xy 137.266074 -261.006359)
			(xy 137.281658 -261.05304) (xy 137.289553 -261.101617) (xy 137.290048 -261.126224) (xy 137.61899 -261.126224)
			(xy 137.62295 -261.07717) (xy 137.634727 -261.029386) (xy 137.654018 -260.98411) (xy 137.680321 -260.942514)
			(xy 137.712956 -260.905677) (xy 137.751077 -260.874552) (xy 137.793698 -260.849945) (xy 137.839714 -260.832493)
			(xy 137.887933 -260.822649) (xy 137.937108 -260.820668) (xy 137.985963 -260.8266) (xy 138.033234 -260.840292)
			(xy 138.077696 -260.86139) (xy 138.118199 -260.889346) (xy 138.153692 -260.923438) (xy 138.183257 -260.962782)
			(xy 138.206128 -261.006359) (xy 138.221712 -261.05304) (xy 138.229607 -261.101617) (xy 138.230102 -261.126224)
			(xy 138.559044 -261.126224) (xy 138.563004 -261.07717) (xy 138.574781 -261.029386) (xy 138.594072 -260.98411)
			(xy 138.620375 -260.942514) (xy 138.65301 -260.905677) (xy 138.691131 -260.874552) (xy 138.733752 -260.849945)
			(xy 138.779768 -260.832493) (xy 138.827987 -260.822649) (xy 138.877162 -260.820668) (xy 138.926017 -260.8266)
			(xy 138.973288 -260.840292) (xy 139.01775 -260.86139) (xy 139.058253 -260.889346) (xy 139.093746 -260.923438)
			(xy 139.123311 -260.962782) (xy 139.146182 -261.006359) (xy 139.161766 -261.05304) (xy 139.169661 -261.101617)
			(xy 139.170156 -261.126224) (xy 139.498844 -261.126224) (xy 139.502804 -261.07717) (xy 139.514581 -261.029386)
			(xy 139.533872 -260.98411) (xy 139.560175 -260.942514) (xy 139.59281 -260.905677) (xy 139.630931 -260.874552)
			(xy 139.673552 -260.849945) (xy 139.719568 -260.832493) (xy 139.767787 -260.822649) (xy 139.816962 -260.820668)
			(xy 139.865817 -260.8266) (xy 139.913088 -260.840292) (xy 139.95755 -260.86139) (xy 139.998053 -260.889346)
			(xy 140.033546 -260.923438) (xy 140.063111 -260.962782) (xy 140.085982 -261.006359) (xy 140.101566 -261.05304)
			(xy 140.109461 -261.101617) (xy 140.109956 -261.126224) (xy 140.438898 -261.126224) (xy 140.442858 -261.07717)
			(xy 140.454635 -261.029386) (xy 140.473926 -260.98411) (xy 140.500229 -260.942514) (xy 140.532864 -260.905677)
			(xy 140.570985 -260.874552) (xy 140.613606 -260.849945) (xy 140.659622 -260.832493) (xy 140.707841 -260.822649)
			(xy 140.757016 -260.820668) (xy 140.805871 -260.8266) (xy 140.853142 -260.840292) (xy 140.897604 -260.86139)
			(xy 140.938107 -260.889346) (xy 140.9736 -260.923438) (xy 141.003165 -260.962782) (xy 141.026036 -261.006359)
			(xy 141.04162 -261.05304) (xy 141.049515 -261.101617) (xy 141.05001 -261.126224) (xy 141.378952 -261.126224)
			(xy 141.382912 -261.07717) (xy 141.394689 -261.029386) (xy 141.41398 -260.98411) (xy 141.440283 -260.942514)
			(xy 141.472918 -260.905677) (xy 141.511039 -260.874552) (xy 141.55366 -260.849945) (xy 141.599676 -260.832493)
			(xy 141.647895 -260.822649) (xy 141.69707 -260.820668) (xy 141.745925 -260.8266) (xy 141.793196 -260.840292)
			(xy 141.837658 -260.86139) (xy 141.878161 -260.889346) (xy 141.913654 -260.923438) (xy 141.943219 -260.962782)
			(xy 141.96609 -261.006359) (xy 141.981674 -261.05304) (xy 141.989569 -261.101617) (xy 141.990064 -261.126224)
			(xy 142.319006 -261.126224) (xy 142.322966 -261.07717) (xy 142.334743 -261.029386) (xy 142.354034 -260.98411)
			(xy 142.380337 -260.942514) (xy 142.412972 -260.905677) (xy 142.451093 -260.874552) (xy 142.493714 -260.849945)
			(xy 142.53973 -260.832493) (xy 142.587949 -260.822649) (xy 142.637124 -260.820668) (xy 142.685979 -260.8266)
			(xy 142.73325 -260.840292) (xy 142.777712 -260.86139) (xy 142.818215 -260.889346) (xy 142.853708 -260.923438)
			(xy 142.883273 -260.962782) (xy 142.906144 -261.006359) (xy 142.921728 -261.05304) (xy 142.929623 -261.101617)
			(xy 142.930118 -261.126224) (xy 143.25906 -261.126224) (xy 143.26302 -261.07717) (xy 143.274797 -261.029386)
			(xy 143.294088 -260.98411) (xy 143.320391 -260.942514) (xy 143.353026 -260.905677) (xy 143.391147 -260.874552)
			(xy 143.433768 -260.849945) (xy 143.479784 -260.832493) (xy 143.528003 -260.822649) (xy 143.577178 -260.820668)
			(xy 143.626033 -260.8266) (xy 143.673304 -260.840292) (xy 143.717766 -260.86139) (xy 143.758269 -260.889346)
			(xy 143.793762 -260.923438) (xy 143.823327 -260.962782) (xy 143.846198 -261.006359) (xy 143.861782 -261.05304)
			(xy 143.869677 -261.101617) (xy 143.870172 -261.126224) (xy 144.19886 -261.126224) (xy 144.20282 -261.07717)
			(xy 144.214597 -261.029386) (xy 144.233888 -260.98411) (xy 144.260191 -260.942514) (xy 144.292826 -260.905677)
			(xy 144.330947 -260.874552) (xy 144.373568 -260.849945) (xy 144.419584 -260.832493) (xy 144.467803 -260.822649)
			(xy 144.516978 -260.820668) (xy 144.565833 -260.8266) (xy 144.613104 -260.840292) (xy 144.657566 -260.86139)
			(xy 144.698069 -260.889346) (xy 144.733562 -260.923438) (xy 144.763127 -260.962782) (xy 144.785998 -261.006359)
			(xy 144.801582 -261.05304) (xy 144.809477 -261.101617) (xy 144.809972 -261.126224) (xy 144.809477 -261.150831)
			(xy 144.801582 -261.199408) (xy 144.785998 -261.246089) (xy 144.763127 -261.289666) (xy 144.733562 -261.32901)
			(xy 144.698069 -261.363102) (xy 144.657566 -261.391058) (xy 144.613104 -261.412156) (xy 144.565833 -261.425848)
			(xy 144.516978 -261.43178) (xy 144.467803 -261.429799) (xy 144.419584 -261.419955) (xy 144.373568 -261.402503)
			(xy 144.330947 -261.377896) (xy 144.292826 -261.346771) (xy 144.260191 -261.309934) (xy 144.233888 -261.268338)
			(xy 144.214597 -261.223062) (xy 144.20282 -261.175278) (xy 144.19886 -261.126224) (xy 143.870172 -261.126224)
			(xy 143.869677 -261.150831) (xy 143.861782 -261.199408) (xy 143.846198 -261.246089) (xy 143.823327 -261.289666)
			(xy 143.793762 -261.32901) (xy 143.758269 -261.363102) (xy 143.717766 -261.391058) (xy 143.673304 -261.412156)
			(xy 143.626033 -261.425848) (xy 143.577178 -261.43178) (xy 143.528003 -261.429799) (xy 143.479784 -261.419955)
			(xy 143.433768 -261.402503) (xy 143.391147 -261.377896) (xy 143.353026 -261.346771) (xy 143.320391 -261.309934)
			(xy 143.294088 -261.268338) (xy 143.274797 -261.223062) (xy 143.26302 -261.175278) (xy 143.25906 -261.126224)
			(xy 142.930118 -261.126224) (xy 142.929623 -261.150831) (xy 142.921728 -261.199408) (xy 142.906144 -261.246089)
			(xy 142.883273 -261.289666) (xy 142.853708 -261.32901) (xy 142.818215 -261.363102) (xy 142.777712 -261.391058)
			(xy 142.73325 -261.412156) (xy 142.685979 -261.425848) (xy 142.637124 -261.43178) (xy 142.587949 -261.429799)
			(xy 142.53973 -261.419955) (xy 142.493714 -261.402503) (xy 142.451093 -261.377896) (xy 142.412972 -261.346771)
			(xy 142.380337 -261.309934) (xy 142.354034 -261.268338) (xy 142.334743 -261.223062) (xy 142.322966 -261.175278)
			(xy 142.319006 -261.126224) (xy 141.990064 -261.126224) (xy 141.989569 -261.150831) (xy 141.981674 -261.199408)
			(xy 141.96609 -261.246089) (xy 141.943219 -261.289666) (xy 141.913654 -261.32901) (xy 141.878161 -261.363102)
			(xy 141.837658 -261.391058) (xy 141.793196 -261.412156) (xy 141.745925 -261.425848) (xy 141.69707 -261.43178)
			(xy 141.647895 -261.429799) (xy 141.599676 -261.419955) (xy 141.55366 -261.402503) (xy 141.511039 -261.377896)
			(xy 141.472918 -261.346771) (xy 141.440283 -261.309934) (xy 141.41398 -261.268338) (xy 141.394689 -261.223062)
			(xy 141.382912 -261.175278) (xy 141.378952 -261.126224) (xy 141.05001 -261.126224) (xy 141.049515 -261.150831)
			(xy 141.04162 -261.199408) (xy 141.026036 -261.246089) (xy 141.003165 -261.289666) (xy 140.9736 -261.32901)
			(xy 140.938107 -261.363102) (xy 140.897604 -261.391058) (xy 140.853142 -261.412156) (xy 140.805871 -261.425848)
			(xy 140.757016 -261.43178) (xy 140.707841 -261.429799) (xy 140.659622 -261.419955) (xy 140.613606 -261.402503)
			(xy 140.570985 -261.377896) (xy 140.532864 -261.346771) (xy 140.500229 -261.309934) (xy 140.473926 -261.268338)
			(xy 140.454635 -261.223062) (xy 140.442858 -261.175278) (xy 140.438898 -261.126224) (xy 140.109956 -261.126224)
			(xy 140.109461 -261.150831) (xy 140.101566 -261.199408) (xy 140.085982 -261.246089) (xy 140.063111 -261.289666)
			(xy 140.033546 -261.32901) (xy 139.998053 -261.363102) (xy 139.95755 -261.391058) (xy 139.913088 -261.412156)
			(xy 139.865817 -261.425848) (xy 139.816962 -261.43178) (xy 139.767787 -261.429799) (xy 139.719568 -261.419955)
			(xy 139.673552 -261.402503) (xy 139.630931 -261.377896) (xy 139.59281 -261.346771) (xy 139.560175 -261.309934)
			(xy 139.533872 -261.268338) (xy 139.514581 -261.223062) (xy 139.502804 -261.175278) (xy 139.498844 -261.126224)
			(xy 139.170156 -261.126224) (xy 139.169661 -261.150831) (xy 139.161766 -261.199408) (xy 139.146182 -261.246089)
			(xy 139.123311 -261.289666) (xy 139.093746 -261.32901) (xy 139.058253 -261.363102) (xy 139.01775 -261.391058)
			(xy 138.973288 -261.412156) (xy 138.926017 -261.425848) (xy 138.877162 -261.43178) (xy 138.827987 -261.429799)
			(xy 138.779768 -261.419955) (xy 138.733752 -261.402503) (xy 138.691131 -261.377896) (xy 138.65301 -261.346771)
			(xy 138.620375 -261.309934) (xy 138.594072 -261.268338) (xy 138.574781 -261.223062) (xy 138.563004 -261.175278)
			(xy 138.559044 -261.126224) (xy 138.230102 -261.126224) (xy 138.229607 -261.150831) (xy 138.221712 -261.199408)
			(xy 138.206128 -261.246089) (xy 138.183257 -261.289666) (xy 138.153692 -261.32901) (xy 138.118199 -261.363102)
			(xy 138.077696 -261.391058) (xy 138.033234 -261.412156) (xy 137.985963 -261.425848) (xy 137.937108 -261.43178)
			(xy 137.887933 -261.429799) (xy 137.839714 -261.419955) (xy 137.793698 -261.402503) (xy 137.751077 -261.377896)
			(xy 137.712956 -261.346771) (xy 137.680321 -261.309934) (xy 137.654018 -261.268338) (xy 137.634727 -261.223062)
			(xy 137.62295 -261.175278) (xy 137.61899 -261.126224) (xy 137.290048 -261.126224) (xy 137.289553 -261.150831)
			(xy 137.281658 -261.199408) (xy 137.266074 -261.246089) (xy 137.243203 -261.289666) (xy 137.213638 -261.32901)
			(xy 137.178145 -261.363102) (xy 137.137642 -261.391058) (xy 137.09318 -261.412156) (xy 137.045909 -261.425848)
			(xy 136.997054 -261.43178) (xy 136.947879 -261.429799) (xy 136.89966 -261.419955) (xy 136.853644 -261.402503)
			(xy 136.811023 -261.377896) (xy 136.772902 -261.346771) (xy 136.740267 -261.309934) (xy 136.713964 -261.268338)
			(xy 136.694673 -261.223062) (xy 136.682896 -261.175278) (xy 136.678936 -261.126224) (xy 136.349994 -261.126224)
			(xy 136.349499 -261.150831) (xy 136.341604 -261.199408) (xy 136.32602 -261.246089) (xy 136.303149 -261.289666)
			(xy 136.273584 -261.32901) (xy 136.238091 -261.363102) (xy 136.197588 -261.391058) (xy 136.153126 -261.412156)
			(xy 136.105855 -261.425848) (xy 136.057 -261.43178) (xy 136.007825 -261.429799) (xy 135.959606 -261.419955)
			(xy 135.91359 -261.402503) (xy 135.870969 -261.377896) (xy 135.832848 -261.346771) (xy 135.800213 -261.309934)
			(xy 135.77391 -261.268338) (xy 135.754619 -261.223062) (xy 135.742842 -261.175278) (xy 135.738882 -261.126224)
			(xy 135.40994 -261.126224) (xy 135.409445 -261.150831) (xy 135.40155 -261.199408) (xy 135.385966 -261.246089)
			(xy 135.363095 -261.289666) (xy 135.33353 -261.32901) (xy 135.298037 -261.363102) (xy 135.257534 -261.391058)
			(xy 135.213072 -261.412156) (xy 135.165801 -261.425848) (xy 135.116946 -261.43178) (xy 135.067771 -261.429799)
			(xy 135.019552 -261.419955) (xy 134.973536 -261.402503) (xy 134.930915 -261.377896) (xy 134.892794 -261.346771)
			(xy 134.860159 -261.309934) (xy 134.833856 -261.268338) (xy 134.814565 -261.223062) (xy 134.802788 -261.175278)
			(xy 134.798828 -261.126224) (xy 134.47014 -261.126224) (xy 134.469645 -261.150831) (xy 134.46175 -261.199408)
			(xy 134.446166 -261.246089) (xy 134.423295 -261.289666) (xy 134.39373 -261.32901) (xy 134.358237 -261.363102)
			(xy 134.317734 -261.391058) (xy 134.273272 -261.412156) (xy 134.226001 -261.425848) (xy 134.177146 -261.43178)
			(xy 134.127971 -261.429799) (xy 134.079752 -261.419955) (xy 134.033736 -261.402503) (xy 133.991115 -261.377896)
			(xy 133.952994 -261.346771) (xy 133.920359 -261.309934) (xy 133.894056 -261.268338) (xy 133.874765 -261.223062)
			(xy 133.862988 -261.175278) (xy 133.859028 -261.126224) (xy 133.530086 -261.126224) (xy 133.529591 -261.150831)
			(xy 133.521696 -261.199408) (xy 133.506112 -261.246089) (xy 133.483241 -261.289666) (xy 133.453676 -261.32901)
			(xy 133.418183 -261.363102) (xy 133.37768 -261.391058) (xy 133.333218 -261.412156) (xy 133.285947 -261.425848)
			(xy 133.237092 -261.43178) (xy 133.187917 -261.429799) (xy 133.139698 -261.419955) (xy 133.093682 -261.402503)
			(xy 133.051061 -261.377896) (xy 133.01294 -261.346771) (xy 132.980305 -261.309934) (xy 132.954002 -261.268338)
			(xy 132.934711 -261.223062) (xy 132.922934 -261.175278) (xy 132.918974 -261.126224) (xy 132.590032 -261.126224)
			(xy 132.589537 -261.150831) (xy 132.581642 -261.199408) (xy 132.566058 -261.246089) (xy 132.543187 -261.289666)
			(xy 132.513622 -261.32901) (xy 132.478129 -261.363102) (xy 132.437626 -261.391058) (xy 132.393164 -261.412156)
			(xy 132.345893 -261.425848) (xy 132.297038 -261.43178) (xy 132.247863 -261.429799) (xy 132.199644 -261.419955)
			(xy 132.153628 -261.402503) (xy 132.111007 -261.377896) (xy 132.072886 -261.346771) (xy 132.040251 -261.309934)
			(xy 132.013948 -261.268338) (xy 131.994657 -261.223062) (xy 131.98288 -261.175278) (xy 131.97892 -261.126224)
			(xy 131.649978 -261.126224) (xy 131.649483 -261.150831) (xy 131.641588 -261.199408) (xy 131.626004 -261.246089)
			(xy 131.603133 -261.289666) (xy 131.573568 -261.32901) (xy 131.538075 -261.363102) (xy 131.497572 -261.391058)
			(xy 131.45311 -261.412156) (xy 131.405839 -261.425848) (xy 131.356984 -261.43178) (xy 131.307809 -261.429799)
			(xy 131.25959 -261.419955) (xy 131.213574 -261.402503) (xy 131.170953 -261.377896) (xy 131.132832 -261.346771)
			(xy 131.100197 -261.309934) (xy 131.073894 -261.268338) (xy 131.054603 -261.223062) (xy 131.042826 -261.175278)
			(xy 131.038866 -261.126224) (xy 130.710178 -261.126224) (xy 130.709683 -261.150831) (xy 130.701788 -261.199408)
			(xy 130.686204 -261.246089) (xy 130.663333 -261.289666) (xy 130.633768 -261.32901) (xy 130.598275 -261.363102)
			(xy 130.557772 -261.391058) (xy 130.51331 -261.412156) (xy 130.466039 -261.425848) (xy 130.417184 -261.43178)
			(xy 130.368009 -261.429799) (xy 130.31979 -261.419955) (xy 130.273774 -261.402503) (xy 130.231153 -261.377896)
			(xy 130.193032 -261.346771) (xy 130.160397 -261.309934) (xy 130.134094 -261.268338) (xy 130.114803 -261.223062)
			(xy 130.103026 -261.175278) (xy 130.099066 -261.126224) (xy 129.770124 -261.126224) (xy 129.769629 -261.150831)
			(xy 129.761734 -261.199408) (xy 129.74615 -261.246089) (xy 129.723279 -261.289666) (xy 129.693714 -261.32901)
			(xy 129.658221 -261.363102) (xy 129.617718 -261.391058) (xy 129.573256 -261.412156) (xy 129.525985 -261.425848)
			(xy 129.47713 -261.43178) (xy 129.427955 -261.429799) (xy 129.379736 -261.419955) (xy 129.33372 -261.402503)
			(xy 129.291099 -261.377896) (xy 129.252978 -261.346771) (xy 129.220343 -261.309934) (xy 129.19404 -261.268338)
			(xy 129.174749 -261.223062) (xy 129.162972 -261.175278) (xy 129.159012 -261.126224) (xy 128.83007 -261.126224)
			(xy 128.829575 -261.150831) (xy 128.82168 -261.199408) (xy 128.806096 -261.246089) (xy 128.783225 -261.289666)
			(xy 128.75366 -261.32901) (xy 128.718167 -261.363102) (xy 128.677664 -261.391058) (xy 128.633202 -261.412156)
			(xy 128.585931 -261.425848) (xy 128.537076 -261.43178) (xy 128.487901 -261.429799) (xy 128.439682 -261.419955)
			(xy 128.393666 -261.402503) (xy 128.351045 -261.377896) (xy 128.312924 -261.346771) (xy 128.280289 -261.309934)
			(xy 128.253986 -261.268338) (xy 128.234695 -261.223062) (xy 128.222918 -261.175278) (xy 128.218958 -261.126224)
			(xy 127.890016 -261.126224) (xy 127.889521 -261.150831) (xy 127.881626 -261.199408) (xy 127.866042 -261.246089)
			(xy 127.843171 -261.289666) (xy 127.813606 -261.32901) (xy 127.778113 -261.363102) (xy 127.73761 -261.391058)
			(xy 127.693148 -261.412156) (xy 127.645877 -261.425848) (xy 127.597022 -261.43178) (xy 127.547847 -261.429799)
			(xy 127.499628 -261.419955) (xy 127.453612 -261.402503) (xy 127.410991 -261.377896) (xy 127.37287 -261.346771)
			(xy 127.340235 -261.309934) (xy 127.313932 -261.268338) (xy 127.294641 -261.223062) (xy 127.282864 -261.175278)
			(xy 127.278904 -261.126224) (xy 126.010162 -261.126224) (xy 126.009667 -261.150831) (xy 126.001772 -261.199408)
			(xy 125.986188 -261.246089) (xy 125.963317 -261.289666) (xy 125.933752 -261.32901) (xy 125.898259 -261.363102)
			(xy 125.857756 -261.391058) (xy 125.813294 -261.412156) (xy 125.766023 -261.425848) (xy 125.717168 -261.43178)
			(xy 125.667993 -261.429799) (xy 125.619774 -261.419955) (xy 125.573758 -261.402503) (xy 125.531137 -261.377896)
			(xy 125.493016 -261.346771) (xy 125.460381 -261.309934) (xy 125.434078 -261.268338) (xy 125.414787 -261.223062)
			(xy 125.40301 -261.175278) (xy 125.39905 -261.126224) (xy 124.130054 -261.126224) (xy 124.129559 -261.150831)
			(xy 124.121664 -261.199408) (xy 124.10608 -261.246089) (xy 124.083209 -261.289666) (xy 124.053644 -261.32901)
			(xy 124.018151 -261.363102) (xy 123.977648 -261.391058) (xy 123.933186 -261.412156) (xy 123.885915 -261.425848)
			(xy 123.83706 -261.43178) (xy 123.787885 -261.429799) (xy 123.739666 -261.419955) (xy 123.69365 -261.402503)
			(xy 123.651029 -261.377896) (xy 123.612908 -261.346771) (xy 123.580273 -261.309934) (xy 123.55397 -261.268338)
			(xy 123.534679 -261.223062) (xy 123.522902 -261.175278) (xy 123.518942 -261.126224) (xy 122.249946 -261.126224)
			(xy 122.249451 -261.150831) (xy 122.241556 -261.199408) (xy 122.225972 -261.246089) (xy 122.203101 -261.289666)
			(xy 122.173536 -261.32901) (xy 122.138043 -261.363102) (xy 122.09754 -261.391058) (xy 122.053078 -261.412156)
			(xy 122.005807 -261.425848) (xy 121.956952 -261.43178) (xy 121.907777 -261.429799) (xy 121.859558 -261.419955)
			(xy 121.813542 -261.402503) (xy 121.770921 -261.377896) (xy 121.7328 -261.346771) (xy 121.700165 -261.309934)
			(xy 121.673862 -261.268338) (xy 121.654571 -261.223062) (xy 121.642794 -261.175278) (xy 121.638834 -261.126224)
			(xy 117.791484 -261.126224) (xy 118.171214 -261.505954) (xy 118.171722 -261.506462) (xy 118.179102 -261.513048)
			(xy 118.197401 -261.520508) (xy 118.207282 -261.52094) (xy 118.508018 -261.52094) (xy 118.518086 -261.521368)
			(xy 118.536682 -261.529091) (xy 118.544086 -261.535926) (xy 118.94439 -261.93623) (xy 122.108988 -261.93623)
			(xy 122.112948 -261.887176) (xy 122.124725 -261.839392) (xy 122.144016 -261.794116) (xy 122.170319 -261.75252)
			(xy 122.202954 -261.715683) (xy 122.241075 -261.684558) (xy 122.283696 -261.659951) (xy 122.329712 -261.642499)
			(xy 122.377931 -261.632655) (xy 122.427106 -261.630674) (xy 122.475961 -261.636606) (xy 122.523232 -261.650298)
			(xy 122.567694 -261.671396) (xy 122.608197 -261.699352) (xy 122.64369 -261.733444) (xy 122.673255 -261.772788)
			(xy 122.696126 -261.816365) (xy 122.71171 -261.863046) (xy 122.719605 -261.911623) (xy 122.7201 -261.93623)
			(xy 123.988842 -261.93623) (xy 123.992802 -261.887176) (xy 124.004579 -261.839392) (xy 124.02387 -261.794116)
			(xy 124.050173 -261.75252) (xy 124.082808 -261.715683) (xy 124.120929 -261.684558) (xy 124.16355 -261.659951)
			(xy 124.209566 -261.642499) (xy 124.257785 -261.632655) (xy 124.30696 -261.630674) (xy 124.355815 -261.636606)
			(xy 124.403086 -261.650298) (xy 124.447548 -261.671396) (xy 124.488051 -261.699352) (xy 124.523544 -261.733444)
			(xy 124.553109 -261.772788) (xy 124.57598 -261.816365) (xy 124.591564 -261.863046) (xy 124.599459 -261.911623)
			(xy 124.599954 -261.93623) (xy 125.86895 -261.93623) (xy 125.87291 -261.887176) (xy 125.884687 -261.839392)
			(xy 125.903978 -261.794116) (xy 125.930281 -261.75252) (xy 125.962916 -261.715683) (xy 126.001037 -261.684558)
			(xy 126.043658 -261.659951) (xy 126.089674 -261.642499) (xy 126.137893 -261.632655) (xy 126.187068 -261.630674)
			(xy 126.235923 -261.636606) (xy 126.283194 -261.650298) (xy 126.327656 -261.671396) (xy 126.368159 -261.699352)
			(xy 126.403652 -261.733444) (xy 126.433217 -261.772788) (xy 126.456088 -261.816365) (xy 126.471672 -261.863046)
			(xy 126.479567 -261.911623) (xy 126.480062 -261.93623) (xy 127.738627 -261.93623) (xy 127.742722 -261.885502)
			(xy 127.754901 -261.836088) (xy 127.774849 -261.789268) (xy 127.80205 -261.746254) (xy 127.835798 -261.70816)
			(xy 127.87522 -261.675973) (xy 127.919294 -261.650527) (xy 127.96688 -261.63248) (xy 128.016744 -261.6223)
			(xy 128.067596 -261.620251) (xy 128.118117 -261.626385) (xy 128.167001 -261.640545) (xy 128.21298 -261.662362)
			(xy 128.254864 -261.691272) (xy 128.291568 -261.726527) (xy 128.322141 -261.767213) (xy 128.345792 -261.812276)
			(xy 128.361908 -261.86055) (xy 128.370072 -261.910784) (xy 128.370584 -261.93623) (xy 128.688858 -261.93623)
			(xy 128.692818 -261.887176) (xy 128.704595 -261.839392) (xy 128.723886 -261.794116) (xy 128.750189 -261.75252)
			(xy 128.782824 -261.715683) (xy 128.820945 -261.684558) (xy 128.863566 -261.659951) (xy 128.909582 -261.642499)
			(xy 128.957801 -261.632655) (xy 129.006976 -261.630674) (xy 129.055831 -261.636606) (xy 129.103102 -261.650298)
			(xy 129.147564 -261.671396) (xy 129.188067 -261.699352) (xy 129.22356 -261.733444) (xy 129.253125 -261.772788)
			(xy 129.275996 -261.816365) (xy 129.29158 -261.863046) (xy 129.299475 -261.911623) (xy 129.29997 -261.93623)
			(xy 129.628912 -261.93623) (xy 129.632872 -261.887176) (xy 129.644649 -261.839392) (xy 129.66394 -261.794116)
			(xy 129.690243 -261.75252) (xy 129.722878 -261.715683) (xy 129.760999 -261.684558) (xy 129.80362 -261.659951)
			(xy 129.849636 -261.642499) (xy 129.897855 -261.632655) (xy 129.94703 -261.630674) (xy 129.995885 -261.636606)
			(xy 130.043156 -261.650298) (xy 130.087618 -261.671396) (xy 130.128121 -261.699352) (xy 130.163614 -261.733444)
			(xy 130.193179 -261.772788) (xy 130.21605 -261.816365) (xy 130.231634 -261.863046) (xy 130.239529 -261.911623)
			(xy 130.240024 -261.93623) (xy 130.568966 -261.93623) (xy 130.572926 -261.887176) (xy 130.584703 -261.839392)
			(xy 130.603994 -261.794116) (xy 130.630297 -261.75252) (xy 130.662932 -261.715683) (xy 130.701053 -261.684558)
			(xy 130.743674 -261.659951) (xy 130.78969 -261.642499) (xy 130.837909 -261.632655) (xy 130.887084 -261.630674)
			(xy 130.935939 -261.636606) (xy 130.98321 -261.650298) (xy 131.027672 -261.671396) (xy 131.068175 -261.699352)
			(xy 131.103668 -261.733444) (xy 131.133233 -261.772788) (xy 131.156104 -261.816365) (xy 131.171688 -261.863046)
			(xy 131.179583 -261.911623) (xy 131.180078 -261.93623) (xy 131.498589 -261.93623) (xy 131.502684 -261.885502)
			(xy 131.514863 -261.836088) (xy 131.534811 -261.789268) (xy 131.562012 -261.746254) (xy 131.59576 -261.70816)
			(xy 131.635182 -261.675973) (xy 131.679256 -261.650527) (xy 131.726842 -261.63248) (xy 131.776706 -261.6223)
			(xy 131.827558 -261.620251) (xy 131.878079 -261.626385) (xy 131.926963 -261.640545) (xy 131.972942 -261.662362)
			(xy 132.014826 -261.691272) (xy 132.05153 -261.726527) (xy 132.082103 -261.767213) (xy 132.105754 -261.812276)
			(xy 132.12187 -261.86055) (xy 132.130034 -261.910784) (xy 132.130546 -261.93623) (xy 132.44882 -261.93623)
			(xy 132.45278 -261.887176) (xy 132.464557 -261.839392) (xy 132.483848 -261.794116) (xy 132.510151 -261.75252)
			(xy 132.542786 -261.715683) (xy 132.580907 -261.684558) (xy 132.623528 -261.659951) (xy 132.669544 -261.642499)
			(xy 132.717763 -261.632655) (xy 132.766938 -261.630674) (xy 132.815793 -261.636606) (xy 132.863064 -261.650298)
			(xy 132.907526 -261.671396) (xy 132.948029 -261.699352) (xy 132.983522 -261.733444) (xy 133.013087 -261.772788)
			(xy 133.035958 -261.816365) (xy 133.051542 -261.863046) (xy 133.059437 -261.911623) (xy 133.059932 -261.93623)
			(xy 133.388874 -261.93623) (xy 133.392834 -261.887176) (xy 133.404611 -261.839392) (xy 133.423902 -261.794116)
			(xy 133.450205 -261.75252) (xy 133.48284 -261.715683) (xy 133.520961 -261.684558) (xy 133.563582 -261.659951)
			(xy 133.609598 -261.642499) (xy 133.657817 -261.632655) (xy 133.706992 -261.630674) (xy 133.755847 -261.636606)
			(xy 133.803118 -261.650298) (xy 133.84758 -261.671396) (xy 133.888083 -261.699352) (xy 133.923576 -261.733444)
			(xy 133.953141 -261.772788) (xy 133.976012 -261.816365) (xy 133.991596 -261.863046) (xy 133.999491 -261.911623)
			(xy 133.999986 -261.93623) (xy 134.318497 -261.93623) (xy 134.322592 -261.885502) (xy 134.334771 -261.836088)
			(xy 134.354719 -261.789268) (xy 134.38192 -261.746254) (xy 134.415668 -261.70816) (xy 134.45509 -261.675973)
			(xy 134.499164 -261.650527) (xy 134.54675 -261.63248) (xy 134.596614 -261.6223) (xy 134.647466 -261.620251)
			(xy 134.697987 -261.626385) (xy 134.746871 -261.640545) (xy 134.79285 -261.662362) (xy 134.834734 -261.691272)
			(xy 134.871438 -261.726527) (xy 134.902011 -261.767213) (xy 134.925662 -261.812276) (xy 134.941778 -261.86055)
			(xy 134.949942 -261.910784) (xy 134.950454 -261.93623) (xy 135.268982 -261.93623) (xy 135.272942 -261.887176)
			(xy 135.284719 -261.839392) (xy 135.30401 -261.794116) (xy 135.330313 -261.75252) (xy 135.362948 -261.715683)
			(xy 135.401069 -261.684558) (xy 135.44369 -261.659951) (xy 135.489706 -261.642499) (xy 135.537925 -261.632655)
			(xy 135.5871 -261.630674) (xy 135.635955 -261.636606) (xy 135.683226 -261.650298) (xy 135.727688 -261.671396)
			(xy 135.768191 -261.699352) (xy 135.803684 -261.733444) (xy 135.833249 -261.772788) (xy 135.85612 -261.816365)
			(xy 135.871704 -261.863046) (xy 135.879599 -261.911623) (xy 135.880094 -261.93623) (xy 136.209036 -261.93623)
			(xy 136.212996 -261.887176) (xy 136.224773 -261.839392) (xy 136.244064 -261.794116) (xy 136.270367 -261.75252)
			(xy 136.303002 -261.715683) (xy 136.341123 -261.684558) (xy 136.383744 -261.659951) (xy 136.42976 -261.642499)
			(xy 136.477979 -261.632655) (xy 136.527154 -261.630674) (xy 136.576009 -261.636606) (xy 136.62328 -261.650298)
			(xy 136.667742 -261.671396) (xy 136.708245 -261.699352) (xy 136.743738 -261.733444) (xy 136.773303 -261.772788)
			(xy 136.796174 -261.816365) (xy 136.811758 -261.863046) (xy 136.819653 -261.911623) (xy 136.820148 -261.93623)
			(xy 137.148836 -261.93623) (xy 137.152796 -261.887176) (xy 137.164573 -261.839392) (xy 137.183864 -261.794116)
			(xy 137.210167 -261.75252) (xy 137.242802 -261.715683) (xy 137.280923 -261.684558) (xy 137.323544 -261.659951)
			(xy 137.36956 -261.642499) (xy 137.417779 -261.632655) (xy 137.466954 -261.630674) (xy 137.515809 -261.636606)
			(xy 137.56308 -261.650298) (xy 137.607542 -261.671396) (xy 137.648045 -261.699352) (xy 137.683538 -261.733444)
			(xy 137.713103 -261.772788) (xy 137.735974 -261.816365) (xy 137.751558 -261.863046) (xy 137.759453 -261.911623)
			(xy 137.759948 -261.93623) (xy 138.078459 -261.93623) (xy 138.082554 -261.885502) (xy 138.094733 -261.836088)
			(xy 138.114681 -261.789268) (xy 138.141882 -261.746254) (xy 138.17563 -261.70816) (xy 138.215052 -261.675973)
			(xy 138.259126 -261.650527) (xy 138.306712 -261.63248) (xy 138.356576 -261.6223) (xy 138.407428 -261.620251)
			(xy 138.457949 -261.626385) (xy 138.506833 -261.640545) (xy 138.552812 -261.662362) (xy 138.594696 -261.691272)
			(xy 138.6314 -261.726527) (xy 138.661973 -261.767213) (xy 138.685624 -261.812276) (xy 138.70174 -261.86055)
			(xy 138.709904 -261.910784) (xy 138.710416 -261.93623) (xy 139.028944 -261.93623) (xy 139.032904 -261.887176)
			(xy 139.044681 -261.839392) (xy 139.063972 -261.794116) (xy 139.090275 -261.75252) (xy 139.12291 -261.715683)
			(xy 139.161031 -261.684558) (xy 139.203652 -261.659951) (xy 139.249668 -261.642499) (xy 139.297887 -261.632655)
			(xy 139.347062 -261.630674) (xy 139.395917 -261.636606) (xy 139.443188 -261.650298) (xy 139.48765 -261.671396)
			(xy 139.528153 -261.699352) (xy 139.563646 -261.733444) (xy 139.593211 -261.772788) (xy 139.616082 -261.816365)
			(xy 139.631666 -261.863046) (xy 139.639561 -261.911623) (xy 139.640056 -261.93623) (xy 139.968998 -261.93623)
			(xy 139.972958 -261.887176) (xy 139.984735 -261.839392) (xy 140.004026 -261.794116) (xy 140.030329 -261.75252)
			(xy 140.062964 -261.715683) (xy 140.101085 -261.684558) (xy 140.143706 -261.659951) (xy 140.189722 -261.642499)
			(xy 140.237941 -261.632655) (xy 140.287116 -261.630674) (xy 140.335971 -261.636606) (xy 140.383242 -261.650298)
			(xy 140.427704 -261.671396) (xy 140.468207 -261.699352) (xy 140.5037 -261.733444) (xy 140.533265 -261.772788)
			(xy 140.556136 -261.816365) (xy 140.57172 -261.863046) (xy 140.579615 -261.911623) (xy 140.58011 -261.93623)
			(xy 140.898621 -261.93623) (xy 140.902716 -261.885502) (xy 140.914895 -261.836088) (xy 140.934843 -261.789268)
			(xy 140.962044 -261.746254) (xy 140.995792 -261.70816) (xy 141.035214 -261.675973) (xy 141.079288 -261.650527)
			(xy 141.126874 -261.63248) (xy 141.176738 -261.6223) (xy 141.22759 -261.620251) (xy 141.278111 -261.626385)
			(xy 141.326995 -261.640545) (xy 141.372974 -261.662362) (xy 141.414858 -261.691272) (xy 141.451562 -261.726527)
			(xy 141.482135 -261.767213) (xy 141.505786 -261.812276) (xy 141.521902 -261.86055) (xy 141.530066 -261.910784)
			(xy 141.530578 -261.93623) (xy 141.848852 -261.93623) (xy 141.852812 -261.887176) (xy 141.864589 -261.839392)
			(xy 141.88388 -261.794116) (xy 141.910183 -261.75252) (xy 141.942818 -261.715683) (xy 141.980939 -261.684558)
			(xy 142.02356 -261.659951) (xy 142.069576 -261.642499) (xy 142.117795 -261.632655) (xy 142.16697 -261.630674)
			(xy 142.215825 -261.636606) (xy 142.263096 -261.650298) (xy 142.307558 -261.671396) (xy 142.348061 -261.699352)
			(xy 142.383554 -261.733444) (xy 142.413119 -261.772788) (xy 142.43599 -261.816365) (xy 142.451574 -261.863046)
			(xy 142.459469 -261.911623) (xy 142.459964 -261.93623) (xy 142.788906 -261.93623) (xy 142.792866 -261.887176)
			(xy 142.804643 -261.839392) (xy 142.823934 -261.794116) (xy 142.850237 -261.75252) (xy 142.882872 -261.715683)
			(xy 142.920993 -261.684558) (xy 142.963614 -261.659951) (xy 143.00963 -261.642499) (xy 143.057849 -261.632655)
			(xy 143.107024 -261.630674) (xy 143.155879 -261.636606) (xy 143.20315 -261.650298) (xy 143.247612 -261.671396)
			(xy 143.288115 -261.699352) (xy 143.323608 -261.733444) (xy 143.353173 -261.772788) (xy 143.376044 -261.816365)
			(xy 143.391628 -261.863046) (xy 143.399523 -261.911623) (xy 143.400018 -261.93623) (xy 143.72896 -261.93623)
			(xy 143.73292 -261.887176) (xy 143.744697 -261.839392) (xy 143.763988 -261.794116) (xy 143.790291 -261.75252)
			(xy 143.822926 -261.715683) (xy 143.861047 -261.684558) (xy 143.903668 -261.659951) (xy 143.949684 -261.642499)
			(xy 143.997903 -261.632655) (xy 144.047078 -261.630674) (xy 144.095933 -261.636606) (xy 144.143204 -261.650298)
			(xy 144.187666 -261.671396) (xy 144.228169 -261.699352) (xy 144.263662 -261.733444) (xy 144.293227 -261.772788)
			(xy 144.316098 -261.816365) (xy 144.331682 -261.863046) (xy 144.339577 -261.911623) (xy 144.340072 -261.93623)
			(xy 144.339577 -261.960837) (xy 144.331682 -262.009414) (xy 144.316098 -262.056095) (xy 144.293227 -262.099672)
			(xy 144.263662 -262.139016) (xy 144.228169 -262.173108) (xy 144.187666 -262.201064) (xy 144.143204 -262.222162)
			(xy 144.095933 -262.235854) (xy 144.047078 -262.241786) (xy 143.997903 -262.239805) (xy 143.949684 -262.229961)
			(xy 143.903668 -262.212509) (xy 143.861047 -262.187902) (xy 143.822926 -262.156777) (xy 143.790291 -262.11994)
			(xy 143.763988 -262.078344) (xy 143.744697 -262.033068) (xy 143.73292 -261.985284) (xy 143.72896 -261.93623)
			(xy 143.400018 -261.93623) (xy 143.399523 -261.960837) (xy 143.391628 -262.009414) (xy 143.376044 -262.056095)
			(xy 143.353173 -262.099672) (xy 143.323608 -262.139016) (xy 143.288115 -262.173108) (xy 143.247612 -262.201064)
			(xy 143.20315 -262.222162) (xy 143.155879 -262.235854) (xy 143.107024 -262.241786) (xy 143.057849 -262.239805)
			(xy 143.00963 -262.229961) (xy 142.963614 -262.212509) (xy 142.920993 -262.187902) (xy 142.882872 -262.156777)
			(xy 142.850237 -262.11994) (xy 142.823934 -262.078344) (xy 142.804643 -262.033068) (xy 142.792866 -261.985284)
			(xy 142.788906 -261.93623) (xy 142.459964 -261.93623) (xy 142.459469 -261.960837) (xy 142.451574 -262.009414)
			(xy 142.43599 -262.056095) (xy 142.413119 -262.099672) (xy 142.383554 -262.139016) (xy 142.348061 -262.173108)
			(xy 142.307558 -262.201064) (xy 142.263096 -262.222162) (xy 142.215825 -262.235854) (xy 142.16697 -262.241786)
			(xy 142.117795 -262.239805) (xy 142.069576 -262.229961) (xy 142.02356 -262.212509) (xy 141.980939 -262.187902)
			(xy 141.942818 -262.156777) (xy 141.910183 -262.11994) (xy 141.88388 -262.078344) (xy 141.864589 -262.033068)
			(xy 141.852812 -261.985284) (xy 141.848852 -261.93623) (xy 141.530578 -261.93623) (xy 141.530066 -261.961676)
			(xy 141.521902 -262.01191) (xy 141.505786 -262.060184) (xy 141.482135 -262.105247) (xy 141.451562 -262.145933)
			(xy 141.414858 -262.181188) (xy 141.372974 -262.210098) (xy 141.326995 -262.231915) (xy 141.278111 -262.246075)
			(xy 141.22759 -262.252209) (xy 141.176738 -262.25016) (xy 141.126874 -262.23998) (xy 141.079288 -262.221933)
			(xy 141.035214 -262.196487) (xy 140.995792 -262.1643) (xy 140.962044 -262.126206) (xy 140.934843 -262.083192)
			(xy 140.914895 -262.036372) (xy 140.902716 -261.986958) (xy 140.898621 -261.93623) (xy 140.58011 -261.93623)
			(xy 140.579615 -261.960837) (xy 140.57172 -262.009414) (xy 140.556136 -262.056095) (xy 140.533265 -262.099672)
			(xy 140.5037 -262.139016) (xy 140.468207 -262.173108) (xy 140.427704 -262.201064) (xy 140.383242 -262.222162)
			(xy 140.335971 -262.235854) (xy 140.287116 -262.241786) (xy 140.237941 -262.239805) (xy 140.189722 -262.229961)
			(xy 140.143706 -262.212509) (xy 140.101085 -262.187902) (xy 140.062964 -262.156777) (xy 140.030329 -262.11994)
			(xy 140.004026 -262.078344) (xy 139.984735 -262.033068) (xy 139.972958 -261.985284) (xy 139.968998 -261.93623)
			(xy 139.640056 -261.93623) (xy 139.639561 -261.960837) (xy 139.631666 -262.009414) (xy 139.616082 -262.056095)
			(xy 139.593211 -262.099672) (xy 139.563646 -262.139016) (xy 139.528153 -262.173108) (xy 139.48765 -262.201064)
			(xy 139.443188 -262.222162) (xy 139.395917 -262.235854) (xy 139.347062 -262.241786) (xy 139.297887 -262.239805)
			(xy 139.249668 -262.229961) (xy 139.203652 -262.212509) (xy 139.161031 -262.187902) (xy 139.12291 -262.156777)
			(xy 139.090275 -262.11994) (xy 139.063972 -262.078344) (xy 139.044681 -262.033068) (xy 139.032904 -261.985284)
			(xy 139.028944 -261.93623) (xy 138.710416 -261.93623) (xy 138.709904 -261.961676) (xy 138.70174 -262.01191)
			(xy 138.685624 -262.060184) (xy 138.661973 -262.105247) (xy 138.6314 -262.145933) (xy 138.594696 -262.181188)
			(xy 138.552812 -262.210098) (xy 138.506833 -262.231915) (xy 138.457949 -262.246075) (xy 138.407428 -262.252209)
			(xy 138.356576 -262.25016) (xy 138.306712 -262.23998) (xy 138.259126 -262.221933) (xy 138.215052 -262.196487)
			(xy 138.17563 -262.1643) (xy 138.141882 -262.126206) (xy 138.114681 -262.083192) (xy 138.094733 -262.036372)
			(xy 138.082554 -261.986958) (xy 138.078459 -261.93623) (xy 137.759948 -261.93623) (xy 137.759453 -261.960837)
			(xy 137.751558 -262.009414) (xy 137.735974 -262.056095) (xy 137.713103 -262.099672) (xy 137.683538 -262.139016)
			(xy 137.648045 -262.173108) (xy 137.607542 -262.201064) (xy 137.56308 -262.222162) (xy 137.515809 -262.235854)
			(xy 137.466954 -262.241786) (xy 137.417779 -262.239805) (xy 137.36956 -262.229961) (xy 137.323544 -262.212509)
			(xy 137.280923 -262.187902) (xy 137.242802 -262.156777) (xy 137.210167 -262.11994) (xy 137.183864 -262.078344)
			(xy 137.164573 -262.033068) (xy 137.152796 -261.985284) (xy 137.148836 -261.93623) (xy 136.820148 -261.93623)
			(xy 136.819653 -261.960837) (xy 136.811758 -262.009414) (xy 136.796174 -262.056095) (xy 136.773303 -262.099672)
			(xy 136.743738 -262.139016) (xy 136.708245 -262.173108) (xy 136.667742 -262.201064) (xy 136.62328 -262.222162)
			(xy 136.576009 -262.235854) (xy 136.527154 -262.241786) (xy 136.477979 -262.239805) (xy 136.42976 -262.229961)
			(xy 136.383744 -262.212509) (xy 136.341123 -262.187902) (xy 136.303002 -262.156777) (xy 136.270367 -262.11994)
			(xy 136.244064 -262.078344) (xy 136.224773 -262.033068) (xy 136.212996 -261.985284) (xy 136.209036 -261.93623)
			(xy 135.880094 -261.93623) (xy 135.879599 -261.960837) (xy 135.871704 -262.009414) (xy 135.85612 -262.056095)
			(xy 135.833249 -262.099672) (xy 135.803684 -262.139016) (xy 135.768191 -262.173108) (xy 135.727688 -262.201064)
			(xy 135.683226 -262.222162) (xy 135.635955 -262.235854) (xy 135.5871 -262.241786) (xy 135.537925 -262.239805)
			(xy 135.489706 -262.229961) (xy 135.44369 -262.212509) (xy 135.401069 -262.187902) (xy 135.362948 -262.156777)
			(xy 135.330313 -262.11994) (xy 135.30401 -262.078344) (xy 135.284719 -262.033068) (xy 135.272942 -261.985284)
			(xy 135.268982 -261.93623) (xy 134.950454 -261.93623) (xy 134.949942 -261.961676) (xy 134.941778 -262.01191)
			(xy 134.925662 -262.060184) (xy 134.902011 -262.105247) (xy 134.871438 -262.145933) (xy 134.834734 -262.181188)
			(xy 134.79285 -262.210098) (xy 134.746871 -262.231915) (xy 134.697987 -262.246075) (xy 134.647466 -262.252209)
			(xy 134.596614 -262.25016) (xy 134.54675 -262.23998) (xy 134.499164 -262.221933) (xy 134.45509 -262.196487)
			(xy 134.415668 -262.1643) (xy 134.38192 -262.126206) (xy 134.354719 -262.083192) (xy 134.334771 -262.036372)
			(xy 134.322592 -261.986958) (xy 134.318497 -261.93623) (xy 133.999986 -261.93623) (xy 133.999491 -261.960837)
			(xy 133.991596 -262.009414) (xy 133.976012 -262.056095) (xy 133.953141 -262.099672) (xy 133.923576 -262.139016)
			(xy 133.888083 -262.173108) (xy 133.84758 -262.201064) (xy 133.803118 -262.222162) (xy 133.755847 -262.235854)
			(xy 133.706992 -262.241786) (xy 133.657817 -262.239805) (xy 133.609598 -262.229961) (xy 133.563582 -262.212509)
			(xy 133.520961 -262.187902) (xy 133.48284 -262.156777) (xy 133.450205 -262.11994) (xy 133.423902 -262.078344)
			(xy 133.404611 -262.033068) (xy 133.392834 -261.985284) (xy 133.388874 -261.93623) (xy 133.059932 -261.93623)
			(xy 133.059437 -261.960837) (xy 133.051542 -262.009414) (xy 133.035958 -262.056095) (xy 133.013087 -262.099672)
			(xy 132.983522 -262.139016) (xy 132.948029 -262.173108) (xy 132.907526 -262.201064) (xy 132.863064 -262.222162)
			(xy 132.815793 -262.235854) (xy 132.766938 -262.241786) (xy 132.717763 -262.239805) (xy 132.669544 -262.229961)
			(xy 132.623528 -262.212509) (xy 132.580907 -262.187902) (xy 132.542786 -262.156777) (xy 132.510151 -262.11994)
			(xy 132.483848 -262.078344) (xy 132.464557 -262.033068) (xy 132.45278 -261.985284) (xy 132.44882 -261.93623)
			(xy 132.130546 -261.93623) (xy 132.130034 -261.961676) (xy 132.12187 -262.01191) (xy 132.105754 -262.060184)
			(xy 132.082103 -262.105247) (xy 132.05153 -262.145933) (xy 132.014826 -262.181188) (xy 131.972942 -262.210098)
			(xy 131.926963 -262.231915) (xy 131.878079 -262.246075) (xy 131.827558 -262.252209) (xy 131.776706 -262.25016)
			(xy 131.726842 -262.23998) (xy 131.679256 -262.221933) (xy 131.635182 -262.196487) (xy 131.59576 -262.1643)
			(xy 131.562012 -262.126206) (xy 131.534811 -262.083192) (xy 131.514863 -262.036372) (xy 131.502684 -261.986958)
			(xy 131.498589 -261.93623) (xy 131.180078 -261.93623) (xy 131.179583 -261.960837) (xy 131.171688 -262.009414)
			(xy 131.156104 -262.056095) (xy 131.133233 -262.099672) (xy 131.103668 -262.139016) (xy 131.068175 -262.173108)
			(xy 131.027672 -262.201064) (xy 130.98321 -262.222162) (xy 130.935939 -262.235854) (xy 130.887084 -262.241786)
			(xy 130.837909 -262.239805) (xy 130.78969 -262.229961) (xy 130.743674 -262.212509) (xy 130.701053 -262.187902)
			(xy 130.662932 -262.156777) (xy 130.630297 -262.11994) (xy 130.603994 -262.078344) (xy 130.584703 -262.033068)
			(xy 130.572926 -261.985284) (xy 130.568966 -261.93623) (xy 130.240024 -261.93623) (xy 130.239529 -261.960837)
			(xy 130.231634 -262.009414) (xy 130.21605 -262.056095) (xy 130.193179 -262.099672) (xy 130.163614 -262.139016)
			(xy 130.128121 -262.173108) (xy 130.087618 -262.201064) (xy 130.043156 -262.222162) (xy 129.995885 -262.235854)
			(xy 129.94703 -262.241786) (xy 129.897855 -262.239805) (xy 129.849636 -262.229961) (xy 129.80362 -262.212509)
			(xy 129.760999 -262.187902) (xy 129.722878 -262.156777) (xy 129.690243 -262.11994) (xy 129.66394 -262.078344)
			(xy 129.644649 -262.033068) (xy 129.632872 -261.985284) (xy 129.628912 -261.93623) (xy 129.29997 -261.93623)
			(xy 129.299475 -261.960837) (xy 129.29158 -262.009414) (xy 129.275996 -262.056095) (xy 129.253125 -262.099672)
			(xy 129.22356 -262.139016) (xy 129.188067 -262.173108) (xy 129.147564 -262.201064) (xy 129.103102 -262.222162)
			(xy 129.055831 -262.235854) (xy 129.006976 -262.241786) (xy 128.957801 -262.239805) (xy 128.909582 -262.229961)
			(xy 128.863566 -262.212509) (xy 128.820945 -262.187902) (xy 128.782824 -262.156777) (xy 128.750189 -262.11994)
			(xy 128.723886 -262.078344) (xy 128.704595 -262.033068) (xy 128.692818 -261.985284) (xy 128.688858 -261.93623)
			(xy 128.370584 -261.93623) (xy 128.370072 -261.961676) (xy 128.361908 -262.01191) (xy 128.345792 -262.060184)
			(xy 128.322141 -262.105247) (xy 128.291568 -262.145933) (xy 128.254864 -262.181188) (xy 128.21298 -262.210098)
			(xy 128.167001 -262.231915) (xy 128.118117 -262.246075) (xy 128.067596 -262.252209) (xy 128.016744 -262.25016)
			(xy 127.96688 -262.23998) (xy 127.919294 -262.221933) (xy 127.87522 -262.196487) (xy 127.835798 -262.1643)
			(xy 127.80205 -262.126206) (xy 127.774849 -262.083192) (xy 127.754901 -262.036372) (xy 127.742722 -261.986958)
			(xy 127.738627 -261.93623) (xy 126.480062 -261.93623) (xy 126.479567 -261.960837) (xy 126.471672 -262.009414)
			(xy 126.456088 -262.056095) (xy 126.433217 -262.099672) (xy 126.403652 -262.139016) (xy 126.368159 -262.173108)
			(xy 126.327656 -262.201064) (xy 126.283194 -262.222162) (xy 126.235923 -262.235854) (xy 126.187068 -262.241786)
			(xy 126.137893 -262.239805) (xy 126.089674 -262.229961) (xy 126.043658 -262.212509) (xy 126.001037 -262.187902)
			(xy 125.962916 -262.156777) (xy 125.930281 -262.11994) (xy 125.903978 -262.078344) (xy 125.884687 -262.033068)
			(xy 125.87291 -261.985284) (xy 125.86895 -261.93623) (xy 124.599954 -261.93623) (xy 124.599459 -261.960837)
			(xy 124.591564 -262.009414) (xy 124.57598 -262.056095) (xy 124.553109 -262.099672) (xy 124.523544 -262.139016)
			(xy 124.488051 -262.173108) (xy 124.447548 -262.201064) (xy 124.403086 -262.222162) (xy 124.355815 -262.235854)
			(xy 124.30696 -262.241786) (xy 124.257785 -262.239805) (xy 124.209566 -262.229961) (xy 124.16355 -262.212509)
			(xy 124.120929 -262.187902) (xy 124.082808 -262.156777) (xy 124.050173 -262.11994) (xy 124.02387 -262.078344)
			(xy 124.004579 -262.033068) (xy 123.992802 -261.985284) (xy 123.988842 -261.93623) (xy 122.7201 -261.93623)
			(xy 122.719605 -261.960837) (xy 122.71171 -262.009414) (xy 122.696126 -262.056095) (xy 122.673255 -262.099672)
			(xy 122.64369 -262.139016) (xy 122.608197 -262.173108) (xy 122.567694 -262.201064) (xy 122.523232 -262.222162)
			(xy 122.475961 -262.235854) (xy 122.427106 -262.241786) (xy 122.377931 -262.239805) (xy 122.329712 -262.229961)
			(xy 122.283696 -262.212509) (xy 122.241075 -262.187902) (xy 122.202954 -262.156777) (xy 122.170319 -262.11994)
			(xy 122.144016 -262.078344) (xy 122.124725 -262.033068) (xy 122.112948 -261.985284) (xy 122.108988 -261.93623)
			(xy 118.94439 -261.93623) (xy 119.939054 -262.930894) (xy 119.939562 -262.931402) (xy 119.946941 -262.937988)
			(xy 119.965241 -262.945443) (xy 119.975122 -262.94588)
		)
		(stroke
			(width 0)
			(type solid)
		)
		(fill yes)
		(layer "In15.Cu")
		(net "PVDDCR_SOC_P1")
	)
	(gr_poly
		(pts
			(xy 388.314184 -266.2555) (xy 388.326917 -266.254797) (xy 388.349311 -266.242667) (xy 388.356856 -266.232386)
			(xy 388.410196 -266.149582) (xy 388.411974 -266.123928) (xy 388.40664 -266.11199) (xy 388.398055 -266.092108)
			(xy 388.385948 -266.05053) (xy 388.379833 -266.007659) (xy 388.379462 -265.986006) (xy 388.379932 -265.962014)
			(xy 388.387437 -265.914619) (xy 388.402264 -265.868983) (xy 388.424047 -265.826227) (xy 388.452249 -265.787405)
			(xy 388.486178 -265.753473) (xy 388.524996 -265.725265) (xy 388.567749 -265.703478) (xy 388.613384 -265.688646)
			(xy 388.660778 -265.681135) (xy 388.68477 -265.680698) (xy 388.709005 -265.681168) (xy 388.756866 -265.688835)
			(xy 388.802914 -265.703966) (xy 388.845995 -265.72618) (xy 388.885025 -265.754921) (xy 388.919027 -265.789465)
			(xy 388.947144 -265.828947) (xy 388.968673 -265.872374) (xy 388.983072 -265.918657) (xy 388.98703 -265.942572)
			(xy 388.988808 -265.955526) (xy 388.990332 -265.986006) (xy 388.989973 -266.007702) (xy 388.983878 -266.050662)
			(xy 388.971768 -266.092329) (xy 388.963154 -266.112244) (xy 388.957566 -266.124182) (xy 388.959598 -266.149836)
			(xy 389.012684 -266.232386) (xy 389.017545 -266.239322) (xy 389.03088 -266.249748) (xy 389.046892 -266.255236)
			(xy 389.055356 -266.2555) (xy 389.249666 -266.2555) (xy 389.262401 -266.254801) (xy 389.284802 -266.242675)
			(xy 389.292338 -266.232386) (xy 389.345932 -266.149836) (xy 389.346948 -266.135866) (xy 389.335122 -266.112675)
			(xy 389.318363 -266.063391) (xy 389.30987 -266.012034) (xy 389.309356 -265.986006) (xy 389.309842 -265.961216)
			(xy 389.317598 -265.912248) (xy 389.332919 -265.865095) (xy 389.355428 -265.82092) (xy 389.38457 -265.780809)
			(xy 389.419627 -265.745752) (xy 389.459738 -265.71661) (xy 389.503913 -265.694101) (xy 389.551066 -265.67878)
			(xy 389.600034 -265.671024) (xy 389.649614 -265.671024) (xy 389.698582 -265.67878) (xy 389.745735 -265.694101)
			(xy 389.78991 -265.71661) (xy 389.830021 -265.745752) (xy 389.865078 -265.780809) (xy 389.89422 -265.82092)
			(xy 389.916729 -265.865095) (xy 389.93205 -265.912248) (xy 389.939806 -265.961216) (xy 389.940292 -265.986006)
			(xy 389.939769 -266.012033) (xy 389.931277 -266.063389) (xy 389.914521 -266.112672) (xy 389.9027 -266.135866)
			(xy 389.903716 -266.149836) (xy 389.95731 -266.232386) (xy 389.962172 -266.239319) (xy 389.975508 -266.249738)
			(xy 389.991519 -266.255219) (xy 389.999982 -266.2555) (xy 390.194292 -266.2555) (xy 390.207024 -266.254796)
			(xy 390.229415 -266.242663) (xy 390.236964 -266.232386) (xy 390.290304 -266.149582) (xy 390.292082 -266.123928)
			(xy 390.286748 -266.11199) (xy 390.278163 -266.092108) (xy 390.266055 -266.05053) (xy 390.25994 -266.007659)
			(xy 390.25957 -265.986006) (xy 390.26004 -265.962014) (xy 390.267545 -265.91462) (xy 390.282372 -265.868984)
			(xy 390.304155 -265.826229) (xy 390.332358 -265.787408) (xy 390.366286 -265.753476) (xy 390.405105 -265.72527)
			(xy 390.447858 -265.703483) (xy 390.493493 -265.688652) (xy 390.540886 -265.681142) (xy 390.564878 -265.680698)
			(xy 390.589113 -265.681169) (xy 390.636972 -265.688837) (xy 390.68302 -265.703968) (xy 390.726099 -265.726183)
			(xy 390.765129 -265.754924) (xy 390.799129 -265.789468) (xy 390.827246 -265.828949) (xy 390.848774 -265.872376)
			(xy 390.863172 -265.918658) (xy 390.867138 -265.942572) (xy 390.868916 -265.955526) (xy 390.87044 -265.986006)
			(xy 390.870081 -266.007702) (xy 390.863986 -266.050662) (xy 390.851876 -266.092329) (xy 390.843262 -266.112244)
			(xy 390.837674 -266.124182) (xy 390.839706 -266.149836) (xy 390.892792 -266.232386) (xy 390.897653 -266.239321)
			(xy 390.910988 -266.249745) (xy 390.927 -266.255231) (xy 390.935464 -266.2555) (xy 393.0142 -266.2555)
			(xy 393.026931 -266.254794) (xy 393.049319 -266.24266) (xy 393.056872 -266.232386) (xy 393.110212 -266.149582)
			(xy 393.11199 -266.123928) (xy 393.106656 -266.11199) (xy 393.098071 -266.092108) (xy 393.085963 -266.05053)
			(xy 393.079847 -266.007659) (xy 393.079478 -265.986006) (xy 393.079948 -265.962014) (xy 393.087453 -265.914621)
			(xy 393.10228 -265.868985) (xy 393.124063 -265.826231) (xy 393.152266 -265.78741) (xy 393.186195 -265.753479)
			(xy 393.225014 -265.725274) (xy 393.267767 -265.703488) (xy 393.313401 -265.688658) (xy 393.360794 -265.68115)
			(xy 393.384786 -265.680698) (xy 393.40902 -265.681169) (xy 393.456879 -265.688839) (xy 393.502925 -265.703971)
			(xy 393.546004 -265.726186) (xy 393.585032 -265.754927) (xy 393.619031 -265.789471) (xy 393.647148 -265.828952)
			(xy 393.668675 -265.872378) (xy 393.683072 -265.91866) (xy 393.687046 -265.942572) (xy 393.688824 -265.955526)
			(xy 393.690348 -265.986006) (xy 393.689989 -266.007701) (xy 393.683892 -266.050661) (xy 393.671778 -266.092326)
			(xy 393.66317 -266.112244) (xy 393.657582 -266.124182) (xy 393.659614 -266.149836) (xy 393.7127 -266.232386)
			(xy 393.717561 -266.23932) (xy 393.730897 -266.249742) (xy 393.746909 -266.255226) (xy 393.755372 -266.2555)
			(xy 394.397738 -266.2555) (xy 394.407613 -266.255036) (xy 394.425907 -266.247588) (xy 394.433298 -266.241022)
			(xy 394.433552 -266.240768) (xy 395.427454 -265.246866) (xy 395.427962 -265.246358) (xy 395.434545 -265.238977)
			(xy 395.441998 -265.220678) (xy 395.44244 -265.210798) (xy 395.44244 -222.464122) (xy 395.442001 -222.454059)
			(xy 395.43426 -222.435481) (xy 395.427454 -222.428054) (xy 394.936726 -221.937326) (xy 394.929614 -221.92996)
			(xy 394.910818 -221.92234) (xy 392.914378 -221.92234) (xy 392.890248 -221.936564) (xy 392.883644 -221.94901)
			(xy 392.876164 -221.96258) (xy 392.858862 -221.988286) (xy 392.8491 -222.000318) (xy 392.84275 -222.007684)
			(xy 392.836654 -222.025718) (xy 392.840464 -222.10395) (xy 392.841339 -222.113254) (xy 392.84889 -222.130329)
			(xy 392.855196 -222.137224) (xy 393.04341 -222.325438) (xy 393.401042 -222.68307) (xy 393.408388 -222.689877)
			(xy 393.426851 -222.697599) (xy 393.436856 -222.698056) (xy 393.46378 -222.698056) (xy 393.499433 -222.698525)
			(xy 393.570294 -222.706484) (xy 393.639818 -222.722327) (xy 393.707131 -222.745855) (xy 393.771387 -222.776772)
			(xy 393.831777 -222.814688) (xy 393.887542 -222.859128) (xy 393.913106 -222.883984) (xy 393.960858 -222.931736)
			(xy 394.004038 -222.974916) (xy 394.030497 -223.002154) (xy 394.077408 -223.061871) (xy 394.116854 -223.126761)
			(xy 394.13307 -223.161098) (xy 394.13815 -223.172274) (xy 394.156946 -223.18726) (xy 394.260578 -223.209358)
			(xy 394.283692 -223.203262) (xy 394.292836 -223.195134) (xy 394.313936 -223.177337) (xy 394.361233 -223.148887)
			(xy 394.41287 -223.129393) (xy 394.467169 -223.119492) (xy 394.494766 -223.118934) (xy 394.520022 -223.119424)
			(xy 394.569846 -223.127733) (xy 394.617623 -223.14413) (xy 394.662049 -223.168168) (xy 394.701912 -223.19919)
			(xy 394.736125 -223.236351) (xy 394.763754 -223.278637) (xy 394.784046 -223.324894) (xy 394.796446 -223.37386)
			(xy 394.800618 -223.4242) (xy 394.796446 -223.47454) (xy 394.784046 -223.523506) (xy 394.763754 -223.569763)
			(xy 394.736125 -223.612049) (xy 394.701912 -223.64921) (xy 394.662049 -223.680232) (xy 394.617623 -223.70427)
			(xy 394.569846 -223.720667) (xy 394.520022 -223.728976) (xy 394.494766 -223.72955) (xy 394.467172 -223.728957)
			(xy 394.412879 -223.719051) (xy 394.361245 -223.699566) (xy 394.313943 -223.671135) (xy 394.292836 -223.65335)
			(xy 394.283692 -223.645222) (xy 394.260578 -223.639126) (xy 394.156946 -223.661224) (xy 394.13815 -223.67621)
			(xy 394.13307 -223.687132) (xy 394.127482 -223.69907) (xy 394.117442 -223.719577) (xy 394.094815 -223.759241)
			(xy 394.08227 -223.778318) (xy 394.077952 -223.784668) (xy 394.073634 -223.799146) (xy 394.073634 -223.848422)
			(xy 394.073721 -223.852366) (xy 394.074995 -223.860151) (xy 394.076174 -223.863916) (xy 394.091922 -223.912938)
			(xy 394.096171 -223.924068) (xy 394.112866 -223.941019) (xy 394.123926 -223.94545) (xy 394.124942 -223.945704)
			(xy 394.147102 -223.953879) (xy 394.188793 -223.976077) (xy 394.226574 -224.004423) (xy 394.259544 -224.038244)
			(xy 394.28692 -224.076733) (xy 394.308049 -224.118976) (xy 394.32243 -224.163966) (xy 394.329718 -224.210632)
			(xy 394.330174 -224.234248) (xy 394.329652 -224.259503) (xy 394.321339 -224.309325) (xy 394.304938 -224.357099)
			(xy 394.280897 -224.401522) (xy 394.249873 -224.441382) (xy 394.212711 -224.475592) (xy 394.170425 -224.503218)
			(xy 394.124169 -224.523508) (xy 394.075204 -224.535908) (xy 394.024866 -224.540079) (xy 393.974528 -224.535908)
			(xy 393.925563 -224.523508) (xy 393.879307 -224.503218) (xy 393.837021 -224.475592) (xy 393.799859 -224.441382)
			(xy 393.768835 -224.401522) (xy 393.744794 -224.357099) (xy 393.728393 -224.309325) (xy 393.72008 -224.259503)
			(xy 393.719558 -224.234248) (xy 393.719703 -224.219811) (xy 393.722373 -224.191061) (xy 393.724892 -224.176844)
			(xy 393.727178 -224.164906) (xy 393.720828 -224.1423) (xy 393.65809 -224.072958) (xy 393.653933 -224.068683)
			(xy 393.644048 -224.062017) (xy 393.638532 -224.05975) (xy 393.627356 -224.055432) (xy 393.609257 -224.057352)
			(xy 393.572913 -224.059384) (xy 393.554712 -224.059496) (xy 393.539513 -224.059439) (xy 393.509146 -224.058044)
			(xy 393.494006 -224.056702) (xy 393.481814 -224.055686) (xy 393.45997 -224.064068) (xy 393.38885 -224.1423)
			(xy 393.3825 -224.164906) (xy 393.384786 -224.176844) (xy 393.387311 -224.19106) (xy 393.389981 -224.21981)
			(xy 393.39012 -224.234248) (xy 393.389598 -224.259503) (xy 393.381285 -224.309325) (xy 393.364884 -224.357099)
			(xy 393.340843 -224.401522) (xy 393.309819 -224.441382) (xy 393.272657 -224.475592) (xy 393.230371 -224.503218)
			(xy 393.184115 -224.523508) (xy 393.13515 -224.535908) (xy 393.084812 -224.540079) (xy 393.034474 -224.535908)
			(xy 392.985509 -224.523508) (xy 392.939253 -224.503218) (xy 392.896967 -224.475592) (xy 392.859805 -224.441382)
			(xy 392.828781 -224.401522) (xy 392.80474 -224.357099) (xy 392.788339 -224.309325) (xy 392.780026 -224.259503)
			(xy 392.779504 -224.234248) (xy 392.779648 -224.219811) (xy 392.782319 -224.19106) (xy 392.784838 -224.176844)
			(xy 392.787124 -224.164906) (xy 392.780774 -224.1423) (xy 392.709654 -224.064068) (xy 392.68781 -224.055686)
			(xy 392.675618 -224.056702) (xy 392.660477 -224.058032) (xy 392.630111 -224.059431) (xy 392.614912 -224.059496)
			(xy 392.577845 -224.058975) (xy 392.504214 -224.05035) (xy 392.432086 -224.033217) (xy 392.362442 -224.007807)
			(xy 392.296228 -223.974467) (xy 392.234343 -223.933649) (xy 392.177627 -223.885907) (xy 392.126852 -223.831891)
			(xy 392.082707 -223.772333) (xy 392.045791 -223.708044) (xy 392.030712 -223.674178) (xy 392.026902 -223.665288)
			(xy 391.305288 -222.94342) (xy 391.281158 -222.936308) (xy 391.268712 -222.938594) (xy 391.252874 -222.941546)
			(xy 391.220813 -222.944723) (xy 391.204704 -222.944944) (xy 391.178716 -222.944435) (xy 391.127379 -222.936305)
			(xy 391.077945 -222.920245) (xy 391.031632 -222.89665) (xy 390.989581 -222.866101) (xy 390.952825 -222.82935)
			(xy 390.922271 -222.787302) (xy 390.898671 -222.740992) (xy 390.882604 -222.69156) (xy 390.874468 -222.640224)
			(xy 390.873996 -222.614236) (xy 390.874216 -222.598127) (xy 390.8774 -222.566067) (xy 390.880346 -222.550228)
			(xy 390.882632 -222.537782) (xy 390.87552 -222.513652) (xy 390.49452 -222.132906) (xy 390.29894 -221.937326)
			(xy 390.291828 -221.92996) (xy 390.273032 -221.92234) (xy 389.154162 -221.92234) (xy 389.130032 -221.936564)
			(xy 389.123428 -221.94901) (xy 389.110993 -221.971045) (xy 389.079981 -222.01102) (xy 389.042802 -222.045335)
			(xy 389.000475 -222.07305) (xy 388.954157 -222.093406) (xy 388.905116 -222.105848) (xy 388.854696 -222.110033)
			(xy 388.804276 -222.105848) (xy 388.755235 -222.093406) (xy 388.708917 -222.07305) (xy 388.66659 -222.045335)
			(xy 388.629411 -222.01102) (xy 388.598399 -221.971045) (xy 388.585964 -221.94901) (xy 388.57936 -221.936564)
			(xy 388.55523 -221.92234) (xy 388.214362 -221.92234) (xy 388.190232 -221.936564) (xy 388.183628 -221.94901)
			(xy 388.171193 -221.971045) (xy 388.140181 -222.01102) (xy 388.103002 -222.045335) (xy 388.060675 -222.07305)
			(xy 388.014357 -222.093406) (xy 387.965316 -222.105848) (xy 387.914896 -222.110033) (xy 387.864476 -222.105848)
			(xy 387.815435 -222.093406) (xy 387.769117 -222.07305) (xy 387.72679 -222.045335) (xy 387.689611 -222.01102)
			(xy 387.658599 -221.971045) (xy 387.646164 -221.94901) (xy 387.63956 -221.936564) (xy 387.61543 -221.92234)
			(xy 387.274308 -221.92234) (xy 387.250178 -221.936564) (xy 387.243574 -221.94901) (xy 387.231139 -221.971045)
			(xy 387.200127 -222.01102) (xy 387.162948 -222.045335) (xy 387.120621 -222.07305) (xy 387.074303 -222.093406)
			(xy 387.025262 -222.105848) (xy 386.974842 -222.110033) (xy 386.924422 -222.105848) (xy 386.875381 -222.093406)
			(xy 386.829063 -222.07305) (xy 386.786736 -222.045335) (xy 386.749557 -222.01102) (xy 386.718545 -221.971045)
			(xy 386.70611 -221.94901) (xy 386.699506 -221.936564) (xy 386.675376 -221.92234) (xy 386.334254 -221.92234)
			(xy 386.310124 -221.936564) (xy 386.30352 -221.94901) (xy 386.291085 -221.971045) (xy 386.260073 -222.01102)
			(xy 386.222894 -222.045335) (xy 386.180567 -222.07305) (xy 386.134249 -222.093406) (xy 386.085208 -222.105848)
			(xy 386.034788 -222.110033) (xy 385.984368 -222.105848) (xy 385.935327 -222.093406) (xy 385.889009 -222.07305)
			(xy 385.846682 -222.045335) (xy 385.809503 -222.01102) (xy 385.778491 -221.971045) (xy 385.766056 -221.94901)
			(xy 385.759452 -221.936564) (xy 385.735322 -221.92234) (xy 385.3942 -221.92234) (xy 385.37007 -221.936564)
			(xy 385.363466 -221.94901) (xy 385.351031 -221.971045) (xy 385.320019 -222.01102) (xy 385.28284 -222.045335)
			(xy 385.240513 -222.07305) (xy 385.194195 -222.093406) (xy 385.145154 -222.105848) (xy 385.094734 -222.110033)
			(xy 385.044314 -222.105848) (xy 384.995273 -222.093406) (xy 384.948955 -222.07305) (xy 384.906628 -222.045335)
			(xy 384.869449 -222.01102) (xy 384.838437 -221.971045) (xy 384.826002 -221.94901) (xy 384.819398 -221.936564)
			(xy 384.795268 -221.92234) (xy 381.800862 -221.92234) (xy 381.790796 -221.922771) (xy 381.772205 -221.9305)
			(xy 381.764794 -221.937326) (xy 381.087884 -222.614236) (xy 382.438922 -222.614236) (xy 382.442882 -222.565182)
			(xy 382.454659 -222.517398) (xy 382.47395 -222.472122) (xy 382.500253 -222.430526) (xy 382.532888 -222.393689)
			(xy 382.571009 -222.362564) (xy 382.61363 -222.337957) (xy 382.659646 -222.320505) (xy 382.707865 -222.310661)
			(xy 382.75704 -222.30868) (xy 382.805895 -222.314612) (xy 382.853166 -222.328304) (xy 382.897628 -222.349402)
			(xy 382.938131 -222.377358) (xy 382.973624 -222.41145) (xy 383.003189 -222.450794) (xy 383.02606 -222.494371)
			(xy 383.041644 -222.541052) (xy 383.049539 -222.589629) (xy 383.050034 -222.614236) (xy 383.378976 -222.614236)
			(xy 383.382936 -222.565182) (xy 383.394713 -222.517398) (xy 383.414004 -222.472122) (xy 383.440307 -222.430526)
			(xy 383.472942 -222.393689) (xy 383.511063 -222.362564) (xy 383.553684 -222.337957) (xy 383.5997 -222.320505)
			(xy 383.647919 -222.310661) (xy 383.697094 -222.30868) (xy 383.745949 -222.314612) (xy 383.79322 -222.328304)
			(xy 383.837682 -222.349402) (xy 383.878185 -222.377358) (xy 383.913678 -222.41145) (xy 383.943243 -222.450794)
			(xy 383.966114 -222.494371) (xy 383.981698 -222.541052) (xy 383.989593 -222.589629) (xy 383.990088 -222.614236)
			(xy 384.31903 -222.614236) (xy 384.32299 -222.565182) (xy 384.334767 -222.517398) (xy 384.354058 -222.472122)
			(xy 384.380361 -222.430526) (xy 384.412996 -222.393689) (xy 384.451117 -222.362564) (xy 384.493738 -222.337957)
			(xy 384.539754 -222.320505) (xy 384.587973 -222.310661) (xy 384.637148 -222.30868) (xy 384.686003 -222.314612)
			(xy 384.733274 -222.328304) (xy 384.777736 -222.349402) (xy 384.818239 -222.377358) (xy 384.853732 -222.41145)
			(xy 384.883297 -222.450794) (xy 384.906168 -222.494371) (xy 384.921752 -222.541052) (xy 384.929647 -222.589629)
			(xy 384.930142 -222.614236) (xy 385.259084 -222.614236) (xy 385.263044 -222.565182) (xy 385.274821 -222.517398)
			(xy 385.294112 -222.472122) (xy 385.320415 -222.430526) (xy 385.35305 -222.393689) (xy 385.391171 -222.362564)
			(xy 385.433792 -222.337957) (xy 385.479808 -222.320505) (xy 385.528027 -222.310661) (xy 385.577202 -222.30868)
			(xy 385.626057 -222.314612) (xy 385.673328 -222.328304) (xy 385.71779 -222.349402) (xy 385.758293 -222.377358)
			(xy 385.793786 -222.41145) (xy 385.823351 -222.450794) (xy 385.846222 -222.494371) (xy 385.861806 -222.541052)
			(xy 385.869701 -222.589629) (xy 385.870196 -222.614236) (xy 386.199138 -222.614236) (xy 386.203098 -222.565182)
			(xy 386.214875 -222.517398) (xy 386.234166 -222.472122) (xy 386.260469 -222.430526) (xy 386.293104 -222.393689)
			(xy 386.331225 -222.362564) (xy 386.373846 -222.337957) (xy 386.419862 -222.320505) (xy 386.468081 -222.310661)
			(xy 386.517256 -222.30868) (xy 386.566111 -222.314612) (xy 386.613382 -222.328304) (xy 386.657844 -222.349402)
			(xy 386.698347 -222.377358) (xy 386.73384 -222.41145) (xy 386.763405 -222.450794) (xy 386.786276 -222.494371)
			(xy 386.80186 -222.541052) (xy 386.809755 -222.589629) (xy 386.81025 -222.614236) (xy 387.138938 -222.614236)
			(xy 387.142898 -222.565182) (xy 387.154675 -222.517398) (xy 387.173966 -222.472122) (xy 387.200269 -222.430526)
			(xy 387.232904 -222.393689) (xy 387.271025 -222.362564) (xy 387.313646 -222.337957) (xy 387.359662 -222.320505)
			(xy 387.407881 -222.310661) (xy 387.457056 -222.30868) (xy 387.505911 -222.314612) (xy 387.553182 -222.328304)
			(xy 387.597644 -222.349402) (xy 387.638147 -222.377358) (xy 387.67364 -222.41145) (xy 387.703205 -222.450794)
			(xy 387.726076 -222.494371) (xy 387.74166 -222.541052) (xy 387.749555 -222.589629) (xy 387.75005 -222.614236)
			(xy 388.078992 -222.614236) (xy 388.082952 -222.565182) (xy 388.094729 -222.517398) (xy 388.11402 -222.472122)
			(xy 388.140323 -222.430526) (xy 388.172958 -222.393689) (xy 388.211079 -222.362564) (xy 388.2537 -222.337957)
			(xy 388.299716 -222.320505) (xy 388.347935 -222.310661) (xy 388.39711 -222.30868) (xy 388.445965 -222.314612)
			(xy 388.493236 -222.328304) (xy 388.537698 -222.349402) (xy 388.578201 -222.377358) (xy 388.613694 -222.41145)
			(xy 388.643259 -222.450794) (xy 388.66613 -222.494371) (xy 388.681714 -222.541052) (xy 388.689609 -222.589629)
			(xy 388.690104 -222.614236) (xy 389.9591 -222.614236) (xy 389.96306 -222.565182) (xy 389.974837 -222.517398)
			(xy 389.994128 -222.472122) (xy 390.020431 -222.430526) (xy 390.053066 -222.393689) (xy 390.091187 -222.362564)
			(xy 390.133808 -222.337957) (xy 390.179824 -222.320505) (xy 390.228043 -222.310661) (xy 390.277218 -222.30868)
			(xy 390.326073 -222.314612) (xy 390.373344 -222.328304) (xy 390.417806 -222.349402) (xy 390.458309 -222.377358)
			(xy 390.493802 -222.41145) (xy 390.523367 -222.450794) (xy 390.546238 -222.494371) (xy 390.561822 -222.541052)
			(xy 390.569717 -222.589629) (xy 390.570212 -222.614236) (xy 390.569717 -222.638843) (xy 390.561822 -222.68742)
			(xy 390.546238 -222.734101) (xy 390.523367 -222.777678) (xy 390.493802 -222.817022) (xy 390.458309 -222.851114)
			(xy 390.417806 -222.87907) (xy 390.373344 -222.900168) (xy 390.326073 -222.91386) (xy 390.277218 -222.919792)
			(xy 390.228043 -222.917811) (xy 390.179824 -222.907967) (xy 390.133808 -222.890515) (xy 390.091187 -222.865908)
			(xy 390.053066 -222.834783) (xy 390.020431 -222.797946) (xy 389.994128 -222.75635) (xy 389.974837 -222.711074)
			(xy 389.96306 -222.66329) (xy 389.9591 -222.614236) (xy 388.690104 -222.614236) (xy 388.689609 -222.638843)
			(xy 388.681714 -222.68742) (xy 388.66613 -222.734101) (xy 388.643259 -222.777678) (xy 388.613694 -222.817022)
			(xy 388.578201 -222.851114) (xy 388.537698 -222.87907) (xy 388.493236 -222.900168) (xy 388.445965 -222.91386)
			(xy 388.39711 -222.919792) (xy 388.347935 -222.917811) (xy 388.299716 -222.907967) (xy 388.2537 -222.890515)
			(xy 388.211079 -222.865908) (xy 388.172958 -222.834783) (xy 388.140323 -222.797946) (xy 388.11402 -222.75635)
			(xy 388.094729 -222.711074) (xy 388.082952 -222.66329) (xy 388.078992 -222.614236) (xy 387.75005 -222.614236)
			(xy 387.749555 -222.638843) (xy 387.74166 -222.68742) (xy 387.726076 -222.734101) (xy 387.703205 -222.777678)
			(xy 387.67364 -222.817022) (xy 387.638147 -222.851114) (xy 387.597644 -222.87907) (xy 387.553182 -222.900168)
			(xy 387.505911 -222.91386) (xy 387.457056 -222.919792) (xy 387.407881 -222.917811) (xy 387.359662 -222.907967)
			(xy 387.313646 -222.890515) (xy 387.271025 -222.865908) (xy 387.232904 -222.834783) (xy 387.200269 -222.797946)
			(xy 387.173966 -222.75635) (xy 387.154675 -222.711074) (xy 387.142898 -222.66329) (xy 387.138938 -222.614236)
			(xy 386.81025 -222.614236) (xy 386.809755 -222.638843) (xy 386.80186 -222.68742) (xy 386.786276 -222.734101)
			(xy 386.763405 -222.777678) (xy 386.73384 -222.817022) (xy 386.698347 -222.851114) (xy 386.657844 -222.87907)
			(xy 386.613382 -222.900168) (xy 386.566111 -222.91386) (xy 386.517256 -222.919792) (xy 386.468081 -222.917811)
			(xy 386.419862 -222.907967) (xy 386.373846 -222.890515) (xy 386.331225 -222.865908) (xy 386.293104 -222.834783)
			(xy 386.260469 -222.797946) (xy 386.234166 -222.75635) (xy 386.214875 -222.711074) (xy 386.203098 -222.66329)
			(xy 386.199138 -222.614236) (xy 385.870196 -222.614236) (xy 385.869701 -222.638843) (xy 385.861806 -222.68742)
			(xy 385.846222 -222.734101) (xy 385.823351 -222.777678) (xy 385.793786 -222.817022) (xy 385.758293 -222.851114)
			(xy 385.71779 -222.87907) (xy 385.673328 -222.900168) (xy 385.626057 -222.91386) (xy 385.577202 -222.919792)
			(xy 385.528027 -222.917811) (xy 385.479808 -222.907967) (xy 385.433792 -222.890515) (xy 385.391171 -222.865908)
			(xy 385.35305 -222.834783) (xy 385.320415 -222.797946) (xy 385.294112 -222.75635) (xy 385.274821 -222.711074)
			(xy 385.263044 -222.66329) (xy 385.259084 -222.614236) (xy 384.930142 -222.614236) (xy 384.929647 -222.638843)
			(xy 384.921752 -222.68742) (xy 384.906168 -222.734101) (xy 384.883297 -222.777678) (xy 384.853732 -222.817022)
			(xy 384.818239 -222.851114) (xy 384.777736 -222.87907) (xy 384.733274 -222.900168) (xy 384.686003 -222.91386)
			(xy 384.637148 -222.919792) (xy 384.587973 -222.917811) (xy 384.539754 -222.907967) (xy 384.493738 -222.890515)
			(xy 384.451117 -222.865908) (xy 384.412996 -222.834783) (xy 384.380361 -222.797946) (xy 384.354058 -222.75635)
			(xy 384.334767 -222.711074) (xy 384.32299 -222.66329) (xy 384.31903 -222.614236) (xy 383.990088 -222.614236)
			(xy 383.989593 -222.638843) (xy 383.981698 -222.68742) (xy 383.966114 -222.734101) (xy 383.943243 -222.777678)
			(xy 383.913678 -222.817022) (xy 383.878185 -222.851114) (xy 383.837682 -222.87907) (xy 383.79322 -222.900168)
			(xy 383.745949 -222.91386) (xy 383.697094 -222.919792) (xy 383.647919 -222.917811) (xy 383.5997 -222.907967)
			(xy 383.553684 -222.890515) (xy 383.511063 -222.865908) (xy 383.472942 -222.834783) (xy 383.440307 -222.797946)
			(xy 383.414004 -222.75635) (xy 383.394713 -222.711074) (xy 383.382936 -222.66329) (xy 383.378976 -222.614236)
			(xy 383.050034 -222.614236) (xy 383.049539 -222.638843) (xy 383.041644 -222.68742) (xy 383.02606 -222.734101)
			(xy 383.003189 -222.777678) (xy 382.973624 -222.817022) (xy 382.938131 -222.851114) (xy 382.897628 -222.87907)
			(xy 382.853166 -222.900168) (xy 382.805895 -222.91386) (xy 382.75704 -222.919792) (xy 382.707865 -222.917811)
			(xy 382.659646 -222.907967) (xy 382.61363 -222.890515) (xy 382.571009 -222.865908) (xy 382.532888 -222.834783)
			(xy 382.500253 -222.797946) (xy 382.47395 -222.75635) (xy 382.454659 -222.711074) (xy 382.442882 -222.66329)
			(xy 382.438922 -222.614236) (xy 381.087884 -222.614236) (xy 380.277878 -223.424242) (xy 381.028968 -223.424242)
			(xy 381.032928 -223.375188) (xy 381.044705 -223.327404) (xy 381.063996 -223.282128) (xy 381.090299 -223.240532)
			(xy 381.122934 -223.203695) (xy 381.161055 -223.17257) (xy 381.203676 -223.147963) (xy 381.249692 -223.130511)
			(xy 381.297911 -223.120667) (xy 381.347086 -223.118686) (xy 381.395941 -223.124618) (xy 381.443212 -223.13831)
			(xy 381.487674 -223.159408) (xy 381.528177 -223.187364) (xy 381.56367 -223.221456) (xy 381.593235 -223.2608)
			(xy 381.616106 -223.304377) (xy 381.63169 -223.351058) (xy 381.639585 -223.399635) (xy 381.64008 -223.424242)
			(xy 381.969022 -223.424242) (xy 381.972982 -223.375188) (xy 381.984759 -223.327404) (xy 382.00405 -223.282128)
			(xy 382.030353 -223.240532) (xy 382.062988 -223.203695) (xy 382.101109 -223.17257) (xy 382.14373 -223.147963)
			(xy 382.189746 -223.130511) (xy 382.237965 -223.120667) (xy 382.28714 -223.118686) (xy 382.335995 -223.124618)
			(xy 382.383266 -223.13831) (xy 382.427728 -223.159408) (xy 382.468231 -223.187364) (xy 382.503724 -223.221456)
			(xy 382.533289 -223.2608) (xy 382.55616 -223.304377) (xy 382.571744 -223.351058) (xy 382.579639 -223.399635)
			(xy 382.580134 -223.424242) (xy 382.909076 -223.424242) (xy 382.913036 -223.375188) (xy 382.924813 -223.327404)
			(xy 382.944104 -223.282128) (xy 382.970407 -223.240532) (xy 383.003042 -223.203695) (xy 383.041163 -223.17257)
			(xy 383.083784 -223.147963) (xy 383.1298 -223.130511) (xy 383.178019 -223.120667) (xy 383.227194 -223.118686)
			(xy 383.276049 -223.124618) (xy 383.32332 -223.13831) (xy 383.367782 -223.159408) (xy 383.408285 -223.187364)
			(xy 383.443778 -223.221456) (xy 383.473343 -223.2608) (xy 383.496214 -223.304377) (xy 383.511798 -223.351058)
			(xy 383.519693 -223.399635) (xy 383.520188 -223.424242) (xy 383.84913 -223.424242) (xy 383.85309 -223.375188)
			(xy 383.864867 -223.327404) (xy 383.884158 -223.282128) (xy 383.910461 -223.240532) (xy 383.943096 -223.203695)
			(xy 383.981217 -223.17257) (xy 384.023838 -223.147963) (xy 384.069854 -223.130511) (xy 384.118073 -223.120667)
			(xy 384.167248 -223.118686) (xy 384.216103 -223.124618) (xy 384.263374 -223.13831) (xy 384.307836 -223.159408)
			(xy 384.348339 -223.187364) (xy 384.383832 -223.221456) (xy 384.413397 -223.2608) (xy 384.436268 -223.304377)
			(xy 384.451852 -223.351058) (xy 384.459747 -223.399635) (xy 384.460242 -223.424242) (xy 384.78893 -223.424242)
			(xy 384.79289 -223.375188) (xy 384.804667 -223.327404) (xy 384.823958 -223.282128) (xy 384.850261 -223.240532)
			(xy 384.882896 -223.203695) (xy 384.921017 -223.17257) (xy 384.963638 -223.147963) (xy 385.009654 -223.130511)
			(xy 385.057873 -223.120667) (xy 385.107048 -223.118686) (xy 385.155903 -223.124618) (xy 385.203174 -223.13831)
			(xy 385.247636 -223.159408) (xy 385.288139 -223.187364) (xy 385.323632 -223.221456) (xy 385.353197 -223.2608)
			(xy 385.376068 -223.304377) (xy 385.391652 -223.351058) (xy 385.399547 -223.399635) (xy 385.400042 -223.424242)
			(xy 385.728984 -223.424242) (xy 385.732944 -223.375188) (xy 385.744721 -223.327404) (xy 385.764012 -223.282128)
			(xy 385.790315 -223.240532) (xy 385.82295 -223.203695) (xy 385.861071 -223.17257) (xy 385.903692 -223.147963)
			(xy 385.949708 -223.130511) (xy 385.997927 -223.120667) (xy 386.047102 -223.118686) (xy 386.095957 -223.124618)
			(xy 386.143228 -223.13831) (xy 386.18769 -223.159408) (xy 386.228193 -223.187364) (xy 386.263686 -223.221456)
			(xy 386.293251 -223.2608) (xy 386.316122 -223.304377) (xy 386.331706 -223.351058) (xy 386.339601 -223.399635)
			(xy 386.340096 -223.424242) (xy 386.669038 -223.424242) (xy 386.672998 -223.375188) (xy 386.684775 -223.327404)
			(xy 386.704066 -223.282128) (xy 386.730369 -223.240532) (xy 386.763004 -223.203695) (xy 386.801125 -223.17257)
			(xy 386.843746 -223.147963) (xy 386.889762 -223.130511) (xy 386.937981 -223.120667) (xy 386.987156 -223.118686)
			(xy 387.036011 -223.124618) (xy 387.083282 -223.13831) (xy 387.127744 -223.159408) (xy 387.168247 -223.187364)
			(xy 387.20374 -223.221456) (xy 387.233305 -223.2608) (xy 387.256176 -223.304377) (xy 387.27176 -223.351058)
			(xy 387.279655 -223.399635) (xy 387.28015 -223.424242) (xy 387.609092 -223.424242) (xy 387.613052 -223.375188)
			(xy 387.624829 -223.327404) (xy 387.64412 -223.282128) (xy 387.670423 -223.240532) (xy 387.703058 -223.203695)
			(xy 387.741179 -223.17257) (xy 387.7838 -223.147963) (xy 387.829816 -223.130511) (xy 387.878035 -223.120667)
			(xy 387.92721 -223.118686) (xy 387.976065 -223.124618) (xy 388.023336 -223.13831) (xy 388.067798 -223.159408)
			(xy 388.108301 -223.187364) (xy 388.143794 -223.221456) (xy 388.173359 -223.2608) (xy 388.19623 -223.304377)
			(xy 388.211814 -223.351058) (xy 388.219709 -223.399635) (xy 388.220204 -223.424242) (xy 389.488946 -223.424242)
			(xy 389.492906 -223.375188) (xy 389.504683 -223.327404) (xy 389.523974 -223.282128) (xy 389.550277 -223.240532)
			(xy 389.582912 -223.203695) (xy 389.621033 -223.17257) (xy 389.663654 -223.147963) (xy 389.70967 -223.130511)
			(xy 389.757889 -223.120667) (xy 389.807064 -223.118686) (xy 389.855919 -223.124618) (xy 389.90319 -223.13831)
			(xy 389.947652 -223.159408) (xy 389.988155 -223.187364) (xy 390.023648 -223.221456) (xy 390.053213 -223.2608)
			(xy 390.076084 -223.304377) (xy 390.091668 -223.351058) (xy 390.099563 -223.399635) (xy 390.100058 -223.424242)
			(xy 390.429 -223.424242) (xy 390.43296 -223.375188) (xy 390.444737 -223.327404) (xy 390.464028 -223.282128)
			(xy 390.490331 -223.240532) (xy 390.522966 -223.203695) (xy 390.561087 -223.17257) (xy 390.603708 -223.147963)
			(xy 390.649724 -223.130511) (xy 390.697943 -223.120667) (xy 390.747118 -223.118686) (xy 390.795973 -223.124618)
			(xy 390.843244 -223.13831) (xy 390.887706 -223.159408) (xy 390.928209 -223.187364) (xy 390.963702 -223.221456)
			(xy 390.993267 -223.2608) (xy 391.016138 -223.304377) (xy 391.031722 -223.351058) (xy 391.039617 -223.399635)
			(xy 391.040112 -223.424242) (xy 391.039617 -223.448849) (xy 391.031722 -223.497426) (xy 391.016138 -223.544107)
			(xy 390.993267 -223.587684) (xy 390.963702 -223.627028) (xy 390.928209 -223.66112) (xy 390.887706 -223.689076)
			(xy 390.843244 -223.710174) (xy 390.795973 -223.723866) (xy 390.747118 -223.729798) (xy 390.697943 -223.727817)
			(xy 390.649724 -223.717973) (xy 390.603708 -223.700521) (xy 390.561087 -223.675914) (xy 390.522966 -223.644789)
			(xy 390.490331 -223.607952) (xy 390.464028 -223.566356) (xy 390.444737 -223.52108) (xy 390.43296 -223.473296)
			(xy 390.429 -223.424242) (xy 390.100058 -223.424242) (xy 390.099563 -223.448849) (xy 390.091668 -223.497426)
			(xy 390.076084 -223.544107) (xy 390.053213 -223.587684) (xy 390.023648 -223.627028) (xy 389.988155 -223.66112)
			(xy 389.947652 -223.689076) (xy 389.90319 -223.710174) (xy 389.855919 -223.723866) (xy 389.807064 -223.729798)
			(xy 389.757889 -223.727817) (xy 389.70967 -223.717973) (xy 389.663654 -223.700521) (xy 389.621033 -223.675914)
			(xy 389.582912 -223.644789) (xy 389.550277 -223.607952) (xy 389.523974 -223.566356) (xy 389.504683 -223.52108)
			(xy 389.492906 -223.473296) (xy 389.488946 -223.424242) (xy 388.220204 -223.424242) (xy 388.219709 -223.448849)
			(xy 388.211814 -223.497426) (xy 388.19623 -223.544107) (xy 388.173359 -223.587684) (xy 388.143794 -223.627028)
			(xy 388.108301 -223.66112) (xy 388.067798 -223.689076) (xy 388.023336 -223.710174) (xy 387.976065 -223.723866)
			(xy 387.92721 -223.729798) (xy 387.878035 -223.727817) (xy 387.829816 -223.717973) (xy 387.7838 -223.700521)
			(xy 387.741179 -223.675914) (xy 387.703058 -223.644789) (xy 387.670423 -223.607952) (xy 387.64412 -223.566356)
			(xy 387.624829 -223.52108) (xy 387.613052 -223.473296) (xy 387.609092 -223.424242) (xy 387.28015 -223.424242)
			(xy 387.279655 -223.448849) (xy 387.27176 -223.497426) (xy 387.256176 -223.544107) (xy 387.233305 -223.587684)
			(xy 387.20374 -223.627028) (xy 387.168247 -223.66112) (xy 387.127744 -223.689076) (xy 387.083282 -223.710174)
			(xy 387.036011 -223.723866) (xy 386.987156 -223.729798) (xy 386.937981 -223.727817) (xy 386.889762 -223.717973)
			(xy 386.843746 -223.700521) (xy 386.801125 -223.675914) (xy 386.763004 -223.644789) (xy 386.730369 -223.607952)
			(xy 386.704066 -223.566356) (xy 386.684775 -223.52108) (xy 386.672998 -223.473296) (xy 386.669038 -223.424242)
			(xy 386.340096 -223.424242) (xy 386.339601 -223.448849) (xy 386.331706 -223.497426) (xy 386.316122 -223.544107)
			(xy 386.293251 -223.587684) (xy 386.263686 -223.627028) (xy 386.228193 -223.66112) (xy 386.18769 -223.689076)
			(xy 386.143228 -223.710174) (xy 386.095957 -223.723866) (xy 386.047102 -223.729798) (xy 385.997927 -223.727817)
			(xy 385.949708 -223.717973) (xy 385.903692 -223.700521) (xy 385.861071 -223.675914) (xy 385.82295 -223.644789)
			(xy 385.790315 -223.607952) (xy 385.764012 -223.566356) (xy 385.744721 -223.52108) (xy 385.732944 -223.473296)
			(xy 385.728984 -223.424242) (xy 385.400042 -223.424242) (xy 385.399547 -223.448849) (xy 385.391652 -223.497426)
			(xy 385.376068 -223.544107) (xy 385.353197 -223.587684) (xy 385.323632 -223.627028) (xy 385.288139 -223.66112)
			(xy 385.247636 -223.689076) (xy 385.203174 -223.710174) (xy 385.155903 -223.723866) (xy 385.107048 -223.729798)
			(xy 385.057873 -223.727817) (xy 385.009654 -223.717973) (xy 384.963638 -223.700521) (xy 384.921017 -223.675914)
			(xy 384.882896 -223.644789) (xy 384.850261 -223.607952) (xy 384.823958 -223.566356) (xy 384.804667 -223.52108)
			(xy 384.79289 -223.473296) (xy 384.78893 -223.424242) (xy 384.460242 -223.424242) (xy 384.459747 -223.448849)
			(xy 384.451852 -223.497426) (xy 384.436268 -223.544107) (xy 384.413397 -223.587684) (xy 384.383832 -223.627028)
			(xy 384.348339 -223.66112) (xy 384.307836 -223.689076) (xy 384.263374 -223.710174) (xy 384.216103 -223.723866)
			(xy 384.167248 -223.729798) (xy 384.118073 -223.727817) (xy 384.069854 -223.717973) (xy 384.023838 -223.700521)
			(xy 383.981217 -223.675914) (xy 383.943096 -223.644789) (xy 383.910461 -223.607952) (xy 383.884158 -223.566356)
			(xy 383.864867 -223.52108) (xy 383.85309 -223.473296) (xy 383.84913 -223.424242) (xy 383.520188 -223.424242)
			(xy 383.519693 -223.448849) (xy 383.511798 -223.497426) (xy 383.496214 -223.544107) (xy 383.473343 -223.587684)
			(xy 383.443778 -223.627028) (xy 383.408285 -223.66112) (xy 383.367782 -223.689076) (xy 383.32332 -223.710174)
			(xy 383.276049 -223.723866) (xy 383.227194 -223.729798) (xy 383.178019 -223.727817) (xy 383.1298 -223.717973)
			(xy 383.083784 -223.700521) (xy 383.041163 -223.675914) (xy 383.003042 -223.644789) (xy 382.970407 -223.607952)
			(xy 382.944104 -223.566356) (xy 382.924813 -223.52108) (xy 382.913036 -223.473296) (xy 382.909076 -223.424242)
			(xy 382.580134 -223.424242) (xy 382.579639 -223.448849) (xy 382.571744 -223.497426) (xy 382.55616 -223.544107)
			(xy 382.533289 -223.587684) (xy 382.503724 -223.627028) (xy 382.468231 -223.66112) (xy 382.427728 -223.689076)
			(xy 382.383266 -223.710174) (xy 382.335995 -223.723866) (xy 382.28714 -223.729798) (xy 382.237965 -223.727817)
			(xy 382.189746 -223.717973) (xy 382.14373 -223.700521) (xy 382.101109 -223.675914) (xy 382.062988 -223.644789)
			(xy 382.030353 -223.607952) (xy 382.00405 -223.566356) (xy 381.984759 -223.52108) (xy 381.972982 -223.473296)
			(xy 381.969022 -223.424242) (xy 381.64008 -223.424242) (xy 381.639585 -223.448849) (xy 381.63169 -223.497426)
			(xy 381.616106 -223.544107) (xy 381.593235 -223.587684) (xy 381.56367 -223.627028) (xy 381.528177 -223.66112)
			(xy 381.487674 -223.689076) (xy 381.443212 -223.710174) (xy 381.395941 -223.723866) (xy 381.347086 -223.729798)
			(xy 381.297911 -223.727817) (xy 381.249692 -223.717973) (xy 381.203676 -223.700521) (xy 381.161055 -223.675914)
			(xy 381.122934 -223.644789) (xy 381.090299 -223.607952) (xy 381.063996 -223.566356) (xy 381.044705 -223.52108)
			(xy 381.032928 -223.473296) (xy 381.028968 -223.424242) (xy 380.277878 -223.424242) (xy 379.937772 -223.764348)
			(xy 379.931637 -223.771073) (xy 379.924145 -223.78765) (xy 379.922895 -223.805799) (xy 379.925072 -223.81464)
			(xy 379.954282 -223.9137) (xy 379.974602 -223.93275) (xy 379.988318 -223.935544) (xy 380.013641 -223.941459)
			(xy 380.061939 -223.960725) (xy 380.106275 -223.987895) (xy 380.145366 -224.022184) (xy 380.178083 -224.0626)
			(xy 380.203479 -224.107975) (xy 380.22082 -224.156997) (xy 380.229606 -224.208248) (xy 380.230126 -224.234248)
			(xy 380.559068 -224.234248) (xy 380.563028 -224.185194) (xy 380.574805 -224.13741) (xy 380.594096 -224.092134)
			(xy 380.620399 -224.050538) (xy 380.653034 -224.013701) (xy 380.691155 -223.982576) (xy 380.733776 -223.957969)
			(xy 380.779792 -223.940517) (xy 380.828011 -223.930673) (xy 380.877186 -223.928692) (xy 380.926041 -223.934624)
			(xy 380.973312 -223.948316) (xy 381.017774 -223.969414) (xy 381.058277 -223.99737) (xy 381.09377 -224.031462)
			(xy 381.123335 -224.070806) (xy 381.146206 -224.114383) (xy 381.16179 -224.161064) (xy 381.169685 -224.209641)
			(xy 381.17018 -224.234248) (xy 382.438922 -224.234248) (xy 382.442882 -224.185194) (xy 382.454659 -224.13741)
			(xy 382.47395 -224.092134) (xy 382.500253 -224.050538) (xy 382.532888 -224.013701) (xy 382.571009 -223.982576)
			(xy 382.61363 -223.957969) (xy 382.659646 -223.940517) (xy 382.707865 -223.930673) (xy 382.75704 -223.928692)
			(xy 382.805895 -223.934624) (xy 382.853166 -223.948316) (xy 382.897628 -223.969414) (xy 382.938131 -223.99737)
			(xy 382.973624 -224.031462) (xy 383.003189 -224.070806) (xy 383.02606 -224.114383) (xy 383.041644 -224.161064)
			(xy 383.049539 -224.209641) (xy 383.050034 -224.234248) (xy 383.378976 -224.234248) (xy 383.382936 -224.185194)
			(xy 383.394713 -224.13741) (xy 383.414004 -224.092134) (xy 383.440307 -224.050538) (xy 383.472942 -224.013701)
			(xy 383.511063 -223.982576) (xy 383.553684 -223.957969) (xy 383.5997 -223.940517) (xy 383.647919 -223.930673)
			(xy 383.697094 -223.928692) (xy 383.745949 -223.934624) (xy 383.79322 -223.948316) (xy 383.837682 -223.969414)
			(xy 383.878185 -223.99737) (xy 383.913678 -224.031462) (xy 383.943243 -224.070806) (xy 383.966114 -224.114383)
			(xy 383.981698 -224.161064) (xy 383.989593 -224.209641) (xy 383.990088 -224.234248) (xy 384.31903 -224.234248)
			(xy 384.32299 -224.185194) (xy 384.334767 -224.13741) (xy 384.354058 -224.092134) (xy 384.380361 -224.050538)
			(xy 384.412996 -224.013701) (xy 384.451117 -223.982576) (xy 384.493738 -223.957969) (xy 384.539754 -223.940517)
			(xy 384.587973 -223.930673) (xy 384.637148 -223.928692) (xy 384.686003 -223.934624) (xy 384.733274 -223.948316)
			(xy 384.777736 -223.969414) (xy 384.818239 -223.99737) (xy 384.853732 -224.031462) (xy 384.883297 -224.070806)
			(xy 384.906168 -224.114383) (xy 384.921752 -224.161064) (xy 384.929647 -224.209641) (xy 384.930142 -224.234248)
			(xy 386.199138 -224.234248) (xy 386.203098 -224.185194) (xy 386.214875 -224.13741) (xy 386.234166 -224.092134)
			(xy 386.260469 -224.050538) (xy 386.293104 -224.013701) (xy 386.331225 -223.982576) (xy 386.373846 -223.957969)
			(xy 386.419862 -223.940517) (xy 386.468081 -223.930673) (xy 386.517256 -223.928692) (xy 386.566111 -223.934624)
			(xy 386.613382 -223.948316) (xy 386.657844 -223.969414) (xy 386.698347 -223.99737) (xy 386.73384 -224.031462)
			(xy 386.763405 -224.070806) (xy 386.786276 -224.114383) (xy 386.80186 -224.161064) (xy 386.809755 -224.209641)
			(xy 386.81025 -224.234248) (xy 387.138938 -224.234248) (xy 387.142898 -224.185194) (xy 387.154675 -224.13741)
			(xy 387.173966 -224.092134) (xy 387.200269 -224.050538) (xy 387.232904 -224.013701) (xy 387.271025 -223.982576)
			(xy 387.313646 -223.957969) (xy 387.359662 -223.940517) (xy 387.407881 -223.930673) (xy 387.457056 -223.928692)
			(xy 387.505911 -223.934624) (xy 387.553182 -223.948316) (xy 387.597644 -223.969414) (xy 387.638147 -223.99737)
			(xy 387.67364 -224.031462) (xy 387.703205 -224.070806) (xy 387.726076 -224.114383) (xy 387.74166 -224.161064)
			(xy 387.749555 -224.209641) (xy 387.75005 -224.234248) (xy 389.019046 -224.234248) (xy 389.023006 -224.185194)
			(xy 389.034783 -224.13741) (xy 389.054074 -224.092134) (xy 389.080377 -224.050538) (xy 389.113012 -224.013701)
			(xy 389.151133 -223.982576) (xy 389.193754 -223.957969) (xy 389.23977 -223.940517) (xy 389.287989 -223.930673)
			(xy 389.337164 -223.928692) (xy 389.386019 -223.934624) (xy 389.43329 -223.948316) (xy 389.477752 -223.969414)
			(xy 389.518255 -223.99737) (xy 389.553748 -224.031462) (xy 389.583313 -224.070806) (xy 389.606184 -224.114383)
			(xy 389.621768 -224.161064) (xy 389.629663 -224.209641) (xy 389.630158 -224.234248) (xy 389.9591 -224.234248)
			(xy 389.96306 -224.185194) (xy 389.974837 -224.13741) (xy 389.994128 -224.092134) (xy 390.020431 -224.050538)
			(xy 390.053066 -224.013701) (xy 390.091187 -223.982576) (xy 390.133808 -223.957969) (xy 390.179824 -223.940517)
			(xy 390.228043 -223.930673) (xy 390.277218 -223.928692) (xy 390.326073 -223.934624) (xy 390.373344 -223.948316)
			(xy 390.417806 -223.969414) (xy 390.458309 -223.99737) (xy 390.493802 -224.031462) (xy 390.523367 -224.070806)
			(xy 390.546238 -224.114383) (xy 390.561822 -224.161064) (xy 390.569717 -224.209641) (xy 390.570212 -224.234248)
			(xy 390.8989 -224.234248) (xy 390.90286 -224.185194) (xy 390.914637 -224.13741) (xy 390.933928 -224.092134)
			(xy 390.960231 -224.050538) (xy 390.992866 -224.013701) (xy 391.030987 -223.982576) (xy 391.073608 -223.957969)
			(xy 391.119624 -223.940517) (xy 391.167843 -223.930673) (xy 391.217018 -223.928692) (xy 391.265873 -223.934624)
			(xy 391.313144 -223.948316) (xy 391.357606 -223.969414) (xy 391.398109 -223.99737) (xy 391.433602 -224.031462)
			(xy 391.463167 -224.070806) (xy 391.486038 -224.114383) (xy 391.501622 -224.161064) (xy 391.509517 -224.209641)
			(xy 391.510012 -224.234248) (xy 391.509517 -224.258855) (xy 391.501622 -224.307432) (xy 391.486038 -224.354113)
			(xy 391.463167 -224.39769) (xy 391.433602 -224.437034) (xy 391.398109 -224.471126) (xy 391.357606 -224.499082)
			(xy 391.313144 -224.52018) (xy 391.265873 -224.533872) (xy 391.217018 -224.539804) (xy 391.167843 -224.537823)
			(xy 391.119624 -224.527979) (xy 391.073608 -224.510527) (xy 391.030987 -224.48592) (xy 390.992866 -224.454795)
			(xy 390.960231 -224.417958) (xy 390.933928 -224.376362) (xy 390.914637 -224.331086) (xy 390.90286 -224.283302)
			(xy 390.8989 -224.234248) (xy 390.570212 -224.234248) (xy 390.569717 -224.258855) (xy 390.561822 -224.307432)
			(xy 390.546238 -224.354113) (xy 390.523367 -224.39769) (xy 390.493802 -224.437034) (xy 390.458309 -224.471126)
			(xy 390.417806 -224.499082) (xy 390.373344 -224.52018) (xy 390.326073 -224.533872) (xy 390.277218 -224.539804)
			(xy 390.228043 -224.537823) (xy 390.179824 -224.527979) (xy 390.133808 -224.510527) (xy 390.091187 -224.48592)
			(xy 390.053066 -224.454795) (xy 390.020431 -224.417958) (xy 389.994128 -224.376362) (xy 389.974837 -224.331086)
			(xy 389.96306 -224.283302) (xy 389.9591 -224.234248) (xy 389.630158 -224.234248) (xy 389.629663 -224.258855)
			(xy 389.621768 -224.307432) (xy 389.606184 -224.354113) (xy 389.583313 -224.39769) (xy 389.553748 -224.437034)
			(xy 389.518255 -224.471126) (xy 389.477752 -224.499082) (xy 389.43329 -224.52018) (xy 389.386019 -224.533872)
			(xy 389.337164 -224.539804) (xy 389.287989 -224.537823) (xy 389.23977 -224.527979) (xy 389.193754 -224.510527)
			(xy 389.151133 -224.48592) (xy 389.113012 -224.454795) (xy 389.080377 -224.417958) (xy 389.054074 -224.376362)
			(xy 389.034783 -224.331086) (xy 389.023006 -224.283302) (xy 389.019046 -224.234248) (xy 387.75005 -224.234248)
			(xy 387.749555 -224.258855) (xy 387.74166 -224.307432) (xy 387.726076 -224.354113) (xy 387.703205 -224.39769)
			(xy 387.67364 -224.437034) (xy 387.638147 -224.471126) (xy 387.597644 -224.499082) (xy 387.553182 -224.52018)
			(xy 387.505911 -224.533872) (xy 387.457056 -224.539804) (xy 387.407881 -224.537823) (xy 387.359662 -224.527979)
			(xy 387.313646 -224.510527) (xy 387.271025 -224.48592) (xy 387.232904 -224.454795) (xy 387.200269 -224.417958)
			(xy 387.173966 -224.376362) (xy 387.154675 -224.331086) (xy 387.142898 -224.283302) (xy 387.138938 -224.234248)
			(xy 386.81025 -224.234248) (xy 386.809755 -224.258855) (xy 386.80186 -224.307432) (xy 386.786276 -224.354113)
			(xy 386.763405 -224.39769) (xy 386.73384 -224.437034) (xy 386.698347 -224.471126) (xy 386.657844 -224.499082)
			(xy 386.613382 -224.52018) (xy 386.566111 -224.533872) (xy 386.517256 -224.539804) (xy 386.468081 -224.537823)
			(xy 386.419862 -224.527979) (xy 386.373846 -224.510527) (xy 386.331225 -224.48592) (xy 386.293104 -224.454795)
			(xy 386.260469 -224.417958) (xy 386.234166 -224.376362) (xy 386.214875 -224.331086) (xy 386.203098 -224.283302)
			(xy 386.199138 -224.234248) (xy 384.930142 -224.234248) (xy 384.929647 -224.258855) (xy 384.921752 -224.307432)
			(xy 384.906168 -224.354113) (xy 384.883297 -224.39769) (xy 384.853732 -224.437034) (xy 384.818239 -224.471126)
			(xy 384.777736 -224.499082) (xy 384.733274 -224.52018) (xy 384.686003 -224.533872) (xy 384.637148 -224.539804)
			(xy 384.587973 -224.537823) (xy 384.539754 -224.527979) (xy 384.493738 -224.510527) (xy 384.451117 -224.48592)
			(xy 384.412996 -224.454795) (xy 384.380361 -224.417958) (xy 384.354058 -224.376362) (xy 384.334767 -224.331086)
			(xy 384.32299 -224.283302) (xy 384.31903 -224.234248) (xy 383.990088 -224.234248) (xy 383.989593 -224.258855)
			(xy 383.981698 -224.307432) (xy 383.966114 -224.354113) (xy 383.943243 -224.39769) (xy 383.913678 -224.437034)
			(xy 383.878185 -224.471126) (xy 383.837682 -224.499082) (xy 383.79322 -224.52018) (xy 383.745949 -224.533872)
			(xy 383.697094 -224.539804) (xy 383.647919 -224.537823) (xy 383.5997 -224.527979) (xy 383.553684 -224.510527)
			(xy 383.511063 -224.48592) (xy 383.472942 -224.454795) (xy 383.440307 -224.417958) (xy 383.414004 -224.376362)
			(xy 383.394713 -224.331086) (xy 383.382936 -224.283302) (xy 383.378976 -224.234248) (xy 383.050034 -224.234248)
			(xy 383.049539 -224.258855) (xy 383.041644 -224.307432) (xy 383.02606 -224.354113) (xy 383.003189 -224.39769)
			(xy 382.973624 -224.437034) (xy 382.938131 -224.471126) (xy 382.897628 -224.499082) (xy 382.853166 -224.52018)
			(xy 382.805895 -224.533872) (xy 382.75704 -224.539804) (xy 382.707865 -224.537823) (xy 382.659646 -224.527979)
			(xy 382.61363 -224.510527) (xy 382.571009 -224.48592) (xy 382.532888 -224.454795) (xy 382.500253 -224.417958)
			(xy 382.47395 -224.376362) (xy 382.454659 -224.331086) (xy 382.442882 -224.283302) (xy 382.438922 -224.234248)
			(xy 381.17018 -224.234248) (xy 381.169685 -224.258855) (xy 381.16179 -224.307432) (xy 381.146206 -224.354113)
			(xy 381.123335 -224.39769) (xy 381.09377 -224.437034) (xy 381.058277 -224.471126) (xy 381.017774 -224.499082)
			(xy 380.973312 -224.52018) (xy 380.926041 -224.533872) (xy 380.877186 -224.539804) (xy 380.828011 -224.537823)
			(xy 380.779792 -224.527979) (xy 380.733776 -224.510527) (xy 380.691155 -224.48592) (xy 380.653034 -224.454795)
			(xy 380.620399 -224.417958) (xy 380.594096 -224.376362) (xy 380.574805 -224.331086) (xy 380.563028 -224.283302)
			(xy 380.559068 -224.234248) (xy 380.230126 -224.234248) (xy 380.229652 -224.258237) (xy 380.22214 -224.305624)
			(xy 380.207308 -224.351253) (xy 380.185523 -224.394) (xy 380.157319 -224.432814) (xy 380.123391 -224.466738)
			(xy 380.084575 -224.494938) (xy 380.041825 -224.51672) (xy 379.996195 -224.531547) (xy 379.948807 -224.539054)
			(xy 379.924818 -224.539556) (xy 379.898824 -224.539027) (xy 379.847588 -224.530213) (xy 379.798583 -224.512855)
			(xy 379.753223 -224.487452) (xy 379.712817 -224.454738) (xy 379.678532 -224.415657) (xy 379.651356 -224.371337)
			(xy 379.632074 -224.323056) (xy 379.626114 -224.297748) (xy 379.62332 -224.284032) (xy 379.60427 -224.263712)
			(xy 379.50521 -224.234502) (xy 379.496375 -224.232258) (xy 379.478201 -224.233493) (xy 379.461612 -224.241017)
			(xy 379.454918 -224.247202) (xy 378.803662 -224.898458) (xy 378.797058 -224.92716) (xy 378.802138 -224.94113)
			(xy 378.810531 -224.966082) (xy 378.819599 -225.017935) (xy 378.820172 -225.044254) (xy 379.149114 -225.044254)
			(xy 379.153074 -224.9952) (xy 379.164851 -224.947416) (xy 379.184142 -224.90214) (xy 379.210445 -224.860544)
			(xy 379.24308 -224.823707) (xy 379.281201 -224.792582) (xy 379.323822 -224.767975) (xy 379.369838 -224.750523)
			(xy 379.418057 -224.740679) (xy 379.467232 -224.738698) (xy 379.516087 -224.74463) (xy 379.563358 -224.758322)
			(xy 379.60782 -224.77942) (xy 379.648323 -224.807376) (xy 379.683816 -224.841468) (xy 379.713381 -224.880812)
			(xy 379.736252 -224.924389) (xy 379.751836 -224.97107) (xy 379.759731 -225.019647) (xy 379.760226 -225.044254)
			(xy 380.078483 -225.044254) (xy 380.082578 -224.993526) (xy 380.094757 -224.944112) (xy 380.114705 -224.897292)
			(xy 380.141906 -224.854278) (xy 380.175654 -224.816184) (xy 380.215076 -224.783997) (xy 380.25915 -224.758551)
			(xy 380.306736 -224.740504) (xy 380.3566 -224.730324) (xy 380.407452 -224.728275) (xy 380.457973 -224.734409)
			(xy 380.506857 -224.748569) (xy 380.552836 -224.770386) (xy 380.59472 -224.799296) (xy 380.631424 -224.834551)
			(xy 380.661997 -224.875237) (xy 380.685648 -224.9203) (xy 380.701764 -224.968574) (xy 380.709928 -225.018808)
			(xy 380.71044 -225.044254) (xy 381.028968 -225.044254) (xy 381.032928 -224.9952) (xy 381.044705 -224.947416)
			(xy 381.063996 -224.90214) (xy 381.090299 -224.860544) (xy 381.122934 -224.823707) (xy 381.161055 -224.792582)
			(xy 381.203676 -224.767975) (xy 381.249692 -224.750523) (xy 381.297911 -224.740679) (xy 381.347086 -224.738698)
			(xy 381.395941 -224.74463) (xy 381.443212 -224.758322) (xy 381.487674 -224.77942) (xy 381.528177 -224.807376)
			(xy 381.56367 -224.841468) (xy 381.593235 -224.880812) (xy 381.616106 -224.924389) (xy 381.63169 -224.97107)
			(xy 381.639585 -225.019647) (xy 381.64008 -225.044254) (xy 381.969022 -225.044254) (xy 381.972982 -224.9952)
			(xy 381.984759 -224.947416) (xy 382.00405 -224.90214) (xy 382.030353 -224.860544) (xy 382.062988 -224.823707)
			(xy 382.101109 -224.792582) (xy 382.14373 -224.767975) (xy 382.189746 -224.750523) (xy 382.237965 -224.740679)
			(xy 382.28714 -224.738698) (xy 382.335995 -224.74463) (xy 382.383266 -224.758322) (xy 382.427728 -224.77942)
			(xy 382.468231 -224.807376) (xy 382.503724 -224.841468) (xy 382.533289 -224.880812) (xy 382.55616 -224.924389)
			(xy 382.571744 -224.97107) (xy 382.579639 -225.019647) (xy 382.580134 -225.044254) (xy 382.909076 -225.044254)
			(xy 382.913036 -224.9952) (xy 382.924813 -224.947416) (xy 382.944104 -224.90214) (xy 382.970407 -224.860544)
			(xy 383.003042 -224.823707) (xy 383.041163 -224.792582) (xy 383.083784 -224.767975) (xy 383.1298 -224.750523)
			(xy 383.178019 -224.740679) (xy 383.227194 -224.738698) (xy 383.276049 -224.74463) (xy 383.32332 -224.758322)
			(xy 383.367782 -224.77942) (xy 383.408285 -224.807376) (xy 383.443778 -224.841468) (xy 383.473343 -224.880812)
			(xy 383.496214 -224.924389) (xy 383.511798 -224.97107) (xy 383.519693 -225.019647) (xy 383.520188 -225.044254)
			(xy 383.838699 -225.044254) (xy 383.842794 -224.993526) (xy 383.854973 -224.944112) (xy 383.874921 -224.897292)
			(xy 383.902122 -224.854278) (xy 383.93587 -224.816184) (xy 383.975292 -224.783997) (xy 384.019366 -224.758551)
			(xy 384.066952 -224.740504) (xy 384.116816 -224.730324) (xy 384.167668 -224.728275) (xy 384.218189 -224.734409)
			(xy 384.267073 -224.748569) (xy 384.313052 -224.770386) (xy 384.354936 -224.799296) (xy 384.39164 -224.834551)
			(xy 384.422213 -224.875237) (xy 384.445864 -224.9203) (xy 384.46198 -224.968574) (xy 384.470144 -225.018808)
			(xy 384.470656 -225.044254) (xy 385.728984 -225.044254) (xy 385.732944 -224.9952) (xy 385.744721 -224.947416)
			(xy 385.764012 -224.90214) (xy 385.790315 -224.860544) (xy 385.82295 -224.823707) (xy 385.861071 -224.792582)
			(xy 385.903692 -224.767975) (xy 385.949708 -224.750523) (xy 385.997927 -224.740679) (xy 386.047102 -224.738698)
			(xy 386.095957 -224.74463) (xy 386.143228 -224.758322) (xy 386.18769 -224.77942) (xy 386.228193 -224.807376)
			(xy 386.263686 -224.841468) (xy 386.293251 -224.880812) (xy 386.316122 -224.924389) (xy 386.331706 -224.97107)
			(xy 386.339601 -225.019647) (xy 386.340096 -225.044254) (xy 386.658607 -225.044254) (xy 386.662702 -224.993526)
			(xy 386.674881 -224.944112) (xy 386.694829 -224.897292) (xy 386.72203 -224.854278) (xy 386.755778 -224.816184)
			(xy 386.7952 -224.783997) (xy 386.839274 -224.758551) (xy 386.88686 -224.740504) (xy 386.936724 -224.730324)
			(xy 386.987576 -224.728275) (xy 387.038097 -224.734409) (xy 387.086981 -224.748569) (xy 387.13296 -224.770386)
			(xy 387.174844 -224.799296) (xy 387.211548 -224.834551) (xy 387.242121 -224.875237) (xy 387.265772 -224.9203)
			(xy 387.281888 -224.968574) (xy 387.290052 -225.018808) (xy 387.290564 -225.044254) (xy 387.609092 -225.044254)
			(xy 387.613052 -224.9952) (xy 387.624829 -224.947416) (xy 387.64412 -224.90214) (xy 387.670423 -224.860544)
			(xy 387.703058 -224.823707) (xy 387.741179 -224.792582) (xy 387.7838 -224.767975) (xy 387.829816 -224.750523)
			(xy 387.878035 -224.740679) (xy 387.92721 -224.738698) (xy 387.976065 -224.74463) (xy 388.023336 -224.758322)
			(xy 388.067798 -224.77942) (xy 388.108301 -224.807376) (xy 388.143794 -224.841468) (xy 388.173359 -224.880812)
			(xy 388.19623 -224.924389) (xy 388.211814 -224.97107) (xy 388.219709 -225.019647) (xy 388.220204 -225.044254)
			(xy 388.549146 -225.044254) (xy 388.553106 -224.9952) (xy 388.564883 -224.947416) (xy 388.584174 -224.90214)
			(xy 388.610477 -224.860544) (xy 388.643112 -224.823707) (xy 388.681233 -224.792582) (xy 388.723854 -224.767975)
			(xy 388.76987 -224.750523) (xy 388.818089 -224.740679) (xy 388.867264 -224.738698) (xy 388.916119 -224.74463)
			(xy 388.96339 -224.758322) (xy 389.007852 -224.77942) (xy 389.048355 -224.807376) (xy 389.083848 -224.841468)
			(xy 389.113413 -224.880812) (xy 389.136284 -224.924389) (xy 389.151868 -224.97107) (xy 389.159763 -225.019647)
			(xy 389.160258 -225.044254) (xy 389.488946 -225.044254) (xy 389.492906 -224.9952) (xy 389.504683 -224.947416)
			(xy 389.523974 -224.90214) (xy 389.550277 -224.860544) (xy 389.582912 -224.823707) (xy 389.621033 -224.792582)
			(xy 389.663654 -224.767975) (xy 389.70967 -224.750523) (xy 389.757889 -224.740679) (xy 389.807064 -224.738698)
			(xy 389.855919 -224.74463) (xy 389.90319 -224.758322) (xy 389.947652 -224.77942) (xy 389.988155 -224.807376)
			(xy 390.023648 -224.841468) (xy 390.053213 -224.880812) (xy 390.076084 -224.924389) (xy 390.091668 -224.97107)
			(xy 390.099563 -225.019647) (xy 390.100058 -225.044254) (xy 390.418569 -225.044254) (xy 390.422664 -224.993526)
			(xy 390.434843 -224.944112) (xy 390.454791 -224.897292) (xy 390.481992 -224.854278) (xy 390.51574 -224.816184)
			(xy 390.555162 -224.783997) (xy 390.599236 -224.758551) (xy 390.646822 -224.740504) (xy 390.696686 -224.730324)
			(xy 390.747538 -224.728275) (xy 390.798059 -224.734409) (xy 390.846943 -224.748569) (xy 390.892922 -224.770386)
			(xy 390.934806 -224.799296) (xy 390.97151 -224.834551) (xy 391.002083 -224.875237) (xy 391.025734 -224.9203)
			(xy 391.04185 -224.968574) (xy 391.050014 -225.018808) (xy 391.050526 -225.044254) (xy 392.309108 -225.044254)
			(xy 392.313068 -224.9952) (xy 392.324845 -224.947416) (xy 392.344136 -224.90214) (xy 392.370439 -224.860544)
			(xy 392.403074 -224.823707) (xy 392.441195 -224.792582) (xy 392.483816 -224.767975) (xy 392.529832 -224.750523)
			(xy 392.578051 -224.740679) (xy 392.627226 -224.738698) (xy 392.676081 -224.74463) (xy 392.723352 -224.758322)
			(xy 392.767814 -224.77942) (xy 392.808317 -224.807376) (xy 392.84381 -224.841468) (xy 392.873375 -224.880812)
			(xy 392.896246 -224.924389) (xy 392.91183 -224.97107) (xy 392.919725 -225.019647) (xy 392.92022 -225.044254)
			(xy 394.188962 -225.044254) (xy 394.192922 -224.9952) (xy 394.204699 -224.947416) (xy 394.22399 -224.90214)
			(xy 394.250293 -224.860544) (xy 394.282928 -224.823707) (xy 394.321049 -224.792582) (xy 394.36367 -224.767975)
			(xy 394.409686 -224.750523) (xy 394.457905 -224.740679) (xy 394.50708 -224.738698) (xy 394.555935 -224.74463)
			(xy 394.603206 -224.758322) (xy 394.647668 -224.77942) (xy 394.688171 -224.807376) (xy 394.723664 -224.841468)
			(xy 394.753229 -224.880812) (xy 394.7761 -224.924389) (xy 394.791684 -224.97107) (xy 394.799579 -225.019647)
			(xy 394.800074 -225.044254) (xy 394.799579 -225.068861) (xy 394.791684 -225.117438) (xy 394.7761 -225.164119)
			(xy 394.753229 -225.207696) (xy 394.723664 -225.24704) (xy 394.688171 -225.281132) (xy 394.647668 -225.309088)
			(xy 394.603206 -225.330186) (xy 394.555935 -225.343878) (xy 394.50708 -225.34981) (xy 394.457905 -225.347829)
			(xy 394.409686 -225.337985) (xy 394.36367 -225.320533) (xy 394.321049 -225.295926) (xy 394.282928 -225.264801)
			(xy 394.250293 -225.227964) (xy 394.22399 -225.186368) (xy 394.204699 -225.141092) (xy 394.192922 -225.093308)
			(xy 394.188962 -225.044254) (xy 392.92022 -225.044254) (xy 392.919725 -225.068861) (xy 392.91183 -225.117438)
			(xy 392.896246 -225.164119) (xy 392.873375 -225.207696) (xy 392.84381 -225.24704) (xy 392.808317 -225.281132)
			(xy 392.767814 -225.309088) (xy 392.723352 -225.330186) (xy 392.676081 -225.343878) (xy 392.627226 -225.34981)
			(xy 392.578051 -225.347829) (xy 392.529832 -225.337985) (xy 392.483816 -225.320533) (xy 392.441195 -225.295926)
			(xy 392.403074 -225.264801) (xy 392.370439 -225.227964) (xy 392.344136 -225.186368) (xy 392.324845 -225.141092)
			(xy 392.313068 -225.093308) (xy 392.309108 -225.044254) (xy 391.050526 -225.044254) (xy 391.050014 -225.0697)
			(xy 391.04185 -225.119934) (xy 391.025734 -225.168208) (xy 391.002083 -225.213271) (xy 390.97151 -225.253957)
			(xy 390.934806 -225.289212) (xy 390.892922 -225.318122) (xy 390.846943 -225.339939) (xy 390.798059 -225.354099)
			(xy 390.747538 -225.360233) (xy 390.696686 -225.358184) (xy 390.646822 -225.348004) (xy 390.599236 -225.329957)
			(xy 390.555162 -225.304511) (xy 390.51574 -225.272324) (xy 390.481992 -225.23423) (xy 390.454791 -225.191216)
			(xy 390.434843 -225.144396) (xy 390.422664 -225.094982) (xy 390.418569 -225.044254) (xy 390.100058 -225.044254)
			(xy 390.099563 -225.068861) (xy 390.091668 -225.117438) (xy 390.076084 -225.164119) (xy 390.053213 -225.207696)
			(xy 390.023648 -225.24704) (xy 389.988155 -225.281132) (xy 389.947652 -225.309088) (xy 389.90319 -225.330186)
			(xy 389.855919 -225.343878) (xy 389.807064 -225.34981) (xy 389.757889 -225.347829) (xy 389.70967 -225.337985)
			(xy 389.663654 -225.320533) (xy 389.621033 -225.295926) (xy 389.582912 -225.264801) (xy 389.550277 -225.227964)
			(xy 389.523974 -225.186368) (xy 389.504683 -225.141092) (xy 389.492906 -225.093308) (xy 389.488946 -225.044254)
			(xy 389.160258 -225.044254) (xy 389.159763 -225.068861) (xy 389.151868 -225.117438) (xy 389.136284 -225.164119)
			(xy 389.113413 -225.207696) (xy 389.083848 -225.24704) (xy 389.048355 -225.281132) (xy 389.007852 -225.309088)
			(xy 388.96339 -225.330186) (xy 388.916119 -225.343878) (xy 388.867264 -225.34981) (xy 388.818089 -225.347829)
			(xy 388.76987 -225.337985) (xy 388.723854 -225.320533) (xy 388.681233 -225.295926) (xy 388.643112 -225.264801)
			(xy 388.610477 -225.227964) (xy 388.584174 -225.186368) (xy 388.564883 -225.141092) (xy 388.553106 -225.093308)
			(xy 388.549146 -225.044254) (xy 388.220204 -225.044254) (xy 388.219709 -225.068861) (xy 388.211814 -225.117438)
			(xy 388.19623 -225.164119) (xy 388.173359 -225.207696) (xy 388.143794 -225.24704) (xy 388.108301 -225.281132)
			(xy 388.067798 -225.309088) (xy 388.023336 -225.330186) (xy 387.976065 -225.343878) (xy 387.92721 -225.34981)
			(xy 387.878035 -225.347829) (xy 387.829816 -225.337985) (xy 387.7838 -225.320533) (xy 387.741179 -225.295926)
			(xy 387.703058 -225.264801) (xy 387.670423 -225.227964) (xy 387.64412 -225.186368) (xy 387.624829 -225.141092)
			(xy 387.613052 -225.093308) (xy 387.609092 -225.044254) (xy 387.290564 -225.044254) (xy 387.290052 -225.0697)
			(xy 387.281888 -225.119934) (xy 387.265772 -225.168208) (xy 387.242121 -225.213271) (xy 387.211548 -225.253957)
			(xy 387.174844 -225.289212) (xy 387.13296 -225.318122) (xy 387.086981 -225.339939) (xy 387.038097 -225.354099)
			(xy 386.987576 -225.360233) (xy 386.936724 -225.358184) (xy 386.88686 -225.348004) (xy 386.839274 -225.329957)
			(xy 386.7952 -225.304511) (xy 386.755778 -225.272324) (xy 386.72203 -225.23423) (xy 386.694829 -225.191216)
			(xy 386.674881 -225.144396) (xy 386.662702 -225.094982) (xy 386.658607 -225.044254) (xy 386.340096 -225.044254)
			(xy 386.339601 -225.068861) (xy 386.331706 -225.117438) (xy 386.316122 -225.164119) (xy 386.293251 -225.207696)
			(xy 386.263686 -225.24704) (xy 386.228193 -225.281132) (xy 386.18769 -225.309088) (xy 386.143228 -225.330186)
			(xy 386.095957 -225.343878) (xy 386.047102 -225.34981) (xy 385.997927 -225.347829) (xy 385.949708 -225.337985)
			(xy 385.903692 -225.320533) (xy 385.861071 -225.295926) (xy 385.82295 -225.264801) (xy 385.790315 -225.227964)
			(xy 385.764012 -225.186368) (xy 385.744721 -225.141092) (xy 385.732944 -225.093308) (xy 385.728984 -225.044254)
			(xy 384.470656 -225.044254) (xy 384.470144 -225.0697) (xy 384.46198 -225.119934) (xy 384.445864 -225.168208)
			(xy 384.422213 -225.213271) (xy 384.39164 -225.253957) (xy 384.354936 -225.289212) (xy 384.313052 -225.318122)
			(xy 384.267073 -225.339939) (xy 384.218189 -225.354099) (xy 384.167668 -225.360233) (xy 384.116816 -225.358184)
			(xy 384.066952 -225.348004) (xy 384.019366 -225.329957) (xy 383.975292 -225.304511) (xy 383.93587 -225.272324)
			(xy 383.902122 -225.23423) (xy 383.874921 -225.191216) (xy 383.854973 -225.144396) (xy 383.842794 -225.094982)
			(xy 383.838699 -225.044254) (xy 383.520188 -225.044254) (xy 383.519693 -225.068861) (xy 383.511798 -225.117438)
			(xy 383.496214 -225.164119) (xy 383.473343 -225.207696) (xy 383.443778 -225.24704) (xy 383.408285 -225.281132)
			(xy 383.367782 -225.309088) (xy 383.32332 -225.330186) (xy 383.276049 -225.343878) (xy 383.227194 -225.34981)
			(xy 383.178019 -225.347829) (xy 383.1298 -225.337985) (xy 383.083784 -225.320533) (xy 383.041163 -225.295926)
			(xy 383.003042 -225.264801) (xy 382.970407 -225.227964) (xy 382.944104 -225.186368) (xy 382.924813 -225.141092)
			(xy 382.913036 -225.093308) (xy 382.909076 -225.044254) (xy 382.580134 -225.044254) (xy 382.579639 -225.068861)
			(xy 382.571744 -225.117438) (xy 382.55616 -225.164119) (xy 382.533289 -225.207696) (xy 382.503724 -225.24704)
			(xy 382.468231 -225.281132) (xy 382.427728 -225.309088) (xy 382.383266 -225.330186) (xy 382.335995 -225.343878)
			(xy 382.28714 -225.34981) (xy 382.237965 -225.347829) (xy 382.189746 -225.337985) (xy 382.14373 -225.320533)
			(xy 382.101109 -225.295926) (xy 382.062988 -225.264801) (xy 382.030353 -225.227964) (xy 382.00405 -225.186368)
			(xy 381.984759 -225.141092) (xy 381.972982 -225.093308) (xy 381.969022 -225.044254) (xy 381.64008 -225.044254)
			(xy 381.639585 -225.068861) (xy 381.63169 -225.117438) (xy 381.616106 -225.164119) (xy 381.593235 -225.207696)
			(xy 381.56367 -225.24704) (xy 381.528177 -225.281132) (xy 381.487674 -225.309088) (xy 381.443212 -225.330186)
			(xy 381.395941 -225.343878) (xy 381.347086 -225.34981) (xy 381.297911 -225.347829) (xy 381.249692 -225.337985)
			(xy 381.203676 -225.320533) (xy 381.161055 -225.295926) (xy 381.122934 -225.264801) (xy 381.090299 -225.227964)
			(xy 381.063996 -225.186368) (xy 381.044705 -225.141092) (xy 381.032928 -225.093308) (xy 381.028968 -225.044254)
			(xy 380.71044 -225.044254) (xy 380.709928 -225.0697) (xy 380.701764 -225.119934) (xy 380.685648 -225.168208)
			(xy 380.661997 -225.213271) (xy 380.631424 -225.253957) (xy 380.59472 -225.289212) (xy 380.552836 -225.318122)
			(xy 380.506857 -225.339939) (xy 380.457973 -225.354099) (xy 380.407452 -225.360233) (xy 380.3566 -225.358184)
			(xy 380.306736 -225.348004) (xy 380.25915 -225.329957) (xy 380.215076 -225.304511) (xy 380.175654 -225.272324)
			(xy 380.141906 -225.23423) (xy 380.114705 -225.191216) (xy 380.094757 -225.144396) (xy 380.082578 -225.094982)
			(xy 380.078483 -225.044254) (xy 379.760226 -225.044254) (xy 379.759731 -225.068861) (xy 379.751836 -225.117438)
			(xy 379.736252 -225.164119) (xy 379.713381 -225.207696) (xy 379.683816 -225.24704) (xy 379.648323 -225.281132)
			(xy 379.60782 -225.309088) (xy 379.563358 -225.330186) (xy 379.516087 -225.343878) (xy 379.467232 -225.34981)
			(xy 379.418057 -225.347829) (xy 379.369838 -225.337985) (xy 379.323822 -225.320533) (xy 379.281201 -225.295926)
			(xy 379.24308 -225.264801) (xy 379.210445 -225.227964) (xy 379.184142 -225.186368) (xy 379.164851 -225.141092)
			(xy 379.153074 -225.093308) (xy 379.149114 -225.044254) (xy 378.820172 -225.044254) (xy 378.819729 -225.068248)
			(xy 378.812228 -225.115647) (xy 378.797403 -225.161289) (xy 378.77562 -225.204049) (xy 378.747414 -225.242874)
			(xy 378.713481 -225.276808) (xy 378.674657 -225.305014) (xy 378.631898 -225.326799) (xy 378.586257 -225.341626)
			(xy 378.538858 -225.349128) (xy 378.514864 -225.349562) (xy 378.488544 -225.34899) (xy 378.436691 -225.339924)
			(xy 378.41174 -225.331528) (xy 378.39777 -225.326448) (xy 378.369068 -225.333052) (xy 378.23267 -225.46945)
			(xy 378.225623 -225.477312) (xy 378.218036 -225.49699) (xy 378.217938 -225.50755) (xy 378.221494 -225.58248)
			(xy 378.221876 -225.587825) (xy 378.224561 -225.598198) (xy 378.226828 -225.603054) (xy 378.231654 -225.612452)
			(xy 378.239782 -225.61931) (xy 378.260049 -225.636889) (xy 378.29468 -225.677858) (xy 378.321631 -225.724242)
			(xy 378.340074 -225.774617) (xy 378.349442 -225.827438) (xy 378.350018 -225.85426) (xy 378.668529 -225.85426)
			(xy 378.672624 -225.803532) (xy 378.684803 -225.754118) (xy 378.704751 -225.707298) (xy 378.731952 -225.664284)
			(xy 378.7657 -225.62619) (xy 378.805122 -225.594003) (xy 378.849196 -225.568557) (xy 378.896782 -225.55051)
			(xy 378.946646 -225.54033) (xy 378.997498 -225.538281) (xy 379.048019 -225.544415) (xy 379.096903 -225.558575)
			(xy 379.142882 -225.580392) (xy 379.184766 -225.609302) (xy 379.22147 -225.644557) (xy 379.252043 -225.685243)
			(xy 379.275694 -225.730306) (xy 379.29181 -225.77858) (xy 379.299974 -225.828814) (xy 379.300486 -225.85426)
			(xy 379.619014 -225.85426) (xy 379.622974 -225.805206) (xy 379.634751 -225.757422) (xy 379.654042 -225.712146)
			(xy 379.680345 -225.67055) (xy 379.71298 -225.633713) (xy 379.751101 -225.602588) (xy 379.793722 -225.577981)
			(xy 379.839738 -225.560529) (xy 379.887957 -225.550685) (xy 379.937132 -225.548704) (xy 379.985987 -225.554636)
			(xy 380.033258 -225.568328) (xy 380.07772 -225.589426) (xy 380.118223 -225.617382) (xy 380.153716 -225.651474)
			(xy 380.183281 -225.690818) (xy 380.206152 -225.734395) (xy 380.221736 -225.781076) (xy 380.229631 -225.829653)
			(xy 380.230126 -225.85426) (xy 380.548637 -225.85426) (xy 380.552732 -225.803532) (xy 380.564911 -225.754118)
			(xy 380.584859 -225.707298) (xy 380.61206 -225.664284) (xy 380.645808 -225.62619) (xy 380.68523 -225.594003)
			(xy 380.729304 -225.568557) (xy 380.77689 -225.55051) (xy 380.826754 -225.54033) (xy 380.877606 -225.538281)
			(xy 380.928127 -225.544415) (xy 380.977011 -225.558575) (xy 381.02299 -225.580392) (xy 381.064874 -225.609302)
			(xy 381.101578 -225.644557) (xy 381.132151 -225.685243) (xy 381.155802 -225.730306) (xy 381.171918 -225.77858)
			(xy 381.180082 -225.828814) (xy 381.180594 -225.85426) (xy 381.499122 -225.85426) (xy 381.503082 -225.805206)
			(xy 381.514859 -225.757422) (xy 381.53415 -225.712146) (xy 381.560453 -225.67055) (xy 381.593088 -225.633713)
			(xy 381.631209 -225.602588) (xy 381.67383 -225.577981) (xy 381.719846 -225.560529) (xy 381.768065 -225.550685)
			(xy 381.81724 -225.548704) (xy 381.866095 -225.554636) (xy 381.913366 -225.568328) (xy 381.957828 -225.589426)
			(xy 381.998331 -225.617382) (xy 382.033824 -225.651474) (xy 382.063389 -225.690818) (xy 382.08626 -225.734395)
			(xy 382.101844 -225.781076) (xy 382.109739 -225.829653) (xy 382.110234 -225.85426) (xy 382.428491 -225.85426)
			(xy 382.432586 -225.803532) (xy 382.444765 -225.754118) (xy 382.464713 -225.707298) (xy 382.491914 -225.664284)
			(xy 382.525662 -225.62619) (xy 382.565084 -225.594003) (xy 382.609158 -225.568557) (xy 382.656744 -225.55051)
			(xy 382.706608 -225.54033) (xy 382.75746 -225.538281) (xy 382.807981 -225.544415) (xy 382.856865 -225.558575)
			(xy 382.902844 -225.580392) (xy 382.944728 -225.609302) (xy 382.981432 -225.644557) (xy 383.012005 -225.685243)
			(xy 383.035656 -225.730306) (xy 383.051772 -225.77858) (xy 383.059936 -225.828814) (xy 383.060448 -225.85426)
			(xy 383.368545 -225.85426) (xy 383.37264 -225.803532) (xy 383.384819 -225.754118) (xy 383.404767 -225.707298)
			(xy 383.431968 -225.664284) (xy 383.465716 -225.62619) (xy 383.505138 -225.594003) (xy 383.549212 -225.568557)
			(xy 383.596798 -225.55051) (xy 383.646662 -225.54033) (xy 383.697514 -225.538281) (xy 383.748035 -225.544415)
			(xy 383.796919 -225.558575) (xy 383.842898 -225.580392) (xy 383.884782 -225.609302) (xy 383.921486 -225.644557)
			(xy 383.952059 -225.685243) (xy 383.97571 -225.730306) (xy 383.991826 -225.77858) (xy 383.99999 -225.828814)
			(xy 384.000502 -225.85426) (xy 384.31903 -225.85426) (xy 384.32299 -225.805206) (xy 384.334767 -225.757422)
			(xy 384.354058 -225.712146) (xy 384.380361 -225.67055) (xy 384.412996 -225.633713) (xy 384.451117 -225.602588)
			(xy 384.493738 -225.577981) (xy 384.539754 -225.560529) (xy 384.587973 -225.550685) (xy 384.637148 -225.548704)
			(xy 384.686003 -225.554636) (xy 384.733274 -225.568328) (xy 384.777736 -225.589426) (xy 384.818239 -225.617382)
			(xy 384.853732 -225.651474) (xy 384.883297 -225.690818) (xy 384.906168 -225.734395) (xy 384.921752 -225.781076)
			(xy 384.929647 -225.829653) (xy 384.930142 -225.85426) (xy 385.248653 -225.85426) (xy 385.252748 -225.803532)
			(xy 385.264927 -225.754118) (xy 385.284875 -225.707298) (xy 385.312076 -225.664284) (xy 385.345824 -225.62619)
			(xy 385.385246 -225.594003) (xy 385.42932 -225.568557) (xy 385.476906 -225.55051) (xy 385.52677 -225.54033)
			(xy 385.577622 -225.538281) (xy 385.628143 -225.544415) (xy 385.677027 -225.558575) (xy 385.723006 -225.580392)
			(xy 385.76489 -225.609302) (xy 385.801594 -225.644557) (xy 385.832167 -225.685243) (xy 385.855818 -225.730306)
			(xy 385.871934 -225.77858) (xy 385.880098 -225.828814) (xy 385.88061 -225.85426) (xy 386.199138 -225.85426)
			(xy 386.203098 -225.805206) (xy 386.214875 -225.757422) (xy 386.234166 -225.712146) (xy 386.260469 -225.67055)
			(xy 386.293104 -225.633713) (xy 386.331225 -225.602588) (xy 386.373846 -225.577981) (xy 386.419862 -225.560529)
			(xy 386.468081 -225.550685) (xy 386.517256 -225.548704) (xy 386.566111 -225.554636) (xy 386.613382 -225.568328)
			(xy 386.657844 -225.589426) (xy 386.698347 -225.617382) (xy 386.73384 -225.651474) (xy 386.763405 -225.690818)
			(xy 386.786276 -225.734395) (xy 386.80186 -225.781076) (xy 386.809755 -225.829653) (xy 386.81025 -225.85426)
			(xy 387.128507 -225.85426) (xy 387.132602 -225.803532) (xy 387.144781 -225.754118) (xy 387.164729 -225.707298)
			(xy 387.19193 -225.664284) (xy 387.225678 -225.62619) (xy 387.2651 -225.594003) (xy 387.309174 -225.568557)
			(xy 387.35676 -225.55051) (xy 387.406624 -225.54033) (xy 387.457476 -225.538281) (xy 387.507997 -225.544415)
			(xy 387.556881 -225.558575) (xy 387.60286 -225.580392) (xy 387.644744 -225.609302) (xy 387.681448 -225.644557)
			(xy 387.712021 -225.685243) (xy 387.735672 -225.730306) (xy 387.751788 -225.77858) (xy 387.759952 -225.828814)
			(xy 387.760464 -225.85426) (xy 388.078992 -225.85426) (xy 388.082952 -225.805206) (xy 388.094729 -225.757422)
			(xy 388.11402 -225.712146) (xy 388.140323 -225.67055) (xy 388.172958 -225.633713) (xy 388.211079 -225.602588)
			(xy 388.2537 -225.577981) (xy 388.299716 -225.560529) (xy 388.347935 -225.550685) (xy 388.39711 -225.548704)
			(xy 388.445965 -225.554636) (xy 388.493236 -225.568328) (xy 388.537698 -225.589426) (xy 388.578201 -225.617382)
			(xy 388.613694 -225.651474) (xy 388.643259 -225.690818) (xy 388.66613 -225.734395) (xy 388.681714 -225.781076)
			(xy 388.689609 -225.829653) (xy 388.690104 -225.85426) (xy 389.008615 -225.85426) (xy 389.01271 -225.803532)
			(xy 389.024889 -225.754118) (xy 389.044837 -225.707298) (xy 389.072038 -225.664284) (xy 389.105786 -225.62619)
			(xy 389.145208 -225.594003) (xy 389.189282 -225.568557) (xy 389.236868 -225.55051) (xy 389.286732 -225.54033)
			(xy 389.337584 -225.538281) (xy 389.388105 -225.544415) (xy 389.436989 -225.558575) (xy 389.482968 -225.580392)
			(xy 389.524852 -225.609302) (xy 389.561556 -225.644557) (xy 389.592129 -225.685243) (xy 389.61578 -225.730306)
			(xy 389.631896 -225.77858) (xy 389.64006 -225.828814) (xy 389.640572 -225.85426) (xy 389.948669 -225.85426)
			(xy 389.952764 -225.803532) (xy 389.964943 -225.754118) (xy 389.984891 -225.707298) (xy 390.012092 -225.664284)
			(xy 390.04584 -225.62619) (xy 390.085262 -225.594003) (xy 390.129336 -225.568557) (xy 390.176922 -225.55051)
			(xy 390.226786 -225.54033) (xy 390.277638 -225.538281) (xy 390.328159 -225.544415) (xy 390.377043 -225.558575)
			(xy 390.423022 -225.580392) (xy 390.464906 -225.609302) (xy 390.50161 -225.644557) (xy 390.532183 -225.685243)
			(xy 390.555834 -225.730306) (xy 390.57195 -225.77858) (xy 390.580114 -225.828814) (xy 390.580626 -225.85426)
			(xy 390.8989 -225.85426) (xy 390.90286 -225.805206) (xy 390.914637 -225.757422) (xy 390.933928 -225.712146)
			(xy 390.960231 -225.67055) (xy 390.992866 -225.633713) (xy 391.030987 -225.602588) (xy 391.073608 -225.577981)
			(xy 391.119624 -225.560529) (xy 391.167843 -225.550685) (xy 391.217018 -225.548704) (xy 391.265873 -225.554636)
			(xy 391.313144 -225.568328) (xy 391.357606 -225.589426) (xy 391.398109 -225.617382) (xy 391.433602 -225.651474)
			(xy 391.463167 -225.690818) (xy 391.486038 -225.734395) (xy 391.501622 -225.781076) (xy 391.509517 -225.829653)
			(xy 391.510012 -225.85426) (xy 392.779008 -225.85426) (xy 392.782968 -225.805206) (xy 392.794745 -225.757422)
			(xy 392.814036 -225.712146) (xy 392.840339 -225.67055) (xy 392.872974 -225.633713) (xy 392.911095 -225.602588)
			(xy 392.953716 -225.577981) (xy 392.999732 -225.560529) (xy 393.047951 -225.550685) (xy 393.097126 -225.548704)
			(xy 393.145981 -225.554636) (xy 393.193252 -225.568328) (xy 393.237714 -225.589426) (xy 393.278217 -225.617382)
			(xy 393.31371 -225.651474) (xy 393.343275 -225.690818) (xy 393.366146 -225.734395) (xy 393.38173 -225.781076)
			(xy 393.389625 -225.829653) (xy 393.39012 -225.85426) (xy 393.389625 -225.878867) (xy 393.38173 -225.927444)
			(xy 393.366146 -225.974125) (xy 393.343275 -226.017702) (xy 393.31371 -226.057046) (xy 393.278217 -226.091138)
			(xy 393.237714 -226.119094) (xy 393.193252 -226.140192) (xy 393.145981 -226.153884) (xy 393.097126 -226.159816)
			(xy 393.047951 -226.157835) (xy 392.999732 -226.147991) (xy 392.953716 -226.130539) (xy 392.911095 -226.105932)
			(xy 392.872974 -226.074807) (xy 392.840339 -226.03797) (xy 392.814036 -225.996374) (xy 392.794745 -225.951098)
			(xy 392.782968 -225.903314) (xy 392.779008 -225.85426) (xy 391.510012 -225.85426) (xy 391.509517 -225.878867)
			(xy 391.501622 -225.927444) (xy 391.486038 -225.974125) (xy 391.463167 -226.017702) (xy 391.433602 -226.057046)
			(xy 391.398109 -226.091138) (xy 391.357606 -226.119094) (xy 391.313144 -226.140192) (xy 391.265873 -226.153884)
			(xy 391.217018 -226.159816) (xy 391.167843 -226.157835) (xy 391.119624 -226.147991) (xy 391.073608 -226.130539)
			(xy 391.030987 -226.105932) (xy 390.992866 -226.074807) (xy 390.960231 -226.03797) (xy 390.933928 -225.996374)
			(xy 390.914637 -225.951098) (xy 390.90286 -225.903314) (xy 390.8989 -225.85426) (xy 390.580626 -225.85426)
			(xy 390.580114 -225.879706) (xy 390.57195 -225.92994) (xy 390.555834 -225.978214) (xy 390.532183 -226.023277)
			(xy 390.50161 -226.063963) (xy 390.464906 -226.099218) (xy 390.423022 -226.128128) (xy 390.377043 -226.149945)
			(xy 390.328159 -226.164105) (xy 390.277638 -226.170239) (xy 390.226786 -226.16819) (xy 390.176922 -226.15801)
			(xy 390.129336 -226.139963) (xy 390.085262 -226.114517) (xy 390.04584 -226.08233) (xy 390.012092 -226.044236)
			(xy 389.984891 -226.001222) (xy 389.964943 -225.954402) (xy 389.952764 -225.904988) (xy 389.948669 -225.85426)
			(xy 389.640572 -225.85426) (xy 389.64006 -225.879706) (xy 389.631896 -225.92994) (xy 389.61578 -225.978214)
			(xy 389.592129 -226.023277) (xy 389.561556 -226.063963) (xy 389.524852 -226.099218) (xy 389.482968 -226.128128)
			(xy 389.436989 -226.149945) (xy 389.388105 -226.164105) (xy 389.337584 -226.170239) (xy 389.286732 -226.16819)
			(xy 389.236868 -226.15801) (xy 389.189282 -226.139963) (xy 389.145208 -226.114517) (xy 389.105786 -226.08233)
			(xy 389.072038 -226.044236) (xy 389.044837 -226.001222) (xy 389.024889 -225.954402) (xy 389.01271 -225.904988)
			(xy 389.008615 -225.85426) (xy 388.690104 -225.85426) (xy 388.689609 -225.878867) (xy 388.681714 -225.927444)
			(xy 388.66613 -225.974125) (xy 388.643259 -226.017702) (xy 388.613694 -226.057046) (xy 388.578201 -226.091138)
			(xy 388.537698 -226.119094) (xy 388.493236 -226.140192) (xy 388.445965 -226.153884) (xy 388.39711 -226.159816)
			(xy 388.347935 -226.157835) (xy 388.299716 -226.147991) (xy 388.2537 -226.130539) (xy 388.211079 -226.105932)
			(xy 388.172958 -226.074807) (xy 388.140323 -226.03797) (xy 388.11402 -225.996374) (xy 388.094729 -225.951098)
			(xy 388.082952 -225.903314) (xy 388.078992 -225.85426) (xy 387.760464 -225.85426) (xy 387.759952 -225.879706)
			(xy 387.751788 -225.92994) (xy 387.735672 -225.978214) (xy 387.712021 -226.023277) (xy 387.681448 -226.063963)
			(xy 387.644744 -226.099218) (xy 387.60286 -226.128128) (xy 387.556881 -226.149945) (xy 387.507997 -226.164105)
			(xy 387.457476 -226.170239) (xy 387.406624 -226.16819) (xy 387.35676 -226.15801) (xy 387.309174 -226.139963)
			(xy 387.2651 -226.114517) (xy 387.225678 -226.08233) (xy 387.19193 -226.044236) (xy 387.164729 -226.001222)
			(xy 387.144781 -225.954402) (xy 387.132602 -225.904988) (xy 387.128507 -225.85426) (xy 386.81025 -225.85426)
			(xy 386.809755 -225.878867) (xy 386.80186 -225.927444) (xy 386.786276 -225.974125) (xy 386.763405 -226.017702)
			(xy 386.73384 -226.057046) (xy 386.698347 -226.091138) (xy 386.657844 -226.119094) (xy 386.613382 -226.140192)
			(xy 386.566111 -226.153884) (xy 386.517256 -226.159816) (xy 386.468081 -226.157835) (xy 386.419862 -226.147991)
			(xy 386.373846 -226.130539) (xy 386.331225 -226.105932) (xy 386.293104 -226.074807) (xy 386.260469 -226.03797)
			(xy 386.234166 -225.996374) (xy 386.214875 -225.951098) (xy 386.203098 -225.903314) (xy 386.199138 -225.85426)
			(xy 385.88061 -225.85426) (xy 385.880098 -225.879706) (xy 385.871934 -225.92994) (xy 385.855818 -225.978214)
			(xy 385.832167 -226.023277) (xy 385.801594 -226.063963) (xy 385.76489 -226.099218) (xy 385.723006 -226.128128)
			(xy 385.677027 -226.149945) (xy 385.628143 -226.164105) (xy 385.577622 -226.170239) (xy 385.52677 -226.16819)
			(xy 385.476906 -226.15801) (xy 385.42932 -226.139963) (xy 385.385246 -226.114517) (xy 385.345824 -226.08233)
			(xy 385.312076 -226.044236) (xy 385.284875 -226.001222) (xy 385.264927 -225.954402) (xy 385.252748 -225.904988)
			(xy 385.248653 -225.85426) (xy 384.930142 -225.85426) (xy 384.929647 -225.878867) (xy 384.921752 -225.927444)
			(xy 384.906168 -225.974125) (xy 384.883297 -226.017702) (xy 384.853732 -226.057046) (xy 384.818239 -226.091138)
			(xy 384.777736 -226.119094) (xy 384.733274 -226.140192) (xy 384.686003 -226.153884) (xy 384.637148 -226.159816)
			(xy 384.587973 -226.157835) (xy 384.539754 -226.147991) (xy 384.493738 -226.130539) (xy 384.451117 -226.105932)
			(xy 384.412996 -226.074807) (xy 384.380361 -226.03797) (xy 384.354058 -225.996374) (xy 384.334767 -225.951098)
			(xy 384.32299 -225.903314) (xy 384.31903 -225.85426) (xy 384.000502 -225.85426) (xy 383.99999 -225.879706)
			(xy 383.991826 -225.92994) (xy 383.97571 -225.978214) (xy 383.952059 -226.023277) (xy 383.921486 -226.063963)
			(xy 383.884782 -226.099218) (xy 383.842898 -226.128128) (xy 383.796919 -226.149945) (xy 383.748035 -226.164105)
			(xy 383.697514 -226.170239) (xy 383.646662 -226.16819) (xy 383.596798 -226.15801) (xy 383.549212 -226.139963)
			(xy 383.505138 -226.114517) (xy 383.465716 -226.08233) (xy 383.431968 -226.044236) (xy 383.404767 -226.001222)
			(xy 383.384819 -225.954402) (xy 383.37264 -225.904988) (xy 383.368545 -225.85426) (xy 383.060448 -225.85426)
			(xy 383.059936 -225.879706) (xy 383.051772 -225.92994) (xy 383.035656 -225.978214) (xy 383.012005 -226.023277)
			(xy 382.981432 -226.063963) (xy 382.944728 -226.099218) (xy 382.902844 -226.128128) (xy 382.856865 -226.149945)
			(xy 382.807981 -226.164105) (xy 382.75746 -226.170239) (xy 382.706608 -226.16819) (xy 382.656744 -226.15801)
			(xy 382.609158 -226.139963) (xy 382.565084 -226.114517) (xy 382.525662 -226.08233) (xy 382.491914 -226.044236)
			(xy 382.464713 -226.001222) (xy 382.444765 -225.954402) (xy 382.432586 -225.904988) (xy 382.428491 -225.85426)
			(xy 382.110234 -225.85426) (xy 382.109739 -225.878867) (xy 382.101844 -225.927444) (xy 382.08626 -225.974125)
			(xy 382.063389 -226.017702) (xy 382.033824 -226.057046) (xy 381.998331 -226.091138) (xy 381.957828 -226.119094)
			(xy 381.913366 -226.140192) (xy 381.866095 -226.153884) (xy 381.81724 -226.159816) (xy 381.768065 -226.157835)
			(xy 381.719846 -226.147991) (xy 381.67383 -226.130539) (xy 381.631209 -226.105932) (xy 381.593088 -226.074807)
			(xy 381.560453 -226.03797) (xy 381.53415 -225.996374) (xy 381.514859 -225.951098) (xy 381.503082 -225.903314)
			(xy 381.499122 -225.85426) (xy 381.180594 -225.85426) (xy 381.180082 -225.879706) (xy 381.171918 -225.92994)
			(xy 381.155802 -225.978214) (xy 381.132151 -226.023277) (xy 381.101578 -226.063963) (xy 381.064874 -226.099218)
			(xy 381.02299 -226.128128) (xy 380.977011 -226.149945) (xy 380.928127 -226.164105) (xy 380.877606 -226.170239)
			(xy 380.826754 -226.16819) (xy 380.77689 -226.15801) (xy 380.729304 -226.139963) (xy 380.68523 -226.114517)
			(xy 380.645808 -226.08233) (xy 380.61206 -226.044236) (xy 380.584859 -226.001222) (xy 380.564911 -225.954402)
			(xy 380.552732 -225.904988) (xy 380.548637 -225.85426) (xy 380.230126 -225.85426) (xy 380.229631 -225.878867)
			(xy 380.221736 -225.927444) (xy 380.206152 -225.974125) (xy 380.183281 -226.017702) (xy 380.153716 -226.057046)
			(xy 380.118223 -226.091138) (xy 380.07772 -226.119094) (xy 380.033258 -226.140192) (xy 379.985987 -226.153884)
			(xy 379.937132 -226.159816) (xy 379.887957 -226.157835) (xy 379.839738 -226.147991) (xy 379.793722 -226.130539)
			(xy 379.751101 -226.105932) (xy 379.71298 -226.074807) (xy 379.680345 -226.03797) (xy 379.654042 -225.996374)
			(xy 379.634751 -225.951098) (xy 379.622974 -225.903314) (xy 379.619014 -225.85426) (xy 379.300486 -225.85426)
			(xy 379.299974 -225.879706) (xy 379.29181 -225.92994) (xy 379.275694 -225.978214) (xy 379.252043 -226.023277)
			(xy 379.22147 -226.063963) (xy 379.184766 -226.099218) (xy 379.142882 -226.128128) (xy 379.096903 -226.149945)
			(xy 379.048019 -226.164105) (xy 378.997498 -226.170239) (xy 378.946646 -226.16819) (xy 378.896782 -226.15801)
			(xy 378.849196 -226.139963) (xy 378.805122 -226.114517) (xy 378.7657 -226.08233) (xy 378.731952 -226.044236)
			(xy 378.704751 -226.001222) (xy 378.684803 -225.954402) (xy 378.672624 -225.904988) (xy 378.668529 -225.85426)
			(xy 378.350018 -225.85426) (xy 378.349575 -225.878255) (xy 378.342073 -225.925656) (xy 378.327248 -225.9713)
			(xy 378.305465 -226.014062) (xy 378.27726 -226.05289) (xy 378.243329 -226.086828) (xy 378.204505 -226.115039)
			(xy 378.161746 -226.136829) (xy 378.116105 -226.151661) (xy 378.068705 -226.159171) (xy 378.04471 -226.159568)
			(xy 378.017896 -226.159035) (xy 377.965085 -226.149723) (xy 377.914712 -226.131332) (xy 377.868324 -226.104426)
			(xy 377.827348 -226.069832) (xy 377.80976 -226.049586) (xy 377.80976 -226.049332) (xy 377.802902 -226.041204)
			(xy 377.793504 -226.036378) (xy 377.788657 -226.034084) (xy 377.778281 -226.031388) (xy 377.77293 -226.031044)
			(xy 377.698 -226.027488) (xy 377.687436 -226.027541) (xy 377.667759 -226.03516) (xy 377.6599 -226.04222)
			(xy 377.5202 -226.18192) (xy 377.513641 -226.189174) (xy 377.506065 -226.207185) (xy 377.505738 -226.226722)
			(xy 377.50877 -226.236022) (xy 377.50877 -226.236276) (xy 377.5456 -226.331018) (xy 377.570238 -226.34829)
			(xy 377.585478 -226.348798) (xy 377.609723 -226.350064) (xy 377.657422 -226.359112) (xy 377.703173 -226.375354)
			(xy 377.745899 -226.398407) (xy 377.784594 -226.427728) (xy 377.818345 -226.462626) (xy 377.846357 -226.502278)
			(xy 377.867971 -226.54575) (xy 377.882677 -226.592018) (xy 377.890127 -226.639992) (xy 377.890532 -226.664266)
			(xy 378.20906 -226.664266) (xy 378.21302 -226.615212) (xy 378.224797 -226.567428) (xy 378.244088 -226.522152)
			(xy 378.270391 -226.480556) (xy 378.303026 -226.443719) (xy 378.341147 -226.412594) (xy 378.383768 -226.387987)
			(xy 378.429784 -226.370535) (xy 378.478003 -226.360691) (xy 378.527178 -226.35871) (xy 378.576033 -226.364642)
			(xy 378.623304 -226.378334) (xy 378.667766 -226.399432) (xy 378.708269 -226.427388) (xy 378.743762 -226.46148)
			(xy 378.773327 -226.500824) (xy 378.796198 -226.544401) (xy 378.811782 -226.591082) (xy 378.819677 -226.639659)
			(xy 378.820172 -226.664266) (xy 379.138683 -226.664266) (xy 379.142778 -226.613538) (xy 379.154957 -226.564124)
			(xy 379.174905 -226.517304) (xy 379.202106 -226.47429) (xy 379.235854 -226.436196) (xy 379.275276 -226.404009)
			(xy 379.31935 -226.378563) (xy 379.366936 -226.360516) (xy 379.4168 -226.350336) (xy 379.467652 -226.348287)
			(xy 379.518173 -226.354421) (xy 379.567057 -226.368581) (xy 379.613036 -226.390398) (xy 379.65492 -226.419308)
			(xy 379.691624 -226.454563) (xy 379.722197 -226.495249) (xy 379.745848 -226.540312) (xy 379.761964 -226.588586)
			(xy 379.770128 -226.63882) (xy 379.77064 -226.664266) (xy 380.078483 -226.664266) (xy 380.082578 -226.613538)
			(xy 380.094757 -226.564124) (xy 380.114705 -226.517304) (xy 380.141906 -226.47429) (xy 380.175654 -226.436196)
			(xy 380.215076 -226.404009) (xy 380.25915 -226.378563) (xy 380.306736 -226.360516) (xy 380.3566 -226.350336)
			(xy 380.407452 -226.348287) (xy 380.457973 -226.354421) (xy 380.506857 -226.368581) (xy 380.552836 -226.390398)
			(xy 380.59472 -226.419308) (xy 380.631424 -226.454563) (xy 380.661997 -226.495249) (xy 380.685648 -226.540312)
			(xy 380.701764 -226.588586) (xy 380.709928 -226.63882) (xy 380.71044 -226.664266) (xy 381.028968 -226.664266)
			(xy 381.032928 -226.615212) (xy 381.044705 -226.567428) (xy 381.063996 -226.522152) (xy 381.090299 -226.480556)
			(xy 381.122934 -226.443719) (xy 381.161055 -226.412594) (xy 381.203676 -226.387987) (xy 381.249692 -226.370535)
			(xy 381.297911 -226.360691) (xy 381.347086 -226.35871) (xy 381.395941 -226.364642) (xy 381.443212 -226.378334)
			(xy 381.487674 -226.399432) (xy 381.528177 -226.427388) (xy 381.56367 -226.46148) (xy 381.593235 -226.500824)
			(xy 381.616106 -226.544401) (xy 381.63169 -226.591082) (xy 381.639585 -226.639659) (xy 381.64008 -226.664266)
			(xy 381.958591 -226.664266) (xy 381.962686 -226.613538) (xy 381.974865 -226.564124) (xy 381.994813 -226.517304)
			(xy 382.022014 -226.47429) (xy 382.055762 -226.436196) (xy 382.095184 -226.404009) (xy 382.139258 -226.378563)
			(xy 382.186844 -226.360516) (xy 382.236708 -226.350336) (xy 382.28756 -226.348287) (xy 382.338081 -226.354421)
			(xy 382.386965 -226.368581) (xy 382.432944 -226.390398) (xy 382.474828 -226.419308) (xy 382.511532 -226.454563)
			(xy 382.542105 -226.495249) (xy 382.565756 -226.540312) (xy 382.581872 -226.588586) (xy 382.590036 -226.63882)
			(xy 382.590548 -226.664266) (xy 382.909076 -226.664266) (xy 382.913036 -226.615212) (xy 382.924813 -226.567428)
			(xy 382.944104 -226.522152) (xy 382.970407 -226.480556) (xy 383.003042 -226.443719) (xy 383.041163 -226.412594)
			(xy 383.083784 -226.387987) (xy 383.1298 -226.370535) (xy 383.178019 -226.360691) (xy 383.227194 -226.35871)
			(xy 383.276049 -226.364642) (xy 383.32332 -226.378334) (xy 383.367782 -226.399432) (xy 383.408285 -226.427388)
			(xy 383.443778 -226.46148) (xy 383.473343 -226.500824) (xy 383.496214 -226.544401) (xy 383.511798 -226.591082)
			(xy 383.519693 -226.639659) (xy 383.520188 -226.664266) (xy 383.838699 -226.664266) (xy 383.842794 -226.613538)
			(xy 383.854973 -226.564124) (xy 383.874921 -226.517304) (xy 383.902122 -226.47429) (xy 383.93587 -226.436196)
			(xy 383.975292 -226.404009) (xy 384.019366 -226.378563) (xy 384.066952 -226.360516) (xy 384.116816 -226.350336)
			(xy 384.167668 -226.348287) (xy 384.218189 -226.354421) (xy 384.267073 -226.368581) (xy 384.313052 -226.390398)
			(xy 384.354936 -226.419308) (xy 384.39164 -226.454563) (xy 384.422213 -226.495249) (xy 384.445864 -226.540312)
			(xy 384.46198 -226.588586) (xy 384.470144 -226.63882) (xy 384.470656 -226.664266) (xy 384.78893 -226.664266)
			(xy 384.79289 -226.615212) (xy 384.804667 -226.567428) (xy 384.823958 -226.522152) (xy 384.850261 -226.480556)
			(xy 384.882896 -226.443719) (xy 384.921017 -226.412594) (xy 384.963638 -226.387987) (xy 385.009654 -226.370535)
			(xy 385.057873 -226.360691) (xy 385.107048 -226.35871) (xy 385.155903 -226.364642) (xy 385.203174 -226.378334)
			(xy 385.247636 -226.399432) (xy 385.288139 -226.427388) (xy 385.323632 -226.46148) (xy 385.353197 -226.500824)
			(xy 385.376068 -226.544401) (xy 385.391652 -226.591082) (xy 385.399547 -226.639659) (xy 385.400042 -226.664266)
			(xy 385.718553 -226.664266) (xy 385.722648 -226.613538) (xy 385.734827 -226.564124) (xy 385.754775 -226.517304)
			(xy 385.781976 -226.47429) (xy 385.815724 -226.436196) (xy 385.855146 -226.404009) (xy 385.89922 -226.378563)
			(xy 385.946806 -226.360516) (xy 385.99667 -226.350336) (xy 386.047522 -226.348287) (xy 386.098043 -226.354421)
			(xy 386.146927 -226.368581) (xy 386.192906 -226.390398) (xy 386.23479 -226.419308) (xy 386.271494 -226.454563)
			(xy 386.302067 -226.495249) (xy 386.325718 -226.540312) (xy 386.341834 -226.588586) (xy 386.349998 -226.63882)
			(xy 386.35051 -226.664266) (xy 386.658607 -226.664266) (xy 386.662702 -226.613538) (xy 386.674881 -226.564124)
			(xy 386.694829 -226.517304) (xy 386.72203 -226.47429) (xy 386.755778 -226.436196) (xy 386.7952 -226.404009)
			(xy 386.839274 -226.378563) (xy 386.88686 -226.360516) (xy 386.936724 -226.350336) (xy 386.987576 -226.348287)
			(xy 387.038097 -226.354421) (xy 387.086981 -226.368581) (xy 387.13296 -226.390398) (xy 387.174844 -226.419308)
			(xy 387.211548 -226.454563) (xy 387.242121 -226.495249) (xy 387.265772 -226.540312) (xy 387.281888 -226.588586)
			(xy 387.290052 -226.63882) (xy 387.290564 -226.664266) (xy 387.609092 -226.664266) (xy 387.613052 -226.615212)
			(xy 387.624829 -226.567428) (xy 387.64412 -226.522152) (xy 387.670423 -226.480556) (xy 387.703058 -226.443719)
			(xy 387.741179 -226.412594) (xy 387.7838 -226.387987) (xy 387.829816 -226.370535) (xy 387.878035 -226.360691)
			(xy 387.92721 -226.35871) (xy 387.976065 -226.364642) (xy 388.023336 -226.378334) (xy 388.067798 -226.399432)
			(xy 388.108301 -226.427388) (xy 388.143794 -226.46148) (xy 388.173359 -226.500824) (xy 388.19623 -226.544401)
			(xy 388.211814 -226.591082) (xy 388.219709 -226.639659) (xy 388.220204 -226.664266) (xy 388.538715 -226.664266)
			(xy 388.54281 -226.613538) (xy 388.554989 -226.564124) (xy 388.574937 -226.517304) (xy 388.602138 -226.47429)
			(xy 388.635886 -226.436196) (xy 388.675308 -226.404009) (xy 388.719382 -226.378563) (xy 388.766968 -226.360516)
			(xy 388.816832 -226.350336) (xy 388.867684 -226.348287) (xy 388.918205 -226.354421) (xy 388.967089 -226.368581)
			(xy 389.013068 -226.390398) (xy 389.054952 -226.419308) (xy 389.091656 -226.454563) (xy 389.122229 -226.495249)
			(xy 389.14588 -226.540312) (xy 389.161996 -226.588586) (xy 389.17016 -226.63882) (xy 389.170672 -226.664266)
			(xy 389.488946 -226.664266) (xy 389.492906 -226.615212) (xy 389.504683 -226.567428) (xy 389.523974 -226.522152)
			(xy 389.550277 -226.480556) (xy 389.582912 -226.443719) (xy 389.621033 -226.412594) (xy 389.663654 -226.387987)
			(xy 389.70967 -226.370535) (xy 389.757889 -226.360691) (xy 389.807064 -226.35871) (xy 389.855919 -226.364642)
			(xy 389.90319 -226.378334) (xy 389.947652 -226.399432) (xy 389.988155 -226.427388) (xy 390.023648 -226.46148)
			(xy 390.053213 -226.500824) (xy 390.076084 -226.544401) (xy 390.091668 -226.591082) (xy 390.099563 -226.639659)
			(xy 390.100058 -226.664266) (xy 390.418569 -226.664266) (xy 390.422664 -226.613538) (xy 390.434843 -226.564124)
			(xy 390.454791 -226.517304) (xy 390.481992 -226.47429) (xy 390.51574 -226.436196) (xy 390.555162 -226.404009)
			(xy 390.599236 -226.378563) (xy 390.646822 -226.360516) (xy 390.696686 -226.350336) (xy 390.747538 -226.348287)
			(xy 390.798059 -226.354421) (xy 390.846943 -226.368581) (xy 390.892922 -226.390398) (xy 390.934806 -226.419308)
			(xy 390.97151 -226.454563) (xy 391.002083 -226.495249) (xy 391.025734 -226.540312) (xy 391.04185 -226.588586)
			(xy 391.050014 -226.63882) (xy 391.050526 -226.664266) (xy 391.369054 -226.664266) (xy 391.373014 -226.615212)
			(xy 391.384791 -226.567428) (xy 391.404082 -226.522152) (xy 391.430385 -226.480556) (xy 391.46302 -226.443719)
			(xy 391.501141 -226.412594) (xy 391.543762 -226.387987) (xy 391.589778 -226.370535) (xy 391.637997 -226.360691)
			(xy 391.687172 -226.35871) (xy 391.736027 -226.364642) (xy 391.783298 -226.378334) (xy 391.82776 -226.399432)
			(xy 391.868263 -226.427388) (xy 391.903756 -226.46148) (xy 391.933321 -226.500824) (xy 391.956192 -226.544401)
			(xy 391.971776 -226.591082) (xy 391.979671 -226.639659) (xy 391.980166 -226.664266) (xy 394.188962 -226.664266)
			(xy 394.192922 -226.615212) (xy 394.204699 -226.567428) (xy 394.22399 -226.522152) (xy 394.250293 -226.480556)
			(xy 394.282928 -226.443719) (xy 394.321049 -226.412594) (xy 394.36367 -226.387987) (xy 394.409686 -226.370535)
			(xy 394.457905 -226.360691) (xy 394.50708 -226.35871) (xy 394.555935 -226.364642) (xy 394.603206 -226.378334)
			(xy 394.647668 -226.399432) (xy 394.688171 -226.427388) (xy 394.723664 -226.46148) (xy 394.753229 -226.500824)
			(xy 394.7761 -226.544401) (xy 394.791684 -226.591082) (xy 394.799579 -226.639659) (xy 394.800074 -226.664266)
			(xy 394.799579 -226.688873) (xy 394.791684 -226.73745) (xy 394.7761 -226.784131) (xy 394.753229 -226.827708)
			(xy 394.723664 -226.867052) (xy 394.688171 -226.901144) (xy 394.647668 -226.9291) (xy 394.603206 -226.950198)
			(xy 394.555935 -226.96389) (xy 394.50708 -226.969822) (xy 394.457905 -226.967841) (xy 394.409686 -226.957997)
			(xy 394.36367 -226.940545) (xy 394.321049 -226.915938) (xy 394.282928 -226.884813) (xy 394.250293 -226.847976)
			(xy 394.22399 -226.80638) (xy 394.204699 -226.761104) (xy 394.192922 -226.71332) (xy 394.188962 -226.664266)
			(xy 391.980166 -226.664266) (xy 391.979671 -226.688873) (xy 391.971776 -226.73745) (xy 391.956192 -226.784131)
			(xy 391.933321 -226.827708) (xy 391.903756 -226.867052) (xy 391.868263 -226.901144) (xy 391.82776 -226.9291)
			(xy 391.783298 -226.950198) (xy 391.736027 -226.96389) (xy 391.687172 -226.969822) (xy 391.637997 -226.967841)
			(xy 391.589778 -226.957997) (xy 391.543762 -226.940545) (xy 391.501141 -226.915938) (xy 391.46302 -226.884813)
			(xy 391.430385 -226.847976) (xy 391.404082 -226.80638) (xy 391.384791 -226.761104) (xy 391.373014 -226.71332)
			(xy 391.369054 -226.664266) (xy 391.050526 -226.664266) (xy 391.050014 -226.689712) (xy 391.04185 -226.739946)
			(xy 391.025734 -226.78822) (xy 391.002083 -226.833283) (xy 390.97151 -226.873969) (xy 390.934806 -226.909224)
			(xy 390.892922 -226.938134) (xy 390.846943 -226.959951) (xy 390.798059 -226.974111) (xy 390.747538 -226.980245)
			(xy 390.696686 -226.978196) (xy 390.646822 -226.968016) (xy 390.599236 -226.949969) (xy 390.555162 -226.924523)
			(xy 390.51574 -226.892336) (xy 390.481992 -226.854242) (xy 390.454791 -226.811228) (xy 390.434843 -226.764408)
			(xy 390.422664 -226.714994) (xy 390.418569 -226.664266) (xy 390.100058 -226.664266) (xy 390.099563 -226.688873)
			(xy 390.091668 -226.73745) (xy 390.076084 -226.784131) (xy 390.053213 -226.827708) (xy 390.023648 -226.867052)
			(xy 389.988155 -226.901144) (xy 389.947652 -226.9291) (xy 389.90319 -226.950198) (xy 389.855919 -226.96389)
			(xy 389.807064 -226.969822) (xy 389.757889 -226.967841) (xy 389.70967 -226.957997) (xy 389.663654 -226.940545)
			(xy 389.621033 -226.915938) (xy 389.582912 -226.884813) (xy 389.550277 -226.847976) (xy 389.523974 -226.80638)
			(xy 389.504683 -226.761104) (xy 389.492906 -226.71332) (xy 389.488946 -226.664266) (xy 389.170672 -226.664266)
			(xy 389.17016 -226.689712) (xy 389.161996 -226.739946) (xy 389.14588 -226.78822) (xy 389.122229 -226.833283)
			(xy 389.091656 -226.873969) (xy 389.054952 -226.909224) (xy 389.013068 -226.938134) (xy 388.967089 -226.959951)
			(xy 388.918205 -226.974111) (xy 388.867684 -226.980245) (xy 388.816832 -226.978196) (xy 388.766968 -226.968016)
			(xy 388.719382 -226.949969) (xy 388.675308 -226.924523) (xy 388.635886 -226.892336) (xy 388.602138 -226.854242)
			(xy 388.574937 -226.811228) (xy 388.554989 -226.764408) (xy 388.54281 -226.714994) (xy 388.538715 -226.664266)
			(xy 388.220204 -226.664266) (xy 388.219709 -226.688873) (xy 388.211814 -226.73745) (xy 388.19623 -226.784131)
			(xy 388.173359 -226.827708) (xy 388.143794 -226.867052) (xy 388.108301 -226.901144) (xy 388.067798 -226.9291)
			(xy 388.023336 -226.950198) (xy 387.976065 -226.96389) (xy 387.92721 -226.969822) (xy 387.878035 -226.967841)
			(xy 387.829816 -226.957997) (xy 387.7838 -226.940545) (xy 387.741179 -226.915938) (xy 387.703058 -226.884813)
			(xy 387.670423 -226.847976) (xy 387.64412 -226.80638) (xy 387.624829 -226.761104) (xy 387.613052 -226.71332)
			(xy 387.609092 -226.664266) (xy 387.290564 -226.664266) (xy 387.290052 -226.689712) (xy 387.281888 -226.739946)
			(xy 387.265772 -226.78822) (xy 387.242121 -226.833283) (xy 387.211548 -226.873969) (xy 387.174844 -226.909224)
			(xy 387.13296 -226.938134) (xy 387.086981 -226.959951) (xy 387.038097 -226.974111) (xy 386.987576 -226.980245)
			(xy 386.936724 -226.978196) (xy 386.88686 -226.968016) (xy 386.839274 -226.949969) (xy 386.7952 -226.924523)
			(xy 386.755778 -226.892336) (xy 386.72203 -226.854242) (xy 386.694829 -226.811228) (xy 386.674881 -226.764408)
			(xy 386.662702 -226.714994) (xy 386.658607 -226.664266) (xy 386.35051 -226.664266) (xy 386.349998 -226.689712)
			(xy 386.341834 -226.739946) (xy 386.325718 -226.78822) (xy 386.302067 -226.833283) (xy 386.271494 -226.873969)
			(xy 386.23479 -226.909224) (xy 386.192906 -226.938134) (xy 386.146927 -226.959951) (xy 386.098043 -226.974111)
			(xy 386.047522 -226.980245) (xy 385.99667 -226.978196) (xy 385.946806 -226.968016) (xy 385.89922 -226.949969)
			(xy 385.855146 -226.924523) (xy 385.815724 -226.892336) (xy 385.781976 -226.854242) (xy 385.754775 -226.811228)
			(xy 385.734827 -226.764408) (xy 385.722648 -226.714994) (xy 385.718553 -226.664266) (xy 385.400042 -226.664266)
			(xy 385.399547 -226.688873) (xy 385.391652 -226.73745) (xy 385.376068 -226.784131) (xy 385.353197 -226.827708)
			(xy 385.323632 -226.867052) (xy 385.288139 -226.901144) (xy 385.247636 -226.9291) (xy 385.203174 -226.950198)
			(xy 385.155903 -226.96389) (xy 385.107048 -226.969822) (xy 385.057873 -226.967841) (xy 385.009654 -226.957997)
			(xy 384.963638 -226.940545) (xy 384.921017 -226.915938) (xy 384.882896 -226.884813) (xy 384.850261 -226.847976)
			(xy 384.823958 -226.80638) (xy 384.804667 -226.761104) (xy 384.79289 -226.71332) (xy 384.78893 -226.664266)
			(xy 384.470656 -226.664266) (xy 384.470144 -226.689712) (xy 384.46198 -226.739946) (xy 384.445864 -226.78822)
			(xy 384.422213 -226.833283) (xy 384.39164 -226.873969) (xy 384.354936 -226.909224) (xy 384.313052 -226.938134)
			(xy 384.267073 -226.959951) (xy 384.218189 -226.974111) (xy 384.167668 -226.980245) (xy 384.116816 -226.978196)
			(xy 384.066952 -226.968016) (xy 384.019366 -226.949969) (xy 383.975292 -226.924523) (xy 383.93587 -226.892336)
			(xy 383.902122 -226.854242) (xy 383.874921 -226.811228) (xy 383.854973 -226.764408) (xy 383.842794 -226.714994)
			(xy 383.838699 -226.664266) (xy 383.520188 -226.664266) (xy 383.519693 -226.688873) (xy 383.511798 -226.73745)
			(xy 383.496214 -226.784131) (xy 383.473343 -226.827708) (xy 383.443778 -226.867052) (xy 383.408285 -226.901144)
			(xy 383.367782 -226.9291) (xy 383.32332 -226.950198) (xy 383.276049 -226.96389) (xy 383.227194 -226.969822)
			(xy 383.178019 -226.967841) (xy 383.1298 -226.957997) (xy 383.083784 -226.940545) (xy 383.041163 -226.915938)
			(xy 383.003042 -226.884813) (xy 382.970407 -226.847976) (xy 382.944104 -226.80638) (xy 382.924813 -226.761104)
			(xy 382.913036 -226.71332) (xy 382.909076 -226.664266) (xy 382.590548 -226.664266) (xy 382.590036 -226.689712)
			(xy 382.581872 -226.739946) (xy 382.565756 -226.78822) (xy 382.542105 -226.833283) (xy 382.511532 -226.873969)
			(xy 382.474828 -226.909224) (xy 382.432944 -226.938134) (xy 382.386965 -226.959951) (xy 382.338081 -226.974111)
			(xy 382.28756 -226.980245) (xy 382.236708 -226.978196) (xy 382.186844 -226.968016) (xy 382.139258 -226.949969)
			(xy 382.095184 -226.924523) (xy 382.055762 -226.892336) (xy 382.022014 -226.854242) (xy 381.994813 -226.811228)
			(xy 381.974865 -226.764408) (xy 381.962686 -226.714994) (xy 381.958591 -226.664266) (xy 381.64008 -226.664266)
			(xy 381.639585 -226.688873) (xy 381.63169 -226.73745) (xy 381.616106 -226.784131) (xy 381.593235 -226.827708)
			(xy 381.56367 -226.867052) (xy 381.528177 -226.901144) (xy 381.487674 -226.9291) (xy 381.443212 -226.950198)
			(xy 381.395941 -226.96389) (xy 381.347086 -226.969822) (xy 381.297911 -226.967841) (xy 381.249692 -226.957997)
			(xy 381.203676 -226.940545) (xy 381.161055 -226.915938) (xy 381.122934 -226.884813) (xy 381.090299 -226.847976)
			(xy 381.063996 -226.80638) (xy 381.044705 -226.761104) (xy 381.032928 -226.71332) (xy 381.028968 -226.664266)
			(xy 380.71044 -226.664266) (xy 380.709928 -226.689712) (xy 380.701764 -226.739946) (xy 380.685648 -226.78822)
			(xy 380.661997 -226.833283) (xy 380.631424 -226.873969) (xy 380.59472 -226.909224) (xy 380.552836 -226.938134)
			(xy 380.506857 -226.959951) (xy 380.457973 -226.974111) (xy 380.407452 -226.980245) (xy 380.3566 -226.978196)
			(xy 380.306736 -226.968016) (xy 380.25915 -226.949969) (xy 380.215076 -226.924523) (xy 380.175654 -226.892336)
			(xy 380.141906 -226.854242) (xy 380.114705 -226.811228) (xy 380.094757 -226.764408) (xy 380.082578 -226.714994)
			(xy 380.078483 -226.664266) (xy 379.77064 -226.664266) (xy 379.770128 -226.689712) (xy 379.761964 -226.739946)
			(xy 379.745848 -226.78822) (xy 379.722197 -226.833283) (xy 379.691624 -226.873969) (xy 379.65492 -226.909224)
			(xy 379.613036 -226.938134) (xy 379.567057 -226.959951) (xy 379.518173 -226.974111) (xy 379.467652 -226.980245)
			(xy 379.4168 -226.978196) (xy 379.366936 -226.968016) (xy 379.31935 -226.949969) (xy 379.275276 -226.924523)
			(xy 379.235854 -226.892336) (xy 379.202106 -226.854242) (xy 379.174905 -226.811228) (xy 379.154957 -226.764408)
			(xy 379.142778 -226.714994) (xy 379.138683 -226.664266) (xy 378.820172 -226.664266) (xy 378.819677 -226.688873)
			(xy 378.811782 -226.73745) (xy 378.796198 -226.784131) (xy 378.773327 -226.827708) (xy 378.743762 -226.867052)
			(xy 378.708269 -226.901144) (xy 378.667766 -226.9291) (xy 378.623304 -226.950198) (xy 378.576033 -226.96389)
			(xy 378.527178 -226.969822) (xy 378.478003 -226.967841) (xy 378.429784 -226.957997) (xy 378.383768 -226.940545)
			(xy 378.341147 -226.915938) (xy 378.303026 -226.884813) (xy 378.270391 -226.847976) (xy 378.244088 -226.80638)
			(xy 378.224797 -226.761104) (xy 378.21302 -226.71332) (xy 378.20906 -226.664266) (xy 377.890532 -226.664266)
			(xy 377.890073 -226.68908) (xy 377.882315 -226.738096) (xy 377.866983 -226.785296) (xy 377.844457 -226.829516)
			(xy 377.81529 -226.869667) (xy 377.780201 -226.904761) (xy 377.740054 -226.933934) (xy 377.695837 -226.956467)
			(xy 377.648639 -226.971804) (xy 377.599624 -226.97957) (xy 377.57481 -226.979988) (xy 377.550536 -226.979543)
			(xy 377.502562 -226.97211) (xy 377.456291 -226.957418) (xy 377.412816 -226.935813) (xy 377.373163 -226.907806)
			(xy 377.338266 -226.874056) (xy 377.308949 -226.83536) (xy 377.285904 -226.792631) (xy 377.269675 -226.746877)
			(xy 377.260643 -226.699178) (xy 377.259342 -226.674934) (xy 377.258834 -226.659694) (xy 377.241562 -226.635056)
			(xy 377.14682 -226.598226) (xy 377.146566 -226.598226) (xy 377.13728 -226.595117) (xy 377.117718 -226.595429)
			(xy 377.099702 -226.60306) (xy 377.092464 -226.609656) (xy 376.913902 -226.788218) (xy 376.910092 -226.796092)
			(xy 376.898429 -226.8192) (xy 376.868534 -226.861451) (xy 376.831943 -226.898057) (xy 376.789704 -226.927968)
			(xy 376.766582 -226.939602) (xy 376.758708 -226.943412) (xy 376.43435 -227.26777) (xy 376.429778 -227.301806)
			(xy 376.438414 -227.316792) (xy 376.451632 -227.340906) (xy 376.47035 -227.392609) (xy 376.479803 -227.446778)
			(xy 376.480324 -227.474272) (xy 376.788675 -227.474272) (xy 376.79277 -227.423544) (xy 376.804949 -227.37413)
			(xy 376.824897 -227.32731) (xy 376.852098 -227.284296) (xy 376.885846 -227.246202) (xy 376.925268 -227.214015)
			(xy 376.969342 -227.188569) (xy 377.016928 -227.170522) (xy 377.066792 -227.160342) (xy 377.117644 -227.158293)
			(xy 377.168165 -227.164427) (xy 377.217049 -227.178587) (xy 377.263028 -227.200404) (xy 377.304912 -227.229314)
			(xy 377.341616 -227.264569) (xy 377.372189 -227.305255) (xy 377.39584 -227.350318) (xy 377.411956 -227.398592)
			(xy 377.42012 -227.448826) (xy 377.420632 -227.474272) (xy 378.668529 -227.474272) (xy 378.672624 -227.423544)
			(xy 378.684803 -227.37413) (xy 378.704751 -227.32731) (xy 378.731952 -227.284296) (xy 378.7657 -227.246202)
			(xy 378.805122 -227.214015) (xy 378.849196 -227.188569) (xy 378.896782 -227.170522) (xy 378.946646 -227.160342)
			(xy 378.997498 -227.158293) (xy 379.048019 -227.164427) (xy 379.096903 -227.178587) (xy 379.142882 -227.200404)
			(xy 379.184766 -227.229314) (xy 379.22147 -227.264569) (xy 379.252043 -227.305255) (xy 379.275694 -227.350318)
			(xy 379.29181 -227.398592) (xy 379.299974 -227.448826) (xy 379.300486 -227.474272) (xy 379.619014 -227.474272)
			(xy 379.622974 -227.425218) (xy 379.634751 -227.377434) (xy 379.654042 -227.332158) (xy 379.680345 -227.290562)
			(xy 379.71298 -227.253725) (xy 379.751101 -227.2226) (xy 379.793722 -227.197993) (xy 379.839738 -227.180541)
			(xy 379.887957 -227.170697) (xy 379.937132 -227.168716) (xy 379.985987 -227.174648) (xy 380.033258 -227.18834)
			(xy 380.07772 -227.209438) (xy 380.118223 -227.237394) (xy 380.153716 -227.271486) (xy 380.183281 -227.31083)
			(xy 380.206152 -227.354407) (xy 380.221736 -227.401088) (xy 380.229631 -227.449665) (xy 380.230126 -227.474272)
			(xy 380.548637 -227.474272) (xy 380.552732 -227.423544) (xy 380.564911 -227.37413) (xy 380.584859 -227.32731)
			(xy 380.61206 -227.284296) (xy 380.645808 -227.246202) (xy 380.68523 -227.214015) (xy 380.729304 -227.188569)
			(xy 380.77689 -227.170522) (xy 380.826754 -227.160342) (xy 380.877606 -227.158293) (xy 380.928127 -227.164427)
			(xy 380.977011 -227.178587) (xy 381.02299 -227.200404) (xy 381.064874 -227.229314) (xy 381.101578 -227.264569)
			(xy 381.132151 -227.305255) (xy 381.155802 -227.350318) (xy 381.171918 -227.398592) (xy 381.180082 -227.448826)
			(xy 381.180594 -227.474272) (xy 381.499122 -227.474272) (xy 381.503082 -227.425218) (xy 381.514859 -227.377434)
			(xy 381.53415 -227.332158) (xy 381.560453 -227.290562) (xy 381.593088 -227.253725) (xy 381.631209 -227.2226)
			(xy 381.67383 -227.197993) (xy 381.719846 -227.180541) (xy 381.768065 -227.170697) (xy 381.81724 -227.168716)
			(xy 381.866095 -227.174648) (xy 381.913366 -227.18834) (xy 381.957828 -227.209438) (xy 381.998331 -227.237394)
			(xy 382.033824 -227.271486) (xy 382.063389 -227.31083) (xy 382.08626 -227.354407) (xy 382.101844 -227.401088)
			(xy 382.109739 -227.449665) (xy 382.110234 -227.474272) (xy 382.428491 -227.474272) (xy 382.432586 -227.423544)
			(xy 382.444765 -227.37413) (xy 382.464713 -227.32731) (xy 382.491914 -227.284296) (xy 382.525662 -227.246202)
			(xy 382.565084 -227.214015) (xy 382.609158 -227.188569) (xy 382.656744 -227.170522) (xy 382.706608 -227.160342)
			(xy 382.75746 -227.158293) (xy 382.807981 -227.164427) (xy 382.856865 -227.178587) (xy 382.902844 -227.200404)
			(xy 382.944728 -227.229314) (xy 382.981432 -227.264569) (xy 383.012005 -227.305255) (xy 383.035656 -227.350318)
			(xy 383.051772 -227.398592) (xy 383.059936 -227.448826) (xy 383.060448 -227.474272) (xy 383.368545 -227.474272)
			(xy 383.37264 -227.423544) (xy 383.384819 -227.37413) (xy 383.404767 -227.32731) (xy 383.431968 -227.284296)
			(xy 383.465716 -227.246202) (xy 383.505138 -227.214015) (xy 383.549212 -227.188569) (xy 383.596798 -227.170522)
			(xy 383.646662 -227.160342) (xy 383.697514 -227.158293) (xy 383.748035 -227.164427) (xy 383.796919 -227.178587)
			(xy 383.842898 -227.200404) (xy 383.884782 -227.229314) (xy 383.921486 -227.264569) (xy 383.952059 -227.305255)
			(xy 383.97571 -227.350318) (xy 383.991826 -227.398592) (xy 383.99999 -227.448826) (xy 384.000502 -227.474272)
			(xy 385.248653 -227.474272) (xy 385.252748 -227.423544) (xy 385.264927 -227.37413) (xy 385.284875 -227.32731)
			(xy 385.312076 -227.284296) (xy 385.345824 -227.246202) (xy 385.385246 -227.214015) (xy 385.42932 -227.188569)
			(xy 385.476906 -227.170522) (xy 385.52677 -227.160342) (xy 385.577622 -227.158293) (xy 385.628143 -227.164427)
			(xy 385.677027 -227.178587) (xy 385.723006 -227.200404) (xy 385.76489 -227.229314) (xy 385.801594 -227.264569)
			(xy 385.832167 -227.305255) (xy 385.855818 -227.350318) (xy 385.871934 -227.398592) (xy 385.880098 -227.448826)
			(xy 385.88061 -227.474272) (xy 386.199138 -227.474272) (xy 386.203098 -227.425218) (xy 386.214875 -227.377434)
			(xy 386.234166 -227.332158) (xy 386.260469 -227.290562) (xy 386.293104 -227.253725) (xy 386.331225 -227.2226)
			(xy 386.373846 -227.197993) (xy 386.419862 -227.180541) (xy 386.468081 -227.170697) (xy 386.517256 -227.168716)
			(xy 386.566111 -227.174648) (xy 386.613382 -227.18834) (xy 386.657844 -227.209438) (xy 386.698347 -227.237394)
			(xy 386.73384 -227.271486) (xy 386.763405 -227.31083) (xy 386.786276 -227.354407) (xy 386.80186 -227.401088)
			(xy 386.809755 -227.449665) (xy 386.81025 -227.474272) (xy 387.128507 -227.474272) (xy 387.132602 -227.423544)
			(xy 387.144781 -227.37413) (xy 387.164729 -227.32731) (xy 387.19193 -227.284296) (xy 387.225678 -227.246202)
			(xy 387.2651 -227.214015) (xy 387.309174 -227.188569) (xy 387.35676 -227.170522) (xy 387.406624 -227.160342)
			(xy 387.457476 -227.158293) (xy 387.507997 -227.164427) (xy 387.556881 -227.178587) (xy 387.60286 -227.200404)
			(xy 387.644744 -227.229314) (xy 387.681448 -227.264569) (xy 387.712021 -227.305255) (xy 387.735672 -227.350318)
			(xy 387.751788 -227.398592) (xy 387.759952 -227.448826) (xy 387.760464 -227.474272) (xy 388.078992 -227.474272)
			(xy 388.082952 -227.425218) (xy 388.094729 -227.377434) (xy 388.11402 -227.332158) (xy 388.140323 -227.290562)
			(xy 388.172958 -227.253725) (xy 388.211079 -227.2226) (xy 388.2537 -227.197993) (xy 388.299716 -227.180541)
			(xy 388.347935 -227.170697) (xy 388.39711 -227.168716) (xy 388.445965 -227.174648) (xy 388.493236 -227.18834)
			(xy 388.537698 -227.209438) (xy 388.578201 -227.237394) (xy 388.613694 -227.271486) (xy 388.643259 -227.31083)
			(xy 388.66613 -227.354407) (xy 388.681714 -227.401088) (xy 388.689609 -227.449665) (xy 388.690104 -227.474272)
			(xy 389.008615 -227.474272) (xy 389.01271 -227.423544) (xy 389.024889 -227.37413) (xy 389.044837 -227.32731)
			(xy 389.072038 -227.284296) (xy 389.105786 -227.246202) (xy 389.145208 -227.214015) (xy 389.189282 -227.188569)
			(xy 389.236868 -227.170522) (xy 389.286732 -227.160342) (xy 389.337584 -227.158293) (xy 389.388105 -227.164427)
			(xy 389.436989 -227.178587) (xy 389.482968 -227.200404) (xy 389.524852 -227.229314) (xy 389.561556 -227.264569)
			(xy 389.592129 -227.305255) (xy 389.61578 -227.350318) (xy 389.631896 -227.398592) (xy 389.64006 -227.448826)
			(xy 389.640572 -227.474272) (xy 389.948669 -227.474272) (xy 389.952764 -227.423544) (xy 389.964943 -227.37413)
			(xy 389.984891 -227.32731) (xy 390.012092 -227.284296) (xy 390.04584 -227.246202) (xy 390.085262 -227.214015)
			(xy 390.129336 -227.188569) (xy 390.176922 -227.170522) (xy 390.226786 -227.160342) (xy 390.277638 -227.158293)
			(xy 390.328159 -227.164427) (xy 390.377043 -227.178587) (xy 390.423022 -227.200404) (xy 390.464906 -227.229314)
			(xy 390.50161 -227.264569) (xy 390.532183 -227.305255) (xy 390.555834 -227.350318) (xy 390.57195 -227.398592)
			(xy 390.580114 -227.448826) (xy 390.580626 -227.474272) (xy 392.779008 -227.474272) (xy 392.782968 -227.425218)
			(xy 392.794745 -227.377434) (xy 392.814036 -227.332158) (xy 392.840339 -227.290562) (xy 392.872974 -227.253725)
			(xy 392.911095 -227.2226) (xy 392.953716 -227.197993) (xy 392.999732 -227.180541) (xy 393.047951 -227.170697)
			(xy 393.097126 -227.168716) (xy 393.145981 -227.174648) (xy 393.193252 -227.18834) (xy 393.237714 -227.209438)
			(xy 393.278217 -227.237394) (xy 393.31371 -227.271486) (xy 393.343275 -227.31083) (xy 393.366146 -227.354407)
			(xy 393.38173 -227.401088) (xy 393.389625 -227.449665) (xy 393.39012 -227.474272) (xy 393.389625 -227.498879)
			(xy 393.38173 -227.547456) (xy 393.366146 -227.594137) (xy 393.343275 -227.637714) (xy 393.31371 -227.677058)
			(xy 393.278217 -227.71115) (xy 393.237714 -227.739106) (xy 393.193252 -227.760204) (xy 393.145981 -227.773896)
			(xy 393.097126 -227.779828) (xy 393.047951 -227.777847) (xy 392.999732 -227.768003) (xy 392.953716 -227.750551)
			(xy 392.911095 -227.725944) (xy 392.872974 -227.694819) (xy 392.840339 -227.657982) (xy 392.814036 -227.616386)
			(xy 392.794745 -227.57111) (xy 392.782968 -227.523326) (xy 392.779008 -227.474272) (xy 390.580626 -227.474272)
			(xy 390.580114 -227.499718) (xy 390.57195 -227.549952) (xy 390.555834 -227.598226) (xy 390.532183 -227.643289)
			(xy 390.50161 -227.683975) (xy 390.464906 -227.71923) (xy 390.423022 -227.74814) (xy 390.377043 -227.769957)
			(xy 390.328159 -227.784117) (xy 390.277638 -227.790251) (xy 390.226786 -227.788202) (xy 390.176922 -227.778022)
			(xy 390.129336 -227.759975) (xy 390.085262 -227.734529) (xy 390.04584 -227.702342) (xy 390.012092 -227.664248)
			(xy 389.984891 -227.621234) (xy 389.964943 -227.574414) (xy 389.952764 -227.525) (xy 389.948669 -227.474272)
			(xy 389.640572 -227.474272) (xy 389.64006 -227.499718) (xy 389.631896 -227.549952) (xy 389.61578 -227.598226)
			(xy 389.592129 -227.643289) (xy 389.561556 -227.683975) (xy 389.524852 -227.71923) (xy 389.482968 -227.74814)
			(xy 389.436989 -227.769957) (xy 389.388105 -227.784117) (xy 389.337584 -227.790251) (xy 389.286732 -227.788202)
			(xy 389.236868 -227.778022) (xy 389.189282 -227.759975) (xy 389.145208 -227.734529) (xy 389.105786 -227.702342)
			(xy 389.072038 -227.664248) (xy 389.044837 -227.621234) (xy 389.024889 -227.574414) (xy 389.01271 -227.525)
			(xy 389.008615 -227.474272) (xy 388.690104 -227.474272) (xy 388.689609 -227.498879) (xy 388.681714 -227.547456)
			(xy 388.66613 -227.594137) (xy 388.643259 -227.637714) (xy 388.613694 -227.677058) (xy 388.578201 -227.71115)
			(xy 388.537698 -227.739106) (xy 388.493236 -227.760204) (xy 388.445965 -227.773896) (xy 388.39711 -227.779828)
			(xy 388.347935 -227.777847) (xy 388.299716 -227.768003) (xy 388.2537 -227.750551) (xy 388.211079 -227.725944)
			(xy 388.172958 -227.694819) (xy 388.140323 -227.657982) (xy 388.11402 -227.616386) (xy 388.094729 -227.57111)
			(xy 388.082952 -227.523326) (xy 388.078992 -227.474272) (xy 387.760464 -227.474272) (xy 387.759952 -227.499718)
			(xy 387.751788 -227.549952) (xy 387.735672 -227.598226) (xy 387.712021 -227.643289) (xy 387.681448 -227.683975)
			(xy 387.644744 -227.71923) (xy 387.60286 -227.74814) (xy 387.556881 -227.769957) (xy 387.507997 -227.784117)
			(xy 387.457476 -227.790251) (xy 387.406624 -227.788202) (xy 387.35676 -227.778022) (xy 387.309174 -227.759975)
			(xy 387.2651 -227.734529) (xy 387.225678 -227.702342) (xy 387.19193 -227.664248) (xy 387.164729 -227.621234)
			(xy 387.144781 -227.574414) (xy 387.132602 -227.525) (xy 387.128507 -227.474272) (xy 386.81025 -227.474272)
			(xy 386.809755 -227.498879) (xy 386.80186 -227.547456) (xy 386.786276 -227.594137) (xy 386.763405 -227.637714)
			(xy 386.73384 -227.677058) (xy 386.698347 -227.71115) (xy 386.657844 -227.739106) (xy 386.613382 -227.760204)
			(xy 386.566111 -227.773896) (xy 386.517256 -227.779828) (xy 386.468081 -227.777847) (xy 386.419862 -227.768003)
			(xy 386.373846 -227.750551) (xy 386.331225 -227.725944) (xy 386.293104 -227.694819) (xy 386.260469 -227.657982)
			(xy 386.234166 -227.616386) (xy 386.214875 -227.57111) (xy 386.203098 -227.523326) (xy 386.199138 -227.474272)
			(xy 385.88061 -227.474272) (xy 385.880098 -227.499718) (xy 385.871934 -227.549952) (xy 385.855818 -227.598226)
			(xy 385.832167 -227.643289) (xy 385.801594 -227.683975) (xy 385.76489 -227.71923) (xy 385.723006 -227.74814)
			(xy 385.677027 -227.769957) (xy 385.628143 -227.784117) (xy 385.577622 -227.790251) (xy 385.52677 -227.788202)
			(xy 385.476906 -227.778022) (xy 385.42932 -227.759975) (xy 385.385246 -227.734529) (xy 385.345824 -227.702342)
			(xy 385.312076 -227.664248) (xy 385.284875 -227.621234) (xy 385.264927 -227.574414) (xy 385.252748 -227.525)
			(xy 385.248653 -227.474272) (xy 384.000502 -227.474272) (xy 383.99999 -227.499718) (xy 383.991826 -227.549952)
			(xy 383.97571 -227.598226) (xy 383.952059 -227.643289) (xy 383.921486 -227.683975) (xy 383.884782 -227.71923)
			(xy 383.842898 -227.74814) (xy 383.796919 -227.769957) (xy 383.748035 -227.784117) (xy 383.697514 -227.790251)
			(xy 383.646662 -227.788202) (xy 383.596798 -227.778022) (xy 383.549212 -227.759975) (xy 383.505138 -227.734529)
			(xy 383.465716 -227.702342) (xy 383.431968 -227.664248) (xy 383.404767 -227.621234) (xy 383.384819 -227.574414)
			(xy 383.37264 -227.525) (xy 383.368545 -227.474272) (xy 383.060448 -227.474272) (xy 383.059936 -227.499718)
			(xy 383.051772 -227.549952) (xy 383.035656 -227.598226) (xy 383.012005 -227.643289) (xy 382.981432 -227.683975)
			(xy 382.944728 -227.71923) (xy 382.902844 -227.74814) (xy 382.856865 -227.769957) (xy 382.807981 -227.784117)
			(xy 382.75746 -227.790251) (xy 382.706608 -227.788202) (xy 382.656744 -227.778022) (xy 382.609158 -227.759975)
			(xy 382.565084 -227.734529) (xy 382.525662 -227.702342) (xy 382.491914 -227.664248) (xy 382.464713 -227.621234)
			(xy 382.444765 -227.574414) (xy 382.432586 -227.525) (xy 382.428491 -227.474272) (xy 382.110234 -227.474272)
			(xy 382.109739 -227.498879) (xy 382.101844 -227.547456) (xy 382.08626 -227.594137) (xy 382.063389 -227.637714)
			(xy 382.033824 -227.677058) (xy 381.998331 -227.71115) (xy 381.957828 -227.739106) (xy 381.913366 -227.760204)
			(xy 381.866095 -227.773896) (xy 381.81724 -227.779828) (xy 381.768065 -227.777847) (xy 381.719846 -227.768003)
			(xy 381.67383 -227.750551) (xy 381.631209 -227.725944) (xy 381.593088 -227.694819) (xy 381.560453 -227.657982)
			(xy 381.53415 -227.616386) (xy 381.514859 -227.57111) (xy 381.503082 -227.523326) (xy 381.499122 -227.474272)
			(xy 381.180594 -227.474272) (xy 381.180082 -227.499718) (xy 381.171918 -227.549952) (xy 381.155802 -227.598226)
			(xy 381.132151 -227.643289) (xy 381.101578 -227.683975) (xy 381.064874 -227.71923) (xy 381.02299 -227.74814)
			(xy 380.977011 -227.769957) (xy 380.928127 -227.784117) (xy 380.877606 -227.790251) (xy 380.826754 -227.788202)
			(xy 380.77689 -227.778022) (xy 380.729304 -227.759975) (xy 380.68523 -227.734529) (xy 380.645808 -227.702342)
			(xy 380.61206 -227.664248) (xy 380.584859 -227.621234) (xy 380.564911 -227.574414) (xy 380.552732 -227.525)
			(xy 380.548637 -227.474272) (xy 380.230126 -227.474272) (xy 380.229631 -227.498879) (xy 380.221736 -227.547456)
			(xy 380.206152 -227.594137) (xy 380.183281 -227.637714) (xy 380.153716 -227.677058) (xy 380.118223 -227.71115)
			(xy 380.07772 -227.739106) (xy 380.033258 -227.760204) (xy 379.985987 -227.773896) (xy 379.937132 -227.779828)
			(xy 379.887957 -227.777847) (xy 379.839738 -227.768003) (xy 379.793722 -227.750551) (xy 379.751101 -227.725944)
			(xy 379.71298 -227.694819) (xy 379.680345 -227.657982) (xy 379.654042 -227.616386) (xy 379.634751 -227.57111)
			(xy 379.622974 -227.523326) (xy 379.619014 -227.474272) (xy 379.300486 -227.474272) (xy 379.299974 -227.499718)
			(xy 379.29181 -227.549952) (xy 379.275694 -227.598226) (xy 379.252043 -227.643289) (xy 379.22147 -227.683975)
			(xy 379.184766 -227.71923) (xy 379.142882 -227.74814) (xy 379.096903 -227.769957) (xy 379.048019 -227.784117)
			(xy 378.997498 -227.790251) (xy 378.946646 -227.788202) (xy 378.896782 -227.778022) (xy 378.849196 -227.759975)
			(xy 378.805122 -227.734529) (xy 378.7657 -227.702342) (xy 378.731952 -227.664248) (xy 378.704751 -227.621234)
			(xy 378.684803 -227.574414) (xy 378.672624 -227.525) (xy 378.668529 -227.474272) (xy 377.420632 -227.474272)
			(xy 377.42012 -227.499718) (xy 377.411956 -227.549952) (xy 377.39584 -227.598226) (xy 377.372189 -227.643289)
			(xy 377.341616 -227.683975) (xy 377.304912 -227.71923) (xy 377.263028 -227.74814) (xy 377.217049 -227.769957)
			(xy 377.168165 -227.784117) (xy 377.117644 -227.790251) (xy 377.066792 -227.788202) (xy 377.016928 -227.778022)
			(xy 376.969342 -227.759975) (xy 376.925268 -227.734529) (xy 376.885846 -227.702342) (xy 376.852098 -227.664248)
			(xy 376.824897 -227.621234) (xy 376.804949 -227.574414) (xy 376.79277 -227.525) (xy 376.788675 -227.474272)
			(xy 376.480324 -227.474272) (xy 376.479865 -227.499064) (xy 376.472112 -227.548037) (xy 376.456792 -227.595195)
			(xy 376.434282 -227.639374) (xy 376.405138 -227.679488) (xy 376.370076 -227.714548) (xy 376.329961 -227.74369)
			(xy 376.28578 -227.766198) (xy 376.238622 -227.781515) (xy 376.189648 -227.789266) (xy 376.164856 -227.78974)
			(xy 376.137368 -227.789163) (xy 376.083215 -227.779687) (xy 376.031515 -227.760992) (xy 376.007376 -227.74783)
			(xy 375.99239 -227.739194) (xy 375.958354 -227.743766) (xy 375.838974 -227.863146) (xy 375.831364 -227.871723)
			(xy 375.823853 -227.893353) (xy 375.824496 -227.904802) (xy 375.83237 -227.972112) (xy 375.83316 -227.977841)
			(xy 375.837016 -227.988742) (xy 375.83999 -227.993702) (xy 375.846594 -228.004116) (xy 375.854722 -228.012244)
			(xy 375.859802 -228.015292) (xy 375.88242 -228.029788) (xy 375.922805 -228.06521) (xy 375.956606 -228.106961)
			(xy 375.982848 -228.153834) (xy 376.00077 -228.204474) (xy 376.009856 -228.257419) (xy 376.010424 -228.284278)
			(xy 376.328952 -228.284278) (xy 376.332912 -228.235224) (xy 376.344689 -228.18744) (xy 376.36398 -228.142164)
			(xy 376.390283 -228.100568) (xy 376.422918 -228.063731) (xy 376.461039 -228.032606) (xy 376.50366 -228.007999)
			(xy 376.549676 -227.990547) (xy 376.597895 -227.980703) (xy 376.64707 -227.978722) (xy 376.695925 -227.984654)
			(xy 376.743196 -227.998346) (xy 376.787658 -228.019444) (xy 376.828161 -228.0474) (xy 376.863654 -228.081492)
			(xy 376.893219 -228.120836) (xy 376.91609 -228.164413) (xy 376.931674 -228.211094) (xy 376.939569 -228.259671)
			(xy 376.940064 -228.284278) (xy 377.258575 -228.284278) (xy 377.26267 -228.23355) (xy 377.274849 -228.184136)
			(xy 377.294797 -228.137316) (xy 377.321998 -228.094302) (xy 377.355746 -228.056208) (xy 377.395168 -228.024021)
			(xy 377.439242 -227.998575) (xy 377.486828 -227.980528) (xy 377.536692 -227.970348) (xy 377.587544 -227.968299)
			(xy 377.638065 -227.974433) (xy 377.686949 -227.988593) (xy 377.732928 -228.01041) (xy 377.774812 -228.03932)
			(xy 377.811516 -228.074575) (xy 377.842089 -228.115261) (xy 377.86574 -228.160324) (xy 377.881856 -228.208598)
			(xy 377.89002 -228.258832) (xy 377.890532 -228.284278) (xy 378.20906 -228.284278) (xy 378.21302 -228.235224)
			(xy 378.224797 -228.18744) (xy 378.244088 -228.142164) (xy 378.270391 -228.100568) (xy 378.303026 -228.063731)
			(xy 378.341147 -228.032606) (xy 378.383768 -228.007999) (xy 378.429784 -227.990547) (xy 378.478003 -227.980703)
			(xy 378.527178 -227.978722) (xy 378.576033 -227.984654) (xy 378.623304 -227.998346) (xy 378.667766 -228.019444)
			(xy 378.708269 -228.0474) (xy 378.743762 -228.081492) (xy 378.773327 -228.120836) (xy 378.796198 -228.164413)
			(xy 378.811782 -228.211094) (xy 378.819677 -228.259671) (xy 378.820172 -228.284278) (xy 379.138683 -228.284278)
			(xy 379.142778 -228.23355) (xy 379.154957 -228.184136) (xy 379.174905 -228.137316) (xy 379.202106 -228.094302)
			(xy 379.235854 -228.056208) (xy 379.275276 -228.024021) (xy 379.31935 -227.998575) (xy 379.366936 -227.980528)
			(xy 379.4168 -227.970348) (xy 379.467652 -227.968299) (xy 379.518173 -227.974433) (xy 379.567057 -227.988593)
			(xy 379.613036 -228.01041) (xy 379.65492 -228.03932) (xy 379.691624 -228.074575) (xy 379.722197 -228.115261)
			(xy 379.745848 -228.160324) (xy 379.761964 -228.208598) (xy 379.770128 -228.258832) (xy 379.77064 -228.284278)
			(xy 380.078483 -228.284278) (xy 380.082578 -228.23355) (xy 380.094757 -228.184136) (xy 380.114705 -228.137316)
			(xy 380.141906 -228.094302) (xy 380.175654 -228.056208) (xy 380.215076 -228.024021) (xy 380.25915 -227.998575)
			(xy 380.306736 -227.980528) (xy 380.3566 -227.970348) (xy 380.407452 -227.968299) (xy 380.457973 -227.974433)
			(xy 380.506857 -227.988593) (xy 380.552836 -228.01041) (xy 380.59472 -228.03932) (xy 380.631424 -228.074575)
			(xy 380.661997 -228.115261) (xy 380.685648 -228.160324) (xy 380.701764 -228.208598) (xy 380.709928 -228.258832)
			(xy 380.71044 -228.284278) (xy 381.028968 -228.284278) (xy 381.032928 -228.235224) (xy 381.044705 -228.18744)
			(xy 381.063996 -228.142164) (xy 381.090299 -228.100568) (xy 381.122934 -228.063731) (xy 381.161055 -228.032606)
			(xy 381.203676 -228.007999) (xy 381.249692 -227.990547) (xy 381.297911 -227.980703) (xy 381.347086 -227.978722)
			(xy 381.395941 -227.984654) (xy 381.443212 -227.998346) (xy 381.487674 -228.019444) (xy 381.528177 -228.0474)
			(xy 381.56367 -228.081492) (xy 381.593235 -228.120836) (xy 381.616106 -228.164413) (xy 381.63169 -228.211094)
			(xy 381.639585 -228.259671) (xy 381.64008 -228.284278) (xy 381.958591 -228.284278) (xy 381.962686 -228.23355)
			(xy 381.974865 -228.184136) (xy 381.994813 -228.137316) (xy 382.022014 -228.094302) (xy 382.055762 -228.056208)
			(xy 382.095184 -228.024021) (xy 382.139258 -227.998575) (xy 382.186844 -227.980528) (xy 382.236708 -227.970348)
			(xy 382.28756 -227.968299) (xy 382.338081 -227.974433) (xy 382.386965 -227.988593) (xy 382.432944 -228.01041)
			(xy 382.474828 -228.03932) (xy 382.511532 -228.074575) (xy 382.542105 -228.115261) (xy 382.565756 -228.160324)
			(xy 382.581872 -228.208598) (xy 382.590036 -228.258832) (xy 382.590548 -228.284278) (xy 382.909076 -228.284278)
			(xy 382.913036 -228.235224) (xy 382.924813 -228.18744) (xy 382.944104 -228.142164) (xy 382.970407 -228.100568)
			(xy 383.003042 -228.063731) (xy 383.041163 -228.032606) (xy 383.083784 -228.007999) (xy 383.1298 -227.990547)
			(xy 383.178019 -227.980703) (xy 383.227194 -227.978722) (xy 383.276049 -227.984654) (xy 383.32332 -227.998346)
			(xy 383.367782 -228.019444) (xy 383.408285 -228.0474) (xy 383.443778 -228.081492) (xy 383.473343 -228.120836)
			(xy 383.496214 -228.164413) (xy 383.511798 -228.211094) (xy 383.519693 -228.259671) (xy 383.520188 -228.284278)
			(xy 383.838699 -228.284278) (xy 383.842794 -228.23355) (xy 383.854973 -228.184136) (xy 383.874921 -228.137316)
			(xy 383.902122 -228.094302) (xy 383.93587 -228.056208) (xy 383.975292 -228.024021) (xy 384.019366 -227.998575)
			(xy 384.066952 -227.980528) (xy 384.116816 -227.970348) (xy 384.167668 -227.968299) (xy 384.218189 -227.974433)
			(xy 384.267073 -227.988593) (xy 384.313052 -228.01041) (xy 384.354936 -228.03932) (xy 384.39164 -228.074575)
			(xy 384.422213 -228.115261) (xy 384.445864 -228.160324) (xy 384.46198 -228.208598) (xy 384.470144 -228.258832)
			(xy 384.470656 -228.284278) (xy 384.78893 -228.284278) (xy 384.79289 -228.235224) (xy 384.804667 -228.18744)
			(xy 384.823958 -228.142164) (xy 384.850261 -228.100568) (xy 384.882896 -228.063731) (xy 384.921017 -228.032606)
			(xy 384.963638 -228.007999) (xy 385.009654 -227.990547) (xy 385.057873 -227.980703) (xy 385.107048 -227.978722)
			(xy 385.155903 -227.984654) (xy 385.203174 -227.998346) (xy 385.247636 -228.019444) (xy 385.288139 -228.0474)
			(xy 385.323632 -228.081492) (xy 385.353197 -228.120836) (xy 385.376068 -228.164413) (xy 385.391652 -228.211094)
			(xy 385.399547 -228.259671) (xy 385.400042 -228.284278) (xy 385.718553 -228.284278) (xy 385.722648 -228.23355)
			(xy 385.734827 -228.184136) (xy 385.754775 -228.137316) (xy 385.781976 -228.094302) (xy 385.815724 -228.056208)
			(xy 385.855146 -228.024021) (xy 385.89922 -227.998575) (xy 385.946806 -227.980528) (xy 385.99667 -227.970348)
			(xy 386.047522 -227.968299) (xy 386.098043 -227.974433) (xy 386.146927 -227.988593) (xy 386.192906 -228.01041)
			(xy 386.23479 -228.03932) (xy 386.271494 -228.074575) (xy 386.302067 -228.115261) (xy 386.325718 -228.160324)
			(xy 386.341834 -228.208598) (xy 386.349998 -228.258832) (xy 386.35051 -228.284278) (xy 386.658607 -228.284278)
			(xy 386.662702 -228.23355) (xy 386.674881 -228.184136) (xy 386.694829 -228.137316) (xy 386.72203 -228.094302)
			(xy 386.755778 -228.056208) (xy 386.7952 -228.024021) (xy 386.839274 -227.998575) (xy 386.88686 -227.980528)
			(xy 386.936724 -227.970348) (xy 386.987576 -227.968299) (xy 387.038097 -227.974433) (xy 387.086981 -227.988593)
			(xy 387.13296 -228.01041) (xy 387.174844 -228.03932) (xy 387.211548 -228.074575) (xy 387.242121 -228.115261)
			(xy 387.265772 -228.160324) (xy 387.281888 -228.208598) (xy 387.290052 -228.258832) (xy 387.290564 -228.284278)
			(xy 387.609092 -228.284278) (xy 387.613052 -228.235224) (xy 387.624829 -228.18744) (xy 387.64412 -228.142164)
			(xy 387.670423 -228.100568) (xy 387.703058 -228.063731) (xy 387.741179 -228.032606) (xy 387.7838 -228.007999)
			(xy 387.829816 -227.990547) (xy 387.878035 -227.980703) (xy 387.92721 -227.978722) (xy 387.976065 -227.984654)
			(xy 388.023336 -227.998346) (xy 388.067798 -228.019444) (xy 388.108301 -228.0474) (xy 388.143794 -228.081492)
			(xy 388.173359 -228.120836) (xy 388.19623 -228.164413) (xy 388.211814 -228.211094) (xy 388.219709 -228.259671)
			(xy 388.220204 -228.284278) (xy 388.538715 -228.284278) (xy 388.54281 -228.23355) (xy 388.554989 -228.184136)
			(xy 388.574937 -228.137316) (xy 388.602138 -228.094302) (xy 388.635886 -228.056208) (xy 388.675308 -228.024021)
			(xy 388.719382 -227.998575) (xy 388.766968 -227.980528) (xy 388.816832 -227.970348) (xy 388.867684 -227.968299)
			(xy 388.918205 -227.974433) (xy 388.967089 -227.988593) (xy 389.013068 -228.01041) (xy 389.054952 -228.03932)
			(xy 389.091656 -228.074575) (xy 389.122229 -228.115261) (xy 389.14588 -228.160324) (xy 389.161996 -228.208598)
			(xy 389.17016 -228.258832) (xy 389.170672 -228.284278) (xy 389.488946 -228.284278) (xy 389.492906 -228.235224)
			(xy 389.504683 -228.18744) (xy 389.523974 -228.142164) (xy 389.550277 -228.100568) (xy 389.582912 -228.063731)
			(xy 389.621033 -228.032606) (xy 389.663654 -228.007999) (xy 389.70967 -227.990547) (xy 389.757889 -227.980703)
			(xy 389.807064 -227.978722) (xy 389.855919 -227.984654) (xy 389.90319 -227.998346) (xy 389.947652 -228.019444)
			(xy 389.988155 -228.0474) (xy 390.023648 -228.081492) (xy 390.053213 -228.120836) (xy 390.076084 -228.164413)
			(xy 390.091668 -228.211094) (xy 390.099563 -228.259671) (xy 390.100058 -228.284278) (xy 390.418569 -228.284278)
			(xy 390.422664 -228.23355) (xy 390.434843 -228.184136) (xy 390.454791 -228.137316) (xy 390.481992 -228.094302)
			(xy 390.51574 -228.056208) (xy 390.555162 -228.024021) (xy 390.599236 -227.998575) (xy 390.646822 -227.980528)
			(xy 390.696686 -227.970348) (xy 390.747538 -227.968299) (xy 390.798059 -227.974433) (xy 390.846943 -227.988593)
			(xy 390.892922 -228.01041) (xy 390.934806 -228.03932) (xy 390.97151 -228.074575) (xy 391.002083 -228.115261)
			(xy 391.025734 -228.160324) (xy 391.04185 -228.208598) (xy 391.050014 -228.258832) (xy 391.050526 -228.284278)
			(xy 391.369054 -228.284278) (xy 391.373014 -228.235224) (xy 391.384791 -228.18744) (xy 391.404082 -228.142164)
			(xy 391.430385 -228.100568) (xy 391.46302 -228.063731) (xy 391.501141 -228.032606) (xy 391.543762 -228.007999)
			(xy 391.589778 -227.990547) (xy 391.637997 -227.980703) (xy 391.687172 -227.978722) (xy 391.736027 -227.984654)
			(xy 391.783298 -227.998346) (xy 391.82776 -228.019444) (xy 391.868263 -228.0474) (xy 391.903756 -228.081492)
			(xy 391.933321 -228.120836) (xy 391.956192 -228.164413) (xy 391.971776 -228.211094) (xy 391.979671 -228.259671)
			(xy 391.980166 -228.284278) (xy 394.188962 -228.284278) (xy 394.192922 -228.235224) (xy 394.204699 -228.18744)
			(xy 394.22399 -228.142164) (xy 394.250293 -228.100568) (xy 394.282928 -228.063731) (xy 394.321049 -228.032606)
			(xy 394.36367 -228.007999) (xy 394.409686 -227.990547) (xy 394.457905 -227.980703) (xy 394.50708 -227.978722)
			(xy 394.555935 -227.984654) (xy 394.603206 -227.998346) (xy 394.647668 -228.019444) (xy 394.688171 -228.0474)
			(xy 394.723664 -228.081492) (xy 394.753229 -228.120836) (xy 394.7761 -228.164413) (xy 394.791684 -228.211094)
			(xy 394.799579 -228.259671) (xy 394.800074 -228.284278) (xy 394.799579 -228.308885) (xy 394.791684 -228.357462)
			(xy 394.7761 -228.404143) (xy 394.753229 -228.44772) (xy 394.723664 -228.487064) (xy 394.688171 -228.521156)
			(xy 394.647668 -228.549112) (xy 394.603206 -228.57021) (xy 394.555935 -228.583902) (xy 394.50708 -228.589834)
			(xy 394.457905 -228.587853) (xy 394.409686 -228.578009) (xy 394.36367 -228.560557) (xy 394.321049 -228.53595)
			(xy 394.282928 -228.504825) (xy 394.250293 -228.467988) (xy 394.22399 -228.426392) (xy 394.204699 -228.381116)
			(xy 394.192922 -228.333332) (xy 394.188962 -228.284278) (xy 391.980166 -228.284278) (xy 391.979671 -228.308885)
			(xy 391.971776 -228.357462) (xy 391.956192 -228.404143) (xy 391.933321 -228.44772) (xy 391.903756 -228.487064)
			(xy 391.868263 -228.521156) (xy 391.82776 -228.549112) (xy 391.783298 -228.57021) (xy 391.736027 -228.583902)
			(xy 391.687172 -228.589834) (xy 391.637997 -228.587853) (xy 391.589778 -228.578009) (xy 391.543762 -228.560557)
			(xy 391.501141 -228.53595) (xy 391.46302 -228.504825) (xy 391.430385 -228.467988) (xy 391.404082 -228.426392)
			(xy 391.384791 -228.381116) (xy 391.373014 -228.333332) (xy 391.369054 -228.284278) (xy 391.050526 -228.284278)
			(xy 391.050014 -228.309724) (xy 391.04185 -228.359958) (xy 391.025734 -228.408232) (xy 391.002083 -228.453295)
			(xy 390.97151 -228.493981) (xy 390.934806 -228.529236) (xy 390.892922 -228.558146) (xy 390.846943 -228.579963)
			(xy 390.798059 -228.594123) (xy 390.747538 -228.600257) (xy 390.696686 -228.598208) (xy 390.646822 -228.588028)
			(xy 390.599236 -228.569981) (xy 390.555162 -228.544535) (xy 390.51574 -228.512348) (xy 390.481992 -228.474254)
			(xy 390.454791 -228.43124) (xy 390.434843 -228.38442) (xy 390.422664 -228.335006) (xy 390.418569 -228.284278)
			(xy 390.100058 -228.284278) (xy 390.099563 -228.308885) (xy 390.091668 -228.357462) (xy 390.076084 -228.404143)
			(xy 390.053213 -228.44772) (xy 390.023648 -228.487064) (xy 389.988155 -228.521156) (xy 389.947652 -228.549112)
			(xy 389.90319 -228.57021) (xy 389.855919 -228.583902) (xy 389.807064 -228.589834) (xy 389.757889 -228.587853)
			(xy 389.70967 -228.578009) (xy 389.663654 -228.560557) (xy 389.621033 -228.53595) (xy 389.582912 -228.504825)
			(xy 389.550277 -228.467988) (xy 389.523974 -228.426392) (xy 389.504683 -228.381116) (xy 389.492906 -228.333332)
			(xy 389.488946 -228.284278) (xy 389.170672 -228.284278) (xy 389.17016 -228.309724) (xy 389.161996 -228.359958)
			(xy 389.14588 -228.408232) (xy 389.122229 -228.453295) (xy 389.091656 -228.493981) (xy 389.054952 -228.529236)
			(xy 389.013068 -228.558146) (xy 388.967089 -228.579963) (xy 388.918205 -228.594123) (xy 388.867684 -228.600257)
			(xy 388.816832 -228.598208) (xy 388.766968 -228.588028) (xy 388.719382 -228.569981) (xy 388.675308 -228.544535)
			(xy 388.635886 -228.512348) (xy 388.602138 -228.474254) (xy 388.574937 -228.43124) (xy 388.554989 -228.38442)
			(xy 388.54281 -228.335006) (xy 388.538715 -228.284278) (xy 388.220204 -228.284278) (xy 388.219709 -228.308885)
			(xy 388.211814 -228.357462) (xy 388.19623 -228.404143) (xy 388.173359 -228.44772) (xy 388.143794 -228.487064)
			(xy 388.108301 -228.521156) (xy 388.067798 -228.549112) (xy 388.023336 -228.57021) (xy 387.976065 -228.583902)
			(xy 387.92721 -228.589834) (xy 387.878035 -228.587853) (xy 387.829816 -228.578009) (xy 387.7838 -228.560557)
			(xy 387.741179 -228.53595) (xy 387.703058 -228.504825) (xy 387.670423 -228.467988) (xy 387.64412 -228.426392)
			(xy 387.624829 -228.381116) (xy 387.613052 -228.333332) (xy 387.609092 -228.284278) (xy 387.290564 -228.284278)
			(xy 387.290052 -228.309724) (xy 387.281888 -228.359958) (xy 387.265772 -228.408232) (xy 387.242121 -228.453295)
			(xy 387.211548 -228.493981) (xy 387.174844 -228.529236) (xy 387.13296 -228.558146) (xy 387.086981 -228.579963)
			(xy 387.038097 -228.594123) (xy 386.987576 -228.600257) (xy 386.936724 -228.598208) (xy 386.88686 -228.588028)
			(xy 386.839274 -228.569981) (xy 386.7952 -228.544535) (xy 386.755778 -228.512348) (xy 386.72203 -228.474254)
			(xy 386.694829 -228.43124) (xy 386.674881 -228.38442) (xy 386.662702 -228.335006) (xy 386.658607 -228.284278)
			(xy 386.35051 -228.284278) (xy 386.349998 -228.309724) (xy 386.341834 -228.359958) (xy 386.325718 -228.408232)
			(xy 386.302067 -228.453295) (xy 386.271494 -228.493981) (xy 386.23479 -228.529236) (xy 386.192906 -228.558146)
			(xy 386.146927 -228.579963) (xy 386.098043 -228.594123) (xy 386.047522 -228.600257) (xy 385.99667 -228.598208)
			(xy 385.946806 -228.588028) (xy 385.89922 -228.569981) (xy 385.855146 -228.544535) (xy 385.815724 -228.512348)
			(xy 385.781976 -228.474254) (xy 385.754775 -228.43124) (xy 385.734827 -228.38442) (xy 385.722648 -228.335006)
			(xy 385.718553 -228.284278) (xy 385.400042 -228.284278) (xy 385.399547 -228.308885) (xy 385.391652 -228.357462)
			(xy 385.376068 -228.404143) (xy 385.353197 -228.44772) (xy 385.323632 -228.487064) (xy 385.288139 -228.521156)
			(xy 385.247636 -228.549112) (xy 385.203174 -228.57021) (xy 385.155903 -228.583902) (xy 385.107048 -228.589834)
			(xy 385.057873 -228.587853) (xy 385.009654 -228.578009) (xy 384.963638 -228.560557) (xy 384.921017 -228.53595)
			(xy 384.882896 -228.504825) (xy 384.850261 -228.467988) (xy 384.823958 -228.426392) (xy 384.804667 -228.381116)
			(xy 384.79289 -228.333332) (xy 384.78893 -228.284278) (xy 384.470656 -228.284278) (xy 384.470144 -228.309724)
			(xy 384.46198 -228.359958) (xy 384.445864 -228.408232) (xy 384.422213 -228.453295) (xy 384.39164 -228.493981)
			(xy 384.354936 -228.529236) (xy 384.313052 -228.558146) (xy 384.267073 -228.579963) (xy 384.218189 -228.594123)
			(xy 384.167668 -228.600257) (xy 384.116816 -228.598208) (xy 384.066952 -228.588028) (xy 384.019366 -228.569981)
			(xy 383.975292 -228.544535) (xy 383.93587 -228.512348) (xy 383.902122 -228.474254) (xy 383.874921 -228.43124)
			(xy 383.854973 -228.38442) (xy 383.842794 -228.335006) (xy 383.838699 -228.284278) (xy 383.520188 -228.284278)
			(xy 383.519693 -228.308885) (xy 383.511798 -228.357462) (xy 383.496214 -228.404143) (xy 383.473343 -228.44772)
			(xy 383.443778 -228.487064) (xy 383.408285 -228.521156) (xy 383.367782 -228.549112) (xy 383.32332 -228.57021)
			(xy 383.276049 -228.583902) (xy 383.227194 -228.589834) (xy 383.178019 -228.587853) (xy 383.1298 -228.578009)
			(xy 383.083784 -228.560557) (xy 383.041163 -228.53595) (xy 383.003042 -228.504825) (xy 382.970407 -228.467988)
			(xy 382.944104 -228.426392) (xy 382.924813 -228.381116) (xy 382.913036 -228.333332) (xy 382.909076 -228.284278)
			(xy 382.590548 -228.284278) (xy 382.590036 -228.309724) (xy 382.581872 -228.359958) (xy 382.565756 -228.408232)
			(xy 382.542105 -228.453295) (xy 382.511532 -228.493981) (xy 382.474828 -228.529236) (xy 382.432944 -228.558146)
			(xy 382.386965 -228.579963) (xy 382.338081 -228.594123) (xy 382.28756 -228.600257) (xy 382.236708 -228.598208)
			(xy 382.186844 -228.588028) (xy 382.139258 -228.569981) (xy 382.095184 -228.544535) (xy 382.055762 -228.512348)
			(xy 382.022014 -228.474254) (xy 381.994813 -228.43124) (xy 381.974865 -228.38442) (xy 381.962686 -228.335006)
			(xy 381.958591 -228.284278) (xy 381.64008 -228.284278) (xy 381.639585 -228.308885) (xy 381.63169 -228.357462)
			(xy 381.616106 -228.404143) (xy 381.593235 -228.44772) (xy 381.56367 -228.487064) (xy 381.528177 -228.521156)
			(xy 381.487674 -228.549112) (xy 381.443212 -228.57021) (xy 381.395941 -228.583902) (xy 381.347086 -228.589834)
			(xy 381.297911 -228.587853) (xy 381.249692 -228.578009) (xy 381.203676 -228.560557) (xy 381.161055 -228.53595)
			(xy 381.122934 -228.504825) (xy 381.090299 -228.467988) (xy 381.063996 -228.426392) (xy 381.044705 -228.381116)
			(xy 381.032928 -228.333332) (xy 381.028968 -228.284278) (xy 380.71044 -228.284278) (xy 380.709928 -228.309724)
			(xy 380.701764 -228.359958) (xy 380.685648 -228.408232) (xy 380.661997 -228.453295) (xy 380.631424 -228.493981)
			(xy 380.59472 -228.529236) (xy 380.552836 -228.558146) (xy 380.506857 -228.579963) (xy 380.457973 -228.594123)
			(xy 380.407452 -228.600257) (xy 380.3566 -228.598208) (xy 380.306736 -228.588028) (xy 380.25915 -228.569981)
			(xy 380.215076 -228.544535) (xy 380.175654 -228.512348) (xy 380.141906 -228.474254) (xy 380.114705 -228.43124)
			(xy 380.094757 -228.38442) (xy 380.082578 -228.335006) (xy 380.078483 -228.284278) (xy 379.77064 -228.284278)
			(xy 379.770128 -228.309724) (xy 379.761964 -228.359958) (xy 379.745848 -228.408232) (xy 379.722197 -228.453295)
			(xy 379.691624 -228.493981) (xy 379.65492 -228.529236) (xy 379.613036 -228.558146) (xy 379.567057 -228.579963)
			(xy 379.518173 -228.594123) (xy 379.467652 -228.600257) (xy 379.4168 -228.598208) (xy 379.366936 -228.588028)
			(xy 379.31935 -228.569981) (xy 379.275276 -228.544535) (xy 379.235854 -228.512348) (xy 379.202106 -228.474254)
			(xy 379.174905 -228.43124) (xy 379.154957 -228.38442) (xy 379.142778 -228.335006) (xy 379.138683 -228.284278)
			(xy 378.820172 -228.284278) (xy 378.819677 -228.308885) (xy 378.811782 -228.357462) (xy 378.796198 -228.404143)
			(xy 378.773327 -228.44772) (xy 378.743762 -228.487064) (xy 378.708269 -228.521156) (xy 378.667766 -228.549112)
			(xy 378.623304 -228.57021) (xy 378.576033 -228.583902) (xy 378.527178 -228.589834) (xy 378.478003 -228.587853)
			(xy 378.429784 -228.578009) (xy 378.383768 -228.560557) (xy 378.341147 -228.53595) (xy 378.303026 -228.504825)
			(xy 378.270391 -228.467988) (xy 378.244088 -228.426392) (xy 378.224797 -228.381116) (xy 378.21302 -228.333332)
			(xy 378.20906 -228.284278) (xy 377.890532 -228.284278) (xy 377.89002 -228.309724) (xy 377.881856 -228.359958)
			(xy 377.86574 -228.408232) (xy 377.842089 -228.453295) (xy 377.811516 -228.493981) (xy 377.774812 -228.529236)
			(xy 377.732928 -228.558146) (xy 377.686949 -228.579963) (xy 377.638065 -228.594123) (xy 377.587544 -228.600257)
			(xy 377.536692 -228.598208) (xy 377.486828 -228.588028) (xy 377.439242 -228.569981) (xy 377.395168 -228.544535)
			(xy 377.355746 -228.512348) (xy 377.321998 -228.474254) (xy 377.294797 -228.43124) (xy 377.274849 -228.38442)
			(xy 377.26267 -228.335006) (xy 377.258575 -228.284278) (xy 376.940064 -228.284278) (xy 376.939569 -228.308885)
			(xy 376.931674 -228.357462) (xy 376.91609 -228.404143) (xy 376.893219 -228.44772) (xy 376.863654 -228.487064)
			(xy 376.828161 -228.521156) (xy 376.787658 -228.549112) (xy 376.743196 -228.57021) (xy 376.695925 -228.583902)
			(xy 376.64707 -228.589834) (xy 376.597895 -228.587853) (xy 376.549676 -228.578009) (xy 376.50366 -228.560557)
			(xy 376.461039 -228.53595) (xy 376.422918 -228.504825) (xy 376.390283 -228.467988) (xy 376.36398 -228.426392)
			(xy 376.344689 -228.381116) (xy 376.332912 -228.333332) (xy 376.328952 -228.284278) (xy 376.010424 -228.284278)
			(xy 376.009964 -228.309091) (xy 376.002204 -228.358106) (xy 375.986872 -228.405303) (xy 375.964345 -228.449521)
			(xy 375.935177 -228.48967) (xy 375.900088 -228.524762) (xy 375.859941 -228.553932) (xy 375.815725 -228.576463)
			(xy 375.768529 -228.591799) (xy 375.719515 -228.599562) (xy 375.694702 -228.6) (xy 375.667842 -228.599459)
			(xy 375.614897 -228.590363) (xy 375.564258 -228.572433) (xy 375.517385 -228.546187) (xy 375.475634 -228.512384)
			(xy 375.44021 -228.471998) (xy 375.425716 -228.449378) (xy 375.422668 -228.444298) (xy 375.41454 -228.43617)
			(xy 375.404126 -228.429566) (xy 375.399153 -228.426619) (xy 375.388257 -228.42277) (xy 375.382536 -228.421946)
			(xy 375.315226 -228.414072) (xy 375.303765 -228.413289) (xy 375.282095 -228.420846) (xy 375.27357 -228.42855)
			(xy 375.000266 -228.701854) (xy 374.9929 -228.708966) (xy 374.98528 -228.727762) (xy 374.98528 -229.094284)
			(xy 375.848621 -229.094284) (xy 375.852716 -229.043556) (xy 375.864895 -228.994142) (xy 375.884843 -228.947322)
			(xy 375.912044 -228.904308) (xy 375.945792 -228.866214) (xy 375.985214 -228.834027) (xy 376.029288 -228.808581)
			(xy 376.076874 -228.790534) (xy 376.126738 -228.780354) (xy 376.17759 -228.778305) (xy 376.228111 -228.784439)
			(xy 376.276995 -228.798599) (xy 376.322974 -228.820416) (xy 376.364858 -228.849326) (xy 376.401562 -228.884581)
			(xy 376.432135 -228.925267) (xy 376.455786 -228.97033) (xy 376.471902 -229.018604) (xy 376.480066 -229.068838)
			(xy 376.480578 -229.094284) (xy 376.788675 -229.094284) (xy 376.79277 -229.043556) (xy 376.804949 -228.994142)
			(xy 376.824897 -228.947322) (xy 376.852098 -228.904308) (xy 376.885846 -228.866214) (xy 376.925268 -228.834027)
			(xy 376.969342 -228.808581) (xy 377.016928 -228.790534) (xy 377.066792 -228.780354) (xy 377.117644 -228.778305)
			(xy 377.168165 -228.784439) (xy 377.217049 -228.798599) (xy 377.263028 -228.820416) (xy 377.304912 -228.849326)
			(xy 377.341616 -228.884581) (xy 377.372189 -228.925267) (xy 377.39584 -228.97033) (xy 377.411956 -229.018604)
			(xy 377.42012 -229.068838) (xy 377.420632 -229.094284) (xy 377.738906 -229.094284) (xy 377.742866 -229.04523)
			(xy 377.754643 -228.997446) (xy 377.773934 -228.95217) (xy 377.800237 -228.910574) (xy 377.832872 -228.873737)
			(xy 377.870993 -228.842612) (xy 377.913614 -228.818005) (xy 377.95963 -228.800553) (xy 378.007849 -228.790709)
			(xy 378.057024 -228.788728) (xy 378.105879 -228.79466) (xy 378.15315 -228.808352) (xy 378.197612 -228.82945)
			(xy 378.238115 -228.857406) (xy 378.273608 -228.891498) (xy 378.303173 -228.930842) (xy 378.326044 -228.974419)
			(xy 378.341628 -229.0211) (xy 378.349523 -229.069677) (xy 378.350018 -229.094284) (xy 378.668529 -229.094284)
			(xy 378.672624 -229.043556) (xy 378.684803 -228.994142) (xy 378.704751 -228.947322) (xy 378.731952 -228.904308)
			(xy 378.7657 -228.866214) (xy 378.805122 -228.834027) (xy 378.849196 -228.808581) (xy 378.896782 -228.790534)
			(xy 378.946646 -228.780354) (xy 378.997498 -228.778305) (xy 379.048019 -228.784439) (xy 379.096903 -228.798599)
			(xy 379.142882 -228.820416) (xy 379.184766 -228.849326) (xy 379.22147 -228.884581) (xy 379.252043 -228.925267)
			(xy 379.275694 -228.97033) (xy 379.29181 -229.018604) (xy 379.299974 -229.068838) (xy 379.300486 -229.094284)
			(xy 379.619014 -229.094284) (xy 379.622974 -229.04523) (xy 379.634751 -228.997446) (xy 379.654042 -228.95217)
			(xy 379.680345 -228.910574) (xy 379.71298 -228.873737) (xy 379.751101 -228.842612) (xy 379.793722 -228.818005)
			(xy 379.839738 -228.800553) (xy 379.887957 -228.790709) (xy 379.937132 -228.788728) (xy 379.985987 -228.79466)
			(xy 380.033258 -228.808352) (xy 380.07772 -228.82945) (xy 380.118223 -228.857406) (xy 380.153716 -228.891498)
			(xy 380.183281 -228.930842) (xy 380.206152 -228.974419) (xy 380.221736 -229.0211) (xy 380.229631 -229.069677)
			(xy 380.230126 -229.094284) (xy 380.548637 -229.094284) (xy 380.552732 -229.043556) (xy 380.564911 -228.994142)
			(xy 380.584859 -228.947322) (xy 380.61206 -228.904308) (xy 380.645808 -228.866214) (xy 380.68523 -228.834027)
			(xy 380.729304 -228.808581) (xy 380.77689 -228.790534) (xy 380.826754 -228.780354) (xy 380.877606 -228.778305)
			(xy 380.928127 -228.784439) (xy 380.977011 -228.798599) (xy 381.02299 -228.820416) (xy 381.064874 -228.849326)
			(xy 381.101578 -228.884581) (xy 381.132151 -228.925267) (xy 381.155802 -228.97033) (xy 381.171918 -229.018604)
			(xy 381.180082 -229.068838) (xy 381.180594 -229.094284) (xy 381.499122 -229.094284) (xy 381.503082 -229.04523)
			(xy 381.514859 -228.997446) (xy 381.53415 -228.95217) (xy 381.560453 -228.910574) (xy 381.593088 -228.873737)
			(xy 381.631209 -228.842612) (xy 381.67383 -228.818005) (xy 381.719846 -228.800553) (xy 381.768065 -228.790709)
			(xy 381.81724 -228.788728) (xy 381.866095 -228.79466) (xy 381.913366 -228.808352) (xy 381.957828 -228.82945)
			(xy 381.998331 -228.857406) (xy 382.033824 -228.891498) (xy 382.063389 -228.930842) (xy 382.08626 -228.974419)
			(xy 382.101844 -229.0211) (xy 382.109739 -229.069677) (xy 382.110234 -229.094284) (xy 382.428491 -229.094284)
			(xy 382.432586 -229.043556) (xy 382.444765 -228.994142) (xy 382.464713 -228.947322) (xy 382.491914 -228.904308)
			(xy 382.525662 -228.866214) (xy 382.565084 -228.834027) (xy 382.609158 -228.808581) (xy 382.656744 -228.790534)
			(xy 382.706608 -228.780354) (xy 382.75746 -228.778305) (xy 382.807981 -228.784439) (xy 382.856865 -228.798599)
			(xy 382.902844 -228.820416) (xy 382.944728 -228.849326) (xy 382.981432 -228.884581) (xy 383.012005 -228.925267)
			(xy 383.035656 -228.97033) (xy 383.051772 -229.018604) (xy 383.059936 -229.068838) (xy 383.060448 -229.094284)
			(xy 383.368545 -229.094284) (xy 383.37264 -229.043556) (xy 383.384819 -228.994142) (xy 383.404767 -228.947322)
			(xy 383.431968 -228.904308) (xy 383.465716 -228.866214) (xy 383.505138 -228.834027) (xy 383.549212 -228.808581)
			(xy 383.596798 -228.790534) (xy 383.646662 -228.780354) (xy 383.697514 -228.778305) (xy 383.748035 -228.784439)
			(xy 383.796919 -228.798599) (xy 383.842898 -228.820416) (xy 383.884782 -228.849326) (xy 383.921486 -228.884581)
			(xy 383.952059 -228.925267) (xy 383.97571 -228.97033) (xy 383.991826 -229.018604) (xy 383.99999 -229.068838)
			(xy 384.000502 -229.094284) (xy 384.31903 -229.094284) (xy 384.32299 -229.04523) (xy 384.334767 -228.997446)
			(xy 384.354058 -228.95217) (xy 384.380361 -228.910574) (xy 384.412996 -228.873737) (xy 384.451117 -228.842612)
			(xy 384.493738 -228.818005) (xy 384.539754 -228.800553) (xy 384.587973 -228.790709) (xy 384.637148 -228.788728)
			(xy 384.686003 -228.79466) (xy 384.733274 -228.808352) (xy 384.777736 -228.82945) (xy 384.818239 -228.857406)
			(xy 384.853732 -228.891498) (xy 384.883297 -228.930842) (xy 384.906168 -228.974419) (xy 384.921752 -229.0211)
			(xy 384.929647 -229.069677) (xy 384.930142 -229.094284) (xy 385.248653 -229.094284) (xy 385.252748 -229.043556)
			(xy 385.264927 -228.994142) (xy 385.284875 -228.947322) (xy 385.312076 -228.904308) (xy 385.345824 -228.866214)
			(xy 385.385246 -228.834027) (xy 385.42932 -228.808581) (xy 385.476906 -228.790534) (xy 385.52677 -228.780354)
			(xy 385.577622 -228.778305) (xy 385.628143 -228.784439) (xy 385.677027 -228.798599) (xy 385.723006 -228.820416)
			(xy 385.76489 -228.849326) (xy 385.801594 -228.884581) (xy 385.832167 -228.925267) (xy 385.855818 -228.97033)
			(xy 385.871934 -229.018604) (xy 385.880098 -229.068838) (xy 385.88061 -229.094284) (xy 386.199138 -229.094284)
			(xy 386.203098 -229.04523) (xy 386.214875 -228.997446) (xy 386.234166 -228.95217) (xy 386.260469 -228.910574)
			(xy 386.293104 -228.873737) (xy 386.331225 -228.842612) (xy 386.373846 -228.818005) (xy 386.419862 -228.800553)
			(xy 386.468081 -228.790709) (xy 386.517256 -228.788728) (xy 386.566111 -228.79466) (xy 386.613382 -228.808352)
			(xy 386.657844 -228.82945) (xy 386.698347 -228.857406) (xy 386.73384 -228.891498) (xy 386.763405 -228.930842)
			(xy 386.786276 -228.974419) (xy 386.80186 -229.0211) (xy 386.809755 -229.069677) (xy 386.81025 -229.094284)
			(xy 387.128507 -229.094284) (xy 387.132602 -229.043556) (xy 387.144781 -228.994142) (xy 387.164729 -228.947322)
			(xy 387.19193 -228.904308) (xy 387.225678 -228.866214) (xy 387.2651 -228.834027) (xy 387.309174 -228.808581)
			(xy 387.35676 -228.790534) (xy 387.406624 -228.780354) (xy 387.457476 -228.778305) (xy 387.507997 -228.784439)
			(xy 387.556881 -228.798599) (xy 387.60286 -228.820416) (xy 387.644744 -228.849326) (xy 387.681448 -228.884581)
			(xy 387.712021 -228.925267) (xy 387.735672 -228.97033) (xy 387.751788 -229.018604) (xy 387.759952 -229.068838)
			(xy 387.760464 -229.094284) (xy 388.078992 -229.094284) (xy 388.082952 -229.04523) (xy 388.094729 -228.997446)
			(xy 388.11402 -228.95217) (xy 388.140323 -228.910574) (xy 388.172958 -228.873737) (xy 388.211079 -228.842612)
			(xy 388.2537 -228.818005) (xy 388.299716 -228.800553) (xy 388.347935 -228.790709) (xy 388.39711 -228.788728)
			(xy 388.445965 -228.79466) (xy 388.493236 -228.808352) (xy 388.537698 -228.82945) (xy 388.578201 -228.857406)
			(xy 388.613694 -228.891498) (xy 388.643259 -228.930842) (xy 388.66613 -228.974419) (xy 388.681714 -229.0211)
			(xy 388.689609 -229.069677) (xy 388.690104 -229.094284) (xy 389.008615 -229.094284) (xy 389.01271 -229.043556)
			(xy 389.024889 -228.994142) (xy 389.044837 -228.947322) (xy 389.072038 -228.904308) (xy 389.105786 -228.866214)
			(xy 389.145208 -228.834027) (xy 389.189282 -228.808581) (xy 389.236868 -228.790534) (xy 389.286732 -228.780354)
			(xy 389.337584 -228.778305) (xy 389.388105 -228.784439) (xy 389.436989 -228.798599) (xy 389.482968 -228.820416)
			(xy 389.524852 -228.849326) (xy 389.561556 -228.884581) (xy 389.592129 -228.925267) (xy 389.61578 -228.97033)
			(xy 389.631896 -229.018604) (xy 389.64006 -229.068838) (xy 389.640572 -229.094284) (xy 389.948669 -229.094284)
			(xy 389.952764 -229.043556) (xy 389.964943 -228.994142) (xy 389.984891 -228.947322) (xy 390.012092 -228.904308)
			(xy 390.04584 -228.866214) (xy 390.085262 -228.834027) (xy 390.129336 -228.808581) (xy 390.176922 -228.790534)
			(xy 390.226786 -228.780354) (xy 390.277638 -228.778305) (xy 390.328159 -228.784439) (xy 390.377043 -228.798599)
			(xy 390.423022 -228.820416) (xy 390.464906 -228.849326) (xy 390.50161 -228.884581) (xy 390.532183 -228.925267)
			(xy 390.555834 -228.97033) (xy 390.57195 -229.018604) (xy 390.580114 -229.068838) (xy 390.580626 -229.094284)
			(xy 390.8989 -229.094284) (xy 390.90286 -229.04523) (xy 390.914637 -228.997446) (xy 390.933928 -228.95217)
			(xy 390.960231 -228.910574) (xy 390.992866 -228.873737) (xy 391.030987 -228.842612) (xy 391.073608 -228.818005)
			(xy 391.119624 -228.800553) (xy 391.167843 -228.790709) (xy 391.217018 -228.788728) (xy 391.265873 -228.79466)
			(xy 391.313144 -228.808352) (xy 391.357606 -228.82945) (xy 391.398109 -228.857406) (xy 391.433602 -228.891498)
			(xy 391.463167 -228.930842) (xy 391.486038 -228.974419) (xy 391.501622 -229.0211) (xy 391.509517 -229.069677)
			(xy 391.510012 -229.094284) (xy 392.779008 -229.094284) (xy 392.782968 -229.04523) (xy 392.794745 -228.997446)
			(xy 392.814036 -228.95217) (xy 392.840339 -228.910574) (xy 392.872974 -228.873737) (xy 392.911095 -228.842612)
			(xy 392.953716 -228.818005) (xy 392.999732 -228.800553) (xy 393.047951 -228.790709) (xy 393.097126 -228.788728)
			(xy 393.145981 -228.79466) (xy 393.193252 -228.808352) (xy 393.237714 -228.82945) (xy 393.278217 -228.857406)
			(xy 393.31371 -228.891498) (xy 393.343275 -228.930842) (xy 393.366146 -228.974419) (xy 393.38173 -229.0211)
			(xy 393.389625 -229.069677) (xy 393.39012 -229.094284) (xy 393.389625 -229.118891) (xy 393.38173 -229.167468)
			(xy 393.366146 -229.214149) (xy 393.343275 -229.257726) (xy 393.31371 -229.29707) (xy 393.278217 -229.331162)
			(xy 393.237714 -229.359118) (xy 393.193252 -229.380216) (xy 393.145981 -229.393908) (xy 393.097126 -229.39984)
			(xy 393.047951 -229.397859) (xy 392.999732 -229.388015) (xy 392.953716 -229.370563) (xy 392.911095 -229.345956)
			(xy 392.872974 -229.314831) (xy 392.840339 -229.277994) (xy 392.814036 -229.236398) (xy 392.794745 -229.191122)
			(xy 392.782968 -229.143338) (xy 392.779008 -229.094284) (xy 391.510012 -229.094284) (xy 391.509517 -229.118891)
			(xy 391.501622 -229.167468) (xy 391.486038 -229.214149) (xy 391.463167 -229.257726) (xy 391.433602 -229.29707)
			(xy 391.398109 -229.331162) (xy 391.357606 -229.359118) (xy 391.313144 -229.380216) (xy 391.265873 -229.393908)
			(xy 391.217018 -229.39984) (xy 391.167843 -229.397859) (xy 391.119624 -229.388015) (xy 391.073608 -229.370563)
			(xy 391.030987 -229.345956) (xy 390.992866 -229.314831) (xy 390.960231 -229.277994) (xy 390.933928 -229.236398)
			(xy 390.914637 -229.191122) (xy 390.90286 -229.143338) (xy 390.8989 -229.094284) (xy 390.580626 -229.094284)
			(xy 390.580114 -229.11973) (xy 390.57195 -229.169964) (xy 390.555834 -229.218238) (xy 390.532183 -229.263301)
			(xy 390.50161 -229.303987) (xy 390.464906 -229.339242) (xy 390.423022 -229.368152) (xy 390.377043 -229.389969)
			(xy 390.328159 -229.404129) (xy 390.277638 -229.410263) (xy 390.226786 -229.408214) (xy 390.176922 -229.398034)
			(xy 390.129336 -229.379987) (xy 390.085262 -229.354541) (xy 390.04584 -229.322354) (xy 390.012092 -229.28426)
			(xy 389.984891 -229.241246) (xy 389.964943 -229.194426) (xy 389.952764 -229.145012) (xy 389.948669 -229.094284)
			(xy 389.640572 -229.094284) (xy 389.64006 -229.11973) (xy 389.631896 -229.169964) (xy 389.61578 -229.218238)
			(xy 389.592129 -229.263301) (xy 389.561556 -229.303987) (xy 389.524852 -229.339242) (xy 389.482968 -229.368152)
			(xy 389.436989 -229.389969) (xy 389.388105 -229.404129) (xy 389.337584 -229.410263) (xy 389.286732 -229.408214)
			(xy 389.236868 -229.398034) (xy 389.189282 -229.379987) (xy 389.145208 -229.354541) (xy 389.105786 -229.322354)
			(xy 389.072038 -229.28426) (xy 389.044837 -229.241246) (xy 389.024889 -229.194426) (xy 389.01271 -229.145012)
			(xy 389.008615 -229.094284) (xy 388.690104 -229.094284) (xy 388.689609 -229.118891) (xy 388.681714 -229.167468)
			(xy 388.66613 -229.214149) (xy 388.643259 -229.257726) (xy 388.613694 -229.29707) (xy 388.578201 -229.331162)
			(xy 388.537698 -229.359118) (xy 388.493236 -229.380216) (xy 388.445965 -229.393908) (xy 388.39711 -229.39984)
			(xy 388.347935 -229.397859) (xy 388.299716 -229.388015) (xy 388.2537 -229.370563) (xy 388.211079 -229.345956)
			(xy 388.172958 -229.314831) (xy 388.140323 -229.277994) (xy 388.11402 -229.236398) (xy 388.094729 -229.191122)
			(xy 388.082952 -229.143338) (xy 388.078992 -229.094284) (xy 387.760464 -229.094284) (xy 387.759952 -229.11973)
			(xy 387.751788 -229.169964) (xy 387.735672 -229.218238) (xy 387.712021 -229.263301) (xy 387.681448 -229.303987)
			(xy 387.644744 -229.339242) (xy 387.60286 -229.368152) (xy 387.556881 -229.389969) (xy 387.507997 -229.404129)
			(xy 387.457476 -229.410263) (xy 387.406624 -229.408214) (xy 387.35676 -229.398034) (xy 387.309174 -229.379987)
			(xy 387.2651 -229.354541) (xy 387.225678 -229.322354) (xy 387.19193 -229.28426) (xy 387.164729 -229.241246)
			(xy 387.144781 -229.194426) (xy 387.132602 -229.145012) (xy 387.128507 -229.094284) (xy 386.81025 -229.094284)
			(xy 386.809755 -229.118891) (xy 386.80186 -229.167468) (xy 386.786276 -229.214149) (xy 386.763405 -229.257726)
			(xy 386.73384 -229.29707) (xy 386.698347 -229.331162) (xy 386.657844 -229.359118) (xy 386.613382 -229.380216)
			(xy 386.566111 -229.393908) (xy 386.517256 -229.39984) (xy 386.468081 -229.397859) (xy 386.419862 -229.388015)
			(xy 386.373846 -229.370563) (xy 386.331225 -229.345956) (xy 386.293104 -229.314831) (xy 386.260469 -229.277994)
			(xy 386.234166 -229.236398) (xy 386.214875 -229.191122) (xy 386.203098 -229.143338) (xy 386.199138 -229.094284)
			(xy 385.88061 -229.094284) (xy 385.880098 -229.11973) (xy 385.871934 -229.169964) (xy 385.855818 -229.218238)
			(xy 385.832167 -229.263301) (xy 385.801594 -229.303987) (xy 385.76489 -229.339242) (xy 385.723006 -229.368152)
			(xy 385.677027 -229.389969) (xy 385.628143 -229.404129) (xy 385.577622 -229.410263) (xy 385.52677 -229.408214)
			(xy 385.476906 -229.398034) (xy 385.42932 -229.379987) (xy 385.385246 -229.354541) (xy 385.345824 -229.322354)
			(xy 385.312076 -229.28426) (xy 385.284875 -229.241246) (xy 385.264927 -229.194426) (xy 385.252748 -229.145012)
			(xy 385.248653 -229.094284) (xy 384.930142 -229.094284) (xy 384.929647 -229.118891) (xy 384.921752 -229.167468)
			(xy 384.906168 -229.214149) (xy 384.883297 -229.257726) (xy 384.853732 -229.29707) (xy 384.818239 -229.331162)
			(xy 384.777736 -229.359118) (xy 384.733274 -229.380216) (xy 384.686003 -229.393908) (xy 384.637148 -229.39984)
			(xy 384.587973 -229.397859) (xy 384.539754 -229.388015) (xy 384.493738 -229.370563) (xy 384.451117 -229.345956)
			(xy 384.412996 -229.314831) (xy 384.380361 -229.277994) (xy 384.354058 -229.236398) (xy 384.334767 -229.191122)
			(xy 384.32299 -229.143338) (xy 384.31903 -229.094284) (xy 384.000502 -229.094284) (xy 383.99999 -229.11973)
			(xy 383.991826 -229.169964) (xy 383.97571 -229.218238) (xy 383.952059 -229.263301) (xy 383.921486 -229.303987)
			(xy 383.884782 -229.339242) (xy 383.842898 -229.368152) (xy 383.796919 -229.389969) (xy 383.748035 -229.404129)
			(xy 383.697514 -229.410263) (xy 383.646662 -229.408214) (xy 383.596798 -229.398034) (xy 383.549212 -229.379987)
			(xy 383.505138 -229.354541) (xy 383.465716 -229.322354) (xy 383.431968 -229.28426) (xy 383.404767 -229.241246)
			(xy 383.384819 -229.194426) (xy 383.37264 -229.145012) (xy 383.368545 -229.094284) (xy 383.060448 -229.094284)
			(xy 383.059936 -229.11973) (xy 383.051772 -229.169964) (xy 383.035656 -229.218238) (xy 383.012005 -229.263301)
			(xy 382.981432 -229.303987) (xy 382.944728 -229.339242) (xy 382.902844 -229.368152) (xy 382.856865 -229.389969)
			(xy 382.807981 -229.404129) (xy 382.75746 -229.410263) (xy 382.706608 -229.408214) (xy 382.656744 -229.398034)
			(xy 382.609158 -229.379987) (xy 382.565084 -229.354541) (xy 382.525662 -229.322354) (xy 382.491914 -229.28426)
			(xy 382.464713 -229.241246) (xy 382.444765 -229.194426) (xy 382.432586 -229.145012) (xy 382.428491 -229.094284)
			(xy 382.110234 -229.094284) (xy 382.109739 -229.118891) (xy 382.101844 -229.167468) (xy 382.08626 -229.214149)
			(xy 382.063389 -229.257726) (xy 382.033824 -229.29707) (xy 381.998331 -229.331162) (xy 381.957828 -229.359118)
			(xy 381.913366 -229.380216) (xy 381.866095 -229.393908) (xy 381.81724 -229.39984) (xy 381.768065 -229.397859)
			(xy 381.719846 -229.388015) (xy 381.67383 -229.370563) (xy 381.631209 -229.345956) (xy 381.593088 -229.314831)
			(xy 381.560453 -229.277994) (xy 381.53415 -229.236398) (xy 381.514859 -229.191122) (xy 381.503082 -229.143338)
			(xy 381.499122 -229.094284) (xy 381.180594 -229.094284) (xy 381.180082 -229.11973) (xy 381.171918 -229.169964)
			(xy 381.155802 -229.218238) (xy 381.132151 -229.263301) (xy 381.101578 -229.303987) (xy 381.064874 -229.339242)
			(xy 381.02299 -229.368152) (xy 380.977011 -229.389969) (xy 380.928127 -229.404129) (xy 380.877606 -229.410263)
			(xy 380.826754 -229.408214) (xy 380.77689 -229.398034) (xy 380.729304 -229.379987) (xy 380.68523 -229.354541)
			(xy 380.645808 -229.322354) (xy 380.61206 -229.28426) (xy 380.584859 -229.241246) (xy 380.564911 -229.194426)
			(xy 380.552732 -229.145012) (xy 380.548637 -229.094284) (xy 380.230126 -229.094284) (xy 380.229631 -229.118891)
			(xy 380.221736 -229.167468) (xy 380.206152 -229.214149) (xy 380.183281 -229.257726) (xy 380.153716 -229.29707)
			(xy 380.118223 -229.331162) (xy 380.07772 -229.359118) (xy 380.033258 -229.380216) (xy 379.985987 -229.393908)
			(xy 379.937132 -229.39984) (xy 379.887957 -229.397859) (xy 379.839738 -229.388015) (xy 379.793722 -229.370563)
			(xy 379.751101 -229.345956) (xy 379.71298 -229.314831) (xy 379.680345 -229.277994) (xy 379.654042 -229.236398)
			(xy 379.634751 -229.191122) (xy 379.622974 -229.143338) (xy 379.619014 -229.094284) (xy 379.300486 -229.094284)
			(xy 379.299974 -229.11973) (xy 379.29181 -229.169964) (xy 379.275694 -229.218238) (xy 379.252043 -229.263301)
			(xy 379.22147 -229.303987) (xy 379.184766 -229.339242) (xy 379.142882 -229.368152) (xy 379.096903 -229.389969)
			(xy 379.048019 -229.404129) (xy 378.997498 -229.410263) (xy 378.946646 -229.408214) (xy 378.896782 -229.398034)
			(xy 378.849196 -229.379987) (xy 378.805122 -229.354541) (xy 378.7657 -229.322354) (xy 378.731952 -229.28426)
			(xy 378.704751 -229.241246) (xy 378.684803 -229.194426) (xy 378.672624 -229.145012) (xy 378.668529 -229.094284)
			(xy 378.350018 -229.094284) (xy 378.349523 -229.118891) (xy 378.341628 -229.167468) (xy 378.326044 -229.214149)
			(xy 378.303173 -229.257726) (xy 378.273608 -229.29707) (xy 378.238115 -229.331162) (xy 378.197612 -229.359118)
			(xy 378.15315 -229.380216) (xy 378.105879 -229.393908) (xy 378.057024 -229.39984) (xy 378.007849 -229.397859)
			(xy 377.95963 -229.388015) (xy 377.913614 -229.370563) (xy 377.870993 -229.345956) (xy 377.832872 -229.314831)
			(xy 377.800237 -229.277994) (xy 377.773934 -229.236398) (xy 377.754643 -229.191122) (xy 377.742866 -229.143338)
			(xy 377.738906 -229.094284) (xy 377.420632 -229.094284) (xy 377.42012 -229.11973) (xy 377.411956 -229.169964)
			(xy 377.39584 -229.218238) (xy 377.372189 -229.263301) (xy 377.341616 -229.303987) (xy 377.304912 -229.339242)
			(xy 377.263028 -229.368152) (xy 377.217049 -229.389969) (xy 377.168165 -229.404129) (xy 377.117644 -229.410263)
			(xy 377.066792 -229.408214) (xy 377.016928 -229.398034) (xy 376.969342 -229.379987) (xy 376.925268 -229.354541)
			(xy 376.885846 -229.322354) (xy 376.852098 -229.28426) (xy 376.824897 -229.241246) (xy 376.804949 -229.194426)
			(xy 376.79277 -229.145012) (xy 376.788675 -229.094284) (xy 376.480578 -229.094284) (xy 376.480066 -229.11973)
			(xy 376.471902 -229.169964) (xy 376.455786 -229.218238) (xy 376.432135 -229.263301) (xy 376.401562 -229.303987)
			(xy 376.364858 -229.339242) (xy 376.322974 -229.368152) (xy 376.276995 -229.389969) (xy 376.228111 -229.404129)
			(xy 376.17759 -229.410263) (xy 376.126738 -229.408214) (xy 376.076874 -229.398034) (xy 376.029288 -229.379987)
			(xy 375.985214 -229.354541) (xy 375.945792 -229.322354) (xy 375.912044 -229.28426) (xy 375.884843 -229.241246)
			(xy 375.864895 -229.194426) (xy 375.852716 -229.145012) (xy 375.848621 -229.094284) (xy 374.98528 -229.094284)
			(xy 374.98528 -229.67696) (xy 374.985353 -229.68117) (xy 374.986753 -229.689472) (xy 374.988074 -229.69347)
			(xy 374.995948 -229.71633) (xy 375.00052 -229.72268) (xy 375.014554 -229.742502) (xy 375.036828 -229.785657)
			(xy 375.051995 -229.831793) (xy 375.059673 -229.879747) (xy 375.05967 -229.904036) (xy 375.378467 -229.904036)
			(xy 375.382562 -229.853308) (xy 375.394741 -229.803894) (xy 375.414689 -229.757074) (xy 375.44189 -229.71406)
			(xy 375.475638 -229.675966) (xy 375.51506 -229.643779) (xy 375.559134 -229.618333) (xy 375.60672 -229.600286)
			(xy 375.656584 -229.590106) (xy 375.707436 -229.588057) (xy 375.757957 -229.594191) (xy 375.806841 -229.608351)
			(xy 375.85282 -229.630168) (xy 375.894704 -229.659078) (xy 375.931408 -229.694333) (xy 375.961981 -229.735019)
			(xy 375.985632 -229.780082) (xy 376.001748 -229.828356) (xy 376.009912 -229.87859) (xy 376.010424 -229.904036)
			(xy 376.328952 -229.904036) (xy 376.332912 -229.854982) (xy 376.344689 -229.807198) (xy 376.36398 -229.761922)
			(xy 376.390283 -229.720326) (xy 376.422918 -229.683489) (xy 376.461039 -229.652364) (xy 376.50366 -229.627757)
			(xy 376.549676 -229.610305) (xy 376.597895 -229.600461) (xy 376.64707 -229.59848) (xy 376.695925 -229.604412)
			(xy 376.743196 -229.618104) (xy 376.787658 -229.639202) (xy 376.828161 -229.667158) (xy 376.863654 -229.70125)
			(xy 376.893219 -229.740594) (xy 376.91609 -229.784171) (xy 376.931674 -229.830852) (xy 376.939569 -229.879429)
			(xy 376.940064 -229.904036) (xy 377.258575 -229.904036) (xy 377.26267 -229.853308) (xy 377.274849 -229.803894)
			(xy 377.294797 -229.757074) (xy 377.321998 -229.71406) (xy 377.355746 -229.675966) (xy 377.395168 -229.643779)
			(xy 377.439242 -229.618333) (xy 377.486828 -229.600286) (xy 377.536692 -229.590106) (xy 377.587544 -229.588057)
			(xy 377.638065 -229.594191) (xy 377.686949 -229.608351) (xy 377.732928 -229.630168) (xy 377.774812 -229.659078)
			(xy 377.811516 -229.694333) (xy 377.842089 -229.735019) (xy 377.86574 -229.780082) (xy 377.881856 -229.828356)
			(xy 377.89002 -229.87859) (xy 377.890532 -229.904036) (xy 379.138683 -229.904036) (xy 379.142778 -229.853308)
			(xy 379.154957 -229.803894) (xy 379.174905 -229.757074) (xy 379.202106 -229.71406) (xy 379.235854 -229.675966)
			(xy 379.275276 -229.643779) (xy 379.31935 -229.618333) (xy 379.366936 -229.600286) (xy 379.4168 -229.590106)
			(xy 379.467652 -229.588057) (xy 379.518173 -229.594191) (xy 379.567057 -229.608351) (xy 379.613036 -229.630168)
			(xy 379.65492 -229.659078) (xy 379.691624 -229.694333) (xy 379.722197 -229.735019) (xy 379.745848 -229.780082)
			(xy 379.761964 -229.828356) (xy 379.770128 -229.87859) (xy 379.77064 -229.904036) (xy 380.078483 -229.904036)
			(xy 380.082578 -229.853308) (xy 380.094757 -229.803894) (xy 380.114705 -229.757074) (xy 380.141906 -229.71406)
			(xy 380.175654 -229.675966) (xy 380.215076 -229.643779) (xy 380.25915 -229.618333) (xy 380.306736 -229.600286)
			(xy 380.3566 -229.590106) (xy 380.407452 -229.588057) (xy 380.457973 -229.594191) (xy 380.506857 -229.608351)
			(xy 380.552836 -229.630168) (xy 380.59472 -229.659078) (xy 380.631424 -229.694333) (xy 380.661997 -229.735019)
			(xy 380.685648 -229.780082) (xy 380.701764 -229.828356) (xy 380.709928 -229.87859) (xy 380.71044 -229.904036)
			(xy 381.028968 -229.904036) (xy 381.032928 -229.854982) (xy 381.044705 -229.807198) (xy 381.063996 -229.761922)
			(xy 381.090299 -229.720326) (xy 381.122934 -229.683489) (xy 381.161055 -229.652364) (xy 381.203676 -229.627757)
			(xy 381.249692 -229.610305) (xy 381.297911 -229.600461) (xy 381.347086 -229.59848) (xy 381.395941 -229.604412)
			(xy 381.443212 -229.618104) (xy 381.487674 -229.639202) (xy 381.528177 -229.667158) (xy 381.56367 -229.70125)
			(xy 381.593235 -229.740594) (xy 381.616106 -229.784171) (xy 381.63169 -229.830852) (xy 381.639585 -229.879429)
			(xy 381.64008 -229.904036) (xy 381.958591 -229.904036) (xy 381.962686 -229.853308) (xy 381.974865 -229.803894)
			(xy 381.994813 -229.757074) (xy 382.022014 -229.71406) (xy 382.055762 -229.675966) (xy 382.095184 -229.643779)
			(xy 382.139258 -229.618333) (xy 382.186844 -229.600286) (xy 382.236708 -229.590106) (xy 382.28756 -229.588057)
			(xy 382.338081 -229.594191) (xy 382.386965 -229.608351) (xy 382.432944 -229.630168) (xy 382.474828 -229.659078)
			(xy 382.511532 -229.694333) (xy 382.542105 -229.735019) (xy 382.565756 -229.780082) (xy 382.581872 -229.828356)
			(xy 382.590036 -229.87859) (xy 382.590548 -229.904036) (xy 382.909076 -229.904036) (xy 382.913036 -229.854982)
			(xy 382.924813 -229.807198) (xy 382.944104 -229.761922) (xy 382.970407 -229.720326) (xy 383.003042 -229.683489)
			(xy 383.041163 -229.652364) (xy 383.083784 -229.627757) (xy 383.1298 -229.610305) (xy 383.178019 -229.600461)
			(xy 383.227194 -229.59848) (xy 383.276049 -229.604412) (xy 383.32332 -229.618104) (xy 383.367782 -229.639202)
			(xy 383.408285 -229.667158) (xy 383.443778 -229.70125) (xy 383.473343 -229.740594) (xy 383.496214 -229.784171)
			(xy 383.511798 -229.830852) (xy 383.519693 -229.879429) (xy 383.520188 -229.904036) (xy 383.838699 -229.904036)
			(xy 383.842794 -229.853308) (xy 383.854973 -229.803894) (xy 383.874921 -229.757074) (xy 383.902122 -229.71406)
			(xy 383.93587 -229.675966) (xy 383.975292 -229.643779) (xy 384.019366 -229.618333) (xy 384.066952 -229.600286)
			(xy 384.116816 -229.590106) (xy 384.167668 -229.588057) (xy 384.218189 -229.594191) (xy 384.267073 -229.608351)
			(xy 384.313052 -229.630168) (xy 384.354936 -229.659078) (xy 384.39164 -229.694333) (xy 384.422213 -229.735019)
			(xy 384.445864 -229.780082) (xy 384.46198 -229.828356) (xy 384.470144 -229.87859) (xy 384.470656 -229.904036)
			(xy 385.718553 -229.904036) (xy 385.722648 -229.853308) (xy 385.734827 -229.803894) (xy 385.754775 -229.757074)
			(xy 385.781976 -229.71406) (xy 385.815724 -229.675966) (xy 385.855146 -229.643779) (xy 385.89922 -229.618333)
			(xy 385.946806 -229.600286) (xy 385.99667 -229.590106) (xy 386.047522 -229.588057) (xy 386.098043 -229.594191)
			(xy 386.146927 -229.608351) (xy 386.192906 -229.630168) (xy 386.23479 -229.659078) (xy 386.271494 -229.694333)
			(xy 386.302067 -229.735019) (xy 386.325718 -229.780082) (xy 386.341834 -229.828356) (xy 386.349998 -229.87859)
			(xy 386.35051 -229.904036) (xy 386.658607 -229.904036) (xy 386.662702 -229.853308) (xy 386.674881 -229.803894)
			(xy 386.694829 -229.757074) (xy 386.72203 -229.71406) (xy 386.755778 -229.675966) (xy 386.7952 -229.643779)
			(xy 386.839274 -229.618333) (xy 386.88686 -229.600286) (xy 386.936724 -229.590106) (xy 386.987576 -229.588057)
			(xy 387.038097 -229.594191) (xy 387.086981 -229.608351) (xy 387.13296 -229.630168) (xy 387.174844 -229.659078)
			(xy 387.211548 -229.694333) (xy 387.242121 -229.735019) (xy 387.265772 -229.780082) (xy 387.281888 -229.828356)
			(xy 387.290052 -229.87859) (xy 387.290564 -229.904036) (xy 387.609092 -229.904036) (xy 387.613052 -229.854982)
			(xy 387.624829 -229.807198) (xy 387.64412 -229.761922) (xy 387.670423 -229.720326) (xy 387.703058 -229.683489)
			(xy 387.741179 -229.652364) (xy 387.7838 -229.627757) (xy 387.829816 -229.610305) (xy 387.878035 -229.600461)
			(xy 387.92721 -229.59848) (xy 387.976065 -229.604412) (xy 388.023336 -229.618104) (xy 388.067798 -229.639202)
			(xy 388.108301 -229.667158) (xy 388.143794 -229.70125) (xy 388.173359 -229.740594) (xy 388.19623 -229.784171)
			(xy 388.211814 -229.830852) (xy 388.219709 -229.879429) (xy 388.220204 -229.904036) (xy 388.538715 -229.904036)
			(xy 388.54281 -229.853308) (xy 388.554989 -229.803894) (xy 388.574937 -229.757074) (xy 388.602138 -229.71406)
			(xy 388.635886 -229.675966) (xy 388.675308 -229.643779) (xy 388.719382 -229.618333) (xy 388.766968 -229.600286)
			(xy 388.816832 -229.590106) (xy 388.867684 -229.588057) (xy 388.918205 -229.594191) (xy 388.967089 -229.608351)
			(xy 389.013068 -229.630168) (xy 389.054952 -229.659078) (xy 389.091656 -229.694333) (xy 389.122229 -229.735019)
			(xy 389.14588 -229.780082) (xy 389.161996 -229.828356) (xy 389.17016 -229.87859) (xy 389.170672 -229.904036)
			(xy 389.488946 -229.904036) (xy 389.492906 -229.854982) (xy 389.504683 -229.807198) (xy 389.523974 -229.761922)
			(xy 389.550277 -229.720326) (xy 389.582912 -229.683489) (xy 389.621033 -229.652364) (xy 389.663654 -229.627757)
			(xy 389.70967 -229.610305) (xy 389.757889 -229.600461) (xy 389.807064 -229.59848) (xy 389.855919 -229.604412)
			(xy 389.90319 -229.618104) (xy 389.947652 -229.639202) (xy 389.988155 -229.667158) (xy 390.023648 -229.70125)
			(xy 390.053213 -229.740594) (xy 390.076084 -229.784171) (xy 390.091668 -229.830852) (xy 390.099563 -229.879429)
			(xy 390.100058 -229.904036) (xy 390.418569 -229.904036) (xy 390.422664 -229.853308) (xy 390.434843 -229.803894)
			(xy 390.454791 -229.757074) (xy 390.481992 -229.71406) (xy 390.51574 -229.675966) (xy 390.555162 -229.643779)
			(xy 390.599236 -229.618333) (xy 390.646822 -229.600286) (xy 390.696686 -229.590106) (xy 390.747538 -229.588057)
			(xy 390.798059 -229.594191) (xy 390.846943 -229.608351) (xy 390.892922 -229.630168) (xy 390.934806 -229.659078)
			(xy 390.97151 -229.694333) (xy 391.002083 -229.735019) (xy 391.025734 -229.780082) (xy 391.04185 -229.828356)
			(xy 391.050014 -229.87859) (xy 391.050526 -229.904036) (xy 391.050014 -229.929482) (xy 391.04185 -229.979716)
			(xy 391.025734 -230.02799) (xy 391.002083 -230.073053) (xy 390.97151 -230.113739) (xy 390.934806 -230.148994)
			(xy 390.904411 -230.169974) (xy 394.377176 -230.169974) (xy 394.381136 -230.12092) (xy 394.392913 -230.073136)
			(xy 394.412204 -230.02786) (xy 394.438507 -229.986264) (xy 394.471142 -229.949427) (xy 394.509263 -229.918302)
			(xy 394.551884 -229.893695) (xy 394.5979 -229.876243) (xy 394.646119 -229.866399) (xy 394.695294 -229.864418)
			(xy 394.744149 -229.87035) (xy 394.79142 -229.884042) (xy 394.835882 -229.90514) (xy 394.876385 -229.933096)
			(xy 394.911878 -229.967188) (xy 394.941443 -230.006532) (xy 394.964314 -230.050109) (xy 394.979898 -230.09679)
			(xy 394.987793 -230.145367) (xy 394.988288 -230.169974) (xy 394.987793 -230.194581) (xy 394.979898 -230.243158)
			(xy 394.964314 -230.289839) (xy 394.941443 -230.333416) (xy 394.911878 -230.37276) (xy 394.876385 -230.406852)
			(xy 394.835882 -230.434808) (xy 394.79142 -230.455906) (xy 394.744149 -230.469598) (xy 394.695294 -230.47553)
			(xy 394.646119 -230.473549) (xy 394.5979 -230.463705) (xy 394.551884 -230.446253) (xy 394.509263 -230.421646)
			(xy 394.471142 -230.390521) (xy 394.438507 -230.353684) (xy 394.412204 -230.312088) (xy 394.392913 -230.266812)
			(xy 394.381136 -230.219028) (xy 394.377176 -230.169974) (xy 390.904411 -230.169974) (xy 390.892922 -230.177904)
			(xy 390.846943 -230.199721) (xy 390.798059 -230.213881) (xy 390.747538 -230.220015) (xy 390.696686 -230.217966)
			(xy 390.646822 -230.207786) (xy 390.599236 -230.189739) (xy 390.555162 -230.164293) (xy 390.51574 -230.132106)
			(xy 390.481992 -230.094012) (xy 390.454791 -230.050998) (xy 390.434843 -230.004178) (xy 390.422664 -229.954764)
			(xy 390.418569 -229.904036) (xy 390.100058 -229.904036) (xy 390.099563 -229.928643) (xy 390.091668 -229.97722)
			(xy 390.076084 -230.023901) (xy 390.053213 -230.067478) (xy 390.023648 -230.106822) (xy 389.988155 -230.140914)
			(xy 389.947652 -230.16887) (xy 389.90319 -230.189968) (xy 389.855919 -230.20366) (xy 389.807064 -230.209592)
			(xy 389.757889 -230.207611) (xy 389.70967 -230.197767) (xy 389.663654 -230.180315) (xy 389.621033 -230.155708)
			(xy 389.582912 -230.124583) (xy 389.550277 -230.087746) (xy 389.523974 -230.04615) (xy 389.504683 -230.000874)
			(xy 389.492906 -229.95309) (xy 389.488946 -229.904036) (xy 389.170672 -229.904036) (xy 389.17016 -229.929482)
			(xy 389.161996 -229.979716) (xy 389.14588 -230.02799) (xy 389.122229 -230.073053) (xy 389.091656 -230.113739)
			(xy 389.054952 -230.148994) (xy 389.013068 -230.177904) (xy 388.967089 -230.199721) (xy 388.918205 -230.213881)
			(xy 388.867684 -230.220015) (xy 388.816832 -230.217966) (xy 388.766968 -230.207786) (xy 388.719382 -230.189739)
			(xy 388.675308 -230.164293) (xy 388.635886 -230.132106) (xy 388.602138 -230.094012) (xy 388.574937 -230.050998)
			(xy 388.554989 -230.004178) (xy 388.54281 -229.954764) (xy 388.538715 -229.904036) (xy 388.220204 -229.904036)
			(xy 388.219709 -229.928643) (xy 388.211814 -229.97722) (xy 388.19623 -230.023901) (xy 388.173359 -230.067478)
			(xy 388.143794 -230.106822) (xy 388.108301 -230.140914) (xy 388.067798 -230.16887) (xy 388.023336 -230.189968)
			(xy 387.976065 -230.20366) (xy 387.92721 -230.209592) (xy 387.878035 -230.207611) (xy 387.829816 -230.197767)
			(xy 387.7838 -230.180315) (xy 387.741179 -230.155708) (xy 387.703058 -230.124583) (xy 387.670423 -230.087746)
			(xy 387.64412 -230.04615) (xy 387.624829 -230.000874) (xy 387.613052 -229.95309) (xy 387.609092 -229.904036)
			(xy 387.290564 -229.904036) (xy 387.290052 -229.929482) (xy 387.281888 -229.979716) (xy 387.265772 -230.02799)
			(xy 387.242121 -230.073053) (xy 387.211548 -230.113739) (xy 387.174844 -230.148994) (xy 387.13296 -230.177904)
			(xy 387.086981 -230.199721) (xy 387.038097 -230.213881) (xy 386.987576 -230.220015) (xy 386.936724 -230.217966)
			(xy 386.88686 -230.207786) (xy 386.839274 -230.189739) (xy 386.7952 -230.164293) (xy 386.755778 -230.132106)
			(xy 386.72203 -230.094012) (xy 386.694829 -230.050998) (xy 386.674881 -230.004178) (xy 386.662702 -229.954764)
			(xy 386.658607 -229.904036) (xy 386.35051 -229.904036) (xy 386.349998 -229.929482) (xy 386.341834 -229.979716)
			(xy 386.325718 -230.02799) (xy 386.302067 -230.073053) (xy 386.271494 -230.113739) (xy 386.23479 -230.148994)
			(xy 386.192906 -230.177904) (xy 386.146927 -230.199721) (xy 386.098043 -230.213881) (xy 386.047522 -230.220015)
			(xy 385.99667 -230.217966) (xy 385.946806 -230.207786) (xy 385.89922 -230.189739) (xy 385.855146 -230.164293)
			(xy 385.815724 -230.132106) (xy 385.781976 -230.094012) (xy 385.754775 -230.050998) (xy 385.734827 -230.004178)
			(xy 385.722648 -229.954764) (xy 385.718553 -229.904036) (xy 384.470656 -229.904036) (xy 384.470144 -229.929482)
			(xy 384.46198 -229.979716) (xy 384.445864 -230.02799) (xy 384.422213 -230.073053) (xy 384.39164 -230.113739)
			(xy 384.354936 -230.148994) (xy 384.313052 -230.177904) (xy 384.267073 -230.199721) (xy 384.218189 -230.213881)
			(xy 384.167668 -230.220015) (xy 384.116816 -230.217966) (xy 384.066952 -230.207786) (xy 384.019366 -230.189739)
			(xy 383.975292 -230.164293) (xy 383.93587 -230.132106) (xy 383.902122 -230.094012) (xy 383.874921 -230.050998)
			(xy 383.854973 -230.004178) (xy 383.842794 -229.954764) (xy 383.838699 -229.904036) (xy 383.520188 -229.904036)
			(xy 383.519693 -229.928643) (xy 383.511798 -229.97722) (xy 383.496214 -230.023901) (xy 383.473343 -230.067478)
			(xy 383.443778 -230.106822) (xy 383.408285 -230.140914) (xy 383.367782 -230.16887) (xy 383.32332 -230.189968)
			(xy 383.276049 -230.20366) (xy 383.227194 -230.209592) (xy 383.178019 -230.207611) (xy 383.1298 -230.197767)
			(xy 383.083784 -230.180315) (xy 383.041163 -230.155708) (xy 383.003042 -230.124583) (xy 382.970407 -230.087746)
			(xy 382.944104 -230.04615) (xy 382.924813 -230.000874) (xy 382.913036 -229.95309) (xy 382.909076 -229.904036)
			(xy 382.590548 -229.904036) (xy 382.590036 -229.929482) (xy 382.581872 -229.979716) (xy 382.565756 -230.02799)
			(xy 382.542105 -230.073053) (xy 382.511532 -230.113739) (xy 382.474828 -230.148994) (xy 382.432944 -230.177904)
			(xy 382.386965 -230.199721) (xy 382.338081 -230.213881) (xy 382.28756 -230.220015) (xy 382.236708 -230.217966)
			(xy 382.186844 -230.207786) (xy 382.139258 -230.189739) (xy 382.095184 -230.164293) (xy 382.055762 -230.132106)
			(xy 382.022014 -230.094012) (xy 381.994813 -230.050998) (xy 381.974865 -230.004178) (xy 381.962686 -229.954764)
			(xy 381.958591 -229.904036) (xy 381.64008 -229.904036) (xy 381.639585 -229.928643) (xy 381.63169 -229.97722)
			(xy 381.616106 -230.023901) (xy 381.593235 -230.067478) (xy 381.56367 -230.106822) (xy 381.528177 -230.140914)
			(xy 381.487674 -230.16887) (xy 381.443212 -230.189968) (xy 381.395941 -230.20366) (xy 381.347086 -230.209592)
			(xy 381.297911 -230.207611) (xy 381.249692 -230.197767) (xy 381.203676 -230.180315) (xy 381.161055 -230.155708)
			(xy 381.122934 -230.124583) (xy 381.090299 -230.087746) (xy 381.063996 -230.04615) (xy 381.044705 -230.000874)
			(xy 381.032928 -229.95309) (xy 381.028968 -229.904036) (xy 380.71044 -229.904036) (xy 380.709928 -229.929482)
			(xy 380.701764 -229.979716) (xy 380.685648 -230.02799) (xy 380.661997 -230.073053) (xy 380.631424 -230.113739)
			(xy 380.59472 -230.148994) (xy 380.552836 -230.177904) (xy 380.506857 -230.199721) (xy 380.457973 -230.213881)
			(xy 380.407452 -230.220015) (xy 380.3566 -230.217966) (xy 380.306736 -230.207786) (xy 380.25915 -230.189739)
			(xy 380.215076 -230.164293) (xy 380.175654 -230.132106) (xy 380.141906 -230.094012) (xy 380.114705 -230.050998)
			(xy 380.094757 -230.004178) (xy 380.082578 -229.954764) (xy 380.078483 -229.904036) (xy 379.77064 -229.904036)
			(xy 379.770128 -229.929482) (xy 379.761964 -229.979716) (xy 379.745848 -230.02799) (xy 379.722197 -230.073053)
			(xy 379.691624 -230.113739) (xy 379.65492 -230.148994) (xy 379.613036 -230.177904) (xy 379.567057 -230.199721)
			(xy 379.518173 -230.213881) (xy 379.467652 -230.220015) (xy 379.4168 -230.217966) (xy 379.366936 -230.207786)
			(xy 379.31935 -230.189739) (xy 379.275276 -230.164293) (xy 379.235854 -230.132106) (xy 379.202106 -230.094012)
			(xy 379.174905 -230.050998) (xy 379.154957 -230.004178) (xy 379.142778 -229.954764) (xy 379.138683 -229.904036)
			(xy 377.890532 -229.904036) (xy 377.89002 -229.929482) (xy 377.881856 -229.979716) (xy 377.86574 -230.02799)
			(xy 377.842089 -230.073053) (xy 377.811516 -230.113739) (xy 377.774812 -230.148994) (xy 377.732928 -230.177904)
			(xy 377.686949 -230.199721) (xy 377.638065 -230.213881) (xy 377.587544 -230.220015) (xy 377.536692 -230.217966)
			(xy 377.486828 -230.207786) (xy 377.439242 -230.189739) (xy 377.395168 -230.164293) (xy 377.355746 -230.132106)
			(xy 377.321998 -230.094012) (xy 377.294797 -230.050998) (xy 377.274849 -230.004178) (xy 377.26267 -229.954764)
			(xy 377.258575 -229.904036) (xy 376.940064 -229.904036) (xy 376.939569 -229.928643) (xy 376.931674 -229.97722)
			(xy 376.91609 -230.023901) (xy 376.893219 -230.067478) (xy 376.863654 -230.106822) (xy 376.828161 -230.140914)
			(xy 376.787658 -230.16887) (xy 376.743196 -230.189968) (xy 376.695925 -230.20366) (xy 376.64707 -230.209592)
			(xy 376.597895 -230.207611) (xy 376.549676 -230.197767) (xy 376.50366 -230.180315) (xy 376.461039 -230.155708)
			(xy 376.422918 -230.124583) (xy 376.390283 -230.087746) (xy 376.36398 -230.04615) (xy 376.344689 -230.000874)
			(xy 376.332912 -229.95309) (xy 376.328952 -229.904036) (xy 376.010424 -229.904036) (xy 376.009912 -229.929482)
			(xy 376.001748 -229.979716) (xy 375.985632 -230.02799) (xy 375.961981 -230.073053) (xy 375.931408 -230.113739)
			(xy 375.894704 -230.148994) (xy 375.85282 -230.177904) (xy 375.806841 -230.199721) (xy 375.757957 -230.213881)
			(xy 375.707436 -230.220015) (xy 375.656584 -230.217966) (xy 375.60672 -230.207786) (xy 375.559134 -230.189739)
			(xy 375.51506 -230.164293) (xy 375.475638 -230.132106) (xy 375.44189 -230.094012) (xy 375.414689 -230.050998)
			(xy 375.394741 -230.004178) (xy 375.382562 -229.954764) (xy 375.378467 -229.904036) (xy 375.05967 -229.904036)
			(xy 375.059668 -229.928311) (xy 375.051981 -229.976264) (xy 375.036805 -230.022396) (xy 375.014523 -230.065547)
			(xy 375.00052 -230.085392) (xy 374.995948 -230.091742) (xy 374.988074 -230.114602) (xy 374.986792 -230.11861)
			(xy 374.985392 -230.126906) (xy 374.98528 -230.131112) (xy 374.98528 -230.331518) (xy 374.98528 -230.33482)
			(xy 374.986466 -230.345568) (xy 374.996598 -230.364648) (xy 375.004838 -230.37165) (xy 375.00687 -230.373174)
			(xy 375.074688 -230.420926) (xy 375.085077 -230.4275) (xy 375.10943 -230.430679) (xy 375.12117 -230.427022)
			(xy 375.121932 -230.426768) (xy 375.12879 -230.424482) (xy 375.152133 -230.417257) (xy 375.200371 -230.409478)
			(xy 375.224802 -230.408988) (xy 375.250058 -230.40951) (xy 375.29988 -230.417824) (xy 375.347654 -230.434225)
			(xy 375.392077 -230.458266) (xy 375.431937 -230.489291) (xy 375.466147 -230.526453) (xy 375.493774 -230.568739)
			(xy 375.514064 -230.614996) (xy 375.526464 -230.663961) (xy 375.530635 -230.714296) (xy 375.848621 -230.714296)
			(xy 375.852716 -230.663568) (xy 375.864895 -230.614154) (xy 375.884843 -230.567334) (xy 375.912044 -230.52432)
			(xy 375.945792 -230.486226) (xy 375.985214 -230.454039) (xy 376.029288 -230.428593) (xy 376.076874 -230.410546)
			(xy 376.126738 -230.400366) (xy 376.17759 -230.398317) (xy 376.228111 -230.404451) (xy 376.276995 -230.418611)
			(xy 376.322974 -230.440428) (xy 376.364858 -230.469338) (xy 376.401562 -230.504593) (xy 376.432135 -230.545279)
			(xy 376.455786 -230.590342) (xy 376.471902 -230.638616) (xy 376.480066 -230.68885) (xy 376.480578 -230.714296)
			(xy 376.788675 -230.714296) (xy 376.79277 -230.663568) (xy 376.804949 -230.614154) (xy 376.824897 -230.567334)
			(xy 376.852098 -230.52432) (xy 376.885846 -230.486226) (xy 376.925268 -230.454039) (xy 376.969342 -230.428593)
			(xy 377.016928 -230.410546) (xy 377.066792 -230.400366) (xy 377.117644 -230.398317) (xy 377.168165 -230.404451)
			(xy 377.217049 -230.418611) (xy 377.263028 -230.440428) (xy 377.304912 -230.469338) (xy 377.341616 -230.504593)
			(xy 377.372189 -230.545279) (xy 377.39584 -230.590342) (xy 377.411956 -230.638616) (xy 377.42012 -230.68885)
			(xy 377.420632 -230.714296) (xy 377.738906 -230.714296) (xy 377.742866 -230.665242) (xy 377.754643 -230.617458)
			(xy 377.773934 -230.572182) (xy 377.800237 -230.530586) (xy 377.832872 -230.493749) (xy 377.870993 -230.462624)
			(xy 377.913614 -230.438017) (xy 377.95963 -230.420565) (xy 378.007849 -230.410721) (xy 378.057024 -230.40874)
			(xy 378.105879 -230.414672) (xy 378.15315 -230.428364) (xy 378.197612 -230.449462) (xy 378.238115 -230.477418)
			(xy 378.273608 -230.51151) (xy 378.303173 -230.550854) (xy 378.326044 -230.594431) (xy 378.341628 -230.641112)
			(xy 378.349523 -230.689689) (xy 378.350018 -230.714296) (xy 378.668529 -230.714296) (xy 378.672624 -230.663568)
			(xy 378.684803 -230.614154) (xy 378.704751 -230.567334) (xy 378.731952 -230.52432) (xy 378.7657 -230.486226)
			(xy 378.805122 -230.454039) (xy 378.849196 -230.428593) (xy 378.896782 -230.410546) (xy 378.946646 -230.400366)
			(xy 378.997498 -230.398317) (xy 379.048019 -230.404451) (xy 379.096903 -230.418611) (xy 379.142882 -230.440428)
			(xy 379.184766 -230.469338) (xy 379.22147 -230.504593) (xy 379.252043 -230.545279) (xy 379.275694 -230.590342)
			(xy 379.29181 -230.638616) (xy 379.299974 -230.68885) (xy 379.300486 -230.714296) (xy 379.619014 -230.714296)
			(xy 379.622974 -230.665242) (xy 379.634751 -230.617458) (xy 379.654042 -230.572182) (xy 379.680345 -230.530586)
			(xy 379.71298 -230.493749) (xy 379.751101 -230.462624) (xy 379.793722 -230.438017) (xy 379.839738 -230.420565)
			(xy 379.887957 -230.410721) (xy 379.937132 -230.40874) (xy 379.985987 -230.414672) (xy 380.033258 -230.428364)
			(xy 380.07772 -230.449462) (xy 380.118223 -230.477418) (xy 380.153716 -230.51151) (xy 380.183281 -230.550854)
			(xy 380.206152 -230.594431) (xy 380.221736 -230.641112) (xy 380.229631 -230.689689) (xy 380.230126 -230.714296)
			(xy 380.548637 -230.714296) (xy 380.552732 -230.663568) (xy 380.564911 -230.614154) (xy 380.584859 -230.567334)
			(xy 380.61206 -230.52432) (xy 380.645808 -230.486226) (xy 380.68523 -230.454039) (xy 380.729304 -230.428593)
			(xy 380.77689 -230.410546) (xy 380.826754 -230.400366) (xy 380.877606 -230.398317) (xy 380.928127 -230.404451)
			(xy 380.977011 -230.418611) (xy 381.02299 -230.440428) (xy 381.064874 -230.469338) (xy 381.101578 -230.504593)
			(xy 381.132151 -230.545279) (xy 381.155802 -230.590342) (xy 381.171918 -230.638616) (xy 381.180082 -230.68885)
			(xy 381.180589 -230.714042) (xy 381.499122 -230.714042) (xy 381.503082 -230.664988) (xy 381.514859 -230.617204)
			(xy 381.53415 -230.571928) (xy 381.560453 -230.530332) (xy 381.593088 -230.493495) (xy 381.631209 -230.46237)
			(xy 381.67383 -230.437763) (xy 381.719846 -230.420311) (xy 381.768065 -230.410467) (xy 381.81724 -230.408486)
			(xy 381.866095 -230.414418) (xy 381.913366 -230.42811) (xy 381.957828 -230.449208) (xy 381.998331 -230.477164)
			(xy 382.033824 -230.511256) (xy 382.063389 -230.5506) (xy 382.08626 -230.594177) (xy 382.101844 -230.640858)
			(xy 382.109739 -230.689435) (xy 382.110234 -230.714042) (xy 382.110229 -230.714296) (xy 382.428491 -230.714296)
			(xy 382.432586 -230.663568) (xy 382.444765 -230.614154) (xy 382.464713 -230.567334) (xy 382.491914 -230.52432)
			(xy 382.525662 -230.486226) (xy 382.565084 -230.454039) (xy 382.609158 -230.428593) (xy 382.656744 -230.410546)
			(xy 382.706608 -230.400366) (xy 382.75746 -230.398317) (xy 382.807981 -230.404451) (xy 382.856865 -230.418611)
			(xy 382.902844 -230.440428) (xy 382.944728 -230.469338) (xy 382.981432 -230.504593) (xy 383.012005 -230.545279)
			(xy 383.035656 -230.590342) (xy 383.051772 -230.638616) (xy 383.059936 -230.68885) (xy 383.060448 -230.714296)
			(xy 383.368545 -230.714296) (xy 383.37264 -230.663568) (xy 383.384819 -230.614154) (xy 383.404767 -230.567334)
			(xy 383.431968 -230.52432) (xy 383.465716 -230.486226) (xy 383.505138 -230.454039) (xy 383.549212 -230.428593)
			(xy 383.596798 -230.410546) (xy 383.646662 -230.400366) (xy 383.697514 -230.398317) (xy 383.748035 -230.404451)
			(xy 383.796919 -230.418611) (xy 383.842898 -230.440428) (xy 383.884782 -230.469338) (xy 383.921486 -230.504593)
			(xy 383.952059 -230.545279) (xy 383.97571 -230.590342) (xy 383.991826 -230.638616) (xy 383.99999 -230.68885)
			(xy 384.000502 -230.714296) (xy 384.31903 -230.714296) (xy 384.32299 -230.665242) (xy 384.334767 -230.617458)
			(xy 384.354058 -230.572182) (xy 384.380361 -230.530586) (xy 384.412996 -230.493749) (xy 384.451117 -230.462624)
			(xy 384.493738 -230.438017) (xy 384.539754 -230.420565) (xy 384.587973 -230.410721) (xy 384.637148 -230.40874)
			(xy 384.686003 -230.414672) (xy 384.733274 -230.428364) (xy 384.777736 -230.449462) (xy 384.818239 -230.477418)
			(xy 384.853732 -230.51151) (xy 384.883297 -230.550854) (xy 384.906168 -230.594431) (xy 384.921752 -230.641112)
			(xy 384.929647 -230.689689) (xy 384.930142 -230.714296) (xy 385.248653 -230.714296) (xy 385.252748 -230.663568)
			(xy 385.264927 -230.614154) (xy 385.284875 -230.567334) (xy 385.312076 -230.52432) (xy 385.345824 -230.486226)
			(xy 385.385246 -230.454039) (xy 385.42932 -230.428593) (xy 385.476906 -230.410546) (xy 385.52677 -230.400366)
			(xy 385.577622 -230.398317) (xy 385.628143 -230.404451) (xy 385.677027 -230.418611) (xy 385.723006 -230.440428)
			(xy 385.76489 -230.469338) (xy 385.801594 -230.504593) (xy 385.832167 -230.545279) (xy 385.855818 -230.590342)
			(xy 385.871934 -230.638616) (xy 385.880098 -230.68885) (xy 385.880605 -230.714042) (xy 386.199138 -230.714042)
			(xy 386.203098 -230.664988) (xy 386.214875 -230.617204) (xy 386.234166 -230.571928) (xy 386.260469 -230.530332)
			(xy 386.293104 -230.493495) (xy 386.331225 -230.46237) (xy 386.373846 -230.437763) (xy 386.419862 -230.420311)
			(xy 386.468081 -230.410467) (xy 386.517256 -230.408486) (xy 386.566111 -230.414418) (xy 386.613382 -230.42811)
			(xy 386.657844 -230.449208) (xy 386.698347 -230.477164) (xy 386.73384 -230.511256) (xy 386.763405 -230.5506)
			(xy 386.786276 -230.594177) (xy 386.80186 -230.640858) (xy 386.809755 -230.689435) (xy 386.81025 -230.714042)
			(xy 386.810245 -230.714296) (xy 387.128507 -230.714296) (xy 387.132602 -230.663568) (xy 387.144781 -230.614154)
			(xy 387.164729 -230.567334) (xy 387.19193 -230.52432) (xy 387.225678 -230.486226) (xy 387.2651 -230.454039)
			(xy 387.309174 -230.428593) (xy 387.35676 -230.410546) (xy 387.406624 -230.400366) (xy 387.457476 -230.398317)
			(xy 387.507997 -230.404451) (xy 387.556881 -230.418611) (xy 387.60286 -230.440428) (xy 387.644744 -230.469338)
			(xy 387.681448 -230.504593) (xy 387.712021 -230.545279) (xy 387.735672 -230.590342) (xy 387.751788 -230.638616)
			(xy 387.759952 -230.68885) (xy 387.760464 -230.714296) (xy 388.078992 -230.714296) (xy 388.082952 -230.665242)
			(xy 388.094729 -230.617458) (xy 388.11402 -230.572182) (xy 388.140323 -230.530586) (xy 388.172958 -230.493749)
			(xy 388.211079 -230.462624) (xy 388.2537 -230.438017) (xy 388.299716 -230.420565) (xy 388.347935 -230.410721)
			(xy 388.39711 -230.40874) (xy 388.445965 -230.414672) (xy 388.493236 -230.428364) (xy 388.537698 -230.449462)
			(xy 388.578201 -230.477418) (xy 388.613694 -230.51151) (xy 388.643259 -230.550854) (xy 388.66613 -230.594431)
			(xy 388.681714 -230.641112) (xy 388.689609 -230.689689) (xy 388.690104 -230.714296) (xy 389.008615 -230.714296)
			(xy 389.01271 -230.663568) (xy 389.024889 -230.614154) (xy 389.044837 -230.567334) (xy 389.072038 -230.52432)
			(xy 389.105786 -230.486226) (xy 389.145208 -230.454039) (xy 389.189282 -230.428593) (xy 389.236868 -230.410546)
			(xy 389.286732 -230.400366) (xy 389.337584 -230.398317) (xy 389.388105 -230.404451) (xy 389.436989 -230.418611)
			(xy 389.482968 -230.440428) (xy 389.524852 -230.469338) (xy 389.561556 -230.504593) (xy 389.592129 -230.545279)
			(xy 389.61578 -230.590342) (xy 389.631896 -230.638616) (xy 389.64006 -230.68885) (xy 389.640572 -230.714296)
			(xy 389.948669 -230.714296) (xy 389.952764 -230.663568) (xy 389.964943 -230.614154) (xy 389.984891 -230.567334)
			(xy 390.012092 -230.52432) (xy 390.04584 -230.486226) (xy 390.085262 -230.454039) (xy 390.129336 -230.428593)
			(xy 390.176922 -230.410546) (xy 390.226786 -230.400366) (xy 390.277638 -230.398317) (xy 390.328159 -230.404451)
			(xy 390.377043 -230.418611) (xy 390.423022 -230.440428) (xy 390.464906 -230.469338) (xy 390.50161 -230.504593)
			(xy 390.532183 -230.545279) (xy 390.555834 -230.590342) (xy 390.57195 -230.638616) (xy 390.580114 -230.68885)
			(xy 390.580626 -230.714296) (xy 390.8989 -230.714296) (xy 390.90286 -230.665242) (xy 390.914637 -230.617458)
			(xy 390.933928 -230.572182) (xy 390.960231 -230.530586) (xy 390.992866 -230.493749) (xy 391.030987 -230.462624)
			(xy 391.073608 -230.438017) (xy 391.119624 -230.420565) (xy 391.167843 -230.410721) (xy 391.217018 -230.40874)
			(xy 391.265873 -230.414672) (xy 391.313144 -230.428364) (xy 391.357606 -230.449462) (xy 391.398109 -230.477418)
			(xy 391.433602 -230.51151) (xy 391.463167 -230.550854) (xy 391.486038 -230.594431) (xy 391.501622 -230.641112)
			(xy 391.509517 -230.689689) (xy 391.510012 -230.714296) (xy 392.779008 -230.714296) (xy 392.782968 -230.665242)
			(xy 392.794745 -230.617458) (xy 392.814036 -230.572182) (xy 392.840339 -230.530586) (xy 392.872974 -230.493749)
			(xy 392.911095 -230.462624) (xy 392.953716 -230.438017) (xy 392.999732 -230.420565) (xy 393.047951 -230.410721)
			(xy 393.097126 -230.40874) (xy 393.145981 -230.414672) (xy 393.193252 -230.428364) (xy 393.237714 -230.449462)
			(xy 393.278217 -230.477418) (xy 393.31371 -230.51151) (xy 393.343275 -230.550854) (xy 393.366146 -230.594431)
			(xy 393.38173 -230.641112) (xy 393.389625 -230.689689) (xy 393.39012 -230.714296) (xy 393.389625 -230.738903)
			(xy 393.38173 -230.78748) (xy 393.366146 -230.834161) (xy 393.343275 -230.877738) (xy 393.31371 -230.917082)
			(xy 393.278217 -230.951174) (xy 393.237714 -230.97913) (xy 393.193252 -231.000228) (xy 393.145981 -231.01392)
			(xy 393.097126 -231.019852) (xy 393.047951 -231.017871) (xy 392.999732 -231.008027) (xy 392.953716 -230.990575)
			(xy 392.911095 -230.965968) (xy 392.872974 -230.934843) (xy 392.840339 -230.898006) (xy 392.814036 -230.85641)
			(xy 392.794745 -230.811134) (xy 392.782968 -230.76335) (xy 392.779008 -230.714296) (xy 391.510012 -230.714296)
			(xy 391.509517 -230.738903) (xy 391.501622 -230.78748) (xy 391.486038 -230.834161) (xy 391.463167 -230.877738)
			(xy 391.433602 -230.917082) (xy 391.398109 -230.951174) (xy 391.357606 -230.97913) (xy 391.313144 -231.000228)
			(xy 391.265873 -231.01392) (xy 391.217018 -231.019852) (xy 391.167843 -231.017871) (xy 391.119624 -231.008027)
			(xy 391.073608 -230.990575) (xy 391.030987 -230.965968) (xy 390.992866 -230.934843) (xy 390.960231 -230.898006)
			(xy 390.933928 -230.85641) (xy 390.914637 -230.811134) (xy 390.90286 -230.76335) (xy 390.8989 -230.714296)
			(xy 390.580626 -230.714296) (xy 390.580114 -230.739742) (xy 390.57195 -230.789976) (xy 390.555834 -230.83825)
			(xy 390.532183 -230.883313) (xy 390.50161 -230.923999) (xy 390.464906 -230.959254) (xy 390.423022 -230.988164)
			(xy 390.377043 -231.009981) (xy 390.328159 -231.024141) (xy 390.277638 -231.030275) (xy 390.226786 -231.028226)
			(xy 390.176922 -231.018046) (xy 390.129336 -230.999999) (xy 390.085262 -230.974553) (xy 390.04584 -230.942366)
			(xy 390.012092 -230.904272) (xy 389.984891 -230.861258) (xy 389.964943 -230.814438) (xy 389.952764 -230.765024)
			(xy 389.948669 -230.714296) (xy 389.640572 -230.714296) (xy 389.64006 -230.739742) (xy 389.631896 -230.789976)
			(xy 389.61578 -230.83825) (xy 389.592129 -230.883313) (xy 389.561556 -230.923999) (xy 389.524852 -230.959254)
			(xy 389.482968 -230.988164) (xy 389.436989 -231.009981) (xy 389.388105 -231.024141) (xy 389.337584 -231.030275)
			(xy 389.286732 -231.028226) (xy 389.236868 -231.018046) (xy 389.189282 -230.999999) (xy 389.145208 -230.974553)
			(xy 389.105786 -230.942366) (xy 389.072038 -230.904272) (xy 389.044837 -230.861258) (xy 389.024889 -230.814438)
			(xy 389.01271 -230.765024) (xy 389.008615 -230.714296) (xy 388.690104 -230.714296) (xy 388.689609 -230.738903)
			(xy 388.681714 -230.78748) (xy 388.66613 -230.834161) (xy 388.643259 -230.877738) (xy 388.613694 -230.917082)
			(xy 388.578201 -230.951174) (xy 388.537698 -230.97913) (xy 388.493236 -231.000228) (xy 388.445965 -231.01392)
			(xy 388.39711 -231.019852) (xy 388.347935 -231.017871) (xy 388.299716 -231.008027) (xy 388.2537 -230.990575)
			(xy 388.211079 -230.965968) (xy 388.172958 -230.934843) (xy 388.140323 -230.898006) (xy 388.11402 -230.85641)
			(xy 388.094729 -230.811134) (xy 388.082952 -230.76335) (xy 388.078992 -230.714296) (xy 387.760464 -230.714296)
			(xy 387.759952 -230.739742) (xy 387.751788 -230.789976) (xy 387.735672 -230.83825) (xy 387.712021 -230.883313)
			(xy 387.681448 -230.923999) (xy 387.644744 -230.959254) (xy 387.60286 -230.988164) (xy 387.556881 -231.009981)
			(xy 387.507997 -231.024141) (xy 387.457476 -231.030275) (xy 387.406624 -231.028226) (xy 387.35676 -231.018046)
			(xy 387.309174 -230.999999) (xy 387.2651 -230.974553) (xy 387.225678 -230.942366) (xy 387.19193 -230.904272)
			(xy 387.164729 -230.861258) (xy 387.144781 -230.814438) (xy 387.132602 -230.765024) (xy 387.128507 -230.714296)
			(xy 386.810245 -230.714296) (xy 386.809755 -230.738649) (xy 386.80186 -230.787226) (xy 386.786276 -230.833907)
			(xy 386.763405 -230.877484) (xy 386.73384 -230.916828) (xy 386.698347 -230.95092) (xy 386.657844 -230.978876)
			(xy 386.613382 -230.999974) (xy 386.566111 -231.013666) (xy 386.517256 -231.019598) (xy 386.468081 -231.017617)
			(xy 386.419862 -231.007773) (xy 386.373846 -230.990321) (xy 386.331225 -230.965714) (xy 386.293104 -230.934589)
			(xy 386.260469 -230.897752) (xy 386.234166 -230.856156) (xy 386.214875 -230.81088) (xy 386.203098 -230.763096)
			(xy 386.199138 -230.714042) (xy 385.880605 -230.714042) (xy 385.88061 -230.714296) (xy 385.880098 -230.739742)
			(xy 385.871934 -230.789976) (xy 385.855818 -230.83825) (xy 385.832167 -230.883313) (xy 385.801594 -230.923999)
			(xy 385.76489 -230.959254) (xy 385.723006 -230.988164) (xy 385.677027 -231.009981) (xy 385.628143 -231.024141)
			(xy 385.577622 -231.030275) (xy 385.52677 -231.028226) (xy 385.476906 -231.018046) (xy 385.42932 -230.999999)
			(xy 385.385246 -230.974553) (xy 385.345824 -230.942366) (xy 385.312076 -230.904272) (xy 385.284875 -230.861258)
			(xy 385.264927 -230.814438) (xy 385.252748 -230.765024) (xy 385.248653 -230.714296) (xy 384.930142 -230.714296)
			(xy 384.929647 -230.738903) (xy 384.921752 -230.78748) (xy 384.906168 -230.834161) (xy 384.883297 -230.877738)
			(xy 384.853732 -230.917082) (xy 384.818239 -230.951174) (xy 384.777736 -230.97913) (xy 384.733274 -231.000228)
			(xy 384.686003 -231.01392) (xy 384.637148 -231.019852) (xy 384.587973 -231.017871) (xy 384.539754 -231.008027)
			(xy 384.493738 -230.990575) (xy 384.451117 -230.965968) (xy 384.412996 -230.934843) (xy 384.380361 -230.898006)
			(xy 384.354058 -230.85641) (xy 384.334767 -230.811134) (xy 384.32299 -230.76335) (xy 384.31903 -230.714296)
			(xy 384.000502 -230.714296) (xy 383.99999 -230.739742) (xy 383.991826 -230.789976) (xy 383.97571 -230.83825)
			(xy 383.952059 -230.883313) (xy 383.921486 -230.923999) (xy 383.884782 -230.959254) (xy 383.842898 -230.988164)
			(xy 383.796919 -231.009981) (xy 383.748035 -231.024141) (xy 383.697514 -231.030275) (xy 383.646662 -231.028226)
			(xy 383.596798 -231.018046) (xy 383.549212 -230.999999) (xy 383.505138 -230.974553) (xy 383.465716 -230.942366)
			(xy 383.431968 -230.904272) (xy 383.404767 -230.861258) (xy 383.384819 -230.814438) (xy 383.37264 -230.765024)
			(xy 383.368545 -230.714296) (xy 383.060448 -230.714296) (xy 383.059936 -230.739742) (xy 383.051772 -230.789976)
			(xy 383.035656 -230.83825) (xy 383.012005 -230.883313) (xy 382.981432 -230.923999) (xy 382.944728 -230.959254)
			(xy 382.902844 -230.988164) (xy 382.856865 -231.009981) (xy 382.807981 -231.024141) (xy 382.75746 -231.030275)
			(xy 382.706608 -231.028226) (xy 382.656744 -231.018046) (xy 382.609158 -230.999999) (xy 382.565084 -230.974553)
			(xy 382.525662 -230.942366) (xy 382.491914 -230.904272) (xy 382.464713 -230.861258) (xy 382.444765 -230.814438)
			(xy 382.432586 -230.765024) (xy 382.428491 -230.714296) (xy 382.110229 -230.714296) (xy 382.109739 -230.738649)
			(xy 382.101844 -230.787226) (xy 382.08626 -230.833907) (xy 382.063389 -230.877484) (xy 382.033824 -230.916828)
			(xy 381.998331 -230.95092) (xy 381.957828 -230.978876) (xy 381.913366 -230.999974) (xy 381.866095 -231.013666)
			(xy 381.81724 -231.019598) (xy 381.768065 -231.017617) (xy 381.719846 -231.007773) (xy 381.67383 -230.990321)
			(xy 381.631209 -230.965714) (xy 381.593088 -230.934589) (xy 381.560453 -230.897752) (xy 381.53415 -230.856156)
			(xy 381.514859 -230.81088) (xy 381.503082 -230.763096) (xy 381.499122 -230.714042) (xy 381.180589 -230.714042)
			(xy 381.180594 -230.714296) (xy 381.180082 -230.739742) (xy 381.171918 -230.789976) (xy 381.155802 -230.83825)
			(xy 381.132151 -230.883313) (xy 381.101578 -230.923999) (xy 381.064874 -230.959254) (xy 381.02299 -230.988164)
			(xy 380.977011 -231.009981) (xy 380.928127 -231.024141) (xy 380.877606 -231.030275) (xy 380.826754 -231.028226)
			(xy 380.77689 -231.018046) (xy 380.729304 -230.999999) (xy 380.68523 -230.974553) (xy 380.645808 -230.942366)
			(xy 380.61206 -230.904272) (xy 380.584859 -230.861258) (xy 380.564911 -230.814438) (xy 380.552732 -230.765024)
			(xy 380.548637 -230.714296) (xy 380.230126 -230.714296) (xy 380.229631 -230.738903) (xy 380.221736 -230.78748)
			(xy 380.206152 -230.834161) (xy 380.183281 -230.877738) (xy 380.153716 -230.917082) (xy 380.118223 -230.951174)
			(xy 380.07772 -230.97913) (xy 380.033258 -231.000228) (xy 379.985987 -231.01392) (xy 379.937132 -231.019852)
			(xy 379.887957 -231.017871) (xy 379.839738 -231.008027) (xy 379.793722 -230.990575) (xy 379.751101 -230.965968)
			(xy 379.71298 -230.934843) (xy 379.680345 -230.898006) (xy 379.654042 -230.85641) (xy 379.634751 -230.811134)
			(xy 379.622974 -230.76335) (xy 379.619014 -230.714296) (xy 379.300486 -230.714296) (xy 379.299974 -230.739742)
			(xy 379.29181 -230.789976) (xy 379.275694 -230.83825) (xy 379.252043 -230.883313) (xy 379.22147 -230.923999)
			(xy 379.184766 -230.959254) (xy 379.142882 -230.988164) (xy 379.096903 -231.009981) (xy 379.048019 -231.024141)
			(xy 378.997498 -231.030275) (xy 378.946646 -231.028226) (xy 378.896782 -231.018046) (xy 378.849196 -230.999999)
			(xy 378.805122 -230.974553) (xy 378.7657 -230.942366) (xy 378.731952 -230.904272) (xy 378.704751 -230.861258)
			(xy 378.684803 -230.814438) (xy 378.672624 -230.765024) (xy 378.668529 -230.714296) (xy 378.350018 -230.714296)
			(xy 378.349523 -230.738903) (xy 378.341628 -230.78748) (xy 378.326044 -230.834161) (xy 378.303173 -230.877738)
			(xy 378.273608 -230.917082) (xy 378.238115 -230.951174) (xy 378.197612 -230.97913) (xy 378.15315 -231.000228)
			(xy 378.105879 -231.01392) (xy 378.057024 -231.019852) (xy 378.007849 -231.017871) (xy 377.95963 -231.008027)
			(xy 377.913614 -230.990575) (xy 377.870993 -230.965968) (xy 377.832872 -230.934843) (xy 377.800237 -230.898006)
			(xy 377.773934 -230.85641) (xy 377.754643 -230.811134) (xy 377.742866 -230.76335) (xy 377.738906 -230.714296)
			(xy 377.420632 -230.714296) (xy 377.42012 -230.739742) (xy 377.411956 -230.789976) (xy 377.39584 -230.83825)
			(xy 377.372189 -230.883313) (xy 377.341616 -230.923999) (xy 377.304912 -230.959254) (xy 377.263028 -230.988164)
			(xy 377.217049 -231.009981) (xy 377.168165 -231.024141) (xy 377.117644 -231.030275) (xy 377.066792 -231.028226)
			(xy 377.016928 -231.018046) (xy 376.969342 -230.999999) (xy 376.925268 -230.974553) (xy 376.885846 -230.942366)
			(xy 376.852098 -230.904272) (xy 376.824897 -230.861258) (xy 376.804949 -230.814438) (xy 376.79277 -230.765024)
			(xy 376.788675 -230.714296) (xy 376.480578 -230.714296) (xy 376.480066 -230.739742) (xy 376.471902 -230.789976)
			(xy 376.455786 -230.83825) (xy 376.432135 -230.883313) (xy 376.401562 -230.923999) (xy 376.364858 -230.959254)
			(xy 376.322974 -230.988164) (xy 376.276995 -231.009981) (xy 376.228111 -231.024141) (xy 376.17759 -231.030275)
			(xy 376.126738 -231.028226) (xy 376.076874 -231.018046) (xy 376.029288 -230.999999) (xy 375.985214 -230.974553)
			(xy 375.945792 -230.942366) (xy 375.912044 -230.904272) (xy 375.884843 -230.861258) (xy 375.864895 -230.814438)
			(xy 375.852716 -230.765024) (xy 375.848621 -230.714296) (xy 375.530635 -230.714296) (xy 375.530635 -230.7143)
			(xy 375.526464 -230.764639) (xy 375.514064 -230.813604) (xy 375.493774 -230.859861) (xy 375.466147 -230.902147)
			(xy 375.431937 -230.939309) (xy 375.392077 -230.970334) (xy 375.347654 -230.994375) (xy 375.29988 -231.010776)
			(xy 375.250058 -231.01909) (xy 375.224802 -231.019604) (xy 375.200371 -231.019123) (xy 375.152133 -231.011335)
			(xy 375.12879 -231.00411) (xy 375.121932 -231.001824) (xy 375.12117 -231.00157) (xy 375.109418 -230.998098)
			(xy 375.085161 -231.001299) (xy 375.074688 -231.007666) (xy 375.00687 -231.055418) (xy 375.004838 -231.056942)
			(xy 374.996616 -231.06396) (xy 374.986473 -231.083029) (xy 374.98528 -231.093772) (xy 374.98528 -231.296972)
			(xy 374.985354 -231.301182) (xy 374.986756 -231.309483) (xy 374.988074 -231.313482) (xy 374.995948 -231.336342)
			(xy 375.00052 -231.342692) (xy 375.014553 -231.362514) (xy 375.036825 -231.405669) (xy 375.05199 -231.451804)
			(xy 375.059666 -231.499757) (xy 375.059663 -231.524048) (xy 375.378467 -231.524048) (xy 375.382562 -231.47332)
			(xy 375.394741 -231.423906) (xy 375.414689 -231.377086) (xy 375.44189 -231.334072) (xy 375.475638 -231.295978)
			(xy 375.51506 -231.263791) (xy 375.559134 -231.238345) (xy 375.60672 -231.220298) (xy 375.656584 -231.210118)
			(xy 375.707436 -231.208069) (xy 375.757957 -231.214203) (xy 375.806841 -231.228363) (xy 375.85282 -231.25018)
			(xy 375.894704 -231.27909) (xy 375.931408 -231.314345) (xy 375.961981 -231.355031) (xy 375.985632 -231.400094)
			(xy 376.001748 -231.448368) (xy 376.009912 -231.498602) (xy 376.010424 -231.524048) (xy 376.328952 -231.524048)
			(xy 376.332912 -231.474994) (xy 376.344689 -231.42721) (xy 376.36398 -231.381934) (xy 376.390283 -231.340338)
			(xy 376.422918 -231.303501) (xy 376.461039 -231.272376) (xy 376.50366 -231.247769) (xy 376.549676 -231.230317)
			(xy 376.597895 -231.220473) (xy 376.64707 -231.218492) (xy 376.695925 -231.224424) (xy 376.743196 -231.238116)
			(xy 376.787658 -231.259214) (xy 376.828161 -231.28717) (xy 376.863654 -231.321262) (xy 376.893219 -231.360606)
			(xy 376.91609 -231.404183) (xy 376.931674 -231.450864) (xy 376.939569 -231.499441) (xy 376.940064 -231.524048)
			(xy 377.258575 -231.524048) (xy 377.26267 -231.47332) (xy 377.274849 -231.423906) (xy 377.294797 -231.377086)
			(xy 377.321998 -231.334072) (xy 377.355746 -231.295978) (xy 377.395168 -231.263791) (xy 377.439242 -231.238345)
			(xy 377.486828 -231.220298) (xy 377.536692 -231.210118) (xy 377.587544 -231.208069) (xy 377.638065 -231.214203)
			(xy 377.686949 -231.228363) (xy 377.732928 -231.25018) (xy 377.774812 -231.27909) (xy 377.811516 -231.314345)
			(xy 377.842089 -231.355031) (xy 377.86574 -231.400094) (xy 377.881856 -231.448368) (xy 377.89002 -231.498602)
			(xy 377.890532 -231.524048) (xy 378.20906 -231.524048) (xy 378.21302 -231.474994) (xy 378.224797 -231.42721)
			(xy 378.244088 -231.381934) (xy 378.270391 -231.340338) (xy 378.303026 -231.303501) (xy 378.341147 -231.272376)
			(xy 378.383768 -231.247769) (xy 378.429784 -231.230317) (xy 378.478003 -231.220473) (xy 378.527178 -231.218492)
			(xy 378.576033 -231.224424) (xy 378.623304 -231.238116) (xy 378.667766 -231.259214) (xy 378.708269 -231.28717)
			(xy 378.743762 -231.321262) (xy 378.773327 -231.360606) (xy 378.796198 -231.404183) (xy 378.811782 -231.450864)
			(xy 378.819677 -231.499441) (xy 378.820172 -231.524048) (xy 379.138683 -231.524048) (xy 379.142778 -231.47332)
			(xy 379.154957 -231.423906) (xy 379.174905 -231.377086) (xy 379.202106 -231.334072) (xy 379.235854 -231.295978)
			(xy 379.275276 -231.263791) (xy 379.31935 -231.238345) (xy 379.366936 -231.220298) (xy 379.4168 -231.210118)
			(xy 379.467652 -231.208069) (xy 379.518173 -231.214203) (xy 379.567057 -231.228363) (xy 379.613036 -231.25018)
			(xy 379.65492 -231.27909) (xy 379.691624 -231.314345) (xy 379.722197 -231.355031) (xy 379.745848 -231.400094)
			(xy 379.761964 -231.448368) (xy 379.770128 -231.498602) (xy 379.77064 -231.524048) (xy 380.078483 -231.524048)
			(xy 380.082578 -231.47332) (xy 380.094757 -231.423906) (xy 380.114705 -231.377086) (xy 380.141906 -231.334072)
			(xy 380.175654 -231.295978) (xy 380.215076 -231.263791) (xy 380.25915 -231.238345) (xy 380.306736 -231.220298)
			(xy 380.3566 -231.210118) (xy 380.407452 -231.208069) (xy 380.457973 -231.214203) (xy 380.506857 -231.228363)
			(xy 380.552836 -231.25018) (xy 380.59472 -231.27909) (xy 380.631424 -231.314345) (xy 380.661997 -231.355031)
			(xy 380.685648 -231.400094) (xy 380.701764 -231.448368) (xy 380.709928 -231.498602) (xy 380.71044 -231.524048)
			(xy 381.028968 -231.524048) (xy 381.032928 -231.474994) (xy 381.044705 -231.42721) (xy 381.063996 -231.381934)
			(xy 381.090299 -231.340338) (xy 381.122934 -231.303501) (xy 381.161055 -231.272376) (xy 381.203676 -231.247769)
			(xy 381.249692 -231.230317) (xy 381.297911 -231.220473) (xy 381.347086 -231.218492) (xy 381.395941 -231.224424)
			(xy 381.443212 -231.238116) (xy 381.487674 -231.259214) (xy 381.528177 -231.28717) (xy 381.56367 -231.321262)
			(xy 381.593235 -231.360606) (xy 381.616106 -231.404183) (xy 381.63169 -231.450864) (xy 381.639585 -231.499441)
			(xy 381.64008 -231.524048) (xy 381.958591 -231.524048) (xy 381.962686 -231.47332) (xy 381.974865 -231.423906)
			(xy 381.994813 -231.377086) (xy 382.022014 -231.334072) (xy 382.055762 -231.295978) (xy 382.095184 -231.263791)
			(xy 382.139258 -231.238345) (xy 382.186844 -231.220298) (xy 382.236708 -231.210118) (xy 382.28756 -231.208069)
			(xy 382.338081 -231.214203) (xy 382.386965 -231.228363) (xy 382.432944 -231.25018) (xy 382.474828 -231.27909)
			(xy 382.511532 -231.314345) (xy 382.542105 -231.355031) (xy 382.565756 -231.400094) (xy 382.581872 -231.448368)
			(xy 382.590036 -231.498602) (xy 382.590548 -231.524048) (xy 382.909076 -231.524048) (xy 382.913036 -231.474994)
			(xy 382.924813 -231.42721) (xy 382.944104 -231.381934) (xy 382.970407 -231.340338) (xy 383.003042 -231.303501)
			(xy 383.041163 -231.272376) (xy 383.083784 -231.247769) (xy 383.1298 -231.230317) (xy 383.178019 -231.220473)
			(xy 383.227194 -231.218492) (xy 383.276049 -231.224424) (xy 383.32332 -231.238116) (xy 383.367782 -231.259214)
			(xy 383.408285 -231.28717) (xy 383.443778 -231.321262) (xy 383.473343 -231.360606) (xy 383.496214 -231.404183)
			(xy 383.511798 -231.450864) (xy 383.519693 -231.499441) (xy 383.520188 -231.524048) (xy 383.838699 -231.524048)
			(xy 383.842794 -231.47332) (xy 383.854973 -231.423906) (xy 383.874921 -231.377086) (xy 383.902122 -231.334072)
			(xy 383.93587 -231.295978) (xy 383.975292 -231.263791) (xy 384.019366 -231.238345) (xy 384.066952 -231.220298)
			(xy 384.116816 -231.210118) (xy 384.167668 -231.208069) (xy 384.218189 -231.214203) (xy 384.267073 -231.228363)
			(xy 384.313052 -231.25018) (xy 384.354936 -231.27909) (xy 384.39164 -231.314345) (xy 384.422213 -231.355031)
			(xy 384.445864 -231.400094) (xy 384.46198 -231.448368) (xy 384.470144 -231.498602) (xy 384.470656 -231.524048)
			(xy 384.78893 -231.524048) (xy 384.79289 -231.474994) (xy 384.804667 -231.42721) (xy 384.823958 -231.381934)
			(xy 384.850261 -231.340338) (xy 384.882896 -231.303501) (xy 384.921017 -231.272376) (xy 384.963638 -231.247769)
			(xy 385.009654 -231.230317) (xy 385.057873 -231.220473) (xy 385.107048 -231.218492) (xy 385.155903 -231.224424)
			(xy 385.203174 -231.238116) (xy 385.247636 -231.259214) (xy 385.288139 -231.28717) (xy 385.323632 -231.321262)
			(xy 385.353197 -231.360606) (xy 385.376068 -231.404183) (xy 385.391652 -231.450864) (xy 385.399547 -231.499441)
			(xy 385.400042 -231.524048) (xy 385.718553 -231.524048) (xy 385.722648 -231.47332) (xy 385.734827 -231.423906)
			(xy 385.754775 -231.377086) (xy 385.781976 -231.334072) (xy 385.815724 -231.295978) (xy 385.855146 -231.263791)
			(xy 385.89922 -231.238345) (xy 385.946806 -231.220298) (xy 385.99667 -231.210118) (xy 386.047522 -231.208069)
			(xy 386.098043 -231.214203) (xy 386.146927 -231.228363) (xy 386.192906 -231.25018) (xy 386.23479 -231.27909)
			(xy 386.271494 -231.314345) (xy 386.302067 -231.355031) (xy 386.325718 -231.400094) (xy 386.341834 -231.448368)
			(xy 386.349998 -231.498602) (xy 386.35051 -231.524048) (xy 386.658607 -231.524048) (xy 386.662702 -231.47332)
			(xy 386.674881 -231.423906) (xy 386.694829 -231.377086) (xy 386.72203 -231.334072) (xy 386.755778 -231.295978)
			(xy 386.7952 -231.263791) (xy 386.839274 -231.238345) (xy 386.88686 -231.220298) (xy 386.936724 -231.210118)
			(xy 386.987576 -231.208069) (xy 387.038097 -231.214203) (xy 387.086981 -231.228363) (xy 387.13296 -231.25018)
			(xy 387.174844 -231.27909) (xy 387.211548 -231.314345) (xy 387.242121 -231.355031) (xy 387.265772 -231.400094)
			(xy 387.281888 -231.448368) (xy 387.290052 -231.498602) (xy 387.290564 -231.524048) (xy 387.609092 -231.524048)
			(xy 387.613052 -231.474994) (xy 387.624829 -231.42721) (xy 387.64412 -231.381934) (xy 387.670423 -231.340338)
			(xy 387.703058 -231.303501) (xy 387.741179 -231.272376) (xy 387.7838 -231.247769) (xy 387.829816 -231.230317)
			(xy 387.878035 -231.220473) (xy 387.92721 -231.218492) (xy 387.976065 -231.224424) (xy 388.023336 -231.238116)
			(xy 388.067798 -231.259214) (xy 388.108301 -231.28717) (xy 388.143794 -231.321262) (xy 388.173359 -231.360606)
			(xy 388.19623 -231.404183) (xy 388.211814 -231.450864) (xy 388.219709 -231.499441) (xy 388.220204 -231.524048)
			(xy 388.538715 -231.524048) (xy 388.54281 -231.47332) (xy 388.554989 -231.423906) (xy 388.574937 -231.377086)
			(xy 388.602138 -231.334072) (xy 388.635886 -231.295978) (xy 388.675308 -231.263791) (xy 388.719382 -231.238345)
			(xy 388.766968 -231.220298) (xy 388.816832 -231.210118) (xy 388.867684 -231.208069) (xy 388.918205 -231.214203)
			(xy 388.967089 -231.228363) (xy 389.013068 -231.25018) (xy 389.054952 -231.27909) (xy 389.091656 -231.314345)
			(xy 389.122229 -231.355031) (xy 389.14588 -231.400094) (xy 389.161996 -231.448368) (xy 389.17016 -231.498602)
			(xy 389.170672 -231.524048) (xy 389.488946 -231.524048) (xy 389.492906 -231.474994) (xy 389.504683 -231.42721)
			(xy 389.523974 -231.381934) (xy 389.550277 -231.340338) (xy 389.582912 -231.303501) (xy 389.621033 -231.272376)
			(xy 389.663654 -231.247769) (xy 389.70967 -231.230317) (xy 389.757889 -231.220473) (xy 389.807064 -231.218492)
			(xy 389.855919 -231.224424) (xy 389.90319 -231.238116) (xy 389.947652 -231.259214) (xy 389.988155 -231.28717)
			(xy 390.023648 -231.321262) (xy 390.053213 -231.360606) (xy 390.076084 -231.404183) (xy 390.091668 -231.450864)
			(xy 390.099563 -231.499441) (xy 390.100058 -231.524048) (xy 390.418569 -231.524048) (xy 390.422664 -231.47332)
			(xy 390.434843 -231.423906) (xy 390.454791 -231.377086) (xy 390.481992 -231.334072) (xy 390.51574 -231.295978)
			(xy 390.555162 -231.263791) (xy 390.599236 -231.238345) (xy 390.646822 -231.220298) (xy 390.696686 -231.210118)
			(xy 390.747538 -231.208069) (xy 390.798059 -231.214203) (xy 390.846943 -231.228363) (xy 390.892922 -231.25018)
			(xy 390.934806 -231.27909) (xy 390.97151 -231.314345) (xy 391.002083 -231.355031) (xy 391.025734 -231.400094)
			(xy 391.04185 -231.448368) (xy 391.050014 -231.498602) (xy 391.050526 -231.524048) (xy 391.369054 -231.524048)
			(xy 391.373014 -231.474994) (xy 391.384791 -231.42721) (xy 391.404082 -231.381934) (xy 391.430385 -231.340338)
			(xy 391.46302 -231.303501) (xy 391.501141 -231.272376) (xy 391.543762 -231.247769) (xy 391.589778 -231.230317)
			(xy 391.637997 -231.220473) (xy 391.687172 -231.218492) (xy 391.736027 -231.224424) (xy 391.783298 -231.238116)
			(xy 391.82776 -231.259214) (xy 391.868263 -231.28717) (xy 391.903756 -231.321262) (xy 391.933321 -231.360606)
			(xy 391.956192 -231.404183) (xy 391.971776 -231.450864) (xy 391.979671 -231.499441) (xy 391.980166 -231.524048)
			(xy 391.979671 -231.548655) (xy 391.971776 -231.597232) (xy 391.956192 -231.643913) (xy 391.933321 -231.68749)
			(xy 391.903756 -231.726834) (xy 391.868263 -231.760926) (xy 391.82776 -231.788882) (xy 391.825433 -231.789986)
			(xy 394.377176 -231.789986) (xy 394.381136 -231.740932) (xy 394.392913 -231.693148) (xy 394.412204 -231.647872)
			(xy 394.438507 -231.606276) (xy 394.471142 -231.569439) (xy 394.509263 -231.538314) (xy 394.551884 -231.513707)
			(xy 394.5979 -231.496255) (xy 394.646119 -231.486411) (xy 394.695294 -231.48443) (xy 394.744149 -231.490362)
			(xy 394.79142 -231.504054) (xy 394.835882 -231.525152) (xy 394.876385 -231.553108) (xy 394.911878 -231.5872)
			(xy 394.941443 -231.626544) (xy 394.964314 -231.670121) (xy 394.979898 -231.716802) (xy 394.987793 -231.765379)
			(xy 394.988288 -231.789986) (xy 394.987793 -231.814593) (xy 394.979898 -231.86317) (xy 394.964314 -231.909851)
			(xy 394.941443 -231.953428) (xy 394.911878 -231.992772) (xy 394.876385 -232.026864) (xy 394.835882 -232.05482)
			(xy 394.79142 -232.075918) (xy 394.744149 -232.08961) (xy 394.695294 -232.095542) (xy 394.646119 -232.093561)
			(xy 394.5979 -232.083717) (xy 394.551884 -232.066265) (xy 394.509263 -232.041658) (xy 394.471142 -232.010533)
			(xy 394.438507 -231.973696) (xy 394.412204 -231.9321) (xy 394.392913 -231.886824) (xy 394.381136 -231.83904)
			(xy 394.377176 -231.789986) (xy 391.825433 -231.789986) (xy 391.783298 -231.80998) (xy 391.736027 -231.823672)
			(xy 391.687172 -231.829604) (xy 391.637997 -231.827623) (xy 391.589778 -231.817779) (xy 391.543762 -231.800327)
			(xy 391.501141 -231.77572) (xy 391.46302 -231.744595) (xy 391.430385 -231.707758) (xy 391.404082 -231.666162)
			(xy 391.384791 -231.620886) (xy 391.373014 -231.573102) (xy 391.369054 -231.524048) (xy 391.050526 -231.524048)
			(xy 391.050014 -231.549494) (xy 391.04185 -231.599728) (xy 391.025734 -231.648002) (xy 391.002083 -231.693065)
			(xy 390.97151 -231.733751) (xy 390.934806 -231.769006) (xy 390.892922 -231.797916) (xy 390.846943 -231.819733)
			(xy 390.798059 -231.833893) (xy 390.747538 -231.840027) (xy 390.696686 -231.837978) (xy 390.646822 -231.827798)
			(xy 390.599236 -231.809751) (xy 390.555162 -231.784305) (xy 390.51574 -231.752118) (xy 390.481992 -231.714024)
			(xy 390.454791 -231.67101) (xy 390.434843 -231.62419) (xy 390.422664 -231.574776) (xy 390.418569 -231.524048)
			(xy 390.100058 -231.524048) (xy 390.099563 -231.548655) (xy 390.091668 -231.597232) (xy 390.076084 -231.643913)
			(xy 390.053213 -231.68749) (xy 390.023648 -231.726834) (xy 389.988155 -231.760926) (xy 389.947652 -231.788882)
			(xy 389.90319 -231.80998) (xy 389.855919 -231.823672) (xy 389.807064 -231.829604) (xy 389.757889 -231.827623)
			(xy 389.70967 -231.817779) (xy 389.663654 -231.800327) (xy 389.621033 -231.77572) (xy 389.582912 -231.744595)
			(xy 389.550277 -231.707758) (xy 389.523974 -231.666162) (xy 389.504683 -231.620886) (xy 389.492906 -231.573102)
			(xy 389.488946 -231.524048) (xy 389.170672 -231.524048) (xy 389.17016 -231.549494) (xy 389.161996 -231.599728)
			(xy 389.14588 -231.648002) (xy 389.122229 -231.693065) (xy 389.091656 -231.733751) (xy 389.054952 -231.769006)
			(xy 389.013068 -231.797916) (xy 388.967089 -231.819733) (xy 388.918205 -231.833893) (xy 388.867684 -231.840027)
			(xy 388.816832 -231.837978) (xy 388.766968 -231.827798) (xy 388.719382 -231.809751) (xy 388.675308 -231.784305)
			(xy 388.635886 -231.752118) (xy 388.602138 -231.714024) (xy 388.574937 -231.67101) (xy 388.554989 -231.62419)
			(xy 388.54281 -231.574776) (xy 388.538715 -231.524048) (xy 388.220204 -231.524048) (xy 388.219709 -231.548655)
			(xy 388.211814 -231.597232) (xy 388.19623 -231.643913) (xy 388.173359 -231.68749) (xy 388.143794 -231.726834)
			(xy 388.108301 -231.760926) (xy 388.067798 -231.788882) (xy 388.023336 -231.80998) (xy 387.976065 -231.823672)
			(xy 387.92721 -231.829604) (xy 387.878035 -231.827623) (xy 387.829816 -231.817779) (xy 387.7838 -231.800327)
			(xy 387.741179 -231.77572) (xy 387.703058 -231.744595) (xy 387.670423 -231.707758) (xy 387.64412 -231.666162)
			(xy 387.624829 -231.620886) (xy 387.613052 -231.573102) (xy 387.609092 -231.524048) (xy 387.290564 -231.524048)
			(xy 387.290052 -231.549494) (xy 387.281888 -231.599728) (xy 387.265772 -231.648002) (xy 387.242121 -231.693065)
			(xy 387.211548 -231.733751) (xy 387.174844 -231.769006) (xy 387.13296 -231.797916) (xy 387.086981 -231.819733)
			(xy 387.038097 -231.833893) (xy 386.987576 -231.840027) (xy 386.936724 -231.837978) (xy 386.88686 -231.827798)
			(xy 386.839274 -231.809751) (xy 386.7952 -231.784305) (xy 386.755778 -231.752118) (xy 386.72203 -231.714024)
			(xy 386.694829 -231.67101) (xy 386.674881 -231.62419) (xy 386.662702 -231.574776) (xy 386.658607 -231.524048)
			(xy 386.35051 -231.524048) (xy 386.349998 -231.549494) (xy 386.341834 -231.599728) (xy 386.325718 -231.648002)
			(xy 386.302067 -231.693065) (xy 386.271494 -231.733751) (xy 386.23479 -231.769006) (xy 386.192906 -231.797916)
			(xy 386.146927 -231.819733) (xy 386.098043 -231.833893) (xy 386.047522 -231.840027) (xy 385.99667 -231.837978)
			(xy 385.946806 -231.827798) (xy 385.89922 -231.809751) (xy 385.855146 -231.784305) (xy 385.815724 -231.752118)
			(xy 385.781976 -231.714024) (xy 385.754775 -231.67101) (xy 385.734827 -231.62419) (xy 385.722648 -231.574776)
			(xy 385.718553 -231.524048) (xy 385.400042 -231.524048) (xy 385.399547 -231.548655) (xy 385.391652 -231.597232)
			(xy 385.376068 -231.643913) (xy 385.353197 -231.68749) (xy 385.323632 -231.726834) (xy 385.288139 -231.760926)
			(xy 385.247636 -231.788882) (xy 385.203174 -231.80998) (xy 385.155903 -231.823672) (xy 385.107048 -231.829604)
			(xy 385.057873 -231.827623) (xy 385.009654 -231.817779) (xy 384.963638 -231.800327) (xy 384.921017 -231.77572)
			(xy 384.882896 -231.744595) (xy 384.850261 -231.707758) (xy 384.823958 -231.666162) (xy 384.804667 -231.620886)
			(xy 384.79289 -231.573102) (xy 384.78893 -231.524048) (xy 384.470656 -231.524048) (xy 384.470144 -231.549494)
			(xy 384.46198 -231.599728) (xy 384.445864 -231.648002) (xy 384.422213 -231.693065) (xy 384.39164 -231.733751)
			(xy 384.354936 -231.769006) (xy 384.313052 -231.797916) (xy 384.267073 -231.819733) (xy 384.218189 -231.833893)
			(xy 384.167668 -231.840027) (xy 384.116816 -231.837978) (xy 384.066952 -231.827798) (xy 384.019366 -231.809751)
			(xy 383.975292 -231.784305) (xy 383.93587 -231.752118) (xy 383.902122 -231.714024) (xy 383.874921 -231.67101)
			(xy 383.854973 -231.62419) (xy 383.842794 -231.574776) (xy 383.838699 -231.524048) (xy 383.520188 -231.524048)
			(xy 383.519693 -231.548655) (xy 383.511798 -231.597232) (xy 383.496214 -231.643913) (xy 383.473343 -231.68749)
			(xy 383.443778 -231.726834) (xy 383.408285 -231.760926) (xy 383.367782 -231.788882) (xy 383.32332 -231.80998)
			(xy 383.276049 -231.823672) (xy 383.227194 -231.829604) (xy 383.178019 -231.827623) (xy 383.1298 -231.817779)
			(xy 383.083784 -231.800327) (xy 383.041163 -231.77572) (xy 383.003042 -231.744595) (xy 382.970407 -231.707758)
			(xy 382.944104 -231.666162) (xy 382.924813 -231.620886) (xy 382.913036 -231.573102) (xy 382.909076 -231.524048)
			(xy 382.590548 -231.524048) (xy 382.590036 -231.549494) (xy 382.581872 -231.599728) (xy 382.565756 -231.648002)
			(xy 382.542105 -231.693065) (xy 382.511532 -231.733751) (xy 382.474828 -231.769006) (xy 382.432944 -231.797916)
			(xy 382.386965 -231.819733) (xy 382.338081 -231.833893) (xy 382.28756 -231.840027) (xy 382.236708 -231.837978)
			(xy 382.186844 -231.827798) (xy 382.139258 -231.809751) (xy 382.095184 -231.784305) (xy 382.055762 -231.752118)
			(xy 382.022014 -231.714024) (xy 381.994813 -231.67101) (xy 381.974865 -231.62419) (xy 381.962686 -231.574776)
			(xy 381.958591 -231.524048) (xy 381.64008 -231.524048) (xy 381.639585 -231.548655) (xy 381.63169 -231.597232)
			(xy 381.616106 -231.643913) (xy 381.593235 -231.68749) (xy 381.56367 -231.726834) (xy 381.528177 -231.760926)
			(xy 381.487674 -231.788882) (xy 381.443212 -231.80998) (xy 381.395941 -231.823672) (xy 381.347086 -231.829604)
			(xy 381.297911 -231.827623) (xy 381.249692 -231.817779) (xy 381.203676 -231.800327) (xy 381.161055 -231.77572)
			(xy 381.122934 -231.744595) (xy 381.090299 -231.707758) (xy 381.063996 -231.666162) (xy 381.044705 -231.620886)
			(xy 381.032928 -231.573102) (xy 381.028968 -231.524048) (xy 380.71044 -231.524048) (xy 380.709928 -231.549494)
			(xy 380.701764 -231.599728) (xy 380.685648 -231.648002) (xy 380.661997 -231.693065) (xy 380.631424 -231.733751)
			(xy 380.59472 -231.769006) (xy 380.552836 -231.797916) (xy 380.506857 -231.819733) (xy 380.457973 -231.833893)
			(xy 380.407452 -231.840027) (xy 380.3566 -231.837978) (xy 380.306736 -231.827798) (xy 380.25915 -231.809751)
			(xy 380.215076 -231.784305) (xy 380.175654 -231.752118) (xy 380.141906 -231.714024) (xy 380.114705 -231.67101)
			(xy 380.094757 -231.62419) (xy 380.082578 -231.574776) (xy 380.078483 -231.524048) (xy 379.77064 -231.524048)
			(xy 379.770128 -231.549494) (xy 379.761964 -231.599728) (xy 379.745848 -231.648002) (xy 379.722197 -231.693065)
			(xy 379.691624 -231.733751) (xy 379.65492 -231.769006) (xy 379.613036 -231.797916) (xy 379.567057 -231.819733)
			(xy 379.518173 -231.833893) (xy 379.467652 -231.840027) (xy 379.4168 -231.837978) (xy 379.366936 -231.827798)
			(xy 379.31935 -231.809751) (xy 379.275276 -231.784305) (xy 379.235854 -231.752118) (xy 379.202106 -231.714024)
			(xy 379.174905 -231.67101) (xy 379.154957 -231.62419) (xy 379.142778 -231.574776) (xy 379.138683 -231.524048)
			(xy 378.820172 -231.524048) (xy 378.819677 -231.548655) (xy 378.811782 -231.597232) (xy 378.796198 -231.643913)
			(xy 378.773327 -231.68749) (xy 378.743762 -231.726834) (xy 378.708269 -231.760926) (xy 378.667766 -231.788882)
			(xy 378.623304 -231.80998) (xy 378.576033 -231.823672) (xy 378.527178 -231.829604) (xy 378.478003 -231.827623)
			(xy 378.429784 -231.817779) (xy 378.383768 -231.800327) (xy 378.341147 -231.77572) (xy 378.303026 -231.744595)
			(xy 378.270391 -231.707758) (xy 378.244088 -231.666162) (xy 378.224797 -231.620886) (xy 378.21302 -231.573102)
			(xy 378.20906 -231.524048) (xy 377.890532 -231.524048) (xy 377.89002 -231.549494) (xy 377.881856 -231.599728)
			(xy 377.86574 -231.648002) (xy 377.842089 -231.693065) (xy 377.811516 -231.733751) (xy 377.774812 -231.769006)
			(xy 377.732928 -231.797916) (xy 377.686949 -231.819733) (xy 377.638065 -231.833893) (xy 377.587544 -231.840027)
			(xy 377.536692 -231.837978) (xy 377.486828 -231.827798) (xy 377.439242 -231.809751) (xy 377.395168 -231.784305)
			(xy 377.355746 -231.752118) (xy 377.321998 -231.714024) (xy 377.294797 -231.67101) (xy 377.274849 -231.62419)
			(xy 377.26267 -231.574776) (xy 377.258575 -231.524048) (xy 376.940064 -231.524048) (xy 376.939569 -231.548655)
			(xy 376.931674 -231.597232) (xy 376.91609 -231.643913) (xy 376.893219 -231.68749) (xy 376.863654 -231.726834)
			(xy 376.828161 -231.760926) (xy 376.787658 -231.788882) (xy 376.743196 -231.80998) (xy 376.695925 -231.823672)
			(xy 376.64707 -231.829604) (xy 376.597895 -231.827623) (xy 376.549676 -231.817779) (xy 376.50366 -231.800327)
			(xy 376.461039 -231.77572) (xy 376.422918 -231.744595) (xy 376.390283 -231.707758) (xy 376.36398 -231.666162)
			(xy 376.344689 -231.620886) (xy 376.332912 -231.573102) (xy 376.328952 -231.524048) (xy 376.010424 -231.524048)
			(xy 376.009912 -231.549494) (xy 376.001748 -231.599728) (xy 375.985632 -231.648002) (xy 375.961981 -231.693065)
			(xy 375.931408 -231.733751) (xy 375.894704 -231.769006) (xy 375.85282 -231.797916) (xy 375.806841 -231.819733)
			(xy 375.757957 -231.833893) (xy 375.707436 -231.840027) (xy 375.656584 -231.837978) (xy 375.60672 -231.827798)
			(xy 375.559134 -231.809751) (xy 375.51506 -231.784305) (xy 375.475638 -231.752118) (xy 375.44189 -231.714024)
			(xy 375.414689 -231.67101) (xy 375.394741 -231.62419) (xy 375.382562 -231.574776) (xy 375.378467 -231.524048)
			(xy 375.059663 -231.524048) (xy 375.05966 -231.54832) (xy 375.051972 -231.596271) (xy 375.036795 -231.642402)
			(xy 375.014512 -231.685552) (xy 375.00052 -231.705404) (xy 374.995948 -231.711754) (xy 374.988074 -231.734614)
			(xy 374.986793 -231.738622) (xy 374.985395 -231.746918) (xy 374.98528 -231.751124) (xy 374.98528 -232.334054)
			(xy 375.848621 -232.334054) (xy 375.852716 -232.283326) (xy 375.864895 -232.233912) (xy 375.884843 -232.187092)
			(xy 375.912044 -232.144078) (xy 375.945792 -232.105984) (xy 375.985214 -232.073797) (xy 376.029288 -232.048351)
			(xy 376.076874 -232.030304) (xy 376.126738 -232.020124) (xy 376.17759 -232.018075) (xy 376.228111 -232.024209)
			(xy 376.276995 -232.038369) (xy 376.322974 -232.060186) (xy 376.364858 -232.089096) (xy 376.401562 -232.124351)
			(xy 376.432135 -232.165037) (xy 376.455786 -232.2101) (xy 376.471902 -232.258374) (xy 376.480066 -232.308608)
			(xy 376.480578 -232.334054) (xy 376.788675 -232.334054) (xy 376.79277 -232.283326) (xy 376.804949 -232.233912)
			(xy 376.824897 -232.187092) (xy 376.852098 -232.144078) (xy 376.885846 -232.105984) (xy 376.925268 -232.073797)
			(xy 376.969342 -232.048351) (xy 377.016928 -232.030304) (xy 377.066792 -232.020124) (xy 377.117644 -232.018075)
			(xy 377.168165 -232.024209) (xy 377.217049 -232.038369) (xy 377.263028 -232.060186) (xy 377.304912 -232.089096)
			(xy 377.341616 -232.124351) (xy 377.372189 -232.165037) (xy 377.39584 -232.2101) (xy 377.411956 -232.258374)
			(xy 377.42012 -232.308608) (xy 377.420632 -232.334054) (xy 378.668529 -232.334054) (xy 378.672624 -232.283326)
			(xy 378.684803 -232.233912) (xy 378.704751 -232.187092) (xy 378.731952 -232.144078) (xy 378.7657 -232.105984)
			(xy 378.805122 -232.073797) (xy 378.849196 -232.048351) (xy 378.896782 -232.030304) (xy 378.946646 -232.020124)
			(xy 378.997498 -232.018075) (xy 379.048019 -232.024209) (xy 379.096903 -232.038369) (xy 379.142882 -232.060186)
			(xy 379.184766 -232.089096) (xy 379.22147 -232.124351) (xy 379.252043 -232.165037) (xy 379.275694 -232.2101)
			(xy 379.29181 -232.258374) (xy 379.299974 -232.308608) (xy 379.300486 -232.334054) (xy 379.619014 -232.334054)
			(xy 379.622974 -232.285) (xy 379.634751 -232.237216) (xy 379.654042 -232.19194) (xy 379.680345 -232.150344)
			(xy 379.71298 -232.113507) (xy 379.751101 -232.082382) (xy 379.793722 -232.057775) (xy 379.839738 -232.040323)
			(xy 379.887957 -232.030479) (xy 379.937132 -232.028498) (xy 379.985987 -232.03443) (xy 380.033258 -232.048122)
			(xy 380.07772 -232.06922) (xy 380.118223 -232.097176) (xy 380.153716 -232.131268) (xy 380.183281 -232.170612)
			(xy 380.206152 -232.214189) (xy 380.221736 -232.26087) (xy 380.229631 -232.309447) (xy 380.230126 -232.334054)
			(xy 380.548637 -232.334054) (xy 380.552732 -232.283326) (xy 380.564911 -232.233912) (xy 380.584859 -232.187092)
			(xy 380.61206 -232.144078) (xy 380.645808 -232.105984) (xy 380.68523 -232.073797) (xy 380.729304 -232.048351)
			(xy 380.77689 -232.030304) (xy 380.826754 -232.020124) (xy 380.877606 -232.018075) (xy 380.928127 -232.024209)
			(xy 380.977011 -232.038369) (xy 381.02299 -232.060186) (xy 381.064874 -232.089096) (xy 381.101578 -232.124351)
			(xy 381.132151 -232.165037) (xy 381.155802 -232.2101) (xy 381.171918 -232.258374) (xy 381.180082 -232.308608)
			(xy 381.180594 -232.334054) (xy 381.499122 -232.334054) (xy 381.503082 -232.285) (xy 381.514859 -232.237216)
			(xy 381.53415 -232.19194) (xy 381.560453 -232.150344) (xy 381.593088 -232.113507) (xy 381.631209 -232.082382)
			(xy 381.67383 -232.057775) (xy 381.719846 -232.040323) (xy 381.768065 -232.030479) (xy 381.81724 -232.028498)
			(xy 381.866095 -232.03443) (xy 381.913366 -232.048122) (xy 381.957828 -232.06922) (xy 381.998331 -232.097176)
			(xy 382.033824 -232.131268) (xy 382.063389 -232.170612) (xy 382.08626 -232.214189) (xy 382.101844 -232.26087)
			(xy 382.109739 -232.309447) (xy 382.110234 -232.334054) (xy 382.428491 -232.334054) (xy 382.432586 -232.283326)
			(xy 382.444765 -232.233912) (xy 382.464713 -232.187092) (xy 382.491914 -232.144078) (xy 382.525662 -232.105984)
			(xy 382.565084 -232.073797) (xy 382.609158 -232.048351) (xy 382.656744 -232.030304) (xy 382.706608 -232.020124)
			(xy 382.75746 -232.018075) (xy 382.807981 -232.024209) (xy 382.856865 -232.038369) (xy 382.902844 -232.060186)
			(xy 382.944728 -232.089096) (xy 382.981432 -232.124351) (xy 383.012005 -232.165037) (xy 383.035656 -232.2101)
			(xy 383.051772 -232.258374) (xy 383.059936 -232.308608) (xy 383.060448 -232.334054) (xy 383.368545 -232.334054)
			(xy 383.37264 -232.283326) (xy 383.384819 -232.233912) (xy 383.404767 -232.187092) (xy 383.431968 -232.144078)
			(xy 383.465716 -232.105984) (xy 383.505138 -232.073797) (xy 383.549212 -232.048351) (xy 383.596798 -232.030304)
			(xy 383.646662 -232.020124) (xy 383.697514 -232.018075) (xy 383.748035 -232.024209) (xy 383.796919 -232.038369)
			(xy 383.842898 -232.060186) (xy 383.884782 -232.089096) (xy 383.921486 -232.124351) (xy 383.952059 -232.165037)
			(xy 383.97571 -232.2101) (xy 383.991826 -232.258374) (xy 383.99999 -232.308608) (xy 384.000502 -232.334054)
			(xy 385.248653 -232.334054) (xy 385.252748 -232.283326) (xy 385.264927 -232.233912) (xy 385.284875 -232.187092)
			(xy 385.312076 -232.144078) (xy 385.345824 -232.105984) (xy 385.385246 -232.073797) (xy 385.42932 -232.048351)
			(xy 385.476906 -232.030304) (xy 385.52677 -232.020124) (xy 385.577622 -232.018075) (xy 385.628143 -232.024209)
			(xy 385.677027 -232.038369) (xy 385.723006 -232.060186) (xy 385.76489 -232.089096) (xy 385.801594 -232.124351)
			(xy 385.832167 -232.165037) (xy 385.855818 -232.2101) (xy 385.871934 -232.258374) (xy 385.880098 -232.308608)
			(xy 385.88061 -232.334054) (xy 386.199138 -232.334054) (xy 386.203098 -232.285) (xy 386.214875 -232.237216)
			(xy 386.234166 -232.19194) (xy 386.260469 -232.150344) (xy 386.293104 -232.113507) (xy 386.331225 -232.082382)
			(xy 386.373846 -232.057775) (xy 386.419862 -232.040323) (xy 386.468081 -232.030479) (xy 386.517256 -232.028498)
			(xy 386.566111 -232.03443) (xy 386.613382 -232.048122) (xy 386.657844 -232.06922) (xy 386.698347 -232.097176)
			(xy 386.73384 -232.131268) (xy 386.763405 -232.170612) (xy 386.786276 -232.214189) (xy 386.80186 -232.26087)
			(xy 386.809755 -232.309447) (xy 386.81025 -232.334054) (xy 387.128507 -232.334054) (xy 387.132602 -232.283326)
			(xy 387.144781 -232.233912) (xy 387.164729 -232.187092) (xy 387.19193 -232.144078) (xy 387.225678 -232.105984)
			(xy 387.2651 -232.073797) (xy 387.309174 -232.048351) (xy 387.35676 -232.030304) (xy 387.406624 -232.020124)
			(xy 387.457476 -232.018075) (xy 387.507997 -232.024209) (xy 387.556881 -232.038369) (xy 387.60286 -232.060186)
			(xy 387.644744 -232.089096) (xy 387.681448 -232.124351) (xy 387.712021 -232.165037) (xy 387.735672 -232.2101)
			(xy 387.751788 -232.258374) (xy 387.759952 -232.308608) (xy 387.760464 -232.334054) (xy 388.078992 -232.334054)
			(xy 388.082952 -232.285) (xy 388.094729 -232.237216) (xy 388.11402 -232.19194) (xy 388.140323 -232.150344)
			(xy 388.172958 -232.113507) (xy 388.211079 -232.082382) (xy 388.2537 -232.057775) (xy 388.299716 -232.040323)
			(xy 388.347935 -232.030479) (xy 388.39711 -232.028498) (xy 388.445965 -232.03443) (xy 388.493236 -232.048122)
			(xy 388.537698 -232.06922) (xy 388.578201 -232.097176) (xy 388.613694 -232.131268) (xy 388.643259 -232.170612)
			(xy 388.66613 -232.214189) (xy 388.681714 -232.26087) (xy 388.689609 -232.309447) (xy 388.690104 -232.334054)
			(xy 389.008615 -232.334054) (xy 389.01271 -232.283326) (xy 389.024889 -232.233912) (xy 389.044837 -232.187092)
			(xy 389.072038 -232.144078) (xy 389.105786 -232.105984) (xy 389.145208 -232.073797) (xy 389.189282 -232.048351)
			(xy 389.236868 -232.030304) (xy 389.286732 -232.020124) (xy 389.337584 -232.018075) (xy 389.388105 -232.024209)
			(xy 389.436989 -232.038369) (xy 389.482968 -232.060186) (xy 389.524852 -232.089096) (xy 389.561556 -232.124351)
			(xy 389.592129 -232.165037) (xy 389.61578 -232.2101) (xy 389.631896 -232.258374) (xy 389.64006 -232.308608)
			(xy 389.640572 -232.334054) (xy 389.948669 -232.334054) (xy 389.952764 -232.283326) (xy 389.964943 -232.233912)
			(xy 389.984891 -232.187092) (xy 390.012092 -232.144078) (xy 390.04584 -232.105984) (xy 390.085262 -232.073797)
			(xy 390.129336 -232.048351) (xy 390.176922 -232.030304) (xy 390.226786 -232.020124) (xy 390.277638 -232.018075)
			(xy 390.328159 -232.024209) (xy 390.377043 -232.038369) (xy 390.423022 -232.060186) (xy 390.464906 -232.089096)
			(xy 390.50161 -232.124351) (xy 390.532183 -232.165037) (xy 390.555834 -232.2101) (xy 390.57195 -232.258374)
			(xy 390.580114 -232.308608) (xy 390.580626 -232.334054) (xy 392.779008 -232.334054) (xy 392.782968 -232.285)
			(xy 392.794745 -232.237216) (xy 392.814036 -232.19194) (xy 392.840339 -232.150344) (xy 392.872974 -232.113507)
			(xy 392.911095 -232.082382) (xy 392.953716 -232.057775) (xy 392.999732 -232.040323) (xy 393.047951 -232.030479)
			(xy 393.097126 -232.028498) (xy 393.145981 -232.03443) (xy 393.193252 -232.048122) (xy 393.237714 -232.06922)
			(xy 393.278217 -232.097176) (xy 393.31371 -232.131268) (xy 393.343275 -232.170612) (xy 393.366146 -232.214189)
			(xy 393.38173 -232.26087) (xy 393.389625 -232.309447) (xy 393.39012 -232.334054) (xy 393.389625 -232.358661)
			(xy 393.38173 -232.407238) (xy 393.366146 -232.453919) (xy 393.343275 -232.497496) (xy 393.31371 -232.53684)
			(xy 393.278217 -232.570932) (xy 393.237714 -232.598888) (xy 393.193252 -232.619986) (xy 393.145981 -232.633678)
			(xy 393.097126 -232.63961) (xy 393.047951 -232.637629) (xy 392.999732 -232.627785) (xy 392.953716 -232.610333)
			(xy 392.911095 -232.585726) (xy 392.872974 -232.554601) (xy 392.840339 -232.517764) (xy 392.814036 -232.476168)
			(xy 392.794745 -232.430892) (xy 392.782968 -232.383108) (xy 392.779008 -232.334054) (xy 390.580626 -232.334054)
			(xy 390.580114 -232.3595) (xy 390.57195 -232.409734) (xy 390.555834 -232.458008) (xy 390.532183 -232.503071)
			(xy 390.50161 -232.543757) (xy 390.464906 -232.579012) (xy 390.423022 -232.607922) (xy 390.377043 -232.629739)
			(xy 390.328159 -232.643899) (xy 390.277638 -232.650033) (xy 390.226786 -232.647984) (xy 390.176922 -232.637804)
			(xy 390.129336 -232.619757) (xy 390.085262 -232.594311) (xy 390.04584 -232.562124) (xy 390.012092 -232.52403)
			(xy 389.984891 -232.481016) (xy 389.964943 -232.434196) (xy 389.952764 -232.384782) (xy 389.948669 -232.334054)
			(xy 389.640572 -232.334054) (xy 389.64006 -232.3595) (xy 389.631896 -232.409734) (xy 389.61578 -232.458008)
			(xy 389.592129 -232.503071) (xy 389.561556 -232.543757) (xy 389.524852 -232.579012) (xy 389.482968 -232.607922)
			(xy 389.436989 -232.629739) (xy 389.388105 -232.643899) (xy 389.337584 -232.650033) (xy 389.286732 -232.647984)
			(xy 389.236868 -232.637804) (xy 389.189282 -232.619757) (xy 389.145208 -232.594311) (xy 389.105786 -232.562124)
			(xy 389.072038 -232.52403) (xy 389.044837 -232.481016) (xy 389.024889 -232.434196) (xy 389.01271 -232.384782)
			(xy 389.008615 -232.334054) (xy 388.690104 -232.334054) (xy 388.689609 -232.358661) (xy 388.681714 -232.407238)
			(xy 388.66613 -232.453919) (xy 388.643259 -232.497496) (xy 388.613694 -232.53684) (xy 388.578201 -232.570932)
			(xy 388.537698 -232.598888) (xy 388.493236 -232.619986) (xy 388.445965 -232.633678) (xy 388.39711 -232.63961)
			(xy 388.347935 -232.637629) (xy 388.299716 -232.627785) (xy 388.2537 -232.610333) (xy 388.211079 -232.585726)
			(xy 388.172958 -232.554601) (xy 388.140323 -232.517764) (xy 388.11402 -232.476168) (xy 388.094729 -232.430892)
			(xy 388.082952 -232.383108) (xy 388.078992 -232.334054) (xy 387.760464 -232.334054) (xy 387.759952 -232.3595)
			(xy 387.751788 -232.409734) (xy 387.735672 -232.458008) (xy 387.712021 -232.503071) (xy 387.681448 -232.543757)
			(xy 387.644744 -232.579012) (xy 387.60286 -232.607922) (xy 387.556881 -232.629739) (xy 387.507997 -232.643899)
			(xy 387.457476 -232.650033) (xy 387.406624 -232.647984) (xy 387.35676 -232.637804) (xy 387.309174 -232.619757)
			(xy 387.2651 -232.594311) (xy 387.225678 -232.562124) (xy 387.19193 -232.52403) (xy 387.164729 -232.481016)
			(xy 387.144781 -232.434196) (xy 387.132602 -232.384782) (xy 387.128507 -232.334054) (xy 386.81025 -232.334054)
			(xy 386.809755 -232.358661) (xy 386.80186 -232.407238) (xy 386.786276 -232.453919) (xy 386.763405 -232.497496)
			(xy 386.73384 -232.53684) (xy 386.698347 -232.570932) (xy 386.657844 -232.598888) (xy 386.613382 -232.619986)
			(xy 386.566111 -232.633678) (xy 386.517256 -232.63961) (xy 386.468081 -232.637629) (xy 386.419862 -232.627785)
			(xy 386.373846 -232.610333) (xy 386.331225 -232.585726) (xy 386.293104 -232.554601) (xy 386.260469 -232.517764)
			(xy 386.234166 -232.476168) (xy 386.214875 -232.430892) (xy 386.203098 -232.383108) (xy 386.199138 -232.334054)
			(xy 385.88061 -232.334054) (xy 385.880098 -232.3595) (xy 385.871934 -232.409734) (xy 385.855818 -232.458008)
			(xy 385.832167 -232.503071) (xy 385.801594 -232.543757) (xy 385.76489 -232.579012) (xy 385.723006 -232.607922)
			(xy 385.677027 -232.629739) (xy 385.628143 -232.643899) (xy 385.577622 -232.650033) (xy 385.52677 -232.647984)
			(xy 385.476906 -232.637804) (xy 385.42932 -232.619757) (xy 385.385246 -232.594311) (xy 385.345824 -232.562124)
			(xy 385.312076 -232.52403) (xy 385.284875 -232.481016) (xy 385.264927 -232.434196) (xy 385.252748 -232.384782)
			(xy 385.248653 -232.334054) (xy 384.000502 -232.334054) (xy 383.99999 -232.3595) (xy 383.991826 -232.409734)
			(xy 383.97571 -232.458008) (xy 383.952059 -232.503071) (xy 383.921486 -232.543757) (xy 383.884782 -232.579012)
			(xy 383.842898 -232.607922) (xy 383.796919 -232.629739) (xy 383.748035 -232.643899) (xy 383.697514 -232.650033)
			(xy 383.646662 -232.647984) (xy 383.596798 -232.637804) (xy 383.549212 -232.619757) (xy 383.505138 -232.594311)
			(xy 383.465716 -232.562124) (xy 383.431968 -232.52403) (xy 383.404767 -232.481016) (xy 383.384819 -232.434196)
			(xy 383.37264 -232.384782) (xy 383.368545 -232.334054) (xy 383.060448 -232.334054) (xy 383.059936 -232.3595)
			(xy 383.051772 -232.409734) (xy 383.035656 -232.458008) (xy 383.012005 -232.503071) (xy 382.981432 -232.543757)
			(xy 382.944728 -232.579012) (xy 382.902844 -232.607922) (xy 382.856865 -232.629739) (xy 382.807981 -232.643899)
			(xy 382.75746 -232.650033) (xy 382.706608 -232.647984) (xy 382.656744 -232.637804) (xy 382.609158 -232.619757)
			(xy 382.565084 -232.594311) (xy 382.525662 -232.562124) (xy 382.491914 -232.52403) (xy 382.464713 -232.481016)
			(xy 382.444765 -232.434196) (xy 382.432586 -232.384782) (xy 382.428491 -232.334054) (xy 382.110234 -232.334054)
			(xy 382.109739 -232.358661) (xy 382.101844 -232.407238) (xy 382.08626 -232.453919) (xy 382.063389 -232.497496)
			(xy 382.033824 -232.53684) (xy 381.998331 -232.570932) (xy 381.957828 -232.598888) (xy 381.913366 -232.619986)
			(xy 381.866095 -232.633678) (xy 381.81724 -232.63961) (xy 381.768065 -232.637629) (xy 381.719846 -232.627785)
			(xy 381.67383 -232.610333) (xy 381.631209 -232.585726) (xy 381.593088 -232.554601) (xy 381.560453 -232.517764)
			(xy 381.53415 -232.476168) (xy 381.514859 -232.430892) (xy 381.503082 -232.383108) (xy 381.499122 -232.334054)
			(xy 381.180594 -232.334054) (xy 381.180082 -232.3595) (xy 381.171918 -232.409734) (xy 381.155802 -232.458008)
			(xy 381.132151 -232.503071) (xy 381.101578 -232.543757) (xy 381.064874 -232.579012) (xy 381.02299 -232.607922)
			(xy 380.977011 -232.629739) (xy 380.928127 -232.643899) (xy 380.877606 -232.650033) (xy 380.826754 -232.647984)
			(xy 380.77689 -232.637804) (xy 380.729304 -232.619757) (xy 380.68523 -232.594311) (xy 380.645808 -232.562124)
			(xy 380.61206 -232.52403) (xy 380.584859 -232.481016) (xy 380.564911 -232.434196) (xy 380.552732 -232.384782)
			(xy 380.548637 -232.334054) (xy 380.230126 -232.334054) (xy 380.229631 -232.358661) (xy 380.221736 -232.407238)
			(xy 380.206152 -232.453919) (xy 380.183281 -232.497496) (xy 380.153716 -232.53684) (xy 380.118223 -232.570932)
			(xy 380.07772 -232.598888) (xy 380.033258 -232.619986) (xy 379.985987 -232.633678) (xy 379.937132 -232.63961)
			(xy 379.887957 -232.637629) (xy 379.839738 -232.627785) (xy 379.793722 -232.610333) (xy 379.751101 -232.585726)
			(xy 379.71298 -232.554601) (xy 379.680345 -232.517764) (xy 379.654042 -232.476168) (xy 379.634751 -232.430892)
			(xy 379.622974 -232.383108) (xy 379.619014 -232.334054) (xy 379.300486 -232.334054) (xy 379.299974 -232.3595)
			(xy 379.29181 -232.409734) (xy 379.275694 -232.458008) (xy 379.252043 -232.503071) (xy 379.22147 -232.543757)
			(xy 379.184766 -232.579012) (xy 379.142882 -232.607922) (xy 379.096903 -232.629739) (xy 379.048019 -232.643899)
			(xy 378.997498 -232.650033) (xy 378.946646 -232.647984) (xy 378.896782 -232.637804) (xy 378.849196 -232.619757)
			(xy 378.805122 -232.594311) (xy 378.7657 -232.562124) (xy 378.731952 -232.52403) (xy 378.704751 -232.481016)
			(xy 378.684803 -232.434196) (xy 378.672624 -232.384782) (xy 378.668529 -232.334054) (xy 377.420632 -232.334054)
			(xy 377.42012 -232.3595) (xy 377.411956 -232.409734) (xy 377.39584 -232.458008) (xy 377.372189 -232.503071)
			(xy 377.341616 -232.543757) (xy 377.304912 -232.579012) (xy 377.263028 -232.607922) (xy 377.217049 -232.629739)
			(xy 377.168165 -232.643899) (xy 377.117644 -232.650033) (xy 377.066792 -232.647984) (xy 377.016928 -232.637804)
			(xy 376.969342 -232.619757) (xy 376.925268 -232.594311) (xy 376.885846 -232.562124) (xy 376.852098 -232.52403)
			(xy 376.824897 -232.481016) (xy 376.804949 -232.434196) (xy 376.79277 -232.384782) (xy 376.788675 -232.334054)
			(xy 376.480578 -232.334054) (xy 376.480066 -232.3595) (xy 376.471902 -232.409734) (xy 376.455786 -232.458008)
			(xy 376.432135 -232.503071) (xy 376.401562 -232.543757) (xy 376.364858 -232.579012) (xy 376.322974 -232.607922)
			(xy 376.276995 -232.629739) (xy 376.228111 -232.643899) (xy 376.17759 -232.650033) (xy 376.126738 -232.647984)
			(xy 376.076874 -232.637804) (xy 376.029288 -232.619757) (xy 375.985214 -232.594311) (xy 375.945792 -232.562124)
			(xy 375.912044 -232.52403) (xy 375.884843 -232.481016) (xy 375.864895 -232.434196) (xy 375.852716 -232.384782)
			(xy 375.848621 -232.334054) (xy 374.98528 -232.334054) (xy 374.98528 -232.916984) (xy 374.985355 -232.921194)
			(xy 374.986758 -232.929495) (xy 374.988074 -232.933494) (xy 374.995948 -232.956354) (xy 375.00052 -232.962704)
			(xy 375.01456 -232.982526) (xy 375.036846 -233.025683) (xy 375.052024 -233.071823) (xy 375.059713 -233.119782)
			(xy 375.059715 -233.14406) (xy 375.378467 -233.14406) (xy 375.382562 -233.093332) (xy 375.394741 -233.043918)
			(xy 375.414689 -232.997098) (xy 375.44189 -232.954084) (xy 375.475638 -232.91599) (xy 375.51506 -232.883803)
			(xy 375.559134 -232.858357) (xy 375.60672 -232.84031) (xy 375.656584 -232.83013) (xy 375.707436 -232.828081)
			(xy 375.757957 -232.834215) (xy 375.806841 -232.848375) (xy 375.85282 -232.870192) (xy 375.894704 -232.899102)
			(xy 375.931408 -232.934357) (xy 375.961981 -232.975043) (xy 375.985632 -233.020106) (xy 376.001748 -233.06838)
			(xy 376.009912 -233.118614) (xy 376.010424 -233.14406) (xy 376.328952 -233.14406) (xy 376.332912 -233.095006)
			(xy 376.344689 -233.047222) (xy 376.36398 -233.001946) (xy 376.390283 -232.96035) (xy 376.422918 -232.923513)
			(xy 376.461039 -232.892388) (xy 376.50366 -232.867781) (xy 376.549676 -232.850329) (xy 376.597895 -232.840485)
			(xy 376.64707 -232.838504) (xy 376.695925 -232.844436) (xy 376.743196 -232.858128) (xy 376.787658 -232.879226)
			(xy 376.828161 -232.907182) (xy 376.863654 -232.941274) (xy 376.893219 -232.980618) (xy 376.91609 -233.024195)
			(xy 376.931674 -233.070876) (xy 376.939569 -233.119453) (xy 376.940064 -233.14406) (xy 377.258575 -233.14406)
			(xy 377.26267 -233.093332) (xy 377.274849 -233.043918) (xy 377.294797 -232.997098) (xy 377.321998 -232.954084)
			(xy 377.355746 -232.91599) (xy 377.395168 -232.883803) (xy 377.439242 -232.858357) (xy 377.486828 -232.84031)
			(xy 377.536692 -232.83013) (xy 377.587544 -232.828081) (xy 377.638065 -232.834215) (xy 377.686949 -232.848375)
			(xy 377.732928 -232.870192) (xy 377.774812 -232.899102) (xy 377.811516 -232.934357) (xy 377.842089 -232.975043)
			(xy 377.86574 -233.020106) (xy 377.881856 -233.06838) (xy 377.89002 -233.118614) (xy 377.890532 -233.14406)
			(xy 378.20906 -233.14406) (xy 378.21302 -233.095006) (xy 378.224797 -233.047222) (xy 378.244088 -233.001946)
			(xy 378.270391 -232.96035) (xy 378.303026 -232.923513) (xy 378.341147 -232.892388) (xy 378.383768 -232.867781)
			(xy 378.429784 -232.850329) (xy 378.478003 -232.840485) (xy 378.527178 -232.838504) (xy 378.576033 -232.844436)
			(xy 378.623304 -232.858128) (xy 378.667766 -232.879226) (xy 378.708269 -232.907182) (xy 378.743762 -232.941274)
			(xy 378.773327 -232.980618) (xy 378.796198 -233.024195) (xy 378.811782 -233.070876) (xy 378.819677 -233.119453)
			(xy 378.820172 -233.14406) (xy 379.138683 -233.14406) (xy 379.142778 -233.093332) (xy 379.154957 -233.043918)
			(xy 379.174905 -232.997098) (xy 379.202106 -232.954084) (xy 379.235854 -232.91599) (xy 379.275276 -232.883803)
			(xy 379.31935 -232.858357) (xy 379.366936 -232.84031) (xy 379.4168 -232.83013) (xy 379.467652 -232.828081)
			(xy 379.518173 -232.834215) (xy 379.567057 -232.848375) (xy 379.613036 -232.870192) (xy 379.65492 -232.899102)
			(xy 379.691624 -232.934357) (xy 379.722197 -232.975043) (xy 379.745848 -233.020106) (xy 379.761964 -233.06838)
			(xy 379.770128 -233.118614) (xy 379.77064 -233.14406) (xy 380.078483 -233.14406) (xy 380.082578 -233.093332)
			(xy 380.094757 -233.043918) (xy 380.114705 -232.997098) (xy 380.141906 -232.954084) (xy 380.175654 -232.91599)
			(xy 380.215076 -232.883803) (xy 380.25915 -232.858357) (xy 380.306736 -232.84031) (xy 380.3566 -232.83013)
			(xy 380.407452 -232.828081) (xy 380.457973 -232.834215) (xy 380.506857 -232.848375) (xy 380.552836 -232.870192)
			(xy 380.59472 -232.899102) (xy 380.631424 -232.934357) (xy 380.661997 -232.975043) (xy 380.685648 -233.020106)
			(xy 380.701764 -233.06838) (xy 380.709928 -233.118614) (xy 380.71044 -233.14406) (xy 381.028968 -233.14406)
			(xy 381.032928 -233.095006) (xy 381.044705 -233.047222) (xy 381.063996 -233.001946) (xy 381.090299 -232.96035)
			(xy 381.122934 -232.923513) (xy 381.161055 -232.892388) (xy 381.203676 -232.867781) (xy 381.249692 -232.850329)
			(xy 381.297911 -232.840485) (xy 381.347086 -232.838504) (xy 381.395941 -232.844436) (xy 381.443212 -232.858128)
			(xy 381.487674 -232.879226) (xy 381.528177 -232.907182) (xy 381.56367 -232.941274) (xy 381.593235 -232.980618)
			(xy 381.616106 -233.024195) (xy 381.63169 -233.070876) (xy 381.639585 -233.119453) (xy 381.64008 -233.14406)
			(xy 381.958591 -233.14406) (xy 381.962686 -233.093332) (xy 381.974865 -233.043918) (xy 381.994813 -232.997098)
			(xy 382.022014 -232.954084) (xy 382.055762 -232.91599) (xy 382.095184 -232.883803) (xy 382.139258 -232.858357)
			(xy 382.186844 -232.84031) (xy 382.236708 -232.83013) (xy 382.28756 -232.828081) (xy 382.338081 -232.834215)
			(xy 382.386965 -232.848375) (xy 382.432944 -232.870192) (xy 382.474828 -232.899102) (xy 382.511532 -232.934357)
			(xy 382.542105 -232.975043) (xy 382.565756 -233.020106) (xy 382.581872 -233.06838) (xy 382.590036 -233.118614)
			(xy 382.590548 -233.14406) (xy 382.909076 -233.14406) (xy 382.913036 -233.095006) (xy 382.924813 -233.047222)
			(xy 382.944104 -233.001946) (xy 382.970407 -232.96035) (xy 383.003042 -232.923513) (xy 383.041163 -232.892388)
			(xy 383.083784 -232.867781) (xy 383.1298 -232.850329) (xy 383.178019 -232.840485) (xy 383.227194 -232.838504)
			(xy 383.276049 -232.844436) (xy 383.32332 -232.858128) (xy 383.367782 -232.879226) (xy 383.408285 -232.907182)
			(xy 383.443778 -232.941274) (xy 383.473343 -232.980618) (xy 383.496214 -233.024195) (xy 383.511798 -233.070876)
			(xy 383.519693 -233.119453) (xy 383.520188 -233.14406) (xy 383.838699 -233.14406) (xy 383.842794 -233.093332)
			(xy 383.854973 -233.043918) (xy 383.874921 -232.997098) (xy 383.902122 -232.954084) (xy 383.93587 -232.91599)
			(xy 383.975292 -232.883803) (xy 384.019366 -232.858357) (xy 384.066952 -232.84031) (xy 384.116816 -232.83013)
			(xy 384.167668 -232.828081) (xy 384.218189 -232.834215) (xy 384.267073 -232.848375) (xy 384.313052 -232.870192)
			(xy 384.354936 -232.899102) (xy 384.39164 -232.934357) (xy 384.422213 -232.975043) (xy 384.445864 -233.020106)
			(xy 384.46198 -233.06838) (xy 384.470144 -233.118614) (xy 384.470656 -233.14406) (xy 384.78893 -233.14406)
			(xy 384.79289 -233.095006) (xy 384.804667 -233.047222) (xy 384.823958 -233.001946) (xy 384.850261 -232.96035)
			(xy 384.882896 -232.923513) (xy 384.921017 -232.892388) (xy 384.963638 -232.867781) (xy 385.009654 -232.850329)
			(xy 385.057873 -232.840485) (xy 385.107048 -232.838504) (xy 385.155903 -232.844436) (xy 385.203174 -232.858128)
			(xy 385.247636 -232.879226) (xy 385.288139 -232.907182) (xy 385.323632 -232.941274) (xy 385.353197 -232.980618)
			(xy 385.376068 -233.024195) (xy 385.391652 -233.070876) (xy 385.399547 -233.119453) (xy 385.400042 -233.14406)
			(xy 385.718553 -233.14406) (xy 385.722648 -233.093332) (xy 385.734827 -233.043918) (xy 385.754775 -232.997098)
			(xy 385.781976 -232.954084) (xy 385.815724 -232.91599) (xy 385.855146 -232.883803) (xy 385.89922 -232.858357)
			(xy 385.946806 -232.84031) (xy 385.99667 -232.83013) (xy 386.047522 -232.828081) (xy 386.098043 -232.834215)
			(xy 386.146927 -232.848375) (xy 386.192906 -232.870192) (xy 386.23479 -232.899102) (xy 386.271494 -232.934357)
			(xy 386.302067 -232.975043) (xy 386.325718 -233.020106) (xy 386.341834 -233.06838) (xy 386.349998 -233.118614)
			(xy 386.35051 -233.14406) (xy 386.658607 -233.14406) (xy 386.662702 -233.093332) (xy 386.674881 -233.043918)
			(xy 386.694829 -232.997098) (xy 386.72203 -232.954084) (xy 386.755778 -232.91599) (xy 386.7952 -232.883803)
			(xy 386.839274 -232.858357) (xy 386.88686 -232.84031) (xy 386.936724 -232.83013) (xy 386.987576 -232.828081)
			(xy 387.038097 -232.834215) (xy 387.086981 -232.848375) (xy 387.13296 -232.870192) (xy 387.174844 -232.899102)
			(xy 387.211548 -232.934357) (xy 387.242121 -232.975043) (xy 387.265772 -233.020106) (xy 387.281888 -233.06838)
			(xy 387.290052 -233.118614) (xy 387.290564 -233.14406) (xy 387.609092 -233.14406) (xy 387.613052 -233.095006)
			(xy 387.624829 -233.047222) (xy 387.64412 -233.001946) (xy 387.670423 -232.96035) (xy 387.703058 -232.923513)
			(xy 387.741179 -232.892388) (xy 387.7838 -232.867781) (xy 387.829816 -232.850329) (xy 387.878035 -232.840485)
			(xy 387.92721 -232.838504) (xy 387.976065 -232.844436) (xy 388.023336 -232.858128) (xy 388.067798 -232.879226)
			(xy 388.108301 -232.907182) (xy 388.143794 -232.941274) (xy 388.173359 -232.980618) (xy 388.19623 -233.024195)
			(xy 388.211814 -233.070876) (xy 388.219709 -233.119453) (xy 388.220204 -233.14406) (xy 388.538715 -233.14406)
			(xy 388.54281 -233.093332) (xy 388.554989 -233.043918) (xy 388.574937 -232.997098) (xy 388.602138 -232.954084)
			(xy 388.635886 -232.91599) (xy 388.675308 -232.883803) (xy 388.719382 -232.858357) (xy 388.766968 -232.84031)
			(xy 388.816832 -232.83013) (xy 388.867684 -232.828081) (xy 388.918205 -232.834215) (xy 388.967089 -232.848375)
			(xy 389.013068 -232.870192) (xy 389.054952 -232.899102) (xy 389.091656 -232.934357) (xy 389.122229 -232.975043)
			(xy 389.14588 -233.020106) (xy 389.161996 -233.06838) (xy 389.17016 -233.118614) (xy 389.170672 -233.14406)
			(xy 389.488946 -233.14406) (xy 389.492906 -233.095006) (xy 389.504683 -233.047222) (xy 389.523974 -233.001946)
			(xy 389.550277 -232.96035) (xy 389.582912 -232.923513) (xy 389.621033 -232.892388) (xy 389.663654 -232.867781)
			(xy 389.70967 -232.850329) (xy 389.757889 -232.840485) (xy 389.807064 -232.838504) (xy 389.855919 -232.844436)
			(xy 389.90319 -232.858128) (xy 389.947652 -232.879226) (xy 389.988155 -232.907182) (xy 390.023648 -232.941274)
			(xy 390.053213 -232.980618) (xy 390.076084 -233.024195) (xy 390.091668 -233.070876) (xy 390.099563 -233.119453)
			(xy 390.100058 -233.14406) (xy 390.418569 -233.14406) (xy 390.422664 -233.093332) (xy 390.434843 -233.043918)
			(xy 390.454791 -232.997098) (xy 390.481992 -232.954084) (xy 390.51574 -232.91599) (xy 390.555162 -232.883803)
			(xy 390.599236 -232.858357) (xy 390.646822 -232.84031) (xy 390.696686 -232.83013) (xy 390.747538 -232.828081)
			(xy 390.798059 -232.834215) (xy 390.846943 -232.848375) (xy 390.892922 -232.870192) (xy 390.934806 -232.899102)
			(xy 390.97151 -232.934357) (xy 391.002083 -232.975043) (xy 391.025734 -233.020106) (xy 391.04185 -233.06838)
			(xy 391.050014 -233.118614) (xy 391.050526 -233.14406) (xy 391.369054 -233.14406) (xy 391.373014 -233.095006)
			(xy 391.384791 -233.047222) (xy 391.404082 -233.001946) (xy 391.430385 -232.96035) (xy 391.46302 -232.923513)
			(xy 391.501141 -232.892388) (xy 391.543762 -232.867781) (xy 391.589778 -232.850329) (xy 391.637997 -232.840485)
			(xy 391.687172 -232.838504) (xy 391.736027 -232.844436) (xy 391.783298 -232.858128) (xy 391.82776 -232.879226)
			(xy 391.868263 -232.907182) (xy 391.903756 -232.941274) (xy 391.933321 -232.980618) (xy 391.956192 -233.024195)
			(xy 391.971776 -233.070876) (xy 391.979671 -233.119453) (xy 391.980166 -233.14406) (xy 391.979671 -233.168667)
			(xy 391.971776 -233.217244) (xy 391.956192 -233.263925) (xy 391.933321 -233.307502) (xy 391.903756 -233.346846)
			(xy 391.868263 -233.380938) (xy 391.82776 -233.408894) (xy 391.825433 -233.409998) (xy 394.377176 -233.409998)
			(xy 394.381136 -233.360944) (xy 394.392913 -233.31316) (xy 394.412204 -233.267884) (xy 394.438507 -233.226288)
			(xy 394.471142 -233.189451) (xy 394.509263 -233.158326) (xy 394.551884 -233.133719) (xy 394.5979 -233.116267)
			(xy 394.646119 -233.106423) (xy 394.695294 -233.104442) (xy 394.744149 -233.110374) (xy 394.79142 -233.124066)
			(xy 394.835882 -233.145164) (xy 394.876385 -233.17312) (xy 394.911878 -233.207212) (xy 394.941443 -233.246556)
			(xy 394.964314 -233.290133) (xy 394.979898 -233.336814) (xy 394.987793 -233.385391) (xy 394.988288 -233.409998)
			(xy 394.987793 -233.434605) (xy 394.979898 -233.483182) (xy 394.964314 -233.529863) (xy 394.941443 -233.57344)
			(xy 394.911878 -233.612784) (xy 394.876385 -233.646876) (xy 394.835882 -233.674832) (xy 394.79142 -233.69593)
			(xy 394.744149 -233.709622) (xy 394.695294 -233.715554) (xy 394.646119 -233.713573) (xy 394.5979 -233.703729)
			(xy 394.551884 -233.686277) (xy 394.509263 -233.66167) (xy 394.471142 -233.630545) (xy 394.438507 -233.593708)
			(xy 394.412204 -233.552112) (xy 394.392913 -233.506836) (xy 394.381136 -233.459052) (xy 394.377176 -233.409998)
			(xy 391.825433 -233.409998) (xy 391.783298 -233.429992) (xy 391.736027 -233.443684) (xy 391.687172 -233.449616)
			(xy 391.637997 -233.447635) (xy 391.589778 -233.437791) (xy 391.543762 -233.420339) (xy 391.501141 -233.395732)
			(xy 391.46302 -233.364607) (xy 391.430385 -233.32777) (xy 391.404082 -233.286174) (xy 391.384791 -233.240898)
			(xy 391.373014 -233.193114) (xy 391.369054 -233.14406) (xy 391.050526 -233.14406) (xy 391.050014 -233.169506)
			(xy 391.04185 -233.21974) (xy 391.025734 -233.268014) (xy 391.002083 -233.313077) (xy 390.97151 -233.353763)
			(xy 390.934806 -233.389018) (xy 390.892922 -233.417928) (xy 390.846943 -233.439745) (xy 390.798059 -233.453905)
			(xy 390.747538 -233.460039) (xy 390.696686 -233.45799) (xy 390.646822 -233.44781) (xy 390.599236 -233.429763)
			(xy 390.555162 -233.404317) (xy 390.51574 -233.37213) (xy 390.481992 -233.334036) (xy 390.454791 -233.291022)
			(xy 390.434843 -233.244202) (xy 390.422664 -233.194788) (xy 390.418569 -233.14406) (xy 390.100058 -233.14406)
			(xy 390.099563 -233.168667) (xy 390.091668 -233.217244) (xy 390.076084 -233.263925) (xy 390.053213 -233.307502)
			(xy 390.023648 -233.346846) (xy 389.988155 -233.380938) (xy 389.947652 -233.408894) (xy 389.90319 -233.429992)
			(xy 389.855919 -233.443684) (xy 389.807064 -233.449616) (xy 389.757889 -233.447635) (xy 389.70967 -233.437791)
			(xy 389.663654 -233.420339) (xy 389.621033 -233.395732) (xy 389.582912 -233.364607) (xy 389.550277 -233.32777)
			(xy 389.523974 -233.286174) (xy 389.504683 -233.240898) (xy 389.492906 -233.193114) (xy 389.488946 -233.14406)
			(xy 389.170672 -233.14406) (xy 389.17016 -233.169506) (xy 389.161996 -233.21974) (xy 389.14588 -233.268014)
			(xy 389.122229 -233.313077) (xy 389.091656 -233.353763) (xy 389.054952 -233.389018) (xy 389.013068 -233.417928)
			(xy 388.967089 -233.439745) (xy 388.918205 -233.453905) (xy 388.867684 -233.460039) (xy 388.816832 -233.45799)
			(xy 388.766968 -233.44781) (xy 388.719382 -233.429763) (xy 388.675308 -233.404317) (xy 388.635886 -233.37213)
			(xy 388.602138 -233.334036) (xy 388.574937 -233.291022) (xy 388.554989 -233.244202) (xy 388.54281 -233.194788)
			(xy 388.538715 -233.14406) (xy 388.220204 -233.14406) (xy 388.219709 -233.168667) (xy 388.211814 -233.217244)
			(xy 388.19623 -233.263925) (xy 388.173359 -233.307502) (xy 388.143794 -233.346846) (xy 388.108301 -233.380938)
			(xy 388.067798 -233.408894) (xy 388.023336 -233.429992) (xy 387.976065 -233.443684) (xy 387.92721 -233.449616)
			(xy 387.878035 -233.447635) (xy 387.829816 -233.437791) (xy 387.7838 -233.420339) (xy 387.741179 -233.395732)
			(xy 387.703058 -233.364607) (xy 387.670423 -233.32777) (xy 387.64412 -233.286174) (xy 387.624829 -233.240898)
			(xy 387.613052 -233.193114) (xy 387.609092 -233.14406) (xy 387.290564 -233.14406) (xy 387.290052 -233.169506)
			(xy 387.281888 -233.21974) (xy 387.265772 -233.268014) (xy 387.242121 -233.313077) (xy 387.211548 -233.353763)
			(xy 387.174844 -233.389018) (xy 387.13296 -233.417928) (xy 387.086981 -233.439745) (xy 387.038097 -233.453905)
			(xy 386.987576 -233.460039) (xy 386.936724 -233.45799) (xy 386.88686 -233.44781) (xy 386.839274 -233.429763)
			(xy 386.7952 -233.404317) (xy 386.755778 -233.37213) (xy 386.72203 -233.334036) (xy 386.694829 -233.291022)
			(xy 386.674881 -233.244202) (xy 386.662702 -233.194788) (xy 386.658607 -233.14406) (xy 386.35051 -233.14406)
			(xy 386.349998 -233.169506) (xy 386.341834 -233.21974) (xy 386.325718 -233.268014) (xy 386.302067 -233.313077)
			(xy 386.271494 -233.353763) (xy 386.23479 -233.389018) (xy 386.192906 -233.417928) (xy 386.146927 -233.439745)
			(xy 386.098043 -233.453905) (xy 386.047522 -233.460039) (xy 385.99667 -233.45799) (xy 385.946806 -233.44781)
			(xy 385.89922 -233.429763) (xy 385.855146 -233.404317) (xy 385.815724 -233.37213) (xy 385.781976 -233.334036)
			(xy 385.754775 -233.291022) (xy 385.734827 -233.244202) (xy 385.722648 -233.194788) (xy 385.718553 -233.14406)
			(xy 385.400042 -233.14406) (xy 385.399547 -233.168667) (xy 385.391652 -233.217244) (xy 385.376068 -233.263925)
			(xy 385.353197 -233.307502) (xy 385.323632 -233.346846) (xy 385.288139 -233.380938) (xy 385.247636 -233.408894)
			(xy 385.203174 -233.429992) (xy 385.155903 -233.443684) (xy 385.107048 -233.449616) (xy 385.057873 -233.447635)
			(xy 385.009654 -233.437791) (xy 384.963638 -233.420339) (xy 384.921017 -233.395732) (xy 384.882896 -233.364607)
			(xy 384.850261 -233.32777) (xy 384.823958 -233.286174) (xy 384.804667 -233.240898) (xy 384.79289 -233.193114)
			(xy 384.78893 -233.14406) (xy 384.470656 -233.14406) (xy 384.470144 -233.169506) (xy 384.46198 -233.21974)
			(xy 384.445864 -233.268014) (xy 384.422213 -233.313077) (xy 384.39164 -233.353763) (xy 384.354936 -233.389018)
			(xy 384.313052 -233.417928) (xy 384.267073 -233.439745) (xy 384.218189 -233.453905) (xy 384.167668 -233.460039)
			(xy 384.116816 -233.45799) (xy 384.066952 -233.44781) (xy 384.019366 -233.429763) (xy 383.975292 -233.404317)
			(xy 383.93587 -233.37213) (xy 383.902122 -233.334036) (xy 383.874921 -233.291022) (xy 383.854973 -233.244202)
			(xy 383.842794 -233.194788) (xy 383.838699 -233.14406) (xy 383.520188 -233.14406) (xy 383.519693 -233.168667)
			(xy 383.511798 -233.217244) (xy 383.496214 -233.263925) (xy 383.473343 -233.307502) (xy 383.443778 -233.346846)
			(xy 383.408285 -233.380938) (xy 383.367782 -233.408894) (xy 383.32332 -233.429992) (xy 383.276049 -233.443684)
			(xy 383.227194 -233.449616) (xy 383.178019 -233.447635) (xy 383.1298 -233.437791) (xy 383.083784 -233.420339)
			(xy 383.041163 -233.395732) (xy 383.003042 -233.364607) (xy 382.970407 -233.32777) (xy 382.944104 -233.286174)
			(xy 382.924813 -233.240898) (xy 382.913036 -233.193114) (xy 382.909076 -233.14406) (xy 382.590548 -233.14406)
			(xy 382.590036 -233.169506) (xy 382.581872 -233.21974) (xy 382.565756 -233.268014) (xy 382.542105 -233.313077)
			(xy 382.511532 -233.353763) (xy 382.474828 -233.389018) (xy 382.432944 -233.417928) (xy 382.386965 -233.439745)
			(xy 382.338081 -233.453905) (xy 382.28756 -233.460039) (xy 382.236708 -233.45799) (xy 382.186844 -233.44781)
			(xy 382.139258 -233.429763) (xy 382.095184 -233.404317) (xy 382.055762 -233.37213) (xy 382.022014 -233.334036)
			(xy 381.994813 -233.291022) (xy 381.974865 -233.244202) (xy 381.962686 -233.194788) (xy 381.958591 -233.14406)
			(xy 381.64008 -233.14406) (xy 381.639585 -233.168667) (xy 381.63169 -233.217244) (xy 381.616106 -233.263925)
			(xy 381.593235 -233.307502) (xy 381.56367 -233.346846) (xy 381.528177 -233.380938) (xy 381.487674 -233.408894)
			(xy 381.443212 -233.429992) (xy 381.395941 -233.443684) (xy 381.347086 -233.449616) (xy 381.297911 -233.447635)
			(xy 381.249692 -233.437791) (xy 381.203676 -233.420339) (xy 381.161055 -233.395732) (xy 381.122934 -233.364607)
			(xy 381.090299 -233.32777) (xy 381.063996 -233.286174) (xy 381.044705 -233.240898) (xy 381.032928 -233.193114)
			(xy 381.028968 -233.14406) (xy 380.71044 -233.14406) (xy 380.709928 -233.169506) (xy 380.701764 -233.21974)
			(xy 380.685648 -233.268014) (xy 380.661997 -233.313077) (xy 380.631424 -233.353763) (xy 380.59472 -233.389018)
			(xy 380.552836 -233.417928) (xy 380.506857 -233.439745) (xy 380.457973 -233.453905) (xy 380.407452 -233.460039)
			(xy 380.3566 -233.45799) (xy 380.306736 -233.44781) (xy 380.25915 -233.429763) (xy 380.215076 -233.404317)
			(xy 380.175654 -233.37213) (xy 380.141906 -233.334036) (xy 380.114705 -233.291022) (xy 380.094757 -233.244202)
			(xy 380.082578 -233.194788) (xy 380.078483 -233.14406) (xy 379.77064 -233.14406) (xy 379.770128 -233.169506)
			(xy 379.761964 -233.21974) (xy 379.745848 -233.268014) (xy 379.722197 -233.313077) (xy 379.691624 -233.353763)
			(xy 379.65492 -233.389018) (xy 379.613036 -233.417928) (xy 379.567057 -233.439745) (xy 379.518173 -233.453905)
			(xy 379.467652 -233.460039) (xy 379.4168 -233.45799) (xy 379.366936 -233.44781) (xy 379.31935 -233.429763)
			(xy 379.275276 -233.404317) (xy 379.235854 -233.37213) (xy 379.202106 -233.334036) (xy 379.174905 -233.291022)
			(xy 379.154957 -233.244202) (xy 379.142778 -233.194788) (xy 379.138683 -233.14406) (xy 378.820172 -233.14406)
			(xy 378.819677 -233.168667) (xy 378.811782 -233.217244) (xy 378.796198 -233.263925) (xy 378.773327 -233.307502)
			(xy 378.743762 -233.346846) (xy 378.708269 -233.380938) (xy 378.667766 -233.408894) (xy 378.623304 -233.429992)
			(xy 378.576033 -233.443684) (xy 378.527178 -233.449616) (xy 378.478003 -233.447635) (xy 378.429784 -233.437791)
			(xy 378.383768 -233.420339) (xy 378.341147 -233.395732) (xy 378.303026 -233.364607) (xy 378.270391 -233.32777)
			(xy 378.244088 -233.286174) (xy 378.224797 -233.240898) (xy 378.21302 -233.193114) (xy 378.20906 -233.14406)
			(xy 377.890532 -233.14406) (xy 377.89002 -233.169506) (xy 377.881856 -233.21974) (xy 377.86574 -233.268014)
			(xy 377.842089 -233.313077) (xy 377.811516 -233.353763) (xy 377.774812 -233.389018) (xy 377.732928 -233.417928)
			(xy 377.686949 -233.439745) (xy 377.638065 -233.453905) (xy 377.587544 -233.460039) (xy 377.536692 -233.45799)
			(xy 377.486828 -233.44781) (xy 377.439242 -233.429763) (xy 377.395168 -233.404317) (xy 377.355746 -233.37213)
			(xy 377.321998 -233.334036) (xy 377.294797 -233.291022) (xy 377.274849 -233.244202) (xy 377.26267 -233.194788)
			(xy 377.258575 -233.14406) (xy 376.940064 -233.14406) (xy 376.939569 -233.168667) (xy 376.931674 -233.217244)
			(xy 376.91609 -233.263925) (xy 376.893219 -233.307502) (xy 376.863654 -233.346846) (xy 376.828161 -233.380938)
			(xy 376.787658 -233.408894) (xy 376.743196 -233.429992) (xy 376.695925 -233.443684) (xy 376.64707 -233.449616)
			(xy 376.597895 -233.447635) (xy 376.549676 -233.437791) (xy 376.50366 -233.420339) (xy 376.461039 -233.395732)
			(xy 376.422918 -233.364607) (xy 376.390283 -233.32777) (xy 376.36398 -233.286174) (xy 376.344689 -233.240898)
			(xy 376.332912 -233.193114) (xy 376.328952 -233.14406) (xy 376.010424 -233.14406) (xy 376.009912 -233.169506)
			(xy 376.001748 -233.21974) (xy 375.985632 -233.268014) (xy 375.961981 -233.313077) (xy 375.931408 -233.353763)
			(xy 375.894704 -233.389018) (xy 375.85282 -233.417928) (xy 375.806841 -233.439745) (xy 375.757957 -233.453905)
			(xy 375.707436 -233.460039) (xy 375.656584 -233.45799) (xy 375.60672 -233.44781) (xy 375.559134 -233.429763)
			(xy 375.51506 -233.404317) (xy 375.475638 -233.37213) (xy 375.44189 -233.334036) (xy 375.414689 -233.291022)
			(xy 375.394741 -233.244202) (xy 375.382562 -233.194788) (xy 375.378467 -233.14406) (xy 375.059715 -233.14406)
			(xy 375.059718 -233.168354) (xy 375.052039 -233.216315) (xy 375.036871 -233.262457) (xy 375.014594 -233.305619)
			(xy 375.00052 -233.325416) (xy 374.995948 -233.331766) (xy 374.988074 -233.354626) (xy 374.986786 -233.358633)
			(xy 374.985374 -233.366929) (xy 374.98528 -233.371136) (xy 374.98528 -233.571288) (xy 374.98528 -233.57459)
			(xy 374.98646 -233.585341) (xy 374.996586 -233.60443) (xy 375.004838 -233.61142) (xy 375.00687 -233.612944)
			(xy 375.074688 -233.660696) (xy 375.085076 -233.667273) (xy 375.109431 -233.670454) (xy 375.12117 -233.666792)
			(xy 375.121932 -233.666538) (xy 375.12879 -233.664252) (xy 375.152133 -233.657028) (xy 375.200371 -233.649249)
			(xy 375.224802 -233.648758) (xy 375.25006 -233.64928) (xy 375.299887 -233.657595) (xy 375.347666 -233.673998)
			(xy 375.392093 -233.698041) (xy 375.431958 -233.729069) (xy 375.466171 -233.766234) (xy 375.493801 -233.808525)
			(xy 375.514093 -233.854786) (xy 375.526493 -233.903756) (xy 375.530662 -233.954066) (xy 375.848621 -233.954066)
			(xy 375.852716 -233.903338) (xy 375.864895 -233.853924) (xy 375.884843 -233.807104) (xy 375.912044 -233.76409)
			(xy 375.945792 -233.725996) (xy 375.985214 -233.693809) (xy 376.029288 -233.668363) (xy 376.076874 -233.650316)
			(xy 376.126738 -233.640136) (xy 376.17759 -233.638087) (xy 376.228111 -233.644221) (xy 376.276995 -233.658381)
			(xy 376.322974 -233.680198) (xy 376.364858 -233.709108) (xy 376.401562 -233.744363) (xy 376.432135 -233.785049)
			(xy 376.455786 -233.830112) (xy 376.471902 -233.878386) (xy 376.480066 -233.92862) (xy 376.480578 -233.954066)
			(xy 376.788675 -233.954066) (xy 376.79277 -233.903338) (xy 376.804949 -233.853924) (xy 376.824897 -233.807104)
			(xy 376.852098 -233.76409) (xy 376.885846 -233.725996) (xy 376.925268 -233.693809) (xy 376.969342 -233.668363)
			(xy 377.016928 -233.650316) (xy 377.066792 -233.640136) (xy 377.117644 -233.638087) (xy 377.168165 -233.644221)
			(xy 377.217049 -233.658381) (xy 377.263028 -233.680198) (xy 377.304912 -233.709108) (xy 377.341616 -233.744363)
			(xy 377.372189 -233.785049) (xy 377.39584 -233.830112) (xy 377.411956 -233.878386) (xy 377.42012 -233.92862)
			(xy 377.420632 -233.954066) (xy 377.738906 -233.954066) (xy 377.742866 -233.905012) (xy 377.754643 -233.857228)
			(xy 377.773934 -233.811952) (xy 377.800237 -233.770356) (xy 377.832872 -233.733519) (xy 377.870993 -233.702394)
			(xy 377.913614 -233.677787) (xy 377.95963 -233.660335) (xy 378.007849 -233.650491) (xy 378.057024 -233.64851)
			(xy 378.105879 -233.654442) (xy 378.15315 -233.668134) (xy 378.197612 -233.689232) (xy 378.238115 -233.717188)
			(xy 378.273608 -233.75128) (xy 378.303173 -233.790624) (xy 378.326044 -233.834201) (xy 378.341628 -233.880882)
			(xy 378.349523 -233.929459) (xy 378.350018 -233.954066) (xy 378.668529 -233.954066) (xy 378.672624 -233.903338)
			(xy 378.684803 -233.853924) (xy 378.704751 -233.807104) (xy 378.731952 -233.76409) (xy 378.7657 -233.725996)
			(xy 378.805122 -233.693809) (xy 378.849196 -233.668363) (xy 378.896782 -233.650316) (xy 378.946646 -233.640136)
			(xy 378.997498 -233.638087) (xy 379.048019 -233.644221) (xy 379.096903 -233.658381) (xy 379.142882 -233.680198)
			(xy 379.184766 -233.709108) (xy 379.22147 -233.744363) (xy 379.252043 -233.785049) (xy 379.275694 -233.830112)
			(xy 379.29181 -233.878386) (xy 379.299974 -233.92862) (xy 379.300486 -233.954066) (xy 379.619014 -233.954066)
			(xy 379.622974 -233.905012) (xy 379.634751 -233.857228) (xy 379.654042 -233.811952) (xy 379.680345 -233.770356)
			(xy 379.71298 -233.733519) (xy 379.751101 -233.702394) (xy 379.793722 -233.677787) (xy 379.839738 -233.660335)
			(xy 379.887957 -233.650491) (xy 379.937132 -233.64851) (xy 379.985987 -233.654442) (xy 380.033258 -233.668134)
			(xy 380.07772 -233.689232) (xy 380.118223 -233.717188) (xy 380.153716 -233.75128) (xy 380.183281 -233.790624)
			(xy 380.206152 -233.834201) (xy 380.221736 -233.880882) (xy 380.229631 -233.929459) (xy 380.230126 -233.954066)
			(xy 380.548637 -233.954066) (xy 380.552732 -233.903338) (xy 380.564911 -233.853924) (xy 380.584859 -233.807104)
			(xy 380.61206 -233.76409) (xy 380.645808 -233.725996) (xy 380.68523 -233.693809) (xy 380.729304 -233.668363)
			(xy 380.77689 -233.650316) (xy 380.826754 -233.640136) (xy 380.877606 -233.638087) (xy 380.928127 -233.644221)
			(xy 380.977011 -233.658381) (xy 381.02299 -233.680198) (xy 381.064874 -233.709108) (xy 381.101578 -233.744363)
			(xy 381.132151 -233.785049) (xy 381.155802 -233.830112) (xy 381.171918 -233.878386) (xy 381.180082 -233.92862)
			(xy 381.180594 -233.954066) (xy 381.499122 -233.954066) (xy 381.503082 -233.905012) (xy 381.514859 -233.857228)
			(xy 381.53415 -233.811952) (xy 381.560453 -233.770356) (xy 381.593088 -233.733519) (xy 381.631209 -233.702394)
			(xy 381.67383 -233.677787) (xy 381.719846 -233.660335) (xy 381.768065 -233.650491) (xy 381.81724 -233.64851)
			(xy 381.866095 -233.654442) (xy 381.913366 -233.668134) (xy 381.957828 -233.689232) (xy 381.998331 -233.717188)
			(xy 382.033824 -233.75128) (xy 382.063389 -233.790624) (xy 382.08626 -233.834201) (xy 382.101844 -233.880882)
			(xy 382.109739 -233.929459) (xy 382.110234 -233.954066) (xy 382.428491 -233.954066) (xy 382.432586 -233.903338)
			(xy 382.444765 -233.853924) (xy 382.464713 -233.807104) (xy 382.491914 -233.76409) (xy 382.525662 -233.725996)
			(xy 382.565084 -233.693809) (xy 382.609158 -233.668363) (xy 382.656744 -233.650316) (xy 382.706608 -233.640136)
			(xy 382.75746 -233.638087) (xy 382.807981 -233.644221) (xy 382.856865 -233.658381) (xy 382.902844 -233.680198)
			(xy 382.944728 -233.709108) (xy 382.981432 -233.744363) (xy 383.012005 -233.785049) (xy 383.035656 -233.830112)
			(xy 383.051772 -233.878386) (xy 383.059936 -233.92862) (xy 383.060448 -233.954066) (xy 383.368545 -233.954066)
			(xy 383.37264 -233.903338) (xy 383.384819 -233.853924) (xy 383.404767 -233.807104) (xy 383.431968 -233.76409)
			(xy 383.465716 -233.725996) (xy 383.505138 -233.693809) (xy 383.549212 -233.668363) (xy 383.596798 -233.650316)
			(xy 383.646662 -233.640136) (xy 383.697514 -233.638087) (xy 383.748035 -233.644221) (xy 383.796919 -233.658381)
			(xy 383.842898 -233.680198) (xy 383.884782 -233.709108) (xy 383.921486 -233.744363) (xy 383.952059 -233.785049)
			(xy 383.97571 -233.830112) (xy 383.991826 -233.878386) (xy 383.99999 -233.92862) (xy 384.000502 -233.954066)
			(xy 384.31903 -233.954066) (xy 384.32299 -233.905012) (xy 384.334767 -233.857228) (xy 384.354058 -233.811952)
			(xy 384.380361 -233.770356) (xy 384.412996 -233.733519) (xy 384.451117 -233.702394) (xy 384.493738 -233.677787)
			(xy 384.539754 -233.660335) (xy 384.587973 -233.650491) (xy 384.637148 -233.64851) (xy 384.686003 -233.654442)
			(xy 384.733274 -233.668134) (xy 384.777736 -233.689232) (xy 384.818239 -233.717188) (xy 384.853732 -233.75128)
			(xy 384.883297 -233.790624) (xy 384.906168 -233.834201) (xy 384.921752 -233.880882) (xy 384.929647 -233.929459)
			(xy 384.930142 -233.954066) (xy 385.248653 -233.954066) (xy 385.252748 -233.903338) (xy 385.264927 -233.853924)
			(xy 385.284875 -233.807104) (xy 385.312076 -233.76409) (xy 385.345824 -233.725996) (xy 385.385246 -233.693809)
			(xy 385.42932 -233.668363) (xy 385.476906 -233.650316) (xy 385.52677 -233.640136) (xy 385.577622 -233.638087)
			(xy 385.628143 -233.644221) (xy 385.677027 -233.658381) (xy 385.723006 -233.680198) (xy 385.76489 -233.709108)
			(xy 385.801594 -233.744363) (xy 385.832167 -233.785049) (xy 385.855818 -233.830112) (xy 385.871934 -233.878386)
			(xy 385.880098 -233.92862) (xy 385.88061 -233.954066) (xy 386.199138 -233.954066) (xy 386.203098 -233.905012)
			(xy 386.214875 -233.857228) (xy 386.234166 -233.811952) (xy 386.260469 -233.770356) (xy 386.293104 -233.733519)
			(xy 386.331225 -233.702394) (xy 386.373846 -233.677787) (xy 386.419862 -233.660335) (xy 386.468081 -233.650491)
			(xy 386.517256 -233.64851) (xy 386.566111 -233.654442) (xy 386.613382 -233.668134) (xy 386.657844 -233.689232)
			(xy 386.698347 -233.717188) (xy 386.73384 -233.75128) (xy 386.763405 -233.790624) (xy 386.786276 -233.834201)
			(xy 386.80186 -233.880882) (xy 386.809755 -233.929459) (xy 386.81025 -233.954066) (xy 387.128507 -233.954066)
			(xy 387.132602 -233.903338) (xy 387.144781 -233.853924) (xy 387.164729 -233.807104) (xy 387.19193 -233.76409)
			(xy 387.225678 -233.725996) (xy 387.2651 -233.693809) (xy 387.309174 -233.668363) (xy 387.35676 -233.650316)
			(xy 387.406624 -233.640136) (xy 387.457476 -233.638087) (xy 387.507997 -233.644221) (xy 387.556881 -233.658381)
			(xy 387.60286 -233.680198) (xy 387.644744 -233.709108) (xy 387.681448 -233.744363) (xy 387.712021 -233.785049)
			(xy 387.735672 -233.830112) (xy 387.751788 -233.878386) (xy 387.759952 -233.92862) (xy 387.760464 -233.954066)
			(xy 388.078992 -233.954066) (xy 388.082952 -233.905012) (xy 388.094729 -233.857228) (xy 388.11402 -233.811952)
			(xy 388.140323 -233.770356) (xy 388.172958 -233.733519) (xy 388.211079 -233.702394) (xy 388.2537 -233.677787)
			(xy 388.299716 -233.660335) (xy 388.347935 -233.650491) (xy 388.39711 -233.64851) (xy 388.445965 -233.654442)
			(xy 388.493236 -233.668134) (xy 388.537698 -233.689232) (xy 388.578201 -233.717188) (xy 388.613694 -233.75128)
			(xy 388.643259 -233.790624) (xy 388.66613 -233.834201) (xy 388.681714 -233.880882) (xy 388.689609 -233.929459)
			(xy 388.690104 -233.954066) (xy 389.008615 -233.954066) (xy 389.01271 -233.903338) (xy 389.024889 -233.853924)
			(xy 389.044837 -233.807104) (xy 389.072038 -233.76409) (xy 389.105786 -233.725996) (xy 389.145208 -233.693809)
			(xy 389.189282 -233.668363) (xy 389.236868 -233.650316) (xy 389.286732 -233.640136) (xy 389.337584 -233.638087)
			(xy 389.388105 -233.644221) (xy 389.436989 -233.658381) (xy 389.482968 -233.680198) (xy 389.524852 -233.709108)
			(xy 389.561556 -233.744363) (xy 389.592129 -233.785049) (xy 389.61578 -233.830112) (xy 389.631896 -233.878386)
			(xy 389.64006 -233.92862) (xy 389.640572 -233.954066) (xy 389.948669 -233.954066) (xy 389.952764 -233.903338)
			(xy 389.964943 -233.853924) (xy 389.984891 -233.807104) (xy 390.012092 -233.76409) (xy 390.04584 -233.725996)
			(xy 390.085262 -233.693809) (xy 390.129336 -233.668363) (xy 390.176922 -233.650316) (xy 390.226786 -233.640136)
			(xy 390.277638 -233.638087) (xy 390.328159 -233.644221) (xy 390.377043 -233.658381) (xy 390.423022 -233.680198)
			(xy 390.464906 -233.709108) (xy 390.50161 -233.744363) (xy 390.532183 -233.785049) (xy 390.555834 -233.830112)
			(xy 390.57195 -233.878386) (xy 390.580114 -233.92862) (xy 390.580626 -233.954066) (xy 390.8989 -233.954066)
			(xy 390.90286 -233.905012) (xy 390.914637 -233.857228) (xy 390.933928 -233.811952) (xy 390.960231 -233.770356)
			(xy 390.992866 -233.733519) (xy 391.030987 -233.702394) (xy 391.073608 -233.677787) (xy 391.119624 -233.660335)
			(xy 391.167843 -233.650491) (xy 391.217018 -233.64851) (xy 391.265873 -233.654442) (xy 391.313144 -233.668134)
			(xy 391.357606 -233.689232) (xy 391.398109 -233.717188) (xy 391.433602 -233.75128) (xy 391.463167 -233.790624)
			(xy 391.486038 -233.834201) (xy 391.501622 -233.880882) (xy 391.509517 -233.929459) (xy 391.510012 -233.954066)
			(xy 392.779008 -233.954066) (xy 392.782968 -233.905012) (xy 392.794745 -233.857228) (xy 392.814036 -233.811952)
			(xy 392.840339 -233.770356) (xy 392.872974 -233.733519) (xy 392.911095 -233.702394) (xy 392.953716 -233.677787)
			(xy 392.999732 -233.660335) (xy 393.047951 -233.650491) (xy 393.097126 -233.64851) (xy 393.145981 -233.654442)
			(xy 393.193252 -233.668134) (xy 393.237714 -233.689232) (xy 393.278217 -233.717188) (xy 393.31371 -233.75128)
			(xy 393.343275 -233.790624) (xy 393.366146 -233.834201) (xy 393.38173 -233.880882) (xy 393.389625 -233.929459)
			(xy 393.39012 -233.954066) (xy 393.389625 -233.978673) (xy 393.38173 -234.02725) (xy 393.366146 -234.073931)
			(xy 393.343275 -234.117508) (xy 393.31371 -234.156852) (xy 393.278217 -234.190944) (xy 393.237714 -234.2189)
			(xy 393.193252 -234.239998) (xy 393.145981 -234.25369) (xy 393.097126 -234.259622) (xy 393.047951 -234.257641)
			(xy 392.999732 -234.247797) (xy 392.953716 -234.230345) (xy 392.911095 -234.205738) (xy 392.872974 -234.174613)
			(xy 392.840339 -234.137776) (xy 392.814036 -234.09618) (xy 392.794745 -234.050904) (xy 392.782968 -234.00312)
			(xy 392.779008 -233.954066) (xy 391.510012 -233.954066) (xy 391.509517 -233.978673) (xy 391.501622 -234.02725)
			(xy 391.486038 -234.073931) (xy 391.463167 -234.117508) (xy 391.433602 -234.156852) (xy 391.398109 -234.190944)
			(xy 391.357606 -234.2189) (xy 391.313144 -234.239998) (xy 391.265873 -234.25369) (xy 391.217018 -234.259622)
			(xy 391.167843 -234.257641) (xy 391.119624 -234.247797) (xy 391.073608 -234.230345) (xy 391.030987 -234.205738)
			(xy 390.992866 -234.174613) (xy 390.960231 -234.137776) (xy 390.933928 -234.09618) (xy 390.914637 -234.050904)
			(xy 390.90286 -234.00312) (xy 390.8989 -233.954066) (xy 390.580626 -233.954066) (xy 390.580114 -233.979512)
			(xy 390.57195 -234.029746) (xy 390.555834 -234.07802) (xy 390.532183 -234.123083) (xy 390.50161 -234.163769)
			(xy 390.464906 -234.199024) (xy 390.423022 -234.227934) (xy 390.377043 -234.249751) (xy 390.328159 -234.263911)
			(xy 390.277638 -234.270045) (xy 390.226786 -234.267996) (xy 390.176922 -234.257816) (xy 390.129336 -234.239769)
			(xy 390.085262 -234.214323) (xy 390.04584 -234.182136) (xy 390.012092 -234.144042) (xy 389.984891 -234.101028)
			(xy 389.964943 -234.054208) (xy 389.952764 -234.004794) (xy 389.948669 -233.954066) (xy 389.640572 -233.954066)
			(xy 389.64006 -233.979512) (xy 389.631896 -234.029746) (xy 389.61578 -234.07802) (xy 389.592129 -234.123083)
			(xy 389.561556 -234.163769) (xy 389.524852 -234.199024) (xy 389.482968 -234.227934) (xy 389.436989 -234.249751)
			(xy 389.388105 -234.263911) (xy 389.337584 -234.270045) (xy 389.286732 -234.267996) (xy 389.236868 -234.257816)
			(xy 389.189282 -234.239769) (xy 389.145208 -234.214323) (xy 389.105786 -234.182136) (xy 389.072038 -234.144042)
			(xy 389.044837 -234.101028) (xy 389.024889 -234.054208) (xy 389.01271 -234.004794) (xy 389.008615 -233.954066)
			(xy 388.690104 -233.954066) (xy 388.689609 -233.978673) (xy 388.681714 -234.02725) (xy 388.66613 -234.073931)
			(xy 388.643259 -234.117508) (xy 388.613694 -234.156852) (xy 388.578201 -234.190944) (xy 388.537698 -234.2189)
			(xy 388.493236 -234.239998) (xy 388.445965 -234.25369) (xy 388.39711 -234.259622) (xy 388.347935 -234.257641)
			(xy 388.299716 -234.247797) (xy 388.2537 -234.230345) (xy 388.211079 -234.205738) (xy 388.172958 -234.174613)
			(xy 388.140323 -234.137776) (xy 388.11402 -234.09618) (xy 388.094729 -234.050904) (xy 388.082952 -234.00312)
			(xy 388.078992 -233.954066) (xy 387.760464 -233.954066) (xy 387.759952 -233.979512) (xy 387.751788 -234.029746)
			(xy 387.735672 -234.07802) (xy 387.712021 -234.123083) (xy 387.681448 -234.163769) (xy 387.644744 -234.199024)
			(xy 387.60286 -234.227934) (xy 387.556881 -234.249751) (xy 387.507997 -234.263911) (xy 387.457476 -234.270045)
			(xy 387.406624 -234.267996) (xy 387.35676 -234.257816) (xy 387.309174 -234.239769) (xy 387.2651 -234.214323)
			(xy 387.225678 -234.182136) (xy 387.19193 -234.144042) (xy 387.164729 -234.101028) (xy 387.144781 -234.054208)
			(xy 387.132602 -234.004794) (xy 387.128507 -233.954066) (xy 386.81025 -233.954066) (xy 386.809755 -233.978673)
			(xy 386.80186 -234.02725) (xy 386.786276 -234.073931) (xy 386.763405 -234.117508) (xy 386.73384 -234.156852)
			(xy 386.698347 -234.190944) (xy 386.657844 -234.2189) (xy 386.613382 -234.239998) (xy 386.566111 -234.25369)
			(xy 386.517256 -234.259622) (xy 386.468081 -234.257641) (xy 386.419862 -234.247797) (xy 386.373846 -234.230345)
			(xy 386.331225 -234.205738) (xy 386.293104 -234.174613) (xy 386.260469 -234.137776) (xy 386.234166 -234.09618)
			(xy 386.214875 -234.050904) (xy 386.203098 -234.00312) (xy 386.199138 -233.954066) (xy 385.88061 -233.954066)
			(xy 385.880098 -233.979512) (xy 385.871934 -234.029746) (xy 385.855818 -234.07802) (xy 385.832167 -234.123083)
			(xy 385.801594 -234.163769) (xy 385.76489 -234.199024) (xy 385.723006 -234.227934) (xy 385.677027 -234.249751)
			(xy 385.628143 -234.263911) (xy 385.577622 -234.270045) (xy 385.52677 -234.267996) (xy 385.476906 -234.257816)
			(xy 385.42932 -234.239769) (xy 385.385246 -234.214323) (xy 385.345824 -234.182136) (xy 385.312076 -234.144042)
			(xy 385.284875 -234.101028) (xy 385.264927 -234.054208) (xy 385.252748 -234.004794) (xy 385.248653 -233.954066)
			(xy 384.930142 -233.954066) (xy 384.929647 -233.978673) (xy 384.921752 -234.02725) (xy 384.906168 -234.073931)
			(xy 384.883297 -234.117508) (xy 384.853732 -234.156852) (xy 384.818239 -234.190944) (xy 384.777736 -234.2189)
			(xy 384.733274 -234.239998) (xy 384.686003 -234.25369) (xy 384.637148 -234.259622) (xy 384.587973 -234.257641)
			(xy 384.539754 -234.247797) (xy 384.493738 -234.230345) (xy 384.451117 -234.205738) (xy 384.412996 -234.174613)
			(xy 384.380361 -234.137776) (xy 384.354058 -234.09618) (xy 384.334767 -234.050904) (xy 384.32299 -234.00312)
			(xy 384.31903 -233.954066) (xy 384.000502 -233.954066) (xy 383.99999 -233.979512) (xy 383.991826 -234.029746)
			(xy 383.97571 -234.07802) (xy 383.952059 -234.123083) (xy 383.921486 -234.163769) (xy 383.884782 -234.199024)
			(xy 383.842898 -234.227934) (xy 383.796919 -234.249751) (xy 383.748035 -234.263911) (xy 383.697514 -234.270045)
			(xy 383.646662 -234.267996) (xy 383.596798 -234.257816) (xy 383.549212 -234.239769) (xy 383.505138 -234.214323)
			(xy 383.465716 -234.182136) (xy 383.431968 -234.144042) (xy 383.404767 -234.101028) (xy 383.384819 -234.054208)
			(xy 383.37264 -234.004794) (xy 383.368545 -233.954066) (xy 383.060448 -233.954066) (xy 383.059936 -233.979512)
			(xy 383.051772 -234.029746) (xy 383.035656 -234.07802) (xy 383.012005 -234.123083) (xy 382.981432 -234.163769)
			(xy 382.944728 -234.199024) (xy 382.902844 -234.227934) (xy 382.856865 -234.249751) (xy 382.807981 -234.263911)
			(xy 382.75746 -234.270045) (xy 382.706608 -234.267996) (xy 382.656744 -234.257816) (xy 382.609158 -234.239769)
			(xy 382.565084 -234.214323) (xy 382.525662 -234.182136) (xy 382.491914 -234.144042) (xy 382.464713 -234.101028)
			(xy 382.444765 -234.054208) (xy 382.432586 -234.004794) (xy 382.428491 -233.954066) (xy 382.110234 -233.954066)
			(xy 382.109739 -233.978673) (xy 382.101844 -234.02725) (xy 382.08626 -234.073931) (xy 382.063389 -234.117508)
			(xy 382.033824 -234.156852) (xy 381.998331 -234.190944) (xy 381.957828 -234.2189) (xy 381.913366 -234.239998)
			(xy 381.866095 -234.25369) (xy 381.81724 -234.259622) (xy 381.768065 -234.257641) (xy 381.719846 -234.247797)
			(xy 381.67383 -234.230345) (xy 381.631209 -234.205738) (xy 381.593088 -234.174613) (xy 381.560453 -234.137776)
			(xy 381.53415 -234.09618) (xy 381.514859 -234.050904) (xy 381.503082 -234.00312) (xy 381.499122 -233.954066)
			(xy 381.180594 -233.954066) (xy 381.180082 -233.979512) (xy 381.171918 -234.029746) (xy 381.155802 -234.07802)
			(xy 381.132151 -234.123083) (xy 381.101578 -234.163769) (xy 381.064874 -234.199024) (xy 381.02299 -234.227934)
			(xy 380.977011 -234.249751) (xy 380.928127 -234.263911) (xy 380.877606 -234.270045) (xy 380.826754 -234.267996)
			(xy 380.77689 -234.257816) (xy 380.729304 -234.239769) (xy 380.68523 -234.214323) (xy 380.645808 -234.182136)
			(xy 380.61206 -234.144042) (xy 380.584859 -234.101028) (xy 380.564911 -234.054208) (xy 380.552732 -234.004794)
			(xy 380.548637 -233.954066) (xy 380.230126 -233.954066) (xy 380.229631 -233.978673) (xy 380.221736 -234.02725)
			(xy 380.206152 -234.073931) (xy 380.183281 -234.117508) (xy 380.153716 -234.156852) (xy 380.118223 -234.190944)
			(xy 380.07772 -234.2189) (xy 380.033258 -234.239998) (xy 379.985987 -234.25369) (xy 379.937132 -234.259622)
			(xy 379.887957 -234.257641) (xy 379.839738 -234.247797) (xy 379.793722 -234.230345) (xy 379.751101 -234.205738)
			(xy 379.71298 -234.174613) (xy 379.680345 -234.137776) (xy 379.654042 -234.09618) (xy 379.634751 -234.050904)
			(xy 379.622974 -234.00312) (xy 379.619014 -233.954066) (xy 379.300486 -233.954066) (xy 379.299974 -233.979512)
			(xy 379.29181 -234.029746) (xy 379.275694 -234.07802) (xy 379.252043 -234.123083) (xy 379.22147 -234.163769)
			(xy 379.184766 -234.199024) (xy 379.142882 -234.227934) (xy 379.096903 -234.249751) (xy 379.048019 -234.263911)
			(xy 378.997498 -234.270045) (xy 378.946646 -234.267996) (xy 378.896782 -234.257816) (xy 378.849196 -234.239769)
			(xy 378.805122 -234.214323) (xy 378.7657 -234.182136) (xy 378.731952 -234.144042) (xy 378.704751 -234.101028)
			(xy 378.684803 -234.054208) (xy 378.672624 -234.004794) (xy 378.668529 -233.954066) (xy 378.350018 -233.954066)
			(xy 378.349523 -233.978673) (xy 378.341628 -234.02725) (xy 378.326044 -234.073931) (xy 378.303173 -234.117508)
			(xy 378.273608 -234.156852) (xy 378.238115 -234.190944) (xy 378.197612 -234.2189) (xy 378.15315 -234.239998)
			(xy 378.105879 -234.25369) (xy 378.057024 -234.259622) (xy 378.007849 -234.257641) (xy 377.95963 -234.247797)
			(xy 377.913614 -234.230345) (xy 377.870993 -234.205738) (xy 377.832872 -234.174613) (xy 377.800237 -234.137776)
			(xy 377.773934 -234.09618) (xy 377.754643 -234.050904) (xy 377.742866 -234.00312) (xy 377.738906 -233.954066)
			(xy 377.420632 -233.954066) (xy 377.42012 -233.979512) (xy 377.411956 -234.029746) (xy 377.39584 -234.07802)
			(xy 377.372189 -234.123083) (xy 377.341616 -234.163769) (xy 377.304912 -234.199024) (xy 377.263028 -234.227934)
			(xy 377.217049 -234.249751) (xy 377.168165 -234.263911) (xy 377.117644 -234.270045) (xy 377.066792 -234.267996)
			(xy 377.016928 -234.257816) (xy 376.969342 -234.239769) (xy 376.925268 -234.214323) (xy 376.885846 -234.182136)
			(xy 376.852098 -234.144042) (xy 376.824897 -234.101028) (xy 376.804949 -234.054208) (xy 376.79277 -234.004794)
			(xy 376.788675 -233.954066) (xy 376.480578 -233.954066) (xy 376.480066 -233.979512) (xy 376.471902 -234.029746)
			(xy 376.455786 -234.07802) (xy 376.432135 -234.123083) (xy 376.401562 -234.163769) (xy 376.364858 -234.199024)
			(xy 376.322974 -234.227934) (xy 376.276995 -234.249751) (xy 376.228111 -234.263911) (xy 376.17759 -234.270045)
			(xy 376.126738 -234.267996) (xy 376.076874 -234.257816) (xy 376.029288 -234.239769) (xy 375.985214 -234.214323)
			(xy 375.945792 -234.182136) (xy 375.912044 -234.144042) (xy 375.884843 -234.101028) (xy 375.864895 -234.054208)
			(xy 375.852716 -234.004794) (xy 375.848621 -233.954066) (xy 375.530662 -233.954066) (xy 375.530665 -233.9541)
			(xy 375.526493 -234.004444) (xy 375.514093 -234.053414) (xy 375.493801 -234.099675) (xy 375.466171 -234.141966)
			(xy 375.431958 -234.179131) (xy 375.392093 -234.210159) (xy 375.347666 -234.234202) (xy 375.299887 -234.250605)
			(xy 375.25006 -234.25892) (xy 375.224802 -234.259374) (xy 375.200371 -234.258892) (xy 375.152134 -234.251104)
			(xy 375.12879 -234.24388) (xy 375.121932 -234.241594) (xy 375.12117 -234.24134) (xy 375.109419 -234.237866)
			(xy 375.085162 -234.24107) (xy 375.074688 -234.247436) (xy 375.00687 -234.295188) (xy 375.004838 -234.296712)
			(xy 374.996626 -234.303734) (xy 374.986509 -234.322806) (xy 374.98528 -234.333542) (xy 374.98528 -234.536996)
			(xy 374.985356 -234.541205) (xy 374.986761 -234.549506) (xy 374.988074 -234.553506) (xy 374.995948 -234.576366)
			(xy 375.00052 -234.582716) (xy 375.014559 -234.602538) (xy 375.036843 -234.645695) (xy 375.05202 -234.691834)
			(xy 375.059706 -234.739792) (xy 375.059708 -234.764072) (xy 375.378467 -234.764072) (xy 375.382562 -234.713344)
			(xy 375.394741 -234.66393) (xy 375.414689 -234.61711) (xy 375.44189 -234.574096) (xy 375.475638 -234.536002)
			(xy 375.51506 -234.503815) (xy 375.559134 -234.478369) (xy 375.60672 -234.460322) (xy 375.656584 -234.450142)
			(xy 375.707436 -234.448093) (xy 375.757957 -234.454227) (xy 375.806841 -234.468387) (xy 375.85282 -234.490204)
			(xy 375.894704 -234.519114) (xy 375.931408 -234.554369) (xy 375.961981 -234.595055) (xy 375.985632 -234.640118)
			(xy 376.001748 -234.688392) (xy 376.009912 -234.738626) (xy 376.010424 -234.764072) (xy 376.328952 -234.764072)
			(xy 376.332912 -234.715018) (xy 376.344689 -234.667234) (xy 376.36398 -234.621958) (xy 376.390283 -234.580362)
			(xy 376.422918 -234.543525) (xy 376.461039 -234.5124) (xy 376.50366 -234.487793) (xy 376.549676 -234.470341)
			(xy 376.597895 -234.460497) (xy 376.64707 -234.458516) (xy 376.695925 -234.464448) (xy 376.743196 -234.47814)
			(xy 376.787658 -234.499238) (xy 376.828161 -234.527194) (xy 376.863654 -234.561286) (xy 376.893219 -234.60063)
			(xy 376.91609 -234.644207) (xy 376.931674 -234.690888) (xy 376.939569 -234.739465) (xy 376.940064 -234.764072)
			(xy 377.258575 -234.764072) (xy 377.26267 -234.713344) (xy 377.274849 -234.66393) (xy 377.294797 -234.61711)
			(xy 377.321998 -234.574096) (xy 377.355746 -234.536002) (xy 377.395168 -234.503815) (xy 377.439242 -234.478369)
			(xy 377.486828 -234.460322) (xy 377.536692 -234.450142) (xy 377.587544 -234.448093) (xy 377.638065 -234.454227)
			(xy 377.686949 -234.468387) (xy 377.732928 -234.490204) (xy 377.774812 -234.519114) (xy 377.811516 -234.554369)
			(xy 377.842089 -234.595055) (xy 377.86574 -234.640118) (xy 377.881856 -234.688392) (xy 377.89002 -234.738626)
			(xy 377.890532 -234.764072) (xy 379.138683 -234.764072) (xy 379.142778 -234.713344) (xy 379.154957 -234.66393)
			(xy 379.174905 -234.61711) (xy 379.202106 -234.574096) (xy 379.235854 -234.536002) (xy 379.275276 -234.503815)
			(xy 379.31935 -234.478369) (xy 379.366936 -234.460322) (xy 379.4168 -234.450142) (xy 379.467652 -234.448093)
			(xy 379.518173 -234.454227) (xy 379.567057 -234.468387) (xy 379.613036 -234.490204) (xy 379.65492 -234.519114)
			(xy 379.691624 -234.554369) (xy 379.722197 -234.595055) (xy 379.745848 -234.640118) (xy 379.761964 -234.688392)
			(xy 379.770128 -234.738626) (xy 379.77064 -234.764072) (xy 380.078483 -234.764072) (xy 380.082578 -234.713344)
			(xy 380.094757 -234.66393) (xy 380.114705 -234.61711) (xy 380.141906 -234.574096) (xy 380.175654 -234.536002)
			(xy 380.215076 -234.503815) (xy 380.25915 -234.478369) (xy 380.306736 -234.460322) (xy 380.3566 -234.450142)
			(xy 380.407452 -234.448093) (xy 380.457973 -234.454227) (xy 380.506857 -234.468387) (xy 380.552836 -234.490204)
			(xy 380.59472 -234.519114) (xy 380.631424 -234.554369) (xy 380.661997 -234.595055) (xy 380.685648 -234.640118)
			(xy 380.701764 -234.688392) (xy 380.709928 -234.738626) (xy 380.71044 -234.764072) (xy 381.028968 -234.764072)
			(xy 381.032928 -234.715018) (xy 381.044705 -234.667234) (xy 381.063996 -234.621958) (xy 381.090299 -234.580362)
			(xy 381.122934 -234.543525) (xy 381.161055 -234.5124) (xy 381.203676 -234.487793) (xy 381.249692 -234.470341)
			(xy 381.297911 -234.460497) (xy 381.347086 -234.458516) (xy 381.395941 -234.464448) (xy 381.443212 -234.47814)
			(xy 381.487674 -234.499238) (xy 381.528177 -234.527194) (xy 381.56367 -234.561286) (xy 381.593235 -234.60063)
			(xy 381.616106 -234.644207) (xy 381.63169 -234.690888) (xy 381.639585 -234.739465) (xy 381.64008 -234.764072)
			(xy 381.958591 -234.764072) (xy 381.962686 -234.713344) (xy 381.974865 -234.66393) (xy 381.994813 -234.61711)
			(xy 382.022014 -234.574096) (xy 382.055762 -234.536002) (xy 382.095184 -234.503815) (xy 382.139258 -234.478369)
			(xy 382.186844 -234.460322) (xy 382.236708 -234.450142) (xy 382.28756 -234.448093) (xy 382.338081 -234.454227)
			(xy 382.386965 -234.468387) (xy 382.432944 -234.490204) (xy 382.474828 -234.519114) (xy 382.511532 -234.554369)
			(xy 382.542105 -234.595055) (xy 382.565756 -234.640118) (xy 382.581872 -234.688392) (xy 382.590036 -234.738626)
			(xy 382.590548 -234.764072) (xy 382.909076 -234.764072) (xy 382.913036 -234.715018) (xy 382.924813 -234.667234)
			(xy 382.944104 -234.621958) (xy 382.970407 -234.580362) (xy 383.003042 -234.543525) (xy 383.041163 -234.5124)
			(xy 383.083784 -234.487793) (xy 383.1298 -234.470341) (xy 383.178019 -234.460497) (xy 383.227194 -234.458516)
			(xy 383.276049 -234.464448) (xy 383.32332 -234.47814) (xy 383.367782 -234.499238) (xy 383.408285 -234.527194)
			(xy 383.443778 -234.561286) (xy 383.473343 -234.60063) (xy 383.496214 -234.644207) (xy 383.511798 -234.690888)
			(xy 383.519693 -234.739465) (xy 383.520188 -234.764072) (xy 383.838699 -234.764072) (xy 383.842794 -234.713344)
			(xy 383.854973 -234.66393) (xy 383.874921 -234.61711) (xy 383.902122 -234.574096) (xy 383.93587 -234.536002)
			(xy 383.975292 -234.503815) (xy 384.019366 -234.478369) (xy 384.066952 -234.460322) (xy 384.116816 -234.450142)
			(xy 384.167668 -234.448093) (xy 384.218189 -234.454227) (xy 384.267073 -234.468387) (xy 384.313052 -234.490204)
			(xy 384.354936 -234.519114) (xy 384.39164 -234.554369) (xy 384.422213 -234.595055) (xy 384.445864 -234.640118)
			(xy 384.46198 -234.688392) (xy 384.470144 -234.738626) (xy 384.470656 -234.764072) (xy 385.718553 -234.764072)
			(xy 385.722648 -234.713344) (xy 385.734827 -234.66393) (xy 385.754775 -234.61711) (xy 385.781976 -234.574096)
			(xy 385.815724 -234.536002) (xy 385.855146 -234.503815) (xy 385.89922 -234.478369) (xy 385.946806 -234.460322)
			(xy 385.99667 -234.450142) (xy 386.047522 -234.448093) (xy 386.098043 -234.454227) (xy 386.146927 -234.468387)
			(xy 386.192906 -234.490204) (xy 386.23479 -234.519114) (xy 386.271494 -234.554369) (xy 386.302067 -234.595055)
			(xy 386.325718 -234.640118) (xy 386.341834 -234.688392) (xy 386.349998 -234.738626) (xy 386.35051 -234.764072)
			(xy 386.658607 -234.764072) (xy 386.662702 -234.713344) (xy 386.674881 -234.66393) (xy 386.694829 -234.61711)
			(xy 386.72203 -234.574096) (xy 386.755778 -234.536002) (xy 386.7952 -234.503815) (xy 386.839274 -234.478369)
			(xy 386.88686 -234.460322) (xy 386.936724 -234.450142) (xy 386.987576 -234.448093) (xy 387.038097 -234.454227)
			(xy 387.086981 -234.468387) (xy 387.13296 -234.490204) (xy 387.174844 -234.519114) (xy 387.211548 -234.554369)
			(xy 387.242121 -234.595055) (xy 387.265772 -234.640118) (xy 387.281888 -234.688392) (xy 387.290052 -234.738626)
			(xy 387.290564 -234.764072) (xy 387.609092 -234.764072) (xy 387.613052 -234.715018) (xy 387.624829 -234.667234)
			(xy 387.64412 -234.621958) (xy 387.670423 -234.580362) (xy 387.703058 -234.543525) (xy 387.741179 -234.5124)
			(xy 387.7838 -234.487793) (xy 387.829816 -234.470341) (xy 387.878035 -234.460497) (xy 387.92721 -234.458516)
			(xy 387.976065 -234.464448) (xy 388.023336 -234.47814) (xy 388.067798 -234.499238) (xy 388.108301 -234.527194)
			(xy 388.143794 -234.561286) (xy 388.173359 -234.60063) (xy 388.19623 -234.644207) (xy 388.211814 -234.690888)
			(xy 388.219709 -234.739465) (xy 388.220204 -234.764072) (xy 388.538715 -234.764072) (xy 388.54281 -234.713344)
			(xy 388.554989 -234.66393) (xy 388.574937 -234.61711) (xy 388.602138 -234.574096) (xy 388.635886 -234.536002)
			(xy 388.675308 -234.503815) (xy 388.719382 -234.478369) (xy 388.766968 -234.460322) (xy 388.816832 -234.450142)
			(xy 388.867684 -234.448093) (xy 388.918205 -234.454227) (xy 388.967089 -234.468387) (xy 389.013068 -234.490204)
			(xy 389.054952 -234.519114) (xy 389.091656 -234.554369) (xy 389.122229 -234.595055) (xy 389.14588 -234.640118)
			(xy 389.161996 -234.688392) (xy 389.17016 -234.738626) (xy 389.170672 -234.764072) (xy 389.488946 -234.764072)
			(xy 389.492906 -234.715018) (xy 389.504683 -234.667234) (xy 389.523974 -234.621958) (xy 389.550277 -234.580362)
			(xy 389.582912 -234.543525) (xy 389.621033 -234.5124) (xy 389.663654 -234.487793) (xy 389.70967 -234.470341)
			(xy 389.757889 -234.460497) (xy 389.807064 -234.458516) (xy 389.855919 -234.464448) (xy 389.90319 -234.47814)
			(xy 389.947652 -234.499238) (xy 389.988155 -234.527194) (xy 390.023648 -234.561286) (xy 390.053213 -234.60063)
			(xy 390.076084 -234.644207) (xy 390.091668 -234.690888) (xy 390.099563 -234.739465) (xy 390.100058 -234.764072)
			(xy 390.418569 -234.764072) (xy 390.422664 -234.713344) (xy 390.434843 -234.66393) (xy 390.454791 -234.61711)
			(xy 390.481992 -234.574096) (xy 390.51574 -234.536002) (xy 390.555162 -234.503815) (xy 390.599236 -234.478369)
			(xy 390.646822 -234.460322) (xy 390.696686 -234.450142) (xy 390.747538 -234.448093) (xy 390.798059 -234.454227)
			(xy 390.846943 -234.468387) (xy 390.892922 -234.490204) (xy 390.934806 -234.519114) (xy 390.97151 -234.554369)
			(xy 391.002083 -234.595055) (xy 391.025734 -234.640118) (xy 391.04185 -234.688392) (xy 391.050014 -234.738626)
			(xy 391.050526 -234.764072) (xy 391.050014 -234.789518) (xy 391.04185 -234.839752) (xy 391.025734 -234.888026)
			(xy 391.002083 -234.933089) (xy 390.97151 -234.973775) (xy 390.934806 -235.00903) (xy 390.904411 -235.03001)
			(xy 394.377176 -235.03001) (xy 394.381136 -234.980956) (xy 394.392913 -234.933172) (xy 394.412204 -234.887896)
			(xy 394.438507 -234.8463) (xy 394.471142 -234.809463) (xy 394.509263 -234.778338) (xy 394.551884 -234.753731)
			(xy 394.5979 -234.736279) (xy 394.646119 -234.726435) (xy 394.695294 -234.724454) (xy 394.744149 -234.730386)
			(xy 394.79142 -234.744078) (xy 394.835882 -234.765176) (xy 394.876385 -234.793132) (xy 394.911878 -234.827224)
			(xy 394.941443 -234.866568) (xy 394.964314 -234.910145) (xy 394.979898 -234.956826) (xy 394.987793 -235.005403)
			(xy 394.988288 -235.03001) (xy 394.987793 -235.054617) (xy 394.979898 -235.103194) (xy 394.964314 -235.149875)
			(xy 394.941443 -235.193452) (xy 394.911878 -235.232796) (xy 394.876385 -235.266888) (xy 394.835882 -235.294844)
			(xy 394.79142 -235.315942) (xy 394.744149 -235.329634) (xy 394.695294 -235.335566) (xy 394.646119 -235.333585)
			(xy 394.5979 -235.323741) (xy 394.551884 -235.306289) (xy 394.509263 -235.281682) (xy 394.471142 -235.250557)
			(xy 394.438507 -235.21372) (xy 394.412204 -235.172124) (xy 394.392913 -235.126848) (xy 394.381136 -235.079064)
			(xy 394.377176 -235.03001) (xy 390.904411 -235.03001) (xy 390.892922 -235.03794) (xy 390.846943 -235.059757)
			(xy 390.798059 -235.073917) (xy 390.747538 -235.080051) (xy 390.696686 -235.078002) (xy 390.646822 -235.067822)
			(xy 390.599236 -235.049775) (xy 390.555162 -235.024329) (xy 390.51574 -234.992142) (xy 390.481992 -234.954048)
			(xy 390.454791 -234.911034) (xy 390.434843 -234.864214) (xy 390.422664 -234.8148) (xy 390.418569 -234.764072)
			(xy 390.100058 -234.764072) (xy 390.099563 -234.788679) (xy 390.091668 -234.837256) (xy 390.076084 -234.883937)
			(xy 390.053213 -234.927514) (xy 390.023648 -234.966858) (xy 389.988155 -235.00095) (xy 389.947652 -235.028906)
			(xy 389.90319 -235.050004) (xy 389.855919 -235.063696) (xy 389.807064 -235.069628) (xy 389.757889 -235.067647)
			(xy 389.70967 -235.057803) (xy 389.663654 -235.040351) (xy 389.621033 -235.015744) (xy 389.582912 -234.984619)
			(xy 389.550277 -234.947782) (xy 389.523974 -234.906186) (xy 389.504683 -234.86091) (xy 389.492906 -234.813126)
			(xy 389.488946 -234.764072) (xy 389.170672 -234.764072) (xy 389.17016 -234.789518) (xy 389.161996 -234.839752)
			(xy 389.14588 -234.888026) (xy 389.122229 -234.933089) (xy 389.091656 -234.973775) (xy 389.054952 -235.00903)
			(xy 389.013068 -235.03794) (xy 388.967089 -235.059757) (xy 388.918205 -235.073917) (xy 388.867684 -235.080051)
			(xy 388.816832 -235.078002) (xy 388.766968 -235.067822) (xy 388.719382 -235.049775) (xy 388.675308 -235.024329)
			(xy 388.635886 -234.992142) (xy 388.602138 -234.954048) (xy 388.574937 -234.911034) (xy 388.554989 -234.864214)
			(xy 388.54281 -234.8148) (xy 388.538715 -234.764072) (xy 388.220204 -234.764072) (xy 388.219709 -234.788679)
			(xy 388.211814 -234.837256) (xy 388.19623 -234.883937) (xy 388.173359 -234.927514) (xy 388.143794 -234.966858)
			(xy 388.108301 -235.00095) (xy 388.067798 -235.028906) (xy 388.023336 -235.050004) (xy 387.976065 -235.063696)
			(xy 387.92721 -235.069628) (xy 387.878035 -235.067647) (xy 387.829816 -235.057803) (xy 387.7838 -235.040351)
			(xy 387.741179 -235.015744) (xy 387.703058 -234.984619) (xy 387.670423 -234.947782) (xy 387.64412 -234.906186)
			(xy 387.624829 -234.86091) (xy 387.613052 -234.813126) (xy 387.609092 -234.764072) (xy 387.290564 -234.764072)
			(xy 387.290052 -234.789518) (xy 387.281888 -234.839752) (xy 387.265772 -234.888026) (xy 387.242121 -234.933089)
			(xy 387.211548 -234.973775) (xy 387.174844 -235.00903) (xy 387.13296 -235.03794) (xy 387.086981 -235.059757)
			(xy 387.038097 -235.073917) (xy 386.987576 -235.080051) (xy 386.936724 -235.078002) (xy 386.88686 -235.067822)
			(xy 386.839274 -235.049775) (xy 386.7952 -235.024329) (xy 386.755778 -234.992142) (xy 386.72203 -234.954048)
			(xy 386.694829 -234.911034) (xy 386.674881 -234.864214) (xy 386.662702 -234.8148) (xy 386.658607 -234.764072)
			(xy 386.35051 -234.764072) (xy 386.349998 -234.789518) (xy 386.341834 -234.839752) (xy 386.325718 -234.888026)
			(xy 386.302067 -234.933089) (xy 386.271494 -234.973775) (xy 386.23479 -235.00903) (xy 386.192906 -235.03794)
			(xy 386.146927 -235.059757) (xy 386.098043 -235.073917) (xy 386.047522 -235.080051) (xy 385.99667 -235.078002)
			(xy 385.946806 -235.067822) (xy 385.89922 -235.049775) (xy 385.855146 -235.024329) (xy 385.815724 -234.992142)
			(xy 385.781976 -234.954048) (xy 385.754775 -234.911034) (xy 385.734827 -234.864214) (xy 385.722648 -234.8148)
			(xy 385.718553 -234.764072) (xy 384.470656 -234.764072) (xy 384.470144 -234.789518) (xy 384.46198 -234.839752)
			(xy 384.445864 -234.888026) (xy 384.422213 -234.933089) (xy 384.39164 -234.973775) (xy 384.354936 -235.00903)
			(xy 384.313052 -235.03794) (xy 384.267073 -235.059757) (xy 384.218189 -235.073917) (xy 384.167668 -235.080051)
			(xy 384.116816 -235.078002) (xy 384.066952 -235.067822) (xy 384.019366 -235.049775) (xy 383.975292 -235.024329)
			(xy 383.93587 -234.992142) (xy 383.902122 -234.954048) (xy 383.874921 -234.911034) (xy 383.854973 -234.864214)
			(xy 383.842794 -234.8148) (xy 383.838699 -234.764072) (xy 383.520188 -234.764072) (xy 383.519693 -234.788679)
			(xy 383.511798 -234.837256) (xy 383.496214 -234.883937) (xy 383.473343 -234.927514) (xy 383.443778 -234.966858)
			(xy 383.408285 -235.00095) (xy 383.367782 -235.028906) (xy 383.32332 -235.050004) (xy 383.276049 -235.063696)
			(xy 383.227194 -235.069628) (xy 383.178019 -235.067647) (xy 383.1298 -235.057803) (xy 383.083784 -235.040351)
			(xy 383.041163 -235.015744) (xy 383.003042 -234.984619) (xy 382.970407 -234.947782) (xy 382.944104 -234.906186)
			(xy 382.924813 -234.86091) (xy 382.913036 -234.813126) (xy 382.909076 -234.764072) (xy 382.590548 -234.764072)
			(xy 382.590036 -234.789518) (xy 382.581872 -234.839752) (xy 382.565756 -234.888026) (xy 382.542105 -234.933089)
			(xy 382.511532 -234.973775) (xy 382.474828 -235.00903) (xy 382.432944 -235.03794) (xy 382.386965 -235.059757)
			(xy 382.338081 -235.073917) (xy 382.28756 -235.080051) (xy 382.236708 -235.078002) (xy 382.186844 -235.067822)
			(xy 382.139258 -235.049775) (xy 382.095184 -235.024329) (xy 382.055762 -234.992142) (xy 382.022014 -234.954048)
			(xy 381.994813 -234.911034) (xy 381.974865 -234.864214) (xy 381.962686 -234.8148) (xy 381.958591 -234.764072)
			(xy 381.64008 -234.764072) (xy 381.639585 -234.788679) (xy 381.63169 -234.837256) (xy 381.616106 -234.883937)
			(xy 381.593235 -234.927514) (xy 381.56367 -234.966858) (xy 381.528177 -235.00095) (xy 381.487674 -235.028906)
			(xy 381.443212 -235.050004) (xy 381.395941 -235.063696) (xy 381.347086 -235.069628) (xy 381.297911 -235.067647)
			(xy 381.249692 -235.057803) (xy 381.203676 -235.040351) (xy 381.161055 -235.015744) (xy 381.122934 -234.984619)
			(xy 381.090299 -234.947782) (xy 381.063996 -234.906186) (xy 381.044705 -234.86091) (xy 381.032928 -234.813126)
			(xy 381.028968 -234.764072) (xy 380.71044 -234.764072) (xy 380.709928 -234.789518) (xy 380.701764 -234.839752)
			(xy 380.685648 -234.888026) (xy 380.661997 -234.933089) (xy 380.631424 -234.973775) (xy 380.59472 -235.00903)
			(xy 380.552836 -235.03794) (xy 380.506857 -235.059757) (xy 380.457973 -235.073917) (xy 380.407452 -235.080051)
			(xy 380.3566 -235.078002) (xy 380.306736 -235.067822) (xy 380.25915 -235.049775) (xy 380.215076 -235.024329)
			(xy 380.175654 -234.992142) (xy 380.141906 -234.954048) (xy 380.114705 -234.911034) (xy 380.094757 -234.864214)
			(xy 380.082578 -234.8148) (xy 380.078483 -234.764072) (xy 379.77064 -234.764072) (xy 379.770128 -234.789518)
			(xy 379.761964 -234.839752) (xy 379.745848 -234.888026) (xy 379.722197 -234.933089) (xy 379.691624 -234.973775)
			(xy 379.65492 -235.00903) (xy 379.613036 -235.03794) (xy 379.567057 -235.059757) (xy 379.518173 -235.073917)
			(xy 379.467652 -235.080051) (xy 379.4168 -235.078002) (xy 379.366936 -235.067822) (xy 379.31935 -235.049775)
			(xy 379.275276 -235.024329) (xy 379.235854 -234.992142) (xy 379.202106 -234.954048) (xy 379.174905 -234.911034)
			(xy 379.154957 -234.864214) (xy 379.142778 -234.8148) (xy 379.138683 -234.764072) (xy 377.890532 -234.764072)
			(xy 377.89002 -234.789518) (xy 377.881856 -234.839752) (xy 377.86574 -234.888026) (xy 377.842089 -234.933089)
			(xy 377.811516 -234.973775) (xy 377.774812 -235.00903) (xy 377.732928 -235.03794) (xy 377.686949 -235.059757)
			(xy 377.638065 -235.073917) (xy 377.587544 -235.080051) (xy 377.536692 -235.078002) (xy 377.486828 -235.067822)
			(xy 377.439242 -235.049775) (xy 377.395168 -235.024329) (xy 377.355746 -234.992142) (xy 377.321998 -234.954048)
			(xy 377.294797 -234.911034) (xy 377.274849 -234.864214) (xy 377.26267 -234.8148) (xy 377.258575 -234.764072)
			(xy 376.940064 -234.764072) (xy 376.939569 -234.788679) (xy 376.931674 -234.837256) (xy 376.91609 -234.883937)
			(xy 376.893219 -234.927514) (xy 376.863654 -234.966858) (xy 376.828161 -235.00095) (xy 376.787658 -235.028906)
			(xy 376.743196 -235.050004) (xy 376.695925 -235.063696) (xy 376.64707 -235.069628) (xy 376.597895 -235.067647)
			(xy 376.549676 -235.057803) (xy 376.50366 -235.040351) (xy 376.461039 -235.015744) (xy 376.422918 -234.984619)
			(xy 376.390283 -234.947782) (xy 376.36398 -234.906186) (xy 376.344689 -234.86091) (xy 376.332912 -234.813126)
			(xy 376.328952 -234.764072) (xy 376.010424 -234.764072) (xy 376.009912 -234.789518) (xy 376.001748 -234.839752)
			(xy 375.985632 -234.888026) (xy 375.961981 -234.933089) (xy 375.931408 -234.973775) (xy 375.894704 -235.00903)
			(xy 375.85282 -235.03794) (xy 375.806841 -235.059757) (xy 375.757957 -235.073917) (xy 375.707436 -235.080051)
			(xy 375.656584 -235.078002) (xy 375.60672 -235.067822) (xy 375.559134 -235.049775) (xy 375.51506 -235.024329)
			(xy 375.475638 -234.992142) (xy 375.44189 -234.954048) (xy 375.414689 -234.911034) (xy 375.394741 -234.864214)
			(xy 375.382562 -234.8148) (xy 375.378467 -234.764072) (xy 375.059708 -234.764072) (xy 375.05971 -234.788363)
			(xy 375.05203 -234.836322) (xy 375.03686 -234.882463) (xy 375.014583 -234.925624) (xy 375.00052 -234.945428)
			(xy 374.995948 -234.951778) (xy 374.988074 -234.974638) (xy 374.986787 -234.978645) (xy 374.985377 -234.986941)
			(xy 374.98528 -234.991148) (xy 374.98528 -235.574078) (xy 375.848621 -235.574078) (xy 375.852716 -235.52335)
			(xy 375.864895 -235.473936) (xy 375.884843 -235.427116) (xy 375.912044 -235.384102) (xy 375.945792 -235.346008)
			(xy 375.985214 -235.313821) (xy 376.029288 -235.288375) (xy 376.076874 -235.270328) (xy 376.126738 -235.260148)
			(xy 376.17759 -235.258099) (xy 376.228111 -235.264233) (xy 376.276995 -235.278393) (xy 376.322974 -235.30021)
			(xy 376.364858 -235.32912) (xy 376.401562 -235.364375) (xy 376.432135 -235.405061) (xy 376.455786 -235.450124)
			(xy 376.471902 -235.498398) (xy 376.480066 -235.548632) (xy 376.480578 -235.574078) (xy 376.788675 -235.574078)
			(xy 376.79277 -235.52335) (xy 376.804949 -235.473936) (xy 376.824897 -235.427116) (xy 376.852098 -235.384102)
			(xy 376.885846 -235.346008) (xy 376.925268 -235.313821) (xy 376.969342 -235.288375) (xy 377.016928 -235.270328)
			(xy 377.066792 -235.260148) (xy 377.117644 -235.258099) (xy 377.168165 -235.264233) (xy 377.217049 -235.278393)
			(xy 377.263028 -235.30021) (xy 377.304912 -235.32912) (xy 377.341616 -235.364375) (xy 377.372189 -235.405061)
			(xy 377.39584 -235.450124) (xy 377.411956 -235.498398) (xy 377.42012 -235.548632) (xy 377.420632 -235.574078)
			(xy 377.738906 -235.574078) (xy 377.742866 -235.525024) (xy 377.754643 -235.47724) (xy 377.773934 -235.431964)
			(xy 377.800237 -235.390368) (xy 377.832872 -235.353531) (xy 377.870993 -235.322406) (xy 377.913614 -235.297799)
			(xy 377.95963 -235.280347) (xy 378.007849 -235.270503) (xy 378.057024 -235.268522) (xy 378.105879 -235.274454)
			(xy 378.15315 -235.288146) (xy 378.197612 -235.309244) (xy 378.238115 -235.3372) (xy 378.273608 -235.371292)
			(xy 378.303173 -235.410636) (xy 378.326044 -235.454213) (xy 378.341628 -235.500894) (xy 378.349523 -235.549471)
			(xy 378.350018 -235.574078) (xy 378.668529 -235.574078) (xy 378.672624 -235.52335) (xy 378.684803 -235.473936)
			(xy 378.704751 -235.427116) (xy 378.731952 -235.384102) (xy 378.7657 -235.346008) (xy 378.805122 -235.313821)
			(xy 378.849196 -235.288375) (xy 378.896782 -235.270328) (xy 378.946646 -235.260148) (xy 378.997498 -235.258099)
			(xy 379.048019 -235.264233) (xy 379.096903 -235.278393) (xy 379.142882 -235.30021) (xy 379.184766 -235.32912)
			(xy 379.22147 -235.364375) (xy 379.252043 -235.405061) (xy 379.275694 -235.450124) (xy 379.29181 -235.498398)
			(xy 379.299974 -235.548632) (xy 379.300486 -235.574078) (xy 379.619014 -235.574078) (xy 379.622974 -235.525024)
			(xy 379.634751 -235.47724) (xy 379.654042 -235.431964) (xy 379.680345 -235.390368) (xy 379.71298 -235.353531)
			(xy 379.751101 -235.322406) (xy 379.793722 -235.297799) (xy 379.839738 -235.280347) (xy 379.887957 -235.270503)
			(xy 379.937132 -235.268522) (xy 379.985987 -235.274454) (xy 380.033258 -235.288146) (xy 380.07772 -235.309244)
			(xy 380.118223 -235.3372) (xy 380.153716 -235.371292) (xy 380.183281 -235.410636) (xy 380.206152 -235.454213)
			(xy 380.221736 -235.500894) (xy 380.229631 -235.549471) (xy 380.230126 -235.574078) (xy 380.548637 -235.574078)
			(xy 380.552732 -235.52335) (xy 380.564911 -235.473936) (xy 380.584859 -235.427116) (xy 380.61206 -235.384102)
			(xy 380.645808 -235.346008) (xy 380.68523 -235.313821) (xy 380.729304 -235.288375) (xy 380.77689 -235.270328)
			(xy 380.826754 -235.260148) (xy 380.877606 -235.258099) (xy 380.928127 -235.264233) (xy 380.977011 -235.278393)
			(xy 381.02299 -235.30021) (xy 381.064874 -235.32912) (xy 381.101578 -235.364375) (xy 381.132151 -235.405061)
			(xy 381.155802 -235.450124) (xy 381.171918 -235.498398) (xy 381.180082 -235.548632) (xy 381.180594 -235.574078)
			(xy 381.499122 -235.574078) (xy 381.503082 -235.525024) (xy 381.514859 -235.47724) (xy 381.53415 -235.431964)
			(xy 381.560453 -235.390368) (xy 381.593088 -235.353531) (xy 381.631209 -235.322406) (xy 381.67383 -235.297799)
			(xy 381.719846 -235.280347) (xy 381.768065 -235.270503) (xy 381.81724 -235.268522) (xy 381.866095 -235.274454)
			(xy 381.913366 -235.288146) (xy 381.957828 -235.309244) (xy 381.998331 -235.3372) (xy 382.033824 -235.371292)
			(xy 382.063389 -235.410636) (xy 382.08626 -235.454213) (xy 382.101844 -235.500894) (xy 382.109739 -235.549471)
			(xy 382.110234 -235.574078) (xy 382.428491 -235.574078) (xy 382.432586 -235.52335) (xy 382.444765 -235.473936)
			(xy 382.464713 -235.427116) (xy 382.491914 -235.384102) (xy 382.525662 -235.346008) (xy 382.565084 -235.313821)
			(xy 382.609158 -235.288375) (xy 382.656744 -235.270328) (xy 382.706608 -235.260148) (xy 382.75746 -235.258099)
			(xy 382.807981 -235.264233) (xy 382.856865 -235.278393) (xy 382.902844 -235.30021) (xy 382.944728 -235.32912)
			(xy 382.981432 -235.364375) (xy 383.012005 -235.405061) (xy 383.035656 -235.450124) (xy 383.051772 -235.498398)
			(xy 383.059936 -235.548632) (xy 383.060448 -235.574078) (xy 383.368545 -235.574078) (xy 383.37264 -235.52335)
			(xy 383.384819 -235.473936) (xy 383.404767 -235.427116) (xy 383.431968 -235.384102) (xy 383.465716 -235.346008)
			(xy 383.505138 -235.313821) (xy 383.549212 -235.288375) (xy 383.596798 -235.270328) (xy 383.646662 -235.260148)
			(xy 383.697514 -235.258099) (xy 383.748035 -235.264233) (xy 383.796919 -235.278393) (xy 383.842898 -235.30021)
			(xy 383.884782 -235.32912) (xy 383.921486 -235.364375) (xy 383.952059 -235.405061) (xy 383.97571 -235.450124)
			(xy 383.991826 -235.498398) (xy 383.99999 -235.548632) (xy 384.000502 -235.574078) (xy 384.31903 -235.574078)
			(xy 384.32299 -235.525024) (xy 384.334767 -235.47724) (xy 384.354058 -235.431964) (xy 384.380361 -235.390368)
			(xy 384.412996 -235.353531) (xy 384.451117 -235.322406) (xy 384.493738 -235.297799) (xy 384.539754 -235.280347)
			(xy 384.587973 -235.270503) (xy 384.637148 -235.268522) (xy 384.686003 -235.274454) (xy 384.733274 -235.288146)
			(xy 384.777736 -235.309244) (xy 384.818239 -235.3372) (xy 384.853732 -235.371292) (xy 384.883297 -235.410636)
			(xy 384.906168 -235.454213) (xy 384.921752 -235.500894) (xy 384.929647 -235.549471) (xy 384.930142 -235.574078)
			(xy 385.248653 -235.574078) (xy 385.252748 -235.52335) (xy 385.264927 -235.473936) (xy 385.284875 -235.427116)
			(xy 385.312076 -235.384102) (xy 385.345824 -235.346008) (xy 385.385246 -235.313821) (xy 385.42932 -235.288375)
			(xy 385.476906 -235.270328) (xy 385.52677 -235.260148) (xy 385.577622 -235.258099) (xy 385.628143 -235.264233)
			(xy 385.677027 -235.278393) (xy 385.723006 -235.30021) (xy 385.76489 -235.32912) (xy 385.801594 -235.364375)
			(xy 385.832167 -235.405061) (xy 385.855818 -235.450124) (xy 385.871934 -235.498398) (xy 385.880098 -235.548632)
			(xy 385.88061 -235.574078) (xy 386.199138 -235.574078) (xy 386.203098 -235.525024) (xy 386.214875 -235.47724)
			(xy 386.234166 -235.431964) (xy 386.260469 -235.390368) (xy 386.293104 -235.353531) (xy 386.331225 -235.322406)
			(xy 386.373846 -235.297799) (xy 386.419862 -235.280347) (xy 386.468081 -235.270503) (xy 386.517256 -235.268522)
			(xy 386.566111 -235.274454) (xy 386.613382 -235.288146) (xy 386.657844 -235.309244) (xy 386.698347 -235.3372)
			(xy 386.73384 -235.371292) (xy 386.763405 -235.410636) (xy 386.786276 -235.454213) (xy 386.80186 -235.500894)
			(xy 386.809755 -235.549471) (xy 386.81025 -235.574078) (xy 387.128507 -235.574078) (xy 387.132602 -235.52335)
			(xy 387.144781 -235.473936) (xy 387.164729 -235.427116) (xy 387.19193 -235.384102) (xy 387.225678 -235.346008)
			(xy 387.2651 -235.313821) (xy 387.309174 -235.288375) (xy 387.35676 -235.270328) (xy 387.406624 -235.260148)
			(xy 387.457476 -235.258099) (xy 387.507997 -235.264233) (xy 387.556881 -235.278393) (xy 387.60286 -235.30021)
			(xy 387.644744 -235.32912) (xy 387.681448 -235.364375) (xy 387.712021 -235.405061) (xy 387.735672 -235.450124)
			(xy 387.751788 -235.498398) (xy 387.759952 -235.548632) (xy 387.760464 -235.574078) (xy 388.078992 -235.574078)
			(xy 388.082952 -235.525024) (xy 388.094729 -235.47724) (xy 388.11402 -235.431964) (xy 388.140323 -235.390368)
			(xy 388.172958 -235.353531) (xy 388.211079 -235.322406) (xy 388.2537 -235.297799) (xy 388.299716 -235.280347)
			(xy 388.347935 -235.270503) (xy 388.39711 -235.268522) (xy 388.445965 -235.274454) (xy 388.493236 -235.288146)
			(xy 388.537698 -235.309244) (xy 388.578201 -235.3372) (xy 388.613694 -235.371292) (xy 388.643259 -235.410636)
			(xy 388.66613 -235.454213) (xy 388.681714 -235.500894) (xy 388.689609 -235.549471) (xy 388.690104 -235.574078)
			(xy 389.008615 -235.574078) (xy 389.01271 -235.52335) (xy 389.024889 -235.473936) (xy 389.044837 -235.427116)
			(xy 389.072038 -235.384102) (xy 389.105786 -235.346008) (xy 389.145208 -235.313821) (xy 389.189282 -235.288375)
			(xy 389.236868 -235.270328) (xy 389.286732 -235.260148) (xy 389.337584 -235.258099) (xy 389.388105 -235.264233)
			(xy 389.436989 -235.278393) (xy 389.482968 -235.30021) (xy 389.524852 -235.32912) (xy 389.561556 -235.364375)
			(xy 389.592129 -235.405061) (xy 389.61578 -235.450124) (xy 389.631896 -235.498398) (xy 389.64006 -235.548632)
			(xy 389.640572 -235.574078) (xy 389.948669 -235.574078) (xy 389.952764 -235.52335) (xy 389.964943 -235.473936)
			(xy 389.984891 -235.427116) (xy 390.012092 -235.384102) (xy 390.04584 -235.346008) (xy 390.085262 -235.313821)
			(xy 390.129336 -235.288375) (xy 390.176922 -235.270328) (xy 390.226786 -235.260148) (xy 390.277638 -235.258099)
			(xy 390.328159 -235.264233) (xy 390.377043 -235.278393) (xy 390.423022 -235.30021) (xy 390.464906 -235.32912)
			(xy 390.50161 -235.364375) (xy 390.532183 -235.405061) (xy 390.555834 -235.450124) (xy 390.57195 -235.498398)
			(xy 390.580114 -235.548632) (xy 390.580626 -235.574078) (xy 390.8989 -235.574078) (xy 390.90286 -235.525024)
			(xy 390.914637 -235.47724) (xy 390.933928 -235.431964) (xy 390.960231 -235.390368) (xy 390.992866 -235.353531)
			(xy 391.030987 -235.322406) (xy 391.073608 -235.297799) (xy 391.119624 -235.280347) (xy 391.167843 -235.270503)
			(xy 391.217018 -235.268522) (xy 391.265873 -235.274454) (xy 391.313144 -235.288146) (xy 391.357606 -235.309244)
			(xy 391.398109 -235.3372) (xy 391.433602 -235.371292) (xy 391.463167 -235.410636) (xy 391.486038 -235.454213)
			(xy 391.501622 -235.500894) (xy 391.509517 -235.549471) (xy 391.510012 -235.574078) (xy 392.779008 -235.574078)
			(xy 392.782968 -235.525024) (xy 392.794745 -235.47724) (xy 392.814036 -235.431964) (xy 392.840339 -235.390368)
			(xy 392.872974 -235.353531) (xy 392.911095 -235.322406) (xy 392.953716 -235.297799) (xy 392.999732 -235.280347)
			(xy 393.047951 -235.270503) (xy 393.097126 -235.268522) (xy 393.145981 -235.274454) (xy 393.193252 -235.288146)
			(xy 393.237714 -235.309244) (xy 393.278217 -235.3372) (xy 393.31371 -235.371292) (xy 393.343275 -235.410636)
			(xy 393.366146 -235.454213) (xy 393.38173 -235.500894) (xy 393.389625 -235.549471) (xy 393.39012 -235.574078)
			(xy 393.389625 -235.598685) (xy 393.38173 -235.647262) (xy 393.366146 -235.693943) (xy 393.343275 -235.73752)
			(xy 393.31371 -235.776864) (xy 393.278217 -235.810956) (xy 393.237714 -235.838912) (xy 393.193252 -235.86001)
			(xy 393.145981 -235.873702) (xy 393.097126 -235.879634) (xy 393.047951 -235.877653) (xy 392.999732 -235.867809)
			(xy 392.953716 -235.850357) (xy 392.911095 -235.82575) (xy 392.872974 -235.794625) (xy 392.840339 -235.757788)
			(xy 392.814036 -235.716192) (xy 392.794745 -235.670916) (xy 392.782968 -235.623132) (xy 392.779008 -235.574078)
			(xy 391.510012 -235.574078) (xy 391.509517 -235.598685) (xy 391.501622 -235.647262) (xy 391.486038 -235.693943)
			(xy 391.463167 -235.73752) (xy 391.433602 -235.776864) (xy 391.398109 -235.810956) (xy 391.357606 -235.838912)
			(xy 391.313144 -235.86001) (xy 391.265873 -235.873702) (xy 391.217018 -235.879634) (xy 391.167843 -235.877653)
			(xy 391.119624 -235.867809) (xy 391.073608 -235.850357) (xy 391.030987 -235.82575) (xy 390.992866 -235.794625)
			(xy 390.960231 -235.757788) (xy 390.933928 -235.716192) (xy 390.914637 -235.670916) (xy 390.90286 -235.623132)
			(xy 390.8989 -235.574078) (xy 390.580626 -235.574078) (xy 390.580114 -235.599524) (xy 390.57195 -235.649758)
			(xy 390.555834 -235.698032) (xy 390.532183 -235.743095) (xy 390.50161 -235.783781) (xy 390.464906 -235.819036)
			(xy 390.423022 -235.847946) (xy 390.377043 -235.869763) (xy 390.328159 -235.883923) (xy 390.277638 -235.890057)
			(xy 390.226786 -235.888008) (xy 390.176922 -235.877828) (xy 390.129336 -235.859781) (xy 390.085262 -235.834335)
			(xy 390.04584 -235.802148) (xy 390.012092 -235.764054) (xy 389.984891 -235.72104) (xy 389.964943 -235.67422)
			(xy 389.952764 -235.624806) (xy 389.948669 -235.574078) (xy 389.640572 -235.574078) (xy 389.64006 -235.599524)
			(xy 389.631896 -235.649758) (xy 389.61578 -235.698032) (xy 389.592129 -235.743095) (xy 389.561556 -235.783781)
			(xy 389.524852 -235.819036) (xy 389.482968 -235.847946) (xy 389.436989 -235.869763) (xy 389.388105 -235.883923)
			(xy 389.337584 -235.890057) (xy 389.286732 -235.888008) (xy 389.236868 -235.877828) (xy 389.189282 -235.859781)
			(xy 389.145208 -235.834335) (xy 389.105786 -235.802148) (xy 389.072038 -235.764054) (xy 389.044837 -235.72104)
			(xy 389.024889 -235.67422) (xy 389.01271 -235.624806) (xy 389.008615 -235.574078) (xy 388.690104 -235.574078)
			(xy 388.689609 -235.598685) (xy 388.681714 -235.647262) (xy 388.66613 -235.693943) (xy 388.643259 -235.73752)
			(xy 388.613694 -235.776864) (xy 388.578201 -235.810956) (xy 388.537698 -235.838912) (xy 388.493236 -235.86001)
			(xy 388.445965 -235.873702) (xy 388.39711 -235.879634) (xy 388.347935 -235.877653) (xy 388.299716 -235.867809)
			(xy 388.2537 -235.850357) (xy 388.211079 -235.82575) (xy 388.172958 -235.794625) (xy 388.140323 -235.757788)
			(xy 388.11402 -235.716192) (xy 388.094729 -235.670916) (xy 388.082952 -235.623132) (xy 388.078992 -235.574078)
			(xy 387.760464 -235.574078) (xy 387.759952 -235.599524) (xy 387.751788 -235.649758) (xy 387.735672 -235.698032)
			(xy 387.712021 -235.743095) (xy 387.681448 -235.783781) (xy 387.644744 -235.819036) (xy 387.60286 -235.847946)
			(xy 387.556881 -235.869763) (xy 387.507997 -235.883923) (xy 387.457476 -235.890057) (xy 387.406624 -235.888008)
			(xy 387.35676 -235.877828) (xy 387.309174 -235.859781) (xy 387.2651 -235.834335) (xy 387.225678 -235.802148)
			(xy 387.19193 -235.764054) (xy 387.164729 -235.72104) (xy 387.144781 -235.67422) (xy 387.132602 -235.624806)
			(xy 387.128507 -235.574078) (xy 386.81025 -235.574078) (xy 386.809755 -235.598685) (xy 386.80186 -235.647262)
			(xy 386.786276 -235.693943) (xy 386.763405 -235.73752) (xy 386.73384 -235.776864) (xy 386.698347 -235.810956)
			(xy 386.657844 -235.838912) (xy 386.613382 -235.86001) (xy 386.566111 -235.873702) (xy 386.517256 -235.879634)
			(xy 386.468081 -235.877653) (xy 386.419862 -235.867809) (xy 386.373846 -235.850357) (xy 386.331225 -235.82575)
			(xy 386.293104 -235.794625) (xy 386.260469 -235.757788) (xy 386.234166 -235.716192) (xy 386.214875 -235.670916)
			(xy 386.203098 -235.623132) (xy 386.199138 -235.574078) (xy 385.88061 -235.574078) (xy 385.880098 -235.599524)
			(xy 385.871934 -235.649758) (xy 385.855818 -235.698032) (xy 385.832167 -235.743095) (xy 385.801594 -235.783781)
			(xy 385.76489 -235.819036) (xy 385.723006 -235.847946) (xy 385.677027 -235.869763) (xy 385.628143 -235.883923)
			(xy 385.577622 -235.890057) (xy 385.52677 -235.888008) (xy 385.476906 -235.877828) (xy 385.42932 -235.859781)
			(xy 385.385246 -235.834335) (xy 385.345824 -235.802148) (xy 385.312076 -235.764054) (xy 385.284875 -235.72104)
			(xy 385.264927 -235.67422) (xy 385.252748 -235.624806) (xy 385.248653 -235.574078) (xy 384.930142 -235.574078)
			(xy 384.929647 -235.598685) (xy 384.921752 -235.647262) (xy 384.906168 -235.693943) (xy 384.883297 -235.73752)
			(xy 384.853732 -235.776864) (xy 384.818239 -235.810956) (xy 384.777736 -235.838912) (xy 384.733274 -235.86001)
			(xy 384.686003 -235.873702) (xy 384.637148 -235.879634) (xy 384.587973 -235.877653) (xy 384.539754 -235.867809)
			(xy 384.493738 -235.850357) (xy 384.451117 -235.82575) (xy 384.412996 -235.794625) (xy 384.380361 -235.757788)
			(xy 384.354058 -235.716192) (xy 384.334767 -235.670916) (xy 384.32299 -235.623132) (xy 384.31903 -235.574078)
			(xy 384.000502 -235.574078) (xy 383.99999 -235.599524) (xy 383.991826 -235.649758) (xy 383.97571 -235.698032)
			(xy 383.952059 -235.743095) (xy 383.921486 -235.783781) (xy 383.884782 -235.819036) (xy 383.842898 -235.847946)
			(xy 383.796919 -235.869763) (xy 383.748035 -235.883923) (xy 383.697514 -235.890057) (xy 383.646662 -235.888008)
			(xy 383.596798 -235.877828) (xy 383.549212 -235.859781) (xy 383.505138 -235.834335) (xy 383.465716 -235.802148)
			(xy 383.431968 -235.764054) (xy 383.404767 -235.72104) (xy 383.384819 -235.67422) (xy 383.37264 -235.624806)
			(xy 383.368545 -235.574078) (xy 383.060448 -235.574078) (xy 383.059936 -235.599524) (xy 383.051772 -235.649758)
			(xy 383.035656 -235.698032) (xy 383.012005 -235.743095) (xy 382.981432 -235.783781) (xy 382.944728 -235.819036)
			(xy 382.902844 -235.847946) (xy 382.856865 -235.869763) (xy 382.807981 -235.883923) (xy 382.75746 -235.890057)
			(xy 382.706608 -235.888008) (xy 382.656744 -235.877828) (xy 382.609158 -235.859781) (xy 382.565084 -235.834335)
			(xy 382.525662 -235.802148) (xy 382.491914 -235.764054) (xy 382.464713 -235.72104) (xy 382.444765 -235.67422)
			(xy 382.432586 -235.624806) (xy 382.428491 -235.574078) (xy 382.110234 -235.574078) (xy 382.109739 -235.598685)
			(xy 382.101844 -235.647262) (xy 382.08626 -235.693943) (xy 382.063389 -235.73752) (xy 382.033824 -235.776864)
			(xy 381.998331 -235.810956) (xy 381.957828 -235.838912) (xy 381.913366 -235.86001) (xy 381.866095 -235.873702)
			(xy 381.81724 -235.879634) (xy 381.768065 -235.877653) (xy 381.719846 -235.867809) (xy 381.67383 -235.850357)
			(xy 381.631209 -235.82575) (xy 381.593088 -235.794625) (xy 381.560453 -235.757788) (xy 381.53415 -235.716192)
			(xy 381.514859 -235.670916) (xy 381.503082 -235.623132) (xy 381.499122 -235.574078) (xy 381.180594 -235.574078)
			(xy 381.180082 -235.599524) (xy 381.171918 -235.649758) (xy 381.155802 -235.698032) (xy 381.132151 -235.743095)
			(xy 381.101578 -235.783781) (xy 381.064874 -235.819036) (xy 381.02299 -235.847946) (xy 380.977011 -235.869763)
			(xy 380.928127 -235.883923) (xy 380.877606 -235.890057) (xy 380.826754 -235.888008) (xy 380.77689 -235.877828)
			(xy 380.729304 -235.859781) (xy 380.68523 -235.834335) (xy 380.645808 -235.802148) (xy 380.61206 -235.764054)
			(xy 380.584859 -235.72104) (xy 380.564911 -235.67422) (xy 380.552732 -235.624806) (xy 380.548637 -235.574078)
			(xy 380.230126 -235.574078) (xy 380.229631 -235.598685) (xy 380.221736 -235.647262) (xy 380.206152 -235.693943)
			(xy 380.183281 -235.73752) (xy 380.153716 -235.776864) (xy 380.118223 -235.810956) (xy 380.07772 -235.838912)
			(xy 380.033258 -235.86001) (xy 379.985987 -235.873702) (xy 379.937132 -235.879634) (xy 379.887957 -235.877653)
			(xy 379.839738 -235.867809) (xy 379.793722 -235.850357) (xy 379.751101 -235.82575) (xy 379.71298 -235.794625)
			(xy 379.680345 -235.757788) (xy 379.654042 -235.716192) (xy 379.634751 -235.670916) (xy 379.622974 -235.623132)
			(xy 379.619014 -235.574078) (xy 379.300486 -235.574078) (xy 379.299974 -235.599524) (xy 379.29181 -235.649758)
			(xy 379.275694 -235.698032) (xy 379.252043 -235.743095) (xy 379.22147 -235.783781) (xy 379.184766 -235.819036)
			(xy 379.142882 -235.847946) (xy 379.096903 -235.869763) (xy 379.048019 -235.883923) (xy 378.997498 -235.890057)
			(xy 378.946646 -235.888008) (xy 378.896782 -235.877828) (xy 378.849196 -235.859781) (xy 378.805122 -235.834335)
			(xy 378.7657 -235.802148) (xy 378.731952 -235.764054) (xy 378.704751 -235.72104) (xy 378.684803 -235.67422)
			(xy 378.672624 -235.624806) (xy 378.668529 -235.574078) (xy 378.350018 -235.574078) (xy 378.349523 -235.598685)
			(xy 378.341628 -235.647262) (xy 378.326044 -235.693943) (xy 378.303173 -235.73752) (xy 378.273608 -235.776864)
			(xy 378.238115 -235.810956) (xy 378.197612 -235.838912) (xy 378.15315 -235.86001) (xy 378.105879 -235.873702)
			(xy 378.057024 -235.879634) (xy 378.007849 -235.877653) (xy 377.95963 -235.867809) (xy 377.913614 -235.850357)
			(xy 377.870993 -235.82575) (xy 377.832872 -235.794625) (xy 377.800237 -235.757788) (xy 377.773934 -235.716192)
			(xy 377.754643 -235.670916) (xy 377.742866 -235.623132) (xy 377.738906 -235.574078) (xy 377.420632 -235.574078)
			(xy 377.42012 -235.599524) (xy 377.411956 -235.649758) (xy 377.39584 -235.698032) (xy 377.372189 -235.743095)
			(xy 377.341616 -235.783781) (xy 377.304912 -235.819036) (xy 377.263028 -235.847946) (xy 377.217049 -235.869763)
			(xy 377.168165 -235.883923) (xy 377.117644 -235.890057) (xy 377.066792 -235.888008) (xy 377.016928 -235.877828)
			(xy 376.969342 -235.859781) (xy 376.925268 -235.834335) (xy 376.885846 -235.802148) (xy 376.852098 -235.764054)
			(xy 376.824897 -235.72104) (xy 376.804949 -235.67422) (xy 376.79277 -235.624806) (xy 376.788675 -235.574078)
			(xy 376.480578 -235.574078) (xy 376.480066 -235.599524) (xy 376.471902 -235.649758) (xy 376.455786 -235.698032)
			(xy 376.432135 -235.743095) (xy 376.401562 -235.783781) (xy 376.364858 -235.819036) (xy 376.322974 -235.847946)
			(xy 376.276995 -235.869763) (xy 376.228111 -235.883923) (xy 376.17759 -235.890057) (xy 376.126738 -235.888008)
			(xy 376.076874 -235.877828) (xy 376.029288 -235.859781) (xy 375.985214 -235.834335) (xy 375.945792 -235.802148)
			(xy 375.912044 -235.764054) (xy 375.884843 -235.72104) (xy 375.864895 -235.67422) (xy 375.852716 -235.624806)
			(xy 375.848621 -235.574078) (xy 374.98528 -235.574078) (xy 374.98528 -236.157008) (xy 374.985357 -236.161217)
			(xy 374.986764 -236.169517) (xy 374.988074 -236.173518) (xy 374.995948 -236.196378) (xy 375.00052 -236.202728)
			(xy 375.014558 -236.22255) (xy 375.03684 -236.265707) (xy 375.052015 -236.311845) (xy 375.0597 -236.359802)
			(xy 375.059701 -236.384084) (xy 375.378467 -236.384084) (xy 375.382562 -236.333356) (xy 375.394741 -236.283942)
			(xy 375.414689 -236.237122) (xy 375.44189 -236.194108) (xy 375.475638 -236.156014) (xy 375.51506 -236.123827)
			(xy 375.559134 -236.098381) (xy 375.60672 -236.080334) (xy 375.656584 -236.070154) (xy 375.707436 -236.068105)
			(xy 375.757957 -236.074239) (xy 375.806841 -236.088399) (xy 375.85282 -236.110216) (xy 375.894704 -236.139126)
			(xy 375.931408 -236.174381) (xy 375.961981 -236.215067) (xy 375.985632 -236.26013) (xy 376.001748 -236.308404)
			(xy 376.009912 -236.358638) (xy 376.010424 -236.384084) (xy 376.328952 -236.384084) (xy 376.332912 -236.33503)
			(xy 376.344689 -236.287246) (xy 376.36398 -236.24197) (xy 376.390283 -236.200374) (xy 376.422918 -236.163537)
			(xy 376.461039 -236.132412) (xy 376.50366 -236.107805) (xy 376.549676 -236.090353) (xy 376.597895 -236.080509)
			(xy 376.64707 -236.078528) (xy 376.695925 -236.08446) (xy 376.743196 -236.098152) (xy 376.787658 -236.11925)
			(xy 376.828161 -236.147206) (xy 376.863654 -236.181298) (xy 376.893219 -236.220642) (xy 376.91609 -236.264219)
			(xy 376.931674 -236.3109) (xy 376.939569 -236.359477) (xy 376.940064 -236.384084) (xy 377.258575 -236.384084)
			(xy 377.26267 -236.333356) (xy 377.274849 -236.283942) (xy 377.294797 -236.237122) (xy 377.321998 -236.194108)
			(xy 377.355746 -236.156014) (xy 377.395168 -236.123827) (xy 377.439242 -236.098381) (xy 377.486828 -236.080334)
			(xy 377.536692 -236.070154) (xy 377.587544 -236.068105) (xy 377.638065 -236.074239) (xy 377.686949 -236.088399)
			(xy 377.732928 -236.110216) (xy 377.774812 -236.139126) (xy 377.811516 -236.174381) (xy 377.842089 -236.215067)
			(xy 377.86574 -236.26013) (xy 377.881856 -236.308404) (xy 377.89002 -236.358638) (xy 377.890532 -236.384084)
			(xy 378.20906 -236.384084) (xy 378.21302 -236.33503) (xy 378.224797 -236.287246) (xy 378.244088 -236.24197)
			(xy 378.270391 -236.200374) (xy 378.303026 -236.163537) (xy 378.341147 -236.132412) (xy 378.383768 -236.107805)
			(xy 378.429784 -236.090353) (xy 378.478003 -236.080509) (xy 378.527178 -236.078528) (xy 378.576033 -236.08446)
			(xy 378.623304 -236.098152) (xy 378.667766 -236.11925) (xy 378.708269 -236.147206) (xy 378.743762 -236.181298)
			(xy 378.773327 -236.220642) (xy 378.796198 -236.264219) (xy 378.811782 -236.3109) (xy 378.819677 -236.359477)
			(xy 378.820172 -236.384084) (xy 379.138683 -236.384084) (xy 379.142778 -236.333356) (xy 379.154957 -236.283942)
			(xy 379.174905 -236.237122) (xy 379.202106 -236.194108) (xy 379.235854 -236.156014) (xy 379.275276 -236.123827)
			(xy 379.31935 -236.098381) (xy 379.366936 -236.080334) (xy 379.4168 -236.070154) (xy 379.467652 -236.068105)
			(xy 379.518173 -236.074239) (xy 379.567057 -236.088399) (xy 379.613036 -236.110216) (xy 379.65492 -236.139126)
			(xy 379.691624 -236.174381) (xy 379.722197 -236.215067) (xy 379.745848 -236.26013) (xy 379.761964 -236.308404)
			(xy 379.770128 -236.358638) (xy 379.77064 -236.384084) (xy 380.078483 -236.384084) (xy 380.082578 -236.333356)
			(xy 380.094757 -236.283942) (xy 380.114705 -236.237122) (xy 380.141906 -236.194108) (xy 380.175654 -236.156014)
			(xy 380.215076 -236.123827) (xy 380.25915 -236.098381) (xy 380.306736 -236.080334) (xy 380.3566 -236.070154)
			(xy 380.407452 -236.068105) (xy 380.457973 -236.074239) (xy 380.506857 -236.088399) (xy 380.552836 -236.110216)
			(xy 380.59472 -236.139126) (xy 380.631424 -236.174381) (xy 380.661997 -236.215067) (xy 380.685648 -236.26013)
			(xy 380.701764 -236.308404) (xy 380.709928 -236.358638) (xy 380.71044 -236.384084) (xy 381.028968 -236.384084)
			(xy 381.032928 -236.33503) (xy 381.044705 -236.287246) (xy 381.063996 -236.24197) (xy 381.090299 -236.200374)
			(xy 381.122934 -236.163537) (xy 381.161055 -236.132412) (xy 381.203676 -236.107805) (xy 381.249692 -236.090353)
			(xy 381.297911 -236.080509) (xy 381.347086 -236.078528) (xy 381.395941 -236.08446) (xy 381.443212 -236.098152)
			(xy 381.487674 -236.11925) (xy 381.528177 -236.147206) (xy 381.56367 -236.181298) (xy 381.593235 -236.220642)
			(xy 381.616106 -236.264219) (xy 381.63169 -236.3109) (xy 381.639585 -236.359477) (xy 381.64008 -236.384084)
			(xy 381.958591 -236.384084) (xy 381.962686 -236.333356) (xy 381.974865 -236.283942) (xy 381.994813 -236.237122)
			(xy 382.022014 -236.194108) (xy 382.055762 -236.156014) (xy 382.095184 -236.123827) (xy 382.139258 -236.098381)
			(xy 382.186844 -236.080334) (xy 382.236708 -236.070154) (xy 382.28756 -236.068105) (xy 382.338081 -236.074239)
			(xy 382.386965 -236.088399) (xy 382.432944 -236.110216) (xy 382.474828 -236.139126) (xy 382.511532 -236.174381)
			(xy 382.542105 -236.215067) (xy 382.565756 -236.26013) (xy 382.581872 -236.308404) (xy 382.590036 -236.358638)
			(xy 382.590548 -236.384084) (xy 382.909076 -236.384084) (xy 382.913036 -236.33503) (xy 382.924813 -236.287246)
			(xy 382.944104 -236.24197) (xy 382.970407 -236.200374) (xy 383.003042 -236.163537) (xy 383.041163 -236.132412)
			(xy 383.083784 -236.107805) (xy 383.1298 -236.090353) (xy 383.178019 -236.080509) (xy 383.227194 -236.078528)
			(xy 383.276049 -236.08446) (xy 383.32332 -236.098152) (xy 383.367782 -236.11925) (xy 383.408285 -236.147206)
			(xy 383.443778 -236.181298) (xy 383.473343 -236.220642) (xy 383.496214 -236.264219) (xy 383.511798 -236.3109)
			(xy 383.519693 -236.359477) (xy 383.520188 -236.384084) (xy 383.838699 -236.384084) (xy 383.842794 -236.333356)
			(xy 383.854973 -236.283942) (xy 383.874921 -236.237122) (xy 383.902122 -236.194108) (xy 383.93587 -236.156014)
			(xy 383.975292 -236.123827) (xy 384.019366 -236.098381) (xy 384.066952 -236.080334) (xy 384.116816 -236.070154)
			(xy 384.167668 -236.068105) (xy 384.218189 -236.074239) (xy 384.267073 -236.088399) (xy 384.313052 -236.110216)
			(xy 384.354936 -236.139126) (xy 384.39164 -236.174381) (xy 384.422213 -236.215067) (xy 384.445864 -236.26013)
			(xy 384.46198 -236.308404) (xy 384.470144 -236.358638) (xy 384.470656 -236.384084) (xy 384.78893 -236.384084)
			(xy 384.79289 -236.33503) (xy 384.804667 -236.287246) (xy 384.823958 -236.24197) (xy 384.850261 -236.200374)
			(xy 384.882896 -236.163537) (xy 384.921017 -236.132412) (xy 384.963638 -236.107805) (xy 385.009654 -236.090353)
			(xy 385.057873 -236.080509) (xy 385.107048 -236.078528) (xy 385.155903 -236.08446) (xy 385.203174 -236.098152)
			(xy 385.247636 -236.11925) (xy 385.288139 -236.147206) (xy 385.323632 -236.181298) (xy 385.353197 -236.220642)
			(xy 385.376068 -236.264219) (xy 385.391652 -236.3109) (xy 385.399547 -236.359477) (xy 385.400042 -236.384084)
			(xy 385.718553 -236.384084) (xy 385.722648 -236.333356) (xy 385.734827 -236.283942) (xy 385.754775 -236.237122)
			(xy 385.781976 -236.194108) (xy 385.815724 -236.156014) (xy 385.855146 -236.123827) (xy 385.89922 -236.098381)
			(xy 385.946806 -236.080334) (xy 385.99667 -236.070154) (xy 386.047522 -236.068105) (xy 386.098043 -236.074239)
			(xy 386.146927 -236.088399) (xy 386.192906 -236.110216) (xy 386.23479 -236.139126) (xy 386.271494 -236.174381)
			(xy 386.302067 -236.215067) (xy 386.325718 -236.26013) (xy 386.341834 -236.308404) (xy 386.349998 -236.358638)
			(xy 386.35051 -236.384084) (xy 386.658607 -236.384084) (xy 386.662702 -236.333356) (xy 386.674881 -236.283942)
			(xy 386.694829 -236.237122) (xy 386.72203 -236.194108) (xy 386.755778 -236.156014) (xy 386.7952 -236.123827)
			(xy 386.839274 -236.098381) (xy 386.88686 -236.080334) (xy 386.936724 -236.070154) (xy 386.987576 -236.068105)
			(xy 387.038097 -236.074239) (xy 387.086981 -236.088399) (xy 387.13296 -236.110216) (xy 387.174844 -236.139126)
			(xy 387.211548 -236.174381) (xy 387.242121 -236.215067) (xy 387.265772 -236.26013) (xy 387.281888 -236.308404)
			(xy 387.290052 -236.358638) (xy 387.290564 -236.384084) (xy 387.609092 -236.384084) (xy 387.613052 -236.33503)
			(xy 387.624829 -236.287246) (xy 387.64412 -236.24197) (xy 387.670423 -236.200374) (xy 387.703058 -236.163537)
			(xy 387.741179 -236.132412) (xy 387.7838 -236.107805) (xy 387.829816 -236.090353) (xy 387.878035 -236.080509)
			(xy 387.92721 -236.078528) (xy 387.976065 -236.08446) (xy 388.023336 -236.098152) (xy 388.067798 -236.11925)
			(xy 388.108301 -236.147206) (xy 388.143794 -236.181298) (xy 388.173359 -236.220642) (xy 388.19623 -236.264219)
			(xy 388.211814 -236.3109) (xy 388.219709 -236.359477) (xy 388.220204 -236.384084) (xy 388.538715 -236.384084)
			(xy 388.54281 -236.333356) (xy 388.554989 -236.283942) (xy 388.574937 -236.237122) (xy 388.602138 -236.194108)
			(xy 388.635886 -236.156014) (xy 388.675308 -236.123827) (xy 388.719382 -236.098381) (xy 388.766968 -236.080334)
			(xy 388.816832 -236.070154) (xy 388.867684 -236.068105) (xy 388.918205 -236.074239) (xy 388.967089 -236.088399)
			(xy 389.013068 -236.110216) (xy 389.054952 -236.139126) (xy 389.091656 -236.174381) (xy 389.122229 -236.215067)
			(xy 389.14588 -236.26013) (xy 389.161996 -236.308404) (xy 389.17016 -236.358638) (xy 389.170672 -236.384084)
			(xy 389.488946 -236.384084) (xy 389.492906 -236.33503) (xy 389.504683 -236.287246) (xy 389.523974 -236.24197)
			(xy 389.550277 -236.200374) (xy 389.582912 -236.163537) (xy 389.621033 -236.132412) (xy 389.663654 -236.107805)
			(xy 389.70967 -236.090353) (xy 389.757889 -236.080509) (xy 389.807064 -236.078528) (xy 389.855919 -236.08446)
			(xy 389.90319 -236.098152) (xy 389.947652 -236.11925) (xy 389.988155 -236.147206) (xy 390.023648 -236.181298)
			(xy 390.053213 -236.220642) (xy 390.076084 -236.264219) (xy 390.091668 -236.3109) (xy 390.099563 -236.359477)
			(xy 390.100058 -236.384084) (xy 390.418569 -236.384084) (xy 390.422664 -236.333356) (xy 390.434843 -236.283942)
			(xy 390.454791 -236.237122) (xy 390.481992 -236.194108) (xy 390.51574 -236.156014) (xy 390.555162 -236.123827)
			(xy 390.599236 -236.098381) (xy 390.646822 -236.080334) (xy 390.696686 -236.070154) (xy 390.747538 -236.068105)
			(xy 390.798059 -236.074239) (xy 390.846943 -236.088399) (xy 390.892922 -236.110216) (xy 390.934806 -236.139126)
			(xy 390.97151 -236.174381) (xy 391.002083 -236.215067) (xy 391.025734 -236.26013) (xy 391.04185 -236.308404)
			(xy 391.050014 -236.358638) (xy 391.050526 -236.384084) (xy 391.369054 -236.384084) (xy 391.373014 -236.33503)
			(xy 391.384791 -236.287246) (xy 391.404082 -236.24197) (xy 391.430385 -236.200374) (xy 391.46302 -236.163537)
			(xy 391.501141 -236.132412) (xy 391.543762 -236.107805) (xy 391.589778 -236.090353) (xy 391.637997 -236.080509)
			(xy 391.687172 -236.078528) (xy 391.736027 -236.08446) (xy 391.783298 -236.098152) (xy 391.82776 -236.11925)
			(xy 391.868263 -236.147206) (xy 391.903756 -236.181298) (xy 391.933321 -236.220642) (xy 391.956192 -236.264219)
			(xy 391.971776 -236.3109) (xy 391.979671 -236.359477) (xy 391.980166 -236.384084) (xy 391.979671 -236.408691)
			(xy 391.971776 -236.457268) (xy 391.956192 -236.503949) (xy 391.933321 -236.547526) (xy 391.903756 -236.58687)
			(xy 391.868263 -236.620962) (xy 391.82776 -236.648918) (xy 391.825433 -236.650022) (xy 394.377176 -236.650022)
			(xy 394.381136 -236.600968) (xy 394.392913 -236.553184) (xy 394.412204 -236.507908) (xy 394.438507 -236.466312)
			(xy 394.471142 -236.429475) (xy 394.509263 -236.39835) (xy 394.551884 -236.373743) (xy 394.5979 -236.356291)
			(xy 394.646119 -236.346447) (xy 394.695294 -236.344466) (xy 394.744149 -236.350398) (xy 394.79142 -236.36409)
			(xy 394.835882 -236.385188) (xy 394.876385 -236.413144) (xy 394.911878 -236.447236) (xy 394.941443 -236.48658)
			(xy 394.964314 -236.530157) (xy 394.979898 -236.576838) (xy 394.987793 -236.625415) (xy 394.988288 -236.650022)
			(xy 394.987793 -236.674629) (xy 394.979898 -236.723206) (xy 394.964314 -236.769887) (xy 394.941443 -236.813464)
			(xy 394.911878 -236.852808) (xy 394.876385 -236.8869) (xy 394.835882 -236.914856) (xy 394.79142 -236.935954)
			(xy 394.744149 -236.949646) (xy 394.695294 -236.955578) (xy 394.646119 -236.953597) (xy 394.5979 -236.943753)
			(xy 394.551884 -236.926301) (xy 394.509263 -236.901694) (xy 394.471142 -236.870569) (xy 394.438507 -236.833732)
			(xy 394.412204 -236.792136) (xy 394.392913 -236.74686) (xy 394.381136 -236.699076) (xy 394.377176 -236.650022)
			(xy 391.825433 -236.650022) (xy 391.783298 -236.670016) (xy 391.736027 -236.683708) (xy 391.687172 -236.68964)
			(xy 391.637997 -236.687659) (xy 391.589778 -236.677815) (xy 391.543762 -236.660363) (xy 391.501141 -236.635756)
			(xy 391.46302 -236.604631) (xy 391.430385 -236.567794) (xy 391.404082 -236.526198) (xy 391.384791 -236.480922)
			(xy 391.373014 -236.433138) (xy 391.369054 -236.384084) (xy 391.050526 -236.384084) (xy 391.050014 -236.40953)
			(xy 391.04185 -236.459764) (xy 391.025734 -236.508038) (xy 391.002083 -236.553101) (xy 390.97151 -236.593787)
			(xy 390.934806 -236.629042) (xy 390.892922 -236.657952) (xy 390.846943 -236.679769) (xy 390.798059 -236.693929)
			(xy 390.747538 -236.700063) (xy 390.696686 -236.698014) (xy 390.646822 -236.687834) (xy 390.599236 -236.669787)
			(xy 390.555162 -236.644341) (xy 390.51574 -236.612154) (xy 390.481992 -236.57406) (xy 390.454791 -236.531046)
			(xy 390.434843 -236.484226) (xy 390.422664 -236.434812) (xy 390.418569 -236.384084) (xy 390.100058 -236.384084)
			(xy 390.099563 -236.408691) (xy 390.091668 -236.457268) (xy 390.076084 -236.503949) (xy 390.053213 -236.547526)
			(xy 390.023648 -236.58687) (xy 389.988155 -236.620962) (xy 389.947652 -236.648918) (xy 389.90319 -236.670016)
			(xy 389.855919 -236.683708) (xy 389.807064 -236.68964) (xy 389.757889 -236.687659) (xy 389.70967 -236.677815)
			(xy 389.663654 -236.660363) (xy 389.621033 -236.635756) (xy 389.582912 -236.604631) (xy 389.550277 -236.567794)
			(xy 389.523974 -236.526198) (xy 389.504683 -236.480922) (xy 389.492906 -236.433138) (xy 389.488946 -236.384084)
			(xy 389.170672 -236.384084) (xy 389.17016 -236.40953) (xy 389.161996 -236.459764) (xy 389.14588 -236.508038)
			(xy 389.122229 -236.553101) (xy 389.091656 -236.593787) (xy 389.054952 -236.629042) (xy 389.013068 -236.657952)
			(xy 388.967089 -236.679769) (xy 388.918205 -236.693929) (xy 388.867684 -236.700063) (xy 388.816832 -236.698014)
			(xy 388.766968 -236.687834) (xy 388.719382 -236.669787) (xy 388.675308 -236.644341) (xy 388.635886 -236.612154)
			(xy 388.602138 -236.57406) (xy 388.574937 -236.531046) (xy 388.554989 -236.484226) (xy 388.54281 -236.434812)
			(xy 388.538715 -236.384084) (xy 388.220204 -236.384084) (xy 388.219709 -236.408691) (xy 388.211814 -236.457268)
			(xy 388.19623 -236.503949) (xy 388.173359 -236.547526) (xy 388.143794 -236.58687) (xy 388.108301 -236.620962)
			(xy 388.067798 -236.648918) (xy 388.023336 -236.670016) (xy 387.976065 -236.683708) (xy 387.92721 -236.68964)
			(xy 387.878035 -236.687659) (xy 387.829816 -236.677815) (xy 387.7838 -236.660363) (xy 387.741179 -236.635756)
			(xy 387.703058 -236.604631) (xy 387.670423 -236.567794) (xy 387.64412 -236.526198) (xy 387.624829 -236.480922)
			(xy 387.613052 -236.433138) (xy 387.609092 -236.384084) (xy 387.290564 -236.384084) (xy 387.290052 -236.40953)
			(xy 387.281888 -236.459764) (xy 387.265772 -236.508038) (xy 387.242121 -236.553101) (xy 387.211548 -236.593787)
			(xy 387.174844 -236.629042) (xy 387.13296 -236.657952) (xy 387.086981 -236.679769) (xy 387.038097 -236.693929)
			(xy 386.987576 -236.700063) (xy 386.936724 -236.698014) (xy 386.88686 -236.687834) (xy 386.839274 -236.669787)
			(xy 386.7952 -236.644341) (xy 386.755778 -236.612154) (xy 386.72203 -236.57406) (xy 386.694829 -236.531046)
			(xy 386.674881 -236.484226) (xy 386.662702 -236.434812) (xy 386.658607 -236.384084) (xy 386.35051 -236.384084)
			(xy 386.349998 -236.40953) (xy 386.341834 -236.459764) (xy 386.325718 -236.508038) (xy 386.302067 -236.553101)
			(xy 386.271494 -236.593787) (xy 386.23479 -236.629042) (xy 386.192906 -236.657952) (xy 386.146927 -236.679769)
			(xy 386.098043 -236.693929) (xy 386.047522 -236.700063) (xy 385.99667 -236.698014) (xy 385.946806 -236.687834)
			(xy 385.89922 -236.669787) (xy 385.855146 -236.644341) (xy 385.815724 -236.612154) (xy 385.781976 -236.57406)
			(xy 385.754775 -236.531046) (xy 385.734827 -236.484226) (xy 385.722648 -236.434812) (xy 385.718553 -236.384084)
			(xy 385.400042 -236.384084) (xy 385.399547 -236.408691) (xy 385.391652 -236.457268) (xy 385.376068 -236.503949)
			(xy 385.353197 -236.547526) (xy 385.323632 -236.58687) (xy 385.288139 -236.620962) (xy 385.247636 -236.648918)
			(xy 385.203174 -236.670016) (xy 385.155903 -236.683708) (xy 385.107048 -236.68964) (xy 385.057873 -236.687659)
			(xy 385.009654 -236.677815) (xy 384.963638 -236.660363) (xy 384.921017 -236.635756) (xy 384.882896 -236.604631)
			(xy 384.850261 -236.567794) (xy 384.823958 -236.526198) (xy 384.804667 -236.480922) (xy 384.79289 -236.433138)
			(xy 384.78893 -236.384084) (xy 384.470656 -236.384084) (xy 384.470144 -236.40953) (xy 384.46198 -236.459764)
			(xy 384.445864 -236.508038) (xy 384.422213 -236.553101) (xy 384.39164 -236.593787) (xy 384.354936 -236.629042)
			(xy 384.313052 -236.657952) (xy 384.267073 -236.679769) (xy 384.218189 -236.693929) (xy 384.167668 -236.700063)
			(xy 384.116816 -236.698014) (xy 384.066952 -236.687834) (xy 384.019366 -236.669787) (xy 383.975292 -236.644341)
			(xy 383.93587 -236.612154) (xy 383.902122 -236.57406) (xy 383.874921 -236.531046) (xy 383.854973 -236.484226)
			(xy 383.842794 -236.434812) (xy 383.838699 -236.384084) (xy 383.520188 -236.384084) (xy 383.519693 -236.408691)
			(xy 383.511798 -236.457268) (xy 383.496214 -236.503949) (xy 383.473343 -236.547526) (xy 383.443778 -236.58687)
			(xy 383.408285 -236.620962) (xy 383.367782 -236.648918) (xy 383.32332 -236.670016) (xy 383.276049 -236.683708)
			(xy 383.227194 -236.68964) (xy 383.178019 -236.687659) (xy 383.1298 -236.677815) (xy 383.083784 -236.660363)
			(xy 383.041163 -236.635756) (xy 383.003042 -236.604631) (xy 382.970407 -236.567794) (xy 382.944104 -236.526198)
			(xy 382.924813 -236.480922) (xy 382.913036 -236.433138) (xy 382.909076 -236.384084) (xy 382.590548 -236.384084)
			(xy 382.590036 -236.40953) (xy 382.581872 -236.459764) (xy 382.565756 -236.508038) (xy 382.542105 -236.553101)
			(xy 382.511532 -236.593787) (xy 382.474828 -236.629042) (xy 382.432944 -236.657952) (xy 382.386965 -236.679769)
			(xy 382.338081 -236.693929) (xy 382.28756 -236.700063) (xy 382.236708 -236.698014) (xy 382.186844 -236.687834)
			(xy 382.139258 -236.669787) (xy 382.095184 -236.644341) (xy 382.055762 -236.612154) (xy 382.022014 -236.57406)
			(xy 381.994813 -236.531046) (xy 381.974865 -236.484226) (xy 381.962686 -236.434812) (xy 381.958591 -236.384084)
			(xy 381.64008 -236.384084) (xy 381.639585 -236.408691) (xy 381.63169 -236.457268) (xy 381.616106 -236.503949)
			(xy 381.593235 -236.547526) (xy 381.56367 -236.58687) (xy 381.528177 -236.620962) (xy 381.487674 -236.648918)
			(xy 381.443212 -236.670016) (xy 381.395941 -236.683708) (xy 381.347086 -236.68964) (xy 381.297911 -236.687659)
			(xy 381.249692 -236.677815) (xy 381.203676 -236.660363) (xy 381.161055 -236.635756) (xy 381.122934 -236.604631)
			(xy 381.090299 -236.567794) (xy 381.063996 -236.526198) (xy 381.044705 -236.480922) (xy 381.032928 -236.433138)
			(xy 381.028968 -236.384084) (xy 380.71044 -236.384084) (xy 380.709928 -236.40953) (xy 380.701764 -236.459764)
			(xy 380.685648 -236.508038) (xy 380.661997 -236.553101) (xy 380.631424 -236.593787) (xy 380.59472 -236.629042)
			(xy 380.552836 -236.657952) (xy 380.506857 -236.679769) (xy 380.457973 -236.693929) (xy 380.407452 -236.700063)
			(xy 380.3566 -236.698014) (xy 380.306736 -236.687834) (xy 380.25915 -236.669787) (xy 380.215076 -236.644341)
			(xy 380.175654 -236.612154) (xy 380.141906 -236.57406) (xy 380.114705 -236.531046) (xy 380.094757 -236.484226)
			(xy 380.082578 -236.434812) (xy 380.078483 -236.384084) (xy 379.77064 -236.384084) (xy 379.770128 -236.40953)
			(xy 379.761964 -236.459764) (xy 379.745848 -236.508038) (xy 379.722197 -236.553101) (xy 379.691624 -236.593787)
			(xy 379.65492 -236.629042) (xy 379.613036 -236.657952) (xy 379.567057 -236.679769) (xy 379.518173 -236.693929)
			(xy 379.467652 -236.700063) (xy 379.4168 -236.698014) (xy 379.366936 -236.687834) (xy 379.31935 -236.669787)
			(xy 379.275276 -236.644341) (xy 379.235854 -236.612154) (xy 379.202106 -236.57406) (xy 379.174905 -236.531046)
			(xy 379.154957 -236.484226) (xy 379.142778 -236.434812) (xy 379.138683 -236.384084) (xy 378.820172 -236.384084)
			(xy 378.819677 -236.408691) (xy 378.811782 -236.457268) (xy 378.796198 -236.503949) (xy 378.773327 -236.547526)
			(xy 378.743762 -236.58687) (xy 378.708269 -236.620962) (xy 378.667766 -236.648918) (xy 378.623304 -236.670016)
			(xy 378.576033 -236.683708) (xy 378.527178 -236.68964) (xy 378.478003 -236.687659) (xy 378.429784 -236.677815)
			(xy 378.383768 -236.660363) (xy 378.341147 -236.635756) (xy 378.303026 -236.604631) (xy 378.270391 -236.567794)
			(xy 378.244088 -236.526198) (xy 378.224797 -236.480922) (xy 378.21302 -236.433138) (xy 378.20906 -236.384084)
			(xy 377.890532 -236.384084) (xy 377.89002 -236.40953) (xy 377.881856 -236.459764) (xy 377.86574 -236.508038)
			(xy 377.842089 -236.553101) (xy 377.811516 -236.593787) (xy 377.774812 -236.629042) (xy 377.732928 -236.657952)
			(xy 377.686949 -236.679769) (xy 377.638065 -236.693929) (xy 377.587544 -236.700063) (xy 377.536692 -236.698014)
			(xy 377.486828 -236.687834) (xy 377.439242 -236.669787) (xy 377.395168 -236.644341) (xy 377.355746 -236.612154)
			(xy 377.321998 -236.57406) (xy 377.294797 -236.531046) (xy 377.274849 -236.484226) (xy 377.26267 -236.434812)
			(xy 377.258575 -236.384084) (xy 376.940064 -236.384084) (xy 376.939569 -236.408691) (xy 376.931674 -236.457268)
			(xy 376.91609 -236.503949) (xy 376.893219 -236.547526) (xy 376.863654 -236.58687) (xy 376.828161 -236.620962)
			(xy 376.787658 -236.648918) (xy 376.743196 -236.670016) (xy 376.695925 -236.683708) (xy 376.64707 -236.68964)
			(xy 376.597895 -236.687659) (xy 376.549676 -236.677815) (xy 376.50366 -236.660363) (xy 376.461039 -236.635756)
			(xy 376.422918 -236.604631) (xy 376.390283 -236.567794) (xy 376.36398 -236.526198) (xy 376.344689 -236.480922)
			(xy 376.332912 -236.433138) (xy 376.328952 -236.384084) (xy 376.010424 -236.384084) (xy 376.009912 -236.40953)
			(xy 376.001748 -236.459764) (xy 375.985632 -236.508038) (xy 375.961981 -236.553101) (xy 375.931408 -236.593787)
			(xy 375.894704 -236.629042) (xy 375.85282 -236.657952) (xy 375.806841 -236.679769) (xy 375.757957 -236.693929)
			(xy 375.707436 -236.700063) (xy 375.656584 -236.698014) (xy 375.60672 -236.687834) (xy 375.559134 -236.669787)
			(xy 375.51506 -236.644341) (xy 375.475638 -236.612154) (xy 375.44189 -236.57406) (xy 375.414689 -236.531046)
			(xy 375.394741 -236.484226) (xy 375.382562 -236.434812) (xy 375.378467 -236.384084) (xy 375.059701 -236.384084)
			(xy 375.059702 -236.408372) (xy 375.052021 -236.45633) (xy 375.03685 -236.50247) (xy 375.014571 -236.545628)
			(xy 375.00052 -236.56544) (xy 374.995948 -236.57179) (xy 374.988074 -236.59465) (xy 374.986788 -236.598657)
			(xy 374.98538 -236.606953) (xy 374.98528 -236.61116) (xy 374.98528 -236.811312) (xy 374.98528 -236.814614)
			(xy 374.986465 -236.825363) (xy 374.996595 -236.844444) (xy 375.004838 -236.851444) (xy 375.00687 -236.852968)
			(xy 375.074688 -236.90072) (xy 375.085077 -236.907295) (xy 375.10943 -236.910474) (xy 375.12117 -236.906816)
			(xy 375.121932 -236.906562) (xy 375.12879 -236.904276) (xy 375.152133 -236.897052) (xy 375.200371 -236.889272)
			(xy 375.224802 -236.888782) (xy 375.250058 -236.889304) (xy 375.299881 -236.897618) (xy 375.347656 -236.91402)
			(xy 375.39208 -236.938061) (xy 375.431941 -236.969086) (xy 375.466152 -237.006249) (xy 375.493779 -237.048536)
			(xy 375.51407 -237.094794) (xy 375.52647 -237.14376) (xy 375.53064 -237.19409) (xy 375.848621 -237.19409)
			(xy 375.852716 -237.143362) (xy 375.864895 -237.093948) (xy 375.884843 -237.047128) (xy 375.912044 -237.004114)
			(xy 375.945792 -236.96602) (xy 375.985214 -236.933833) (xy 376.029288 -236.908387) (xy 376.076874 -236.89034)
			(xy 376.126738 -236.88016) (xy 376.17759 -236.878111) (xy 376.228111 -236.884245) (xy 376.276995 -236.898405)
			(xy 376.322974 -236.920222) (xy 376.364858 -236.949132) (xy 376.401562 -236.984387) (xy 376.432135 -237.025073)
			(xy 376.455786 -237.070136) (xy 376.471902 -237.11841) (xy 376.480066 -237.168644) (xy 376.480578 -237.19409)
			(xy 376.788675 -237.19409) (xy 376.79277 -237.143362) (xy 376.804949 -237.093948) (xy 376.824897 -237.047128)
			(xy 376.852098 -237.004114) (xy 376.885846 -236.96602) (xy 376.925268 -236.933833) (xy 376.969342 -236.908387)
			(xy 377.016928 -236.89034) (xy 377.066792 -236.88016) (xy 377.117644 -236.878111) (xy 377.168165 -236.884245)
			(xy 377.217049 -236.898405) (xy 377.263028 -236.920222) (xy 377.304912 -236.949132) (xy 377.341616 -236.984387)
			(xy 377.372189 -237.025073) (xy 377.39584 -237.070136) (xy 377.411956 -237.11841) (xy 377.42012 -237.168644)
			(xy 377.420632 -237.19409) (xy 378.668529 -237.19409) (xy 378.672624 -237.143362) (xy 378.684803 -237.093948)
			(xy 378.704751 -237.047128) (xy 378.731952 -237.004114) (xy 378.7657 -236.96602) (xy 378.805122 -236.933833)
			(xy 378.849196 -236.908387) (xy 378.896782 -236.89034) (xy 378.946646 -236.88016) (xy 378.997498 -236.878111)
			(xy 379.048019 -236.884245) (xy 379.096903 -236.898405) (xy 379.142882 -236.920222) (xy 379.184766 -236.949132)
			(xy 379.22147 -236.984387) (xy 379.252043 -237.025073) (xy 379.275694 -237.070136) (xy 379.29181 -237.11841)
			(xy 379.299974 -237.168644) (xy 379.300486 -237.19409) (xy 379.619014 -237.19409) (xy 379.622974 -237.145036)
			(xy 379.634751 -237.097252) (xy 379.654042 -237.051976) (xy 379.680345 -237.01038) (xy 379.71298 -236.973543)
			(xy 379.751101 -236.942418) (xy 379.793722 -236.917811) (xy 379.839738 -236.900359) (xy 379.887957 -236.890515)
			(xy 379.937132 -236.888534) (xy 379.985987 -236.894466) (xy 380.033258 -236.908158) (xy 380.07772 -236.929256)
			(xy 380.118223 -236.957212) (xy 380.153716 -236.991304) (xy 380.183281 -237.030648) (xy 380.206152 -237.074225)
			(xy 380.221736 -237.120906) (xy 380.229631 -237.169483) (xy 380.230126 -237.19409) (xy 380.548637 -237.19409)
			(xy 380.552732 -237.143362) (xy 380.564911 -237.093948) (xy 380.584859 -237.047128) (xy 380.61206 -237.004114)
			(xy 380.645808 -236.96602) (xy 380.68523 -236.933833) (xy 380.729304 -236.908387) (xy 380.77689 -236.89034)
			(xy 380.826754 -236.88016) (xy 380.877606 -236.878111) (xy 380.928127 -236.884245) (xy 380.977011 -236.898405)
			(xy 381.02299 -236.920222) (xy 381.064874 -236.949132) (xy 381.101578 -236.984387) (xy 381.132151 -237.025073)
			(xy 381.155802 -237.070136) (xy 381.171918 -237.11841) (xy 381.180082 -237.168644) (xy 381.180594 -237.19409)
			(xy 381.499122 -237.19409) (xy 381.503082 -237.145036) (xy 381.514859 -237.097252) (xy 381.53415 -237.051976)
			(xy 381.560453 -237.01038) (xy 381.593088 -236.973543) (xy 381.631209 -236.942418) (xy 381.67383 -236.917811)
			(xy 381.719846 -236.900359) (xy 381.768065 -236.890515) (xy 381.81724 -236.888534) (xy 381.866095 -236.894466)
			(xy 381.913366 -236.908158) (xy 381.957828 -236.929256) (xy 381.998331 -236.957212) (xy 382.033824 -236.991304)
			(xy 382.063389 -237.030648) (xy 382.08626 -237.074225) (xy 382.101844 -237.120906) (xy 382.109739 -237.169483)
			(xy 382.110234 -237.19409) (xy 382.428491 -237.19409) (xy 382.432586 -237.143362) (xy 382.444765 -237.093948)
			(xy 382.464713 -237.047128) (xy 382.491914 -237.004114) (xy 382.525662 -236.96602) (xy 382.565084 -236.933833)
			(xy 382.609158 -236.908387) (xy 382.656744 -236.89034) (xy 382.706608 -236.88016) (xy 382.75746 -236.878111)
			(xy 382.807981 -236.884245) (xy 382.856865 -236.898405) (xy 382.902844 -236.920222) (xy 382.944728 -236.949132)
			(xy 382.981432 -236.984387) (xy 383.012005 -237.025073) (xy 383.035656 -237.070136) (xy 383.051772 -237.11841)
			(xy 383.059936 -237.168644) (xy 383.060448 -237.19409) (xy 383.368545 -237.19409) (xy 383.37264 -237.143362)
			(xy 383.384819 -237.093948) (xy 383.404767 -237.047128) (xy 383.431968 -237.004114) (xy 383.465716 -236.96602)
			(xy 383.505138 -236.933833) (xy 383.549212 -236.908387) (xy 383.596798 -236.89034) (xy 383.646662 -236.88016)
			(xy 383.697514 -236.878111) (xy 383.748035 -236.884245) (xy 383.796919 -236.898405) (xy 383.842898 -236.920222)
			(xy 383.884782 -236.949132) (xy 383.921486 -236.984387) (xy 383.952059 -237.025073) (xy 383.97571 -237.070136)
			(xy 383.991826 -237.11841) (xy 383.99999 -237.168644) (xy 384.000502 -237.19409) (xy 385.248653 -237.19409)
			(xy 385.252748 -237.143362) (xy 385.264927 -237.093948) (xy 385.284875 -237.047128) (xy 385.312076 -237.004114)
			(xy 385.345824 -236.96602) (xy 385.385246 -236.933833) (xy 385.42932 -236.908387) (xy 385.476906 -236.89034)
			(xy 385.52677 -236.88016) (xy 385.577622 -236.878111) (xy 385.628143 -236.884245) (xy 385.677027 -236.898405)
			(xy 385.723006 -236.920222) (xy 385.76489 -236.949132) (xy 385.801594 -236.984387) (xy 385.832167 -237.025073)
			(xy 385.855818 -237.070136) (xy 385.871934 -237.11841) (xy 385.880098 -237.168644) (xy 385.88061 -237.19409)
			(xy 386.199138 -237.19409) (xy 386.203098 -237.145036) (xy 386.214875 -237.097252) (xy 386.234166 -237.051976)
			(xy 386.260469 -237.01038) (xy 386.293104 -236.973543) (xy 386.331225 -236.942418) (xy 386.373846 -236.917811)
			(xy 386.419862 -236.900359) (xy 386.468081 -236.890515) (xy 386.517256 -236.888534) (xy 386.566111 -236.894466)
			(xy 386.613382 -236.908158) (xy 386.657844 -236.929256) (xy 386.698347 -236.957212) (xy 386.73384 -236.991304)
			(xy 386.763405 -237.030648) (xy 386.786276 -237.074225) (xy 386.80186 -237.120906) (xy 386.809755 -237.169483)
			(xy 386.81025 -237.19409) (xy 387.128507 -237.19409) (xy 387.132602 -237.143362) (xy 387.144781 -237.093948)
			(xy 387.164729 -237.047128) (xy 387.19193 -237.004114) (xy 387.225678 -236.96602) (xy 387.2651 -236.933833)
			(xy 387.309174 -236.908387) (xy 387.35676 -236.89034) (xy 387.406624 -236.88016) (xy 387.457476 -236.878111)
			(xy 387.507997 -236.884245) (xy 387.556881 -236.898405) (xy 387.60286 -236.920222) (xy 387.644744 -236.949132)
			(xy 387.681448 -236.984387) (xy 387.712021 -237.025073) (xy 387.735672 -237.070136) (xy 387.751788 -237.11841)
			(xy 387.759952 -237.168644) (xy 387.760464 -237.19409) (xy 388.078992 -237.19409) (xy 388.082952 -237.145036)
			(xy 388.094729 -237.097252) (xy 388.11402 -237.051976) (xy 388.140323 -237.01038) (xy 388.172958 -236.973543)
			(xy 388.211079 -236.942418) (xy 388.2537 -236.917811) (xy 388.299716 -236.900359) (xy 388.347935 -236.890515)
			(xy 388.39711 -236.888534) (xy 388.445965 -236.894466) (xy 388.493236 -236.908158) (xy 388.537698 -236.929256)
			(xy 388.578201 -236.957212) (xy 388.613694 -236.991304) (xy 388.643259 -237.030648) (xy 388.66613 -237.074225)
			(xy 388.681714 -237.120906) (xy 388.689609 -237.169483) (xy 388.690104 -237.19409) (xy 389.008615 -237.19409)
			(xy 389.01271 -237.143362) (xy 389.024889 -237.093948) (xy 389.044837 -237.047128) (xy 389.072038 -237.004114)
			(xy 389.105786 -236.96602) (xy 389.145208 -236.933833) (xy 389.189282 -236.908387) (xy 389.236868 -236.89034)
			(xy 389.286732 -236.88016) (xy 389.337584 -236.878111) (xy 389.388105 -236.884245) (xy 389.436989 -236.898405)
			(xy 389.482968 -236.920222) (xy 389.524852 -236.949132) (xy 389.561556 -236.984387) (xy 389.592129 -237.025073)
			(xy 389.61578 -237.070136) (xy 389.631896 -237.11841) (xy 389.64006 -237.168644) (xy 389.640572 -237.19409)
			(xy 389.948669 -237.19409) (xy 389.952764 -237.143362) (xy 389.964943 -237.093948) (xy 389.984891 -237.047128)
			(xy 390.012092 -237.004114) (xy 390.04584 -236.96602) (xy 390.085262 -236.933833) (xy 390.129336 -236.908387)
			(xy 390.176922 -236.89034) (xy 390.226786 -236.88016) (xy 390.277638 -236.878111) (xy 390.328159 -236.884245)
			(xy 390.377043 -236.898405) (xy 390.423022 -236.920222) (xy 390.464906 -236.949132) (xy 390.50161 -236.984387)
			(xy 390.532183 -237.025073) (xy 390.555834 -237.070136) (xy 390.57195 -237.11841) (xy 390.580114 -237.168644)
			(xy 390.580626 -237.19409) (xy 392.779008 -237.19409) (xy 392.782968 -237.145036) (xy 392.794745 -237.097252)
			(xy 392.814036 -237.051976) (xy 392.840339 -237.01038) (xy 392.872974 -236.973543) (xy 392.911095 -236.942418)
			(xy 392.953716 -236.917811) (xy 392.999732 -236.900359) (xy 393.047951 -236.890515) (xy 393.097126 -236.888534)
			(xy 393.145981 -236.894466) (xy 393.193252 -236.908158) (xy 393.237714 -236.929256) (xy 393.278217 -236.957212)
			(xy 393.31371 -236.991304) (xy 393.343275 -237.030648) (xy 393.366146 -237.074225) (xy 393.38173 -237.120906)
			(xy 393.389625 -237.169483) (xy 393.39012 -237.19409) (xy 393.389625 -237.218697) (xy 393.38173 -237.267274)
			(xy 393.366146 -237.313955) (xy 393.343275 -237.357532) (xy 393.31371 -237.396876) (xy 393.278217 -237.430968)
			(xy 393.237714 -237.458924) (xy 393.193252 -237.480022) (xy 393.145981 -237.493714) (xy 393.097126 -237.499646)
			(xy 393.047951 -237.497665) (xy 392.999732 -237.487821) (xy 392.953716 -237.470369) (xy 392.911095 -237.445762)
			(xy 392.872974 -237.414637) (xy 392.840339 -237.3778) (xy 392.814036 -237.336204) (xy 392.794745 -237.290928)
			(xy 392.782968 -237.243144) (xy 392.779008 -237.19409) (xy 390.580626 -237.19409) (xy 390.580114 -237.219536)
			(xy 390.57195 -237.26977) (xy 390.555834 -237.318044) (xy 390.532183 -237.363107) (xy 390.50161 -237.403793)
			(xy 390.464906 -237.439048) (xy 390.423022 -237.467958) (xy 390.377043 -237.489775) (xy 390.328159 -237.503935)
			(xy 390.277638 -237.510069) (xy 390.226786 -237.50802) (xy 390.176922 -237.49784) (xy 390.129336 -237.479793)
			(xy 390.085262 -237.454347) (xy 390.04584 -237.42216) (xy 390.012092 -237.384066) (xy 389.984891 -237.341052)
			(xy 389.964943 -237.294232) (xy 389.952764 -237.244818) (xy 389.948669 -237.19409) (xy 389.640572 -237.19409)
			(xy 389.64006 -237.219536) (xy 389.631896 -237.26977) (xy 389.61578 -237.318044) (xy 389.592129 -237.363107)
			(xy 389.561556 -237.403793) (xy 389.524852 -237.439048) (xy 389.482968 -237.467958) (xy 389.436989 -237.489775)
			(xy 389.388105 -237.503935) (xy 389.337584 -237.510069) (xy 389.286732 -237.50802) (xy 389.236868 -237.49784)
			(xy 389.189282 -237.479793) (xy 389.145208 -237.454347) (xy 389.105786 -237.42216) (xy 389.072038 -237.384066)
			(xy 389.044837 -237.341052) (xy 389.024889 -237.294232) (xy 389.01271 -237.244818) (xy 389.008615 -237.19409)
			(xy 388.690104 -237.19409) (xy 388.689609 -237.218697) (xy 388.681714 -237.267274) (xy 388.66613 -237.313955)
			(xy 388.643259 -237.357532) (xy 388.613694 -237.396876) (xy 388.578201 -237.430968) (xy 388.537698 -237.458924)
			(xy 388.493236 -237.480022) (xy 388.445965 -237.493714) (xy 388.39711 -237.499646) (xy 388.347935 -237.497665)
			(xy 388.299716 -237.487821) (xy 388.2537 -237.470369) (xy 388.211079 -237.445762) (xy 388.172958 -237.414637)
			(xy 388.140323 -237.3778) (xy 388.11402 -237.336204) (xy 388.094729 -237.290928) (xy 388.082952 -237.243144)
			(xy 388.078992 -237.19409) (xy 387.760464 -237.19409) (xy 387.759952 -237.219536) (xy 387.751788 -237.26977)
			(xy 387.735672 -237.318044) (xy 387.712021 -237.363107) (xy 387.681448 -237.403793) (xy 387.644744 -237.439048)
			(xy 387.60286 -237.467958) (xy 387.556881 -237.489775) (xy 387.507997 -237.503935) (xy 387.457476 -237.510069)
			(xy 387.406624 -237.50802) (xy 387.35676 -237.49784) (xy 387.309174 -237.479793) (xy 387.2651 -237.454347)
			(xy 387.225678 -237.42216) (xy 387.19193 -237.384066) (xy 387.164729 -237.341052) (xy 387.144781 -237.294232)
			(xy 387.132602 -237.244818) (xy 387.128507 -237.19409) (xy 386.81025 -237.19409) (xy 386.809755 -237.218697)
			(xy 386.80186 -237.267274) (xy 386.786276 -237.313955) (xy 386.763405 -237.357532) (xy 386.73384 -237.396876)
			(xy 386.698347 -237.430968) (xy 386.657844 -237.458924) (xy 386.613382 -237.480022) (xy 386.566111 -237.493714)
			(xy 386.517256 -237.499646) (xy 386.468081 -237.497665) (xy 386.419862 -237.487821) (xy 386.373846 -237.470369)
			(xy 386.331225 -237.445762) (xy 386.293104 -237.414637) (xy 386.260469 -237.3778) (xy 386.234166 -237.336204)
			(xy 386.214875 -237.290928) (xy 386.203098 -237.243144) (xy 386.199138 -237.19409) (xy 385.88061 -237.19409)
			(xy 385.880098 -237.219536) (xy 385.871934 -237.26977) (xy 385.855818 -237.318044) (xy 385.832167 -237.363107)
			(xy 385.801594 -237.403793) (xy 385.76489 -237.439048) (xy 385.723006 -237.467958) (xy 385.677027 -237.489775)
			(xy 385.628143 -237.503935) (xy 385.577622 -237.510069) (xy 385.52677 -237.50802) (xy 385.476906 -237.49784)
			(xy 385.42932 -237.479793) (xy 385.385246 -237.454347) (xy 385.345824 -237.42216) (xy 385.312076 -237.384066)
			(xy 385.284875 -237.341052) (xy 385.264927 -237.294232) (xy 385.252748 -237.244818) (xy 385.248653 -237.19409)
			(xy 384.000502 -237.19409) (xy 383.99999 -237.219536) (xy 383.991826 -237.26977) (xy 383.97571 -237.318044)
			(xy 383.952059 -237.363107) (xy 383.921486 -237.403793) (xy 383.884782 -237.439048) (xy 383.842898 -237.467958)
			(xy 383.796919 -237.489775) (xy 383.748035 -237.503935) (xy 383.697514 -237.510069) (xy 383.646662 -237.50802)
			(xy 383.596798 -237.49784) (xy 383.549212 -237.479793) (xy 383.505138 -237.454347) (xy 383.465716 -237.42216)
			(xy 383.431968 -237.384066) (xy 383.404767 -237.341052) (xy 383.384819 -237.294232) (xy 383.37264 -237.244818)
			(xy 383.368545 -237.19409) (xy 383.060448 -237.19409) (xy 383.059936 -237.219536) (xy 383.051772 -237.26977)
			(xy 383.035656 -237.318044) (xy 383.012005 -237.363107) (xy 382.981432 -237.403793) (xy 382.944728 -237.439048)
			(xy 382.902844 -237.467958) (xy 382.856865 -237.489775) (xy 382.807981 -237.503935) (xy 382.75746 -237.510069)
			(xy 382.706608 -237.50802) (xy 382.656744 -237.49784) (xy 382.609158 -237.479793) (xy 382.565084 -237.454347)
			(xy 382.525662 -237.42216) (xy 382.491914 -237.384066) (xy 382.464713 -237.341052) (xy 382.444765 -237.294232)
			(xy 382.432586 -237.244818) (xy 382.428491 -237.19409) (xy 382.110234 -237.19409) (xy 382.109739 -237.218697)
			(xy 382.101844 -237.267274) (xy 382.08626 -237.313955) (xy 382.063389 -237.357532) (xy 382.033824 -237.396876)
			(xy 381.998331 -237.430968) (xy 381.957828 -237.458924) (xy 381.913366 -237.480022) (xy 381.866095 -237.493714)
			(xy 381.81724 -237.499646) (xy 381.768065 -237.497665) (xy 381.719846 -237.487821) (xy 381.67383 -237.470369)
			(xy 381.631209 -237.445762) (xy 381.593088 -237.414637) (xy 381.560453 -237.3778) (xy 381.53415 -237.336204)
			(xy 381.514859 -237.290928) (xy 381.503082 -237.243144) (xy 381.499122 -237.19409) (xy 381.180594 -237.19409)
			(xy 381.180082 -237.219536) (xy 381.171918 -237.26977) (xy 381.155802 -237.318044) (xy 381.132151 -237.363107)
			(xy 381.101578 -237.403793) (xy 381.064874 -237.439048) (xy 381.02299 -237.467958) (xy 380.977011 -237.489775)
			(xy 380.928127 -237.503935) (xy 380.877606 -237.510069) (xy 380.826754 -237.50802) (xy 380.77689 -237.49784)
			(xy 380.729304 -237.479793) (xy 380.68523 -237.454347) (xy 380.645808 -237.42216) (xy 380.61206 -237.384066)
			(xy 380.584859 -237.341052) (xy 380.564911 -237.294232) (xy 380.552732 -237.244818) (xy 380.548637 -237.19409)
			(xy 380.230126 -237.19409) (xy 380.229631 -237.218697) (xy 380.221736 -237.267274) (xy 380.206152 -237.313955)
			(xy 380.183281 -237.357532) (xy 380.153716 -237.396876) (xy 380.118223 -237.430968) (xy 380.07772 -237.458924)
			(xy 380.033258 -237.480022) (xy 379.985987 -237.493714) (xy 379.937132 -237.499646) (xy 379.887957 -237.497665)
			(xy 379.839738 -237.487821) (xy 379.793722 -237.470369) (xy 379.751101 -237.445762) (xy 379.71298 -237.414637)
			(xy 379.680345 -237.3778) (xy 379.654042 -237.336204) (xy 379.634751 -237.290928) (xy 379.622974 -237.243144)
			(xy 379.619014 -237.19409) (xy 379.300486 -237.19409) (xy 379.299974 -237.219536) (xy 379.29181 -237.26977)
			(xy 379.275694 -237.318044) (xy 379.252043 -237.363107) (xy 379.22147 -237.403793) (xy 379.184766 -237.439048)
			(xy 379.142882 -237.467958) (xy 379.096903 -237.489775) (xy 379.048019 -237.503935) (xy 378.997498 -237.510069)
			(xy 378.946646 -237.50802) (xy 378.896782 -237.49784) (xy 378.849196 -237.479793) (xy 378.805122 -237.454347)
			(xy 378.7657 -237.42216) (xy 378.731952 -237.384066) (xy 378.704751 -237.341052) (xy 378.684803 -237.294232)
			(xy 378.672624 -237.244818) (xy 378.668529 -237.19409) (xy 377.420632 -237.19409) (xy 377.42012 -237.219536)
			(xy 377.411956 -237.26977) (xy 377.39584 -237.318044) (xy 377.372189 -237.363107) (xy 377.341616 -237.403793)
			(xy 377.304912 -237.439048) (xy 377.263028 -237.467958) (xy 377.217049 -237.489775) (xy 377.168165 -237.503935)
			(xy 377.117644 -237.510069) (xy 377.066792 -237.50802) (xy 377.016928 -237.49784) (xy 376.969342 -237.479793)
			(xy 376.925268 -237.454347) (xy 376.885846 -237.42216) (xy 376.852098 -237.384066) (xy 376.824897 -237.341052)
			(xy 376.804949 -237.294232) (xy 376.79277 -237.244818) (xy 376.788675 -237.19409) (xy 376.480578 -237.19409)
			(xy 376.480066 -237.219536) (xy 376.471902 -237.26977) (xy 376.455786 -237.318044) (xy 376.432135 -237.363107)
			(xy 376.401562 -237.403793) (xy 376.364858 -237.439048) (xy 376.322974 -237.467958) (xy 376.276995 -237.489775)
			(xy 376.228111 -237.503935) (xy 376.17759 -237.510069) (xy 376.126738 -237.50802) (xy 376.076874 -237.49784)
			(xy 376.029288 -237.479793) (xy 375.985214 -237.454347) (xy 375.945792 -237.42216) (xy 375.912044 -237.384066)
			(xy 375.884843 -237.341052) (xy 375.864895 -237.294232) (xy 375.852716 -237.244818) (xy 375.848621 -237.19409)
			(xy 375.53064 -237.19409) (xy 375.530641 -237.1941) (xy 375.52647 -237.24444) (xy 375.51407 -237.293406)
			(xy 375.493779 -237.339664) (xy 375.466152 -237.381951) (xy 375.431941 -237.419114) (xy 375.39208 -237.450139)
			(xy 375.347656 -237.47418) (xy 375.299881 -237.490582) (xy 375.250058 -237.498896) (xy 375.224802 -237.499398)
			(xy 375.200371 -237.498917) (xy 375.152133 -237.491129) (xy 375.12879 -237.483904) (xy 375.121932 -237.481618)
			(xy 375.12117 -237.481364) (xy 375.109418 -237.477893) (xy 375.08516 -237.481093) (xy 375.074688 -237.48746)
			(xy 375.00687 -237.535212) (xy 375.004838 -237.536736) (xy 374.99663 -237.54376) (xy 374.986521 -237.562832)
			(xy 374.98528 -237.573566) (xy 374.98528 -237.736634) (xy 374.985372 -237.741389) (xy 374.987154 -237.750728)
			(xy 374.988836 -237.755176) (xy 374.998742 -237.780322) (xy 375.00433 -237.786926) (xy 375.021241 -237.807127)
			(xy 375.049098 -237.851838) (xy 375.069515 -237.9004) (xy 375.081975 -237.951584) (xy 375.086164 -238.004096)
			(xy 375.378467 -238.004096) (xy 375.382562 -237.953368) (xy 375.394741 -237.903954) (xy 375.414689 -237.857134)
			(xy 375.44189 -237.81412) (xy 375.475638 -237.776026) (xy 375.51506 -237.743839) (xy 375.559134 -237.718393)
			(xy 375.60672 -237.700346) (xy 375.656584 -237.690166) (xy 375.707436 -237.688117) (xy 375.757957 -237.694251)
			(xy 375.806841 -237.708411) (xy 375.85282 -237.730228) (xy 375.894704 -237.759138) (xy 375.931408 -237.794393)
			(xy 375.961981 -237.835079) (xy 375.985632 -237.880142) (xy 376.001748 -237.928416) (xy 376.009912 -237.97865)
			(xy 376.010424 -238.004096) (xy 376.328952 -238.004096) (xy 376.332912 -237.955042) (xy 376.344689 -237.907258)
			(xy 376.36398 -237.861982) (xy 376.390283 -237.820386) (xy 376.422918 -237.783549) (xy 376.461039 -237.752424)
			(xy 376.50366 -237.727817) (xy 376.549676 -237.710365) (xy 376.597895 -237.700521) (xy 376.64707 -237.69854)
			(xy 376.695925 -237.704472) (xy 376.743196 -237.718164) (xy 376.787658 -237.739262) (xy 376.828161 -237.767218)
			(xy 376.863654 -237.80131) (xy 376.893219 -237.840654) (xy 376.91609 -237.884231) (xy 376.931674 -237.930912)
			(xy 376.939569 -237.979489) (xy 376.940064 -238.004096) (xy 377.258575 -238.004096) (xy 377.26267 -237.953368)
			(xy 377.274849 -237.903954) (xy 377.294797 -237.857134) (xy 377.321998 -237.81412) (xy 377.355746 -237.776026)
			(xy 377.395168 -237.743839) (xy 377.439242 -237.718393) (xy 377.486828 -237.700346) (xy 377.536692 -237.690166)
			(xy 377.587544 -237.688117) (xy 377.638065 -237.694251) (xy 377.686949 -237.708411) (xy 377.732928 -237.730228)
			(xy 377.774812 -237.759138) (xy 377.811516 -237.794393) (xy 377.842089 -237.835079) (xy 377.86574 -237.880142)
			(xy 377.881856 -237.928416) (xy 377.89002 -237.97865) (xy 377.890532 -238.004096) (xy 378.20906 -238.004096)
			(xy 378.21302 -237.955042) (xy 378.224797 -237.907258) (xy 378.244088 -237.861982) (xy 378.270391 -237.820386)
			(xy 378.303026 -237.783549) (xy 378.341147 -237.752424) (xy 378.383768 -237.727817) (xy 378.429784 -237.710365)
			(xy 378.478003 -237.700521) (xy 378.527178 -237.69854) (xy 378.576033 -237.704472) (xy 378.623304 -237.718164)
			(xy 378.667766 -237.739262) (xy 378.708269 -237.767218) (xy 378.743762 -237.80131) (xy 378.773327 -237.840654)
			(xy 378.796198 -237.884231) (xy 378.811782 -237.930912) (xy 378.819677 -237.979489) (xy 378.820172 -238.004096)
			(xy 379.138683 -238.004096) (xy 379.142778 -237.953368) (xy 379.154957 -237.903954) (xy 379.174905 -237.857134)
			(xy 379.202106 -237.81412) (xy 379.235854 -237.776026) (xy 379.275276 -237.743839) (xy 379.31935 -237.718393)
			(xy 379.366936 -237.700346) (xy 379.4168 -237.690166) (xy 379.467652 -237.688117) (xy 379.518173 -237.694251)
			(xy 379.567057 -237.708411) (xy 379.613036 -237.730228) (xy 379.65492 -237.759138) (xy 379.691624 -237.794393)
			(xy 379.722197 -237.835079) (xy 379.745848 -237.880142) (xy 379.761964 -237.928416) (xy 379.770128 -237.97865)
			(xy 379.77064 -238.004096) (xy 380.078483 -238.004096) (xy 380.082578 -237.953368) (xy 380.094757 -237.903954)
			(xy 380.114705 -237.857134) (xy 380.141906 -237.81412) (xy 380.175654 -237.776026) (xy 380.215076 -237.743839)
			(xy 380.25915 -237.718393) (xy 380.306736 -237.700346) (xy 380.3566 -237.690166) (xy 380.407452 -237.688117)
			(xy 380.457973 -237.694251) (xy 380.506857 -237.708411) (xy 380.552836 -237.730228) (xy 380.59472 -237.759138)
			(xy 380.631424 -237.794393) (xy 380.661997 -237.835079) (xy 380.685648 -237.880142) (xy 380.701764 -237.928416)
			(xy 380.709928 -237.97865) (xy 380.71044 -238.004096) (xy 381.028968 -238.004096) (xy 381.032928 -237.955042)
			(xy 381.044705 -237.907258) (xy 381.063996 -237.861982) (xy 381.090299 -237.820386) (xy 381.122934 -237.783549)
			(xy 381.161055 -237.752424) (xy 381.203676 -237.727817) (xy 381.249692 -237.710365) (xy 381.297911 -237.700521)
			(xy 381.347086 -237.69854) (xy 381.395941 -237.704472) (xy 381.443212 -237.718164) (xy 381.487674 -237.739262)
			(xy 381.528177 -237.767218) (xy 381.56367 -237.80131) (xy 381.593235 -237.840654) (xy 381.616106 -237.884231)
			(xy 381.63169 -237.930912) (xy 381.639585 -237.979489) (xy 381.64008 -238.004096) (xy 381.958591 -238.004096)
			(xy 381.962686 -237.953368) (xy 381.974865 -237.903954) (xy 381.994813 -237.857134) (xy 382.022014 -237.81412)
			(xy 382.055762 -237.776026) (xy 382.095184 -237.743839) (xy 382.139258 -237.718393) (xy 382.186844 -237.700346)
			(xy 382.236708 -237.690166) (xy 382.28756 -237.688117) (xy 382.338081 -237.694251) (xy 382.386965 -237.708411)
			(xy 382.432944 -237.730228) (xy 382.474828 -237.759138) (xy 382.511532 -237.794393) (xy 382.542105 -237.835079)
			(xy 382.565756 -237.880142) (xy 382.581872 -237.928416) (xy 382.590036 -237.97865) (xy 382.590548 -238.004096)
			(xy 382.909076 -238.004096) (xy 382.913036 -237.955042) (xy 382.924813 -237.907258) (xy 382.944104 -237.861982)
			(xy 382.970407 -237.820386) (xy 383.003042 -237.783549) (xy 383.041163 -237.752424) (xy 383.083784 -237.727817)
			(xy 383.1298 -237.710365) (xy 383.178019 -237.700521) (xy 383.227194 -237.69854) (xy 383.276049 -237.704472)
			(xy 383.32332 -237.718164) (xy 383.367782 -237.739262) (xy 383.408285 -237.767218) (xy 383.443778 -237.80131)
			(xy 383.473343 -237.840654) (xy 383.496214 -237.884231) (xy 383.511798 -237.930912) (xy 383.519693 -237.979489)
			(xy 383.520188 -238.004096) (xy 383.838699 -238.004096) (xy 383.842794 -237.953368) (xy 383.854973 -237.903954)
			(xy 383.874921 -237.857134) (xy 383.902122 -237.81412) (xy 383.93587 -237.776026) (xy 383.975292 -237.743839)
			(xy 384.019366 -237.718393) (xy 384.066952 -237.700346) (xy 384.116816 -237.690166) (xy 384.167668 -237.688117)
			(xy 384.218189 -237.694251) (xy 384.267073 -237.708411) (xy 384.313052 -237.730228) (xy 384.354936 -237.759138)
			(xy 384.39164 -237.794393) (xy 384.422213 -237.835079) (xy 384.445864 -237.880142) (xy 384.46198 -237.928416)
			(xy 384.470144 -237.97865) (xy 384.470656 -238.004096) (xy 384.78893 -238.004096) (xy 384.79289 -237.955042)
			(xy 384.804667 -237.907258) (xy 384.823958 -237.861982) (xy 384.850261 -237.820386) (xy 384.882896 -237.783549)
			(xy 384.921017 -237.752424) (xy 384.963638 -237.727817) (xy 385.009654 -237.710365) (xy 385.057873 -237.700521)
			(xy 385.107048 -237.69854) (xy 385.155903 -237.704472) (xy 385.203174 -237.718164) (xy 385.247636 -237.739262)
			(xy 385.288139 -237.767218) (xy 385.323632 -237.80131) (xy 385.353197 -237.840654) (xy 385.376068 -237.884231)
			(xy 385.391652 -237.930912) (xy 385.399547 -237.979489) (xy 385.400042 -238.004096) (xy 385.718553 -238.004096)
			(xy 385.722648 -237.953368) (xy 385.734827 -237.903954) (xy 385.754775 -237.857134) (xy 385.781976 -237.81412)
			(xy 385.815724 -237.776026) (xy 385.855146 -237.743839) (xy 385.89922 -237.718393) (xy 385.946806 -237.700346)
			(xy 385.99667 -237.690166) (xy 386.047522 -237.688117) (xy 386.098043 -237.694251) (xy 386.146927 -237.708411)
			(xy 386.192906 -237.730228) (xy 386.23479 -237.759138) (xy 386.271494 -237.794393) (xy 386.302067 -237.835079)
			(xy 386.325718 -237.880142) (xy 386.341834 -237.928416) (xy 386.349998 -237.97865) (xy 386.35051 -238.004096)
			(xy 386.658607 -238.004096) (xy 386.662702 -237.953368) (xy 386.674881 -237.903954) (xy 386.694829 -237.857134)
			(xy 386.72203 -237.81412) (xy 386.755778 -237.776026) (xy 386.7952 -237.743839) (xy 386.839274 -237.718393)
			(xy 386.88686 -237.700346) (xy 386.936724 -237.690166) (xy 386.987576 -237.688117) (xy 387.038097 -237.694251)
			(xy 387.086981 -237.708411) (xy 387.13296 -237.730228) (xy 387.174844 -237.759138) (xy 387.211548 -237.794393)
			(xy 387.242121 -237.835079) (xy 387.265772 -237.880142) (xy 387.281888 -237.928416) (xy 387.290052 -237.97865)
			(xy 387.290564 -238.004096) (xy 387.609092 -238.004096) (xy 387.613052 -237.955042) (xy 387.624829 -237.907258)
			(xy 387.64412 -237.861982) (xy 387.670423 -237.820386) (xy 387.703058 -237.783549) (xy 387.741179 -237.752424)
			(xy 387.7838 -237.727817) (xy 387.829816 -237.710365) (xy 387.878035 -237.700521) (xy 387.92721 -237.69854)
			(xy 387.976065 -237.704472) (xy 388.023336 -237.718164) (xy 388.067798 -237.739262) (xy 388.108301 -237.767218)
			(xy 388.143794 -237.80131) (xy 388.173359 -237.840654) (xy 388.19623 -237.884231) (xy 388.211814 -237.930912)
			(xy 388.219709 -237.979489) (xy 388.220204 -238.004096) (xy 388.538715 -238.004096) (xy 388.54281 -237.953368)
			(xy 388.554989 -237.903954) (xy 388.574937 -237.857134) (xy 388.602138 -237.81412) (xy 388.635886 -237.776026)
			(xy 388.675308 -237.743839) (xy 388.719382 -237.718393) (xy 388.766968 -237.700346) (xy 388.816832 -237.690166)
			(xy 388.867684 -237.688117) (xy 388.918205 -237.694251) (xy 388.967089 -237.708411) (xy 389.013068 -237.730228)
			(xy 389.054952 -237.759138) (xy 389.091656 -237.794393) (xy 389.122229 -237.835079) (xy 389.14588 -237.880142)
			(xy 389.161996 -237.928416) (xy 389.17016 -237.97865) (xy 389.170672 -238.004096) (xy 389.488946 -238.004096)
			(xy 389.492906 -237.955042) (xy 389.504683 -237.907258) (xy 389.523974 -237.861982) (xy 389.550277 -237.820386)
			(xy 389.582912 -237.783549) (xy 389.621033 -237.752424) (xy 389.663654 -237.727817) (xy 389.70967 -237.710365)
			(xy 389.757889 -237.700521) (xy 389.807064 -237.69854) (xy 389.855919 -237.704472) (xy 389.90319 -237.718164)
			(xy 389.947652 -237.739262) (xy 389.988155 -237.767218) (xy 390.023648 -237.80131) (xy 390.053213 -237.840654)
			(xy 390.076084 -237.884231) (xy 390.091668 -237.930912) (xy 390.099563 -237.979489) (xy 390.100058 -238.004096)
			(xy 390.418569 -238.004096) (xy 390.422664 -237.953368) (xy 390.434843 -237.903954) (xy 390.454791 -237.857134)
			(xy 390.481992 -237.81412) (xy 390.51574 -237.776026) (xy 390.555162 -237.743839) (xy 390.599236 -237.718393)
			(xy 390.646822 -237.700346) (xy 390.696686 -237.690166) (xy 390.747538 -237.688117) (xy 390.798059 -237.694251)
			(xy 390.846943 -237.708411) (xy 390.892922 -237.730228) (xy 390.934806 -237.759138) (xy 390.97151 -237.794393)
			(xy 391.002083 -237.835079) (xy 391.025734 -237.880142) (xy 391.04185 -237.928416) (xy 391.050014 -237.97865)
			(xy 391.050526 -238.004096) (xy 391.369054 -238.004096) (xy 391.373014 -237.955042) (xy 391.384791 -237.907258)
			(xy 391.404082 -237.861982) (xy 391.430385 -237.820386) (xy 391.46302 -237.783549) (xy 391.501141 -237.752424)
			(xy 391.543762 -237.727817) (xy 391.589778 -237.710365) (xy 391.637997 -237.700521) (xy 391.687172 -237.69854)
			(xy 391.736027 -237.704472) (xy 391.783298 -237.718164) (xy 391.82776 -237.739262) (xy 391.868263 -237.767218)
			(xy 391.903756 -237.80131) (xy 391.933321 -237.840654) (xy 391.956192 -237.884231) (xy 391.971776 -237.930912)
			(xy 391.979671 -237.979489) (xy 391.980166 -238.004096) (xy 391.979671 -238.028703) (xy 391.971776 -238.07728)
			(xy 391.956192 -238.123961) (xy 391.933321 -238.167538) (xy 391.903756 -238.206882) (xy 391.868263 -238.240974)
			(xy 391.82776 -238.26893) (xy 391.825433 -238.270034) (xy 394.377176 -238.270034) (xy 394.381136 -238.22098)
			(xy 394.392913 -238.173196) (xy 394.412204 -238.12792) (xy 394.438507 -238.086324) (xy 394.471142 -238.049487)
			(xy 394.509263 -238.018362) (xy 394.551884 -237.993755) (xy 394.5979 -237.976303) (xy 394.646119 -237.966459)
			(xy 394.695294 -237.964478) (xy 394.744149 -237.97041) (xy 394.79142 -237.984102) (xy 394.835882 -238.0052)
			(xy 394.876385 -238.033156) (xy 394.911878 -238.067248) (xy 394.941443 -238.106592) (xy 394.964314 -238.150169)
			(xy 394.979898 -238.19685) (xy 394.987793 -238.245427) (xy 394.988288 -238.270034) (xy 394.987793 -238.294641)
			(xy 394.979898 -238.343218) (xy 394.964314 -238.389899) (xy 394.941443 -238.433476) (xy 394.911878 -238.47282)
			(xy 394.876385 -238.506912) (xy 394.835882 -238.534868) (xy 394.79142 -238.555966) (xy 394.744149 -238.569658)
			(xy 394.695294 -238.57559) (xy 394.646119 -238.573609) (xy 394.5979 -238.563765) (xy 394.551884 -238.546313)
			(xy 394.509263 -238.521706) (xy 394.471142 -238.490581) (xy 394.438507 -238.453744) (xy 394.412204 -238.412148)
			(xy 394.392913 -238.366872) (xy 394.381136 -238.319088) (xy 394.377176 -238.270034) (xy 391.825433 -238.270034)
			(xy 391.783298 -238.290028) (xy 391.736027 -238.30372) (xy 391.687172 -238.309652) (xy 391.637997 -238.307671)
			(xy 391.589778 -238.297827) (xy 391.543762 -238.280375) (xy 391.501141 -238.255768) (xy 391.46302 -238.224643)
			(xy 391.430385 -238.187806) (xy 391.404082 -238.14621) (xy 391.384791 -238.100934) (xy 391.373014 -238.05315)
			(xy 391.369054 -238.004096) (xy 391.050526 -238.004096) (xy 391.050014 -238.029542) (xy 391.04185 -238.079776)
			(xy 391.025734 -238.12805) (xy 391.002083 -238.173113) (xy 390.97151 -238.213799) (xy 390.934806 -238.249054)
			(xy 390.892922 -238.277964) (xy 390.846943 -238.299781) (xy 390.798059 -238.313941) (xy 390.747538 -238.320075)
			(xy 390.696686 -238.318026) (xy 390.646822 -238.307846) (xy 390.599236 -238.289799) (xy 390.555162 -238.264353)
			(xy 390.51574 -238.232166) (xy 390.481992 -238.194072) (xy 390.454791 -238.151058) (xy 390.434843 -238.104238)
			(xy 390.422664 -238.054824) (xy 390.418569 -238.004096) (xy 390.100058 -238.004096) (xy 390.099563 -238.028703)
			(xy 390.091668 -238.07728) (xy 390.076084 -238.123961) (xy 390.053213 -238.167538) (xy 390.023648 -238.206882)
			(xy 389.988155 -238.240974) (xy 389.947652 -238.26893) (xy 389.90319 -238.290028) (xy 389.855919 -238.30372)
			(xy 389.807064 -238.309652) (xy 389.757889 -238.307671) (xy 389.70967 -238.297827) (xy 389.663654 -238.280375)
			(xy 389.621033 -238.255768) (xy 389.582912 -238.224643) (xy 389.550277 -238.187806) (xy 389.523974 -238.14621)
			(xy 389.504683 -238.100934) (xy 389.492906 -238.05315) (xy 389.488946 -238.004096) (xy 389.170672 -238.004096)
			(xy 389.17016 -238.029542) (xy 389.161996 -238.079776) (xy 389.14588 -238.12805) (xy 389.122229 -238.173113)
			(xy 389.091656 -238.213799) (xy 389.054952 -238.249054) (xy 389.013068 -238.277964) (xy 388.967089 -238.299781)
			(xy 388.918205 -238.313941) (xy 388.867684 -238.320075) (xy 388.816832 -238.318026) (xy 388.766968 -238.307846)
			(xy 388.719382 -238.289799) (xy 388.675308 -238.264353) (xy 388.635886 -238.232166) (xy 388.602138 -238.194072)
			(xy 388.574937 -238.151058) (xy 388.554989 -238.104238) (xy 388.54281 -238.054824) (xy 388.538715 -238.004096)
			(xy 388.220204 -238.004096) (xy 388.219709 -238.028703) (xy 388.211814 -238.07728) (xy 388.19623 -238.123961)
			(xy 388.173359 -238.167538) (xy 388.143794 -238.206882) (xy 388.108301 -238.240974) (xy 388.067798 -238.26893)
			(xy 388.023336 -238.290028) (xy 387.976065 -238.30372) (xy 387.92721 -238.309652) (xy 387.878035 -238.307671)
			(xy 387.829816 -238.297827) (xy 387.7838 -238.280375) (xy 387.741179 -238.255768) (xy 387.703058 -238.224643)
			(xy 387.670423 -238.187806) (xy 387.64412 -238.14621) (xy 387.624829 -238.100934) (xy 387.613052 -238.05315)
			(xy 387.609092 -238.004096) (xy 387.290564 -238.004096) (xy 387.290052 -238.029542) (xy 387.281888 -238.079776)
			(xy 387.265772 -238.12805) (xy 387.242121 -238.173113) (xy 387.211548 -238.213799) (xy 387.174844 -238.249054)
			(xy 387.13296 -238.277964) (xy 387.086981 -238.299781) (xy 387.038097 -238.313941) (xy 386.987576 -238.320075)
			(xy 386.936724 -238.318026) (xy 386.88686 -238.307846) (xy 386.839274 -238.289799) (xy 386.7952 -238.264353)
			(xy 386.755778 -238.232166) (xy 386.72203 -238.194072) (xy 386.694829 -238.151058) (xy 386.674881 -238.104238)
			(xy 386.662702 -238.054824) (xy 386.658607 -238.004096) (xy 386.35051 -238.004096) (xy 386.349998 -238.029542)
			(xy 386.341834 -238.079776) (xy 386.325718 -238.12805) (xy 386.302067 -238.173113) (xy 386.271494 -238.213799)
			(xy 386.23479 -238.249054) (xy 386.192906 -238.277964) (xy 386.146927 -238.299781) (xy 386.098043 -238.313941)
			(xy 386.047522 -238.320075) (xy 385.99667 -238.318026) (xy 385.946806 -238.307846) (xy 385.89922 -238.289799)
			(xy 385.855146 -238.264353) (xy 385.815724 -238.232166) (xy 385.781976 -238.194072) (xy 385.754775 -238.151058)
			(xy 385.734827 -238.104238) (xy 385.722648 -238.054824) (xy 385.718553 -238.004096) (xy 385.400042 -238.004096)
			(xy 385.399547 -238.028703) (xy 385.391652 -238.07728) (xy 385.376068 -238.123961) (xy 385.353197 -238.167538)
			(xy 385.323632 -238.206882) (xy 385.288139 -238.240974) (xy 385.247636 -238.26893) (xy 385.203174 -238.290028)
			(xy 385.155903 -238.30372) (xy 385.107048 -238.309652) (xy 385.057873 -238.307671) (xy 385.009654 -238.297827)
			(xy 384.963638 -238.280375) (xy 384.921017 -238.255768) (xy 384.882896 -238.224643) (xy 384.850261 -238.187806)
			(xy 384.823958 -238.14621) (xy 384.804667 -238.100934) (xy 384.79289 -238.05315) (xy 384.78893 -238.004096)
			(xy 384.470656 -238.004096) (xy 384.470144 -238.029542) (xy 384.46198 -238.079776) (xy 384.445864 -238.12805)
			(xy 384.422213 -238.173113) (xy 384.39164 -238.213799) (xy 384.354936 -238.249054) (xy 384.313052 -238.277964)
			(xy 384.267073 -238.299781) (xy 384.218189 -238.313941) (xy 384.167668 -238.320075) (xy 384.116816 -238.318026)
			(xy 384.066952 -238.307846) (xy 384.019366 -238.289799) (xy 383.975292 -238.264353) (xy 383.93587 -238.232166)
			(xy 383.902122 -238.194072) (xy 383.874921 -238.151058) (xy 383.854973 -238.104238) (xy 383.842794 -238.054824)
			(xy 383.838699 -238.004096) (xy 383.520188 -238.004096) (xy 383.519693 -238.028703) (xy 383.511798 -238.07728)
			(xy 383.496214 -238.123961) (xy 383.473343 -238.167538) (xy 383.443778 -238.206882) (xy 383.408285 -238.240974)
			(xy 383.367782 -238.26893) (xy 383.32332 -238.290028) (xy 383.276049 -238.30372) (xy 383.227194 -238.309652)
			(xy 383.178019 -238.307671) (xy 383.1298 -238.297827) (xy 383.083784 -238.280375) (xy 383.041163 -238.255768)
			(xy 383.003042 -238.224643) (xy 382.970407 -238.187806) (xy 382.944104 -238.14621) (xy 382.924813 -238.100934)
			(xy 382.913036 -238.05315) (xy 382.909076 -238.004096) (xy 382.590548 -238.004096) (xy 382.590036 -238.029542)
			(xy 382.581872 -238.079776) (xy 382.565756 -238.12805) (xy 382.542105 -238.173113) (xy 382.511532 -238.213799)
			(xy 382.474828 -238.249054) (xy 382.432944 -238.277964) (xy 382.386965 -238.299781) (xy 382.338081 -238.313941)
			(xy 382.28756 -238.320075) (xy 382.236708 -238.318026) (xy 382.186844 -238.307846) (xy 382.139258 -238.289799)
			(xy 382.095184 -238.264353) (xy 382.055762 -238.232166) (xy 382.022014 -238.194072) (xy 381.994813 -238.151058)
			(xy 381.974865 -238.104238) (xy 381.962686 -238.054824) (xy 381.958591 -238.004096) (xy 381.64008 -238.004096)
			(xy 381.639585 -238.028703) (xy 381.63169 -238.07728) (xy 381.616106 -238.123961) (xy 381.593235 -238.167538)
			(xy 381.56367 -238.206882) (xy 381.528177 -238.240974) (xy 381.487674 -238.26893) (xy 381.443212 -238.290028)
			(xy 381.395941 -238.30372) (xy 381.347086 -238.309652) (xy 381.297911 -238.307671) (xy 381.249692 -238.297827)
			(xy 381.203676 -238.280375) (xy 381.161055 -238.255768) (xy 381.122934 -238.224643) (xy 381.090299 -238.187806)
			(xy 381.063996 -238.14621) (xy 381.044705 -238.100934) (xy 381.032928 -238.05315) (xy 381.028968 -238.004096)
			(xy 380.71044 -238.004096) (xy 380.709928 -238.029542) (xy 380.701764 -238.079776) (xy 380.685648 -238.12805)
			(xy 380.661997 -238.173113) (xy 380.631424 -238.213799) (xy 380.59472 -238.249054) (xy 380.552836 -238.277964)
			(xy 380.506857 -238.299781) (xy 380.457973 -238.313941) (xy 380.407452 -238.320075) (xy 380.3566 -238.318026)
			(xy 380.306736 -238.307846) (xy 380.25915 -238.289799) (xy 380.215076 -238.264353) (xy 380.175654 -238.232166)
			(xy 380.141906 -238.194072) (xy 380.114705 -238.151058) (xy 380.094757 -238.104238) (xy 380.082578 -238.054824)
			(xy 380.078483 -238.004096) (xy 379.77064 -238.004096) (xy 379.770128 -238.029542) (xy 379.761964 -238.079776)
			(xy 379.745848 -238.12805) (xy 379.722197 -238.173113) (xy 379.691624 -238.213799) (xy 379.65492 -238.249054)
			(xy 379.613036 -238.277964) (xy 379.567057 -238.299781) (xy 379.518173 -238.313941) (xy 379.467652 -238.320075)
			(xy 379.4168 -238.318026) (xy 379.366936 -238.307846) (xy 379.31935 -238.289799) (xy 379.275276 -238.264353)
			(xy 379.235854 -238.232166) (xy 379.202106 -238.194072) (xy 379.174905 -238.151058) (xy 379.154957 -238.104238)
			(xy 379.142778 -238.054824) (xy 379.138683 -238.004096) (xy 378.820172 -238.004096) (xy 378.819677 -238.028703)
			(xy 378.811782 -238.07728) (xy 378.796198 -238.123961) (xy 378.773327 -238.167538) (xy 378.743762 -238.206882)
			(xy 378.708269 -238.240974) (xy 378.667766 -238.26893) (xy 378.623304 -238.290028) (xy 378.576033 -238.30372)
			(xy 378.527178 -238.309652) (xy 378.478003 -238.307671) (xy 378.429784 -238.297827) (xy 378.383768 -238.280375)
			(xy 378.341147 -238.255768) (xy 378.303026 -238.224643) (xy 378.270391 -238.187806) (xy 378.244088 -238.14621)
			(xy 378.224797 -238.100934) (xy 378.21302 -238.05315) (xy 378.20906 -238.004096) (xy 377.890532 -238.004096)
			(xy 377.89002 -238.029542) (xy 377.881856 -238.079776) (xy 377.86574 -238.12805) (xy 377.842089 -238.173113)
			(xy 377.811516 -238.213799) (xy 377.774812 -238.249054) (xy 377.732928 -238.277964) (xy 377.686949 -238.299781)
			(xy 377.638065 -238.313941) (xy 377.587544 -238.320075) (xy 377.536692 -238.318026) (xy 377.486828 -238.307846)
			(xy 377.439242 -238.289799) (xy 377.395168 -238.264353) (xy 377.355746 -238.232166) (xy 377.321998 -238.194072)
			(xy 377.294797 -238.151058) (xy 377.274849 -238.104238) (xy 377.26267 -238.054824) (xy 377.258575 -238.004096)
			(xy 376.940064 -238.004096) (xy 376.939569 -238.028703) (xy 376.931674 -238.07728) (xy 376.91609 -238.123961)
			(xy 376.893219 -238.167538) (xy 376.863654 -238.206882) (xy 376.828161 -238.240974) (xy 376.787658 -238.26893)
			(xy 376.743196 -238.290028) (xy 376.695925 -238.30372) (xy 376.64707 -238.309652) (xy 376.597895 -238.307671)
			(xy 376.549676 -238.297827) (xy 376.50366 -238.280375) (xy 376.461039 -238.255768) (xy 376.422918 -238.224643)
			(xy 376.390283 -238.187806) (xy 376.36398 -238.14621) (xy 376.344689 -238.100934) (xy 376.332912 -238.05315)
			(xy 376.328952 -238.004096) (xy 376.010424 -238.004096) (xy 376.009912 -238.029542) (xy 376.001748 -238.079776)
			(xy 375.985632 -238.12805) (xy 375.961981 -238.173113) (xy 375.931408 -238.213799) (xy 375.894704 -238.249054)
			(xy 375.85282 -238.277964) (xy 375.806841 -238.299781) (xy 375.757957 -238.313941) (xy 375.707436 -238.320075)
			(xy 375.656584 -238.318026) (xy 375.60672 -238.307846) (xy 375.559134 -238.289799) (xy 375.51506 -238.264353)
			(xy 375.475638 -238.232166) (xy 375.44189 -238.194072) (xy 375.414689 -238.151058) (xy 375.394741 -238.104238)
			(xy 375.382562 -238.054824) (xy 375.378467 -238.004096) (xy 375.086164 -238.004096) (xy 375.086164 -238.004097)
			(xy 375.081976 -238.05661) (xy 375.069516 -238.107794) (xy 375.0491 -238.156357) (xy 375.021244 -238.201069)
			(xy 375.00433 -238.221266) (xy 374.998742 -238.22787) (xy 374.988836 -238.253016) (xy 374.987213 -238.25748)
			(xy 374.985431 -238.26681) (xy 374.98528 -238.271558) (xy 374.98528 -238.431324) (xy 374.98528 -238.434626)
			(xy 374.986467 -238.445373) (xy 374.9966 -238.464452) (xy 375.004838 -238.471456) (xy 375.00687 -238.47298)
			(xy 375.074688 -238.520732) (xy 375.085077 -238.527306) (xy 375.10943 -238.530484) (xy 375.12117 -238.526828)
			(xy 375.121932 -238.526574) (xy 375.12879 -238.524288) (xy 375.152133 -238.517063) (xy 375.200371 -238.509284)
			(xy 375.224802 -238.508794) (xy 375.250057 -238.509316) (xy 375.299878 -238.51763) (xy 375.347651 -238.534031)
			(xy 375.392074 -238.558071) (xy 375.431933 -238.589095) (xy 375.466143 -238.626257) (xy 375.493769 -238.668542)
			(xy 375.514058 -238.714798) (xy 375.526458 -238.763762) (xy 375.530629 -238.8141) (xy 375.530629 -238.814102)
			(xy 375.848621 -238.814102) (xy 375.852716 -238.763374) (xy 375.864895 -238.71396) (xy 375.884843 -238.66714)
			(xy 375.912044 -238.624126) (xy 375.945792 -238.586032) (xy 375.985214 -238.553845) (xy 376.029288 -238.528399)
			(xy 376.076874 -238.510352) (xy 376.126738 -238.500172) (xy 376.17759 -238.498123) (xy 376.228111 -238.504257)
			(xy 376.276995 -238.518417) (xy 376.322974 -238.540234) (xy 376.364858 -238.569144) (xy 376.401562 -238.604399)
			(xy 376.432135 -238.645085) (xy 376.455786 -238.690148) (xy 376.471902 -238.738422) (xy 376.480066 -238.788656)
			(xy 376.480578 -238.814102) (xy 376.788675 -238.814102) (xy 376.79277 -238.763374) (xy 376.804949 -238.71396)
			(xy 376.824897 -238.66714) (xy 376.852098 -238.624126) (xy 376.885846 -238.586032) (xy 376.925268 -238.553845)
			(xy 376.969342 -238.528399) (xy 377.016928 -238.510352) (xy 377.066792 -238.500172) (xy 377.117644 -238.498123)
			(xy 377.168165 -238.504257) (xy 377.217049 -238.518417) (xy 377.263028 -238.540234) (xy 377.304912 -238.569144)
			(xy 377.341616 -238.604399) (xy 377.372189 -238.645085) (xy 377.39584 -238.690148) (xy 377.411956 -238.738422)
			(xy 377.42012 -238.788656) (xy 377.420632 -238.814102) (xy 377.738906 -238.814102) (xy 377.742866 -238.765048)
			(xy 377.754643 -238.717264) (xy 377.773934 -238.671988) (xy 377.800237 -238.630392) (xy 377.832872 -238.593555)
			(xy 377.870993 -238.56243) (xy 377.913614 -238.537823) (xy 377.95963 -238.520371) (xy 378.007849 -238.510527)
			(xy 378.057024 -238.508546) (xy 378.105879 -238.514478) (xy 378.15315 -238.52817) (xy 378.197612 -238.549268)
			(xy 378.238115 -238.577224) (xy 378.273608 -238.611316) (xy 378.303173 -238.65066) (xy 378.326044 -238.694237)
			(xy 378.341628 -238.740918) (xy 378.349523 -238.789495) (xy 378.350018 -238.814102) (xy 378.668529 -238.814102)
			(xy 378.672624 -238.763374) (xy 378.684803 -238.71396) (xy 378.704751 -238.66714) (xy 378.731952 -238.624126)
			(xy 378.7657 -238.586032) (xy 378.805122 -238.553845) (xy 378.849196 -238.528399) (xy 378.896782 -238.510352)
			(xy 378.946646 -238.500172) (xy 378.997498 -238.498123) (xy 379.048019 -238.504257) (xy 379.096903 -238.518417)
			(xy 379.142882 -238.540234) (xy 379.184766 -238.569144) (xy 379.22147 -238.604399) (xy 379.252043 -238.645085)
			(xy 379.275694 -238.690148) (xy 379.29181 -238.738422) (xy 379.299974 -238.788656) (xy 379.300486 -238.814102)
			(xy 379.619014 -238.814102) (xy 379.622974 -238.765048) (xy 379.634751 -238.717264) (xy 379.654042 -238.671988)
			(xy 379.680345 -238.630392) (xy 379.71298 -238.593555) (xy 379.751101 -238.56243) (xy 379.793722 -238.537823)
			(xy 379.839738 -238.520371) (xy 379.887957 -238.510527) (xy 379.937132 -238.508546) (xy 379.985987 -238.514478)
			(xy 380.033258 -238.52817) (xy 380.07772 -238.549268) (xy 380.118223 -238.577224) (xy 380.153716 -238.611316)
			(xy 380.183281 -238.65066) (xy 380.206152 -238.694237) (xy 380.221736 -238.740918) (xy 380.229631 -238.789495)
			(xy 380.230126 -238.814102) (xy 380.548637 -238.814102) (xy 380.552732 -238.763374) (xy 380.564911 -238.71396)
			(xy 380.584859 -238.66714) (xy 380.61206 -238.624126) (xy 380.645808 -238.586032) (xy 380.68523 -238.553845)
			(xy 380.729304 -238.528399) (xy 380.77689 -238.510352) (xy 380.826754 -238.500172) (xy 380.877606 -238.498123)
			(xy 380.928127 -238.504257) (xy 380.977011 -238.518417) (xy 381.02299 -238.540234) (xy 381.064874 -238.569144)
			(xy 381.101578 -238.604399) (xy 381.132151 -238.645085) (xy 381.155802 -238.690148) (xy 381.171918 -238.738422)
			(xy 381.180082 -238.788656) (xy 381.180594 -238.814102) (xy 381.499122 -238.814102) (xy 381.503082 -238.765048)
			(xy 381.514859 -238.717264) (xy 381.53415 -238.671988) (xy 381.560453 -238.630392) (xy 381.593088 -238.593555)
			(xy 381.631209 -238.56243) (xy 381.67383 -238.537823) (xy 381.719846 -238.520371) (xy 381.768065 -238.510527)
			(xy 381.81724 -238.508546) (xy 381.866095 -238.514478) (xy 381.913366 -238.52817) (xy 381.957828 -238.549268)
			(xy 381.998331 -238.577224) (xy 382.033824 -238.611316) (xy 382.063389 -238.65066) (xy 382.08626 -238.694237)
			(xy 382.101844 -238.740918) (xy 382.109739 -238.789495) (xy 382.110234 -238.814102) (xy 382.428491 -238.814102)
			(xy 382.432586 -238.763374) (xy 382.444765 -238.71396) (xy 382.464713 -238.66714) (xy 382.491914 -238.624126)
			(xy 382.525662 -238.586032) (xy 382.565084 -238.553845) (xy 382.609158 -238.528399) (xy 382.656744 -238.510352)
			(xy 382.706608 -238.500172) (xy 382.75746 -238.498123) (xy 382.807981 -238.504257) (xy 382.856865 -238.518417)
			(xy 382.902844 -238.540234) (xy 382.944728 -238.569144) (xy 382.981432 -238.604399) (xy 383.012005 -238.645085)
			(xy 383.035656 -238.690148) (xy 383.051772 -238.738422) (xy 383.059936 -238.788656) (xy 383.060448 -238.814102)
			(xy 383.368545 -238.814102) (xy 383.37264 -238.763374) (xy 383.384819 -238.71396) (xy 383.404767 -238.66714)
			(xy 383.431968 -238.624126) (xy 383.465716 -238.586032) (xy 383.505138 -238.553845) (xy 383.549212 -238.528399)
			(xy 383.596798 -238.510352) (xy 383.646662 -238.500172) (xy 383.697514 -238.498123) (xy 383.748035 -238.504257)
			(xy 383.796919 -238.518417) (xy 383.842898 -238.540234) (xy 383.884782 -238.569144) (xy 383.921486 -238.604399)
			(xy 383.952059 -238.645085) (xy 383.97571 -238.690148) (xy 383.991826 -238.738422) (xy 383.99999 -238.788656)
			(xy 384.000502 -238.814102) (xy 384.31903 -238.814102) (xy 384.32299 -238.765048) (xy 384.334767 -238.717264)
			(xy 384.354058 -238.671988) (xy 384.380361 -238.630392) (xy 384.412996 -238.593555) (xy 384.451117 -238.56243)
			(xy 384.493738 -238.537823) (xy 384.539754 -238.520371) (xy 384.587973 -238.510527) (xy 384.637148 -238.508546)
			(xy 384.686003 -238.514478) (xy 384.733274 -238.52817) (xy 384.777736 -238.549268) (xy 384.818239 -238.577224)
			(xy 384.853732 -238.611316) (xy 384.883297 -238.65066) (xy 384.906168 -238.694237) (xy 384.921752 -238.740918)
			(xy 384.929647 -238.789495) (xy 384.930142 -238.814102) (xy 385.248653 -238.814102) (xy 385.252748 -238.763374)
			(xy 385.264927 -238.71396) (xy 385.284875 -238.66714) (xy 385.312076 -238.624126) (xy 385.345824 -238.586032)
			(xy 385.385246 -238.553845) (xy 385.42932 -238.528399) (xy 385.476906 -238.510352) (xy 385.52677 -238.500172)
			(xy 385.577622 -238.498123) (xy 385.628143 -238.504257) (xy 385.677027 -238.518417) (xy 385.723006 -238.540234)
			(xy 385.76489 -238.569144) (xy 385.801594 -238.604399) (xy 385.832167 -238.645085) (xy 385.855818 -238.690148)
			(xy 385.871934 -238.738422) (xy 385.880098 -238.788656) (xy 385.88061 -238.814102) (xy 386.199138 -238.814102)
			(xy 386.203098 -238.765048) (xy 386.214875 -238.717264) (xy 386.234166 -238.671988) (xy 386.260469 -238.630392)
			(xy 386.293104 -238.593555) (xy 386.331225 -238.56243) (xy 386.373846 -238.537823) (xy 386.419862 -238.520371)
			(xy 386.468081 -238.510527) (xy 386.517256 -238.508546) (xy 386.566111 -238.514478) (xy 386.613382 -238.52817)
			(xy 386.657844 -238.549268) (xy 386.698347 -238.577224) (xy 386.73384 -238.611316) (xy 386.763405 -238.65066)
			(xy 386.786276 -238.694237) (xy 386.80186 -238.740918) (xy 386.809755 -238.789495) (xy 386.81025 -238.814102)
			(xy 387.128507 -238.814102) (xy 387.132602 -238.763374) (xy 387.144781 -238.71396) (xy 387.164729 -238.66714)
			(xy 387.19193 -238.624126) (xy 387.225678 -238.586032) (xy 387.2651 -238.553845) (xy 387.309174 -238.528399)
			(xy 387.35676 -238.510352) (xy 387.406624 -238.500172) (xy 387.457476 -238.498123) (xy 387.507997 -238.504257)
			(xy 387.556881 -238.518417) (xy 387.60286 -238.540234) (xy 387.644744 -238.569144) (xy 387.681448 -238.604399)
			(xy 387.712021 -238.645085) (xy 387.735672 -238.690148) (xy 387.751788 -238.738422) (xy 387.759952 -238.788656)
			(xy 387.760464 -238.814102) (xy 388.078992 -238.814102) (xy 388.082952 -238.765048) (xy 388.094729 -238.717264)
			(xy 388.11402 -238.671988) (xy 388.140323 -238.630392) (xy 388.172958 -238.593555) (xy 388.211079 -238.56243)
			(xy 388.2537 -238.537823) (xy 388.299716 -238.520371) (xy 388.347935 -238.510527) (xy 388.39711 -238.508546)
			(xy 388.445965 -238.514478) (xy 388.493236 -238.52817) (xy 388.537698 -238.549268) (xy 388.578201 -238.577224)
			(xy 388.613694 -238.611316) (xy 388.643259 -238.65066) (xy 388.66613 -238.694237) (xy 388.681714 -238.740918)
			(xy 388.689609 -238.789495) (xy 388.690104 -238.814102) (xy 389.008615 -238.814102) (xy 389.01271 -238.763374)
			(xy 389.024889 -238.71396) (xy 389.044837 -238.66714) (xy 389.072038 -238.624126) (xy 389.105786 -238.586032)
			(xy 389.145208 -238.553845) (xy 389.189282 -238.528399) (xy 389.236868 -238.510352) (xy 389.286732 -238.500172)
			(xy 389.337584 -238.498123) (xy 389.388105 -238.504257) (xy 389.436989 -238.518417) (xy 389.482968 -238.540234)
			(xy 389.524852 -238.569144) (xy 389.561556 -238.604399) (xy 389.592129 -238.645085) (xy 389.61578 -238.690148)
			(xy 389.631896 -238.738422) (xy 389.64006 -238.788656) (xy 389.640572 -238.814102) (xy 389.948669 -238.814102)
			(xy 389.952764 -238.763374) (xy 389.964943 -238.71396) (xy 389.984891 -238.66714) (xy 390.012092 -238.624126)
			(xy 390.04584 -238.586032) (xy 390.085262 -238.553845) (xy 390.129336 -238.528399) (xy 390.176922 -238.510352)
			(xy 390.226786 -238.500172) (xy 390.277638 -238.498123) (xy 390.328159 -238.504257) (xy 390.377043 -238.518417)
			(xy 390.423022 -238.540234) (xy 390.464906 -238.569144) (xy 390.50161 -238.604399) (xy 390.532183 -238.645085)
			(xy 390.555834 -238.690148) (xy 390.57195 -238.738422) (xy 390.580114 -238.788656) (xy 390.580626 -238.814102)
			(xy 390.8989 -238.814102) (xy 390.90286 -238.765048) (xy 390.914637 -238.717264) (xy 390.933928 -238.671988)
			(xy 390.960231 -238.630392) (xy 390.992866 -238.593555) (xy 391.030987 -238.56243) (xy 391.073608 -238.537823)
			(xy 391.119624 -238.520371) (xy 391.167843 -238.510527) (xy 391.217018 -238.508546) (xy 391.265873 -238.514478)
			(xy 391.313144 -238.52817) (xy 391.357606 -238.549268) (xy 391.398109 -238.577224) (xy 391.433602 -238.611316)
			(xy 391.463167 -238.65066) (xy 391.486038 -238.694237) (xy 391.501622 -238.740918) (xy 391.509517 -238.789495)
			(xy 391.510012 -238.814102) (xy 392.779008 -238.814102) (xy 392.782968 -238.765048) (xy 392.794745 -238.717264)
			(xy 392.814036 -238.671988) (xy 392.840339 -238.630392) (xy 392.872974 -238.593555) (xy 392.911095 -238.56243)
			(xy 392.953716 -238.537823) (xy 392.999732 -238.520371) (xy 393.047951 -238.510527) (xy 393.097126 -238.508546)
			(xy 393.145981 -238.514478) (xy 393.193252 -238.52817) (xy 393.237714 -238.549268) (xy 393.278217 -238.577224)
			(xy 393.31371 -238.611316) (xy 393.343275 -238.65066) (xy 393.366146 -238.694237) (xy 393.38173 -238.740918)
			(xy 393.389625 -238.789495) (xy 393.39012 -238.814102) (xy 393.389625 -238.838709) (xy 393.38173 -238.887286)
			(xy 393.366146 -238.933967) (xy 393.343275 -238.977544) (xy 393.31371 -239.016888) (xy 393.278217 -239.05098)
			(xy 393.237714 -239.078936) (xy 393.193252 -239.100034) (xy 393.145981 -239.113726) (xy 393.097126 -239.119658)
			(xy 393.047951 -239.117677) (xy 392.999732 -239.107833) (xy 392.953716 -239.090381) (xy 392.911095 -239.065774)
			(xy 392.872974 -239.034649) (xy 392.840339 -238.997812) (xy 392.814036 -238.956216) (xy 392.794745 -238.91094)
			(xy 392.782968 -238.863156) (xy 392.779008 -238.814102) (xy 391.510012 -238.814102) (xy 391.509517 -238.838709)
			(xy 391.501622 -238.887286) (xy 391.486038 -238.933967) (xy 391.463167 -238.977544) (xy 391.433602 -239.016888)
			(xy 391.398109 -239.05098) (xy 391.357606 -239.078936) (xy 391.313144 -239.100034) (xy 391.265873 -239.113726)
			(xy 391.217018 -239.119658) (xy 391.167843 -239.117677) (xy 391.119624 -239.107833) (xy 391.073608 -239.090381)
			(xy 391.030987 -239.065774) (xy 390.992866 -239.034649) (xy 390.960231 -238.997812) (xy 390.933928 -238.956216)
			(xy 390.914637 -238.91094) (xy 390.90286 -238.863156) (xy 390.8989 -238.814102) (xy 390.580626 -238.814102)
			(xy 390.580114 -238.839548) (xy 390.57195 -238.889782) (xy 390.555834 -238.938056) (xy 390.532183 -238.983119)
			(xy 390.50161 -239.023805) (xy 390.464906 -239.05906) (xy 390.423022 -239.08797) (xy 390.377043 -239.109787)
			(xy 390.328159 -239.123947) (xy 390.277638 -239.130081) (xy 390.226786 -239.128032) (xy 390.176922 -239.117852)
			(xy 390.129336 -239.099805) (xy 390.085262 -239.074359) (xy 390.04584 -239.042172) (xy 390.012092 -239.004078)
			(xy 389.984891 -238.961064) (xy 389.964943 -238.914244) (xy 389.952764 -238.86483) (xy 389.948669 -238.814102)
			(xy 389.640572 -238.814102) (xy 389.64006 -238.839548) (xy 389.631896 -238.889782) (xy 389.61578 -238.938056)
			(xy 389.592129 -238.983119) (xy 389.561556 -239.023805) (xy 389.524852 -239.05906) (xy 389.482968 -239.08797)
			(xy 389.436989 -239.109787) (xy 389.388105 -239.123947) (xy 389.337584 -239.130081) (xy 389.286732 -239.128032)
			(xy 389.236868 -239.117852) (xy 389.189282 -239.099805) (xy 389.145208 -239.074359) (xy 389.105786 -239.042172)
			(xy 389.072038 -239.004078) (xy 389.044837 -238.961064) (xy 389.024889 -238.914244) (xy 389.01271 -238.86483)
			(xy 389.008615 -238.814102) (xy 388.690104 -238.814102) (xy 388.689609 -238.838709) (xy 388.681714 -238.887286)
			(xy 388.66613 -238.933967) (xy 388.643259 -238.977544) (xy 388.613694 -239.016888) (xy 388.578201 -239.05098)
			(xy 388.537698 -239.078936) (xy 388.493236 -239.100034) (xy 388.445965 -239.113726) (xy 388.39711 -239.119658)
			(xy 388.347935 -239.117677) (xy 388.299716 -239.107833) (xy 388.2537 -239.090381) (xy 388.211079 -239.065774)
			(xy 388.172958 -239.034649) (xy 388.140323 -238.997812) (xy 388.11402 -238.956216) (xy 388.094729 -238.91094)
			(xy 388.082952 -238.863156) (xy 388.078992 -238.814102) (xy 387.760464 -238.814102) (xy 387.759952 -238.839548)
			(xy 387.751788 -238.889782) (xy 387.735672 -238.938056) (xy 387.712021 -238.983119) (xy 387.681448 -239.023805)
			(xy 387.644744 -239.05906) (xy 387.60286 -239.08797) (xy 387.556881 -239.109787) (xy 387.507997 -239.123947)
			(xy 387.457476 -239.130081) (xy 387.406624 -239.128032) (xy 387.35676 -239.117852) (xy 387.309174 -239.099805)
			(xy 387.2651 -239.074359) (xy 387.225678 -239.042172) (xy 387.19193 -239.004078) (xy 387.164729 -238.961064)
			(xy 387.144781 -238.914244) (xy 387.132602 -238.86483) (xy 387.128507 -238.814102) (xy 386.81025 -238.814102)
			(xy 386.809755 -238.838709) (xy 386.80186 -238.887286) (xy 386.786276 -238.933967) (xy 386.763405 -238.977544)
			(xy 386.73384 -239.016888) (xy 386.698347 -239.05098) (xy 386.657844 -239.078936) (xy 386.613382 -239.100034)
			(xy 386.566111 -239.113726) (xy 386.517256 -239.119658) (xy 386.468081 -239.117677) (xy 386.419862 -239.107833)
			(xy 386.373846 -239.090381) (xy 386.331225 -239.065774) (xy 386.293104 -239.034649) (xy 386.260469 -238.997812)
			(xy 386.234166 -238.956216) (xy 386.214875 -238.91094) (xy 386.203098 -238.863156) (xy 386.199138 -238.814102)
			(xy 385.88061 -238.814102) (xy 385.880098 -238.839548) (xy 385.871934 -238.889782) (xy 385.855818 -238.938056)
			(xy 385.832167 -238.983119) (xy 385.801594 -239.023805) (xy 385.76489 -239.05906) (xy 385.723006 -239.08797)
			(xy 385.677027 -239.109787) (xy 385.628143 -239.123947) (xy 385.577622 -239.130081) (xy 385.52677 -239.128032)
			(xy 385.476906 -239.117852) (xy 385.42932 -239.099805) (xy 385.385246 -239.074359) (xy 385.345824 -239.042172)
			(xy 385.312076 -239.004078) (xy 385.284875 -238.961064) (xy 385.264927 -238.914244) (xy 385.252748 -238.86483)
			(xy 385.248653 -238.814102) (xy 384.930142 -238.814102) (xy 384.929647 -238.838709) (xy 384.921752 -238.887286)
			(xy 384.906168 -238.933967) (xy 384.883297 -238.977544) (xy 384.853732 -239.016888) (xy 384.818239 -239.05098)
			(xy 384.777736 -239.078936) (xy 384.733274 -239.100034) (xy 384.686003 -239.113726) (xy 384.637148 -239.119658)
			(xy 384.587973 -239.117677) (xy 384.539754 -239.107833) (xy 384.493738 -239.090381) (xy 384.451117 -239.065774)
			(xy 384.412996 -239.034649) (xy 384.380361 -238.997812) (xy 384.354058 -238.956216) (xy 384.334767 -238.91094)
			(xy 384.32299 -238.863156) (xy 384.31903 -238.814102) (xy 384.000502 -238.814102) (xy 383.99999 -238.839548)
			(xy 383.991826 -238.889782) (xy 383.97571 -238.938056) (xy 383.952059 -238.983119) (xy 383.921486 -239.023805)
			(xy 383.884782 -239.05906) (xy 383.842898 -239.08797) (xy 383.796919 -239.109787) (xy 383.748035 -239.123947)
			(xy 383.697514 -239.130081) (xy 383.646662 -239.128032) (xy 383.596798 -239.117852) (xy 383.549212 -239.099805)
			(xy 383.505138 -239.074359) (xy 383.465716 -239.042172) (xy 383.431968 -239.004078) (xy 383.404767 -238.961064)
			(xy 383.384819 -238.914244) (xy 383.37264 -238.86483) (xy 383.368545 -238.814102) (xy 383.060448 -238.814102)
			(xy 383.059936 -238.839548) (xy 383.051772 -238.889782) (xy 383.035656 -238.938056) (xy 383.012005 -238.983119)
			(xy 382.981432 -239.023805) (xy 382.944728 -239.05906) (xy 382.902844 -239.08797) (xy 382.856865 -239.109787)
			(xy 382.807981 -239.123947) (xy 382.75746 -239.130081) (xy 382.706608 -239.128032) (xy 382.656744 -239.117852)
			(xy 382.609158 -239.099805) (xy 382.565084 -239.074359) (xy 382.525662 -239.042172) (xy 382.491914 -239.004078)
			(xy 382.464713 -238.961064) (xy 382.444765 -238.914244) (xy 382.432586 -238.86483) (xy 382.428491 -238.814102)
			(xy 382.110234 -238.814102) (xy 382.109739 -238.838709) (xy 382.101844 -238.887286) (xy 382.08626 -238.933967)
			(xy 382.063389 -238.977544) (xy 382.033824 -239.016888) (xy 381.998331 -239.05098) (xy 381.957828 -239.078936)
			(xy 381.913366 -239.100034) (xy 381.866095 -239.113726) (xy 381.81724 -239.119658) (xy 381.768065 -239.117677)
			(xy 381.719846 -239.107833) (xy 381.67383 -239.090381) (xy 381.631209 -239.065774) (xy 381.593088 -239.034649)
			(xy 381.560453 -238.997812) (xy 381.53415 -238.956216) (xy 381.514859 -238.91094) (xy 381.503082 -238.863156)
			(xy 381.499122 -238.814102) (xy 381.180594 -238.814102) (xy 381.180082 -238.839548) (xy 381.171918 -238.889782)
			(xy 381.155802 -238.938056) (xy 381.132151 -238.983119) (xy 381.101578 -239.023805) (xy 381.064874 -239.05906)
			(xy 381.02299 -239.08797) (xy 380.977011 -239.109787) (xy 380.928127 -239.123947) (xy 380.877606 -239.130081)
			(xy 380.826754 -239.128032) (xy 380.77689 -239.117852) (xy 380.729304 -239.099805) (xy 380.68523 -239.074359)
			(xy 380.645808 -239.042172) (xy 380.61206 -239.004078) (xy 380.584859 -238.961064) (xy 380.564911 -238.914244)
			(xy 380.552732 -238.86483) (xy 380.548637 -238.814102) (xy 380.230126 -238.814102) (xy 380.229631 -238.838709)
			(xy 380.221736 -238.887286) (xy 380.206152 -238.933967) (xy 380.183281 -238.977544) (xy 380.153716 -239.016888)
			(xy 380.118223 -239.05098) (xy 380.07772 -239.078936) (xy 380.033258 -239.100034) (xy 379.985987 -239.113726)
			(xy 379.937132 -239.119658) (xy 379.887957 -239.117677) (xy 379.839738 -239.107833) (xy 379.793722 -239.090381)
			(xy 379.751101 -239.065774) (xy 379.71298 -239.034649) (xy 379.680345 -238.997812) (xy 379.654042 -238.956216)
			(xy 379.634751 -238.91094) (xy 379.622974 -238.863156) (xy 379.619014 -238.814102) (xy 379.300486 -238.814102)
			(xy 379.299974 -238.839548) (xy 379.29181 -238.889782) (xy 379.275694 -238.938056) (xy 379.252043 -238.983119)
			(xy 379.22147 -239.023805) (xy 379.184766 -239.05906) (xy 379.142882 -239.08797) (xy 379.096903 -239.109787)
			(xy 379.048019 -239.123947) (xy 378.997498 -239.130081) (xy 378.946646 -239.128032) (xy 378.896782 -239.117852)
			(xy 378.849196 -239.099805) (xy 378.805122 -239.074359) (xy 378.7657 -239.042172) (xy 378.731952 -239.004078)
			(xy 378.704751 -238.961064) (xy 378.684803 -238.914244) (xy 378.672624 -238.86483) (xy 378.668529 -238.814102)
			(xy 378.350018 -238.814102) (xy 378.349523 -238.838709) (xy 378.341628 -238.887286) (xy 378.326044 -238.933967)
			(xy 378.303173 -238.977544) (xy 378.273608 -239.016888) (xy 378.238115 -239.05098) (xy 378.197612 -239.078936)
			(xy 378.15315 -239.100034) (xy 378.105879 -239.113726) (xy 378.057024 -239.119658) (xy 378.007849 -239.117677)
			(xy 377.95963 -239.107833) (xy 377.913614 -239.090381) (xy 377.870993 -239.065774) (xy 377.832872 -239.034649)
			(xy 377.800237 -238.997812) (xy 377.773934 -238.956216) (xy 377.754643 -238.91094) (xy 377.742866 -238.863156)
			(xy 377.738906 -238.814102) (xy 377.420632 -238.814102) (xy 377.42012 -238.839548) (xy 377.411956 -238.889782)
			(xy 377.39584 -238.938056) (xy 377.372189 -238.983119) (xy 377.341616 -239.023805) (xy 377.304912 -239.05906)
			(xy 377.263028 -239.08797) (xy 377.217049 -239.109787) (xy 377.168165 -239.123947) (xy 377.117644 -239.130081)
			(xy 377.066792 -239.128032) (xy 377.016928 -239.117852) (xy 376.969342 -239.099805) (xy 376.925268 -239.074359)
			(xy 376.885846 -239.042172) (xy 376.852098 -239.004078) (xy 376.824897 -238.961064) (xy 376.804949 -238.914244)
			(xy 376.79277 -238.86483) (xy 376.788675 -238.814102) (xy 376.480578 -238.814102) (xy 376.480066 -238.839548)
			(xy 376.471902 -238.889782) (xy 376.455786 -238.938056) (xy 376.432135 -238.983119) (xy 376.401562 -239.023805)
			(xy 376.364858 -239.05906) (xy 376.322974 -239.08797) (xy 376.276995 -239.109787) (xy 376.228111 -239.123947)
			(xy 376.17759 -239.130081) (xy 376.126738 -239.128032) (xy 376.076874 -239.117852) (xy 376.029288 -239.099805)
			(xy 375.985214 -239.074359) (xy 375.945792 -239.042172) (xy 375.912044 -239.004078) (xy 375.884843 -238.961064)
			(xy 375.864895 -238.914244) (xy 375.852716 -238.86483) (xy 375.848621 -238.814102) (xy 375.530629 -238.814102)
			(xy 375.526458 -238.864438) (xy 375.514058 -238.913402) (xy 375.493769 -238.959658) (xy 375.466143 -239.001943)
			(xy 375.431933 -239.039105) (xy 375.392074 -239.070129) (xy 375.347651 -239.094169) (xy 375.299878 -239.11057)
			(xy 375.250057 -239.118884) (xy 375.224802 -239.11941) (xy 375.200371 -239.118929) (xy 375.152133 -239.111141)
			(xy 375.12879 -239.103916) (xy 375.121932 -239.10163) (xy 375.12117 -239.101376) (xy 375.109418 -239.097904)
			(xy 375.085161 -239.101105) (xy 375.074688 -239.107472) (xy 375.00687 -239.155224) (xy 375.004838 -239.156748)
			(xy 374.996617 -239.163766) (xy 374.986476 -239.182836) (xy 374.98528 -239.193578) (xy 374.98528 -239.397032)
			(xy 374.985359 -239.401241) (xy 374.98677 -239.409539) (xy 374.988074 -239.413542) (xy 374.995948 -239.436402)
			(xy 375.00052 -239.442752) (xy 375.014556 -239.462574) (xy 375.036834 -239.50573) (xy 375.052006 -239.551867)
			(xy 375.059687 -239.599823) (xy 375.059686 -239.624108) (xy 375.378467 -239.624108) (xy 375.382562 -239.57338)
			(xy 375.394741 -239.523966) (xy 375.414689 -239.477146) (xy 375.44189 -239.434132) (xy 375.475638 -239.396038)
			(xy 375.51506 -239.363851) (xy 375.559134 -239.338405) (xy 375.60672 -239.320358) (xy 375.656584 -239.310178)
			(xy 375.707436 -239.308129) (xy 375.757957 -239.314263) (xy 375.806841 -239.328423) (xy 375.85282 -239.35024)
			(xy 375.894704 -239.37915) (xy 375.931408 -239.414405) (xy 375.961981 -239.455091) (xy 375.985632 -239.500154)
			(xy 376.001748 -239.548428) (xy 376.009912 -239.598662) (xy 376.010424 -239.624108) (xy 376.328952 -239.624108)
			(xy 376.332912 -239.575054) (xy 376.344689 -239.52727) (xy 376.36398 -239.481994) (xy 376.390283 -239.440398)
			(xy 376.422918 -239.403561) (xy 376.461039 -239.372436) (xy 376.50366 -239.347829) (xy 376.549676 -239.330377)
			(xy 376.597895 -239.320533) (xy 376.64707 -239.318552) (xy 376.695925 -239.324484) (xy 376.743196 -239.338176)
			(xy 376.787658 -239.359274) (xy 376.828161 -239.38723) (xy 376.863654 -239.421322) (xy 376.893219 -239.460666)
			(xy 376.91609 -239.504243) (xy 376.931674 -239.550924) (xy 376.939569 -239.599501) (xy 376.940064 -239.624108)
			(xy 377.258575 -239.624108) (xy 377.26267 -239.57338) (xy 377.274849 -239.523966) (xy 377.294797 -239.477146)
			(xy 377.321998 -239.434132) (xy 377.355746 -239.396038) (xy 377.395168 -239.363851) (xy 377.439242 -239.338405)
			(xy 377.486828 -239.320358) (xy 377.536692 -239.310178) (xy 377.587544 -239.308129) (xy 377.638065 -239.314263)
			(xy 377.686949 -239.328423) (xy 377.732928 -239.35024) (xy 377.774812 -239.37915) (xy 377.811516 -239.414405)
			(xy 377.842089 -239.455091) (xy 377.86574 -239.500154) (xy 377.881856 -239.548428) (xy 377.89002 -239.598662)
			(xy 377.890532 -239.624108) (xy 379.138683 -239.624108) (xy 379.142778 -239.57338) (xy 379.154957 -239.523966)
			(xy 379.174905 -239.477146) (xy 379.202106 -239.434132) (xy 379.235854 -239.396038) (xy 379.275276 -239.363851)
			(xy 379.31935 -239.338405) (xy 379.366936 -239.320358) (xy 379.4168 -239.310178) (xy 379.467652 -239.308129)
			(xy 379.518173 -239.314263) (xy 379.567057 -239.328423) (xy 379.613036 -239.35024) (xy 379.65492 -239.37915)
			(xy 379.691624 -239.414405) (xy 379.722197 -239.455091) (xy 379.745848 -239.500154) (xy 379.761964 -239.548428)
			(xy 379.770128 -239.598662) (xy 379.77064 -239.624108) (xy 380.078483 -239.624108) (xy 380.082578 -239.57338)
			(xy 380.094757 -239.523966) (xy 380.114705 -239.477146) (xy 380.141906 -239.434132) (xy 380.175654 -239.396038)
			(xy 380.215076 -239.363851) (xy 380.25915 -239.338405) (xy 380.306736 -239.320358) (xy 380.3566 -239.310178)
			(xy 380.407452 -239.308129) (xy 380.457973 -239.314263) (xy 380.506857 -239.328423) (xy 380.552836 -239.35024)
			(xy 380.59472 -239.37915) (xy 380.631424 -239.414405) (xy 380.661997 -239.455091) (xy 380.685648 -239.500154)
			(xy 380.701764 -239.548428) (xy 380.709928 -239.598662) (xy 380.71044 -239.624108) (xy 381.028968 -239.624108)
			(xy 381.032928 -239.575054) (xy 381.044705 -239.52727) (xy 381.063996 -239.481994) (xy 381.090299 -239.440398)
			(xy 381.122934 -239.403561) (xy 381.161055 -239.372436) (xy 381.203676 -239.347829) (xy 381.249692 -239.330377)
			(xy 381.297911 -239.320533) (xy 381.347086 -239.318552) (xy 381.395941 -239.324484) (xy 381.443212 -239.338176)
			(xy 381.487674 -239.359274) (xy 381.528177 -239.38723) (xy 381.56367 -239.421322) (xy 381.593235 -239.460666)
			(xy 381.616106 -239.504243) (xy 381.63169 -239.550924) (xy 381.639585 -239.599501) (xy 381.64008 -239.624108)
			(xy 381.958591 -239.624108) (xy 381.962686 -239.57338) (xy 381.974865 -239.523966) (xy 381.994813 -239.477146)
			(xy 382.022014 -239.434132) (xy 382.055762 -239.396038) (xy 382.095184 -239.363851) (xy 382.139258 -239.338405)
			(xy 382.186844 -239.320358) (xy 382.236708 -239.310178) (xy 382.28756 -239.308129) (xy 382.338081 -239.314263)
			(xy 382.386965 -239.328423) (xy 382.432944 -239.35024) (xy 382.474828 -239.37915) (xy 382.511532 -239.414405)
			(xy 382.542105 -239.455091) (xy 382.565756 -239.500154) (xy 382.581872 -239.548428) (xy 382.590036 -239.598662)
			(xy 382.590548 -239.624108) (xy 382.909076 -239.624108) (xy 382.913036 -239.575054) (xy 382.924813 -239.52727)
			(xy 382.944104 -239.481994) (xy 382.970407 -239.440398) (xy 383.003042 -239.403561) (xy 383.041163 -239.372436)
			(xy 383.083784 -239.347829) (xy 383.1298 -239.330377) (xy 383.178019 -239.320533) (xy 383.227194 -239.318552)
			(xy 383.276049 -239.324484) (xy 383.32332 -239.338176) (xy 383.367782 -239.359274) (xy 383.408285 -239.38723)
			(xy 383.443778 -239.421322) (xy 383.473343 -239.460666) (xy 383.496214 -239.504243) (xy 383.511798 -239.550924)
			(xy 383.519693 -239.599501) (xy 383.520188 -239.624108) (xy 383.838699 -239.624108) (xy 383.842794 -239.57338)
			(xy 383.854973 -239.523966) (xy 383.874921 -239.477146) (xy 383.902122 -239.434132) (xy 383.93587 -239.396038)
			(xy 383.975292 -239.363851) (xy 384.019366 -239.338405) (xy 384.066952 -239.320358) (xy 384.116816 -239.310178)
			(xy 384.167668 -239.308129) (xy 384.218189 -239.314263) (xy 384.267073 -239.328423) (xy 384.313052 -239.35024)
			(xy 384.354936 -239.37915) (xy 384.39164 -239.414405) (xy 384.422213 -239.455091) (xy 384.445864 -239.500154)
			(xy 384.46198 -239.548428) (xy 384.470144 -239.598662) (xy 384.470656 -239.624108) (xy 385.718553 -239.624108)
			(xy 385.722648 -239.57338) (xy 385.734827 -239.523966) (xy 385.754775 -239.477146) (xy 385.781976 -239.434132)
			(xy 385.815724 -239.396038) (xy 385.855146 -239.363851) (xy 385.89922 -239.338405) (xy 385.946806 -239.320358)
			(xy 385.99667 -239.310178) (xy 386.047522 -239.308129) (xy 386.098043 -239.314263) (xy 386.146927 -239.328423)
			(xy 386.192906 -239.35024) (xy 386.23479 -239.37915) (xy 386.271494 -239.414405) (xy 386.302067 -239.455091)
			(xy 386.325718 -239.500154) (xy 386.341834 -239.548428) (xy 386.349998 -239.598662) (xy 386.35051 -239.624108)
			(xy 386.658607 -239.624108) (xy 386.662702 -239.57338) (xy 386.674881 -239.523966) (xy 386.694829 -239.477146)
			(xy 386.72203 -239.434132) (xy 386.755778 -239.396038) (xy 386.7952 -239.363851) (xy 386.839274 -239.338405)
			(xy 386.88686 -239.320358) (xy 386.936724 -239.310178) (xy 386.987576 -239.308129) (xy 387.038097 -239.314263)
			(xy 387.086981 -239.328423) (xy 387.13296 -239.35024) (xy 387.174844 -239.37915) (xy 387.211548 -239.414405)
			(xy 387.242121 -239.455091) (xy 387.265772 -239.500154) (xy 387.281888 -239.548428) (xy 387.290052 -239.598662)
			(xy 387.290564 -239.624108) (xy 387.609092 -239.624108) (xy 387.613052 -239.575054) (xy 387.624829 -239.52727)
			(xy 387.64412 -239.481994) (xy 387.670423 -239.440398) (xy 387.703058 -239.403561) (xy 387.741179 -239.372436)
			(xy 387.7838 -239.347829) (xy 387.829816 -239.330377) (xy 387.878035 -239.320533) (xy 387.92721 -239.318552)
			(xy 387.976065 -239.324484) (xy 388.023336 -239.338176) (xy 388.067798 -239.359274) (xy 388.108301 -239.38723)
			(xy 388.143794 -239.421322) (xy 388.173359 -239.460666) (xy 388.19623 -239.504243) (xy 388.211814 -239.550924)
			(xy 388.219709 -239.599501) (xy 388.220204 -239.624108) (xy 388.538715 -239.624108) (xy 388.54281 -239.57338)
			(xy 388.554989 -239.523966) (xy 388.574937 -239.477146) (xy 388.602138 -239.434132) (xy 388.635886 -239.396038)
			(xy 388.675308 -239.363851) (xy 388.719382 -239.338405) (xy 388.766968 -239.320358) (xy 388.816832 -239.310178)
			(xy 388.867684 -239.308129) (xy 388.918205 -239.314263) (xy 388.967089 -239.328423) (xy 389.013068 -239.35024)
			(xy 389.054952 -239.37915) (xy 389.091656 -239.414405) (xy 389.122229 -239.455091) (xy 389.14588 -239.500154)
			(xy 389.161996 -239.548428) (xy 389.17016 -239.598662) (xy 389.170672 -239.624108) (xy 389.488946 -239.624108)
			(xy 389.492906 -239.575054) (xy 389.504683 -239.52727) (xy 389.523974 -239.481994) (xy 389.550277 -239.440398)
			(xy 389.582912 -239.403561) (xy 389.621033 -239.372436) (xy 389.663654 -239.347829) (xy 389.70967 -239.330377)
			(xy 389.757889 -239.320533) (xy 389.807064 -239.318552) (xy 389.855919 -239.324484) (xy 389.90319 -239.338176)
			(xy 389.947652 -239.359274) (xy 389.988155 -239.38723) (xy 390.023648 -239.421322) (xy 390.053213 -239.460666)
			(xy 390.076084 -239.504243) (xy 390.091668 -239.550924) (xy 390.099563 -239.599501) (xy 390.100058 -239.624108)
			(xy 390.418569 -239.624108) (xy 390.422664 -239.57338) (xy 390.434843 -239.523966) (xy 390.454791 -239.477146)
			(xy 390.481992 -239.434132) (xy 390.51574 -239.396038) (xy 390.555162 -239.363851) (xy 390.599236 -239.338405)
			(xy 390.646822 -239.320358) (xy 390.696686 -239.310178) (xy 390.747538 -239.308129) (xy 390.798059 -239.314263)
			(xy 390.846943 -239.328423) (xy 390.892922 -239.35024) (xy 390.934806 -239.37915) (xy 390.97151 -239.414405)
			(xy 391.002083 -239.455091) (xy 391.025734 -239.500154) (xy 391.04185 -239.548428) (xy 391.050014 -239.598662)
			(xy 391.050526 -239.624108) (xy 391.050014 -239.649554) (xy 391.04185 -239.699788) (xy 391.025734 -239.748062)
			(xy 391.002083 -239.793125) (xy 390.97151 -239.833811) (xy 390.934806 -239.869066) (xy 390.904411 -239.890046)
			(xy 394.377176 -239.890046) (xy 394.381136 -239.840992) (xy 394.392913 -239.793208) (xy 394.412204 -239.747932)
			(xy 394.438507 -239.706336) (xy 394.471142 -239.669499) (xy 394.509263 -239.638374) (xy 394.551884 -239.613767)
			(xy 394.5979 -239.596315) (xy 394.646119 -239.586471) (xy 394.695294 -239.58449) (xy 394.744149 -239.590422)
			(xy 394.79142 -239.604114) (xy 394.835882 -239.625212) (xy 394.876385 -239.653168) (xy 394.911878 -239.68726)
			(xy 394.941443 -239.726604) (xy 394.964314 -239.770181) (xy 394.979898 -239.816862) (xy 394.987793 -239.865439)
			(xy 394.988288 -239.890046) (xy 394.987793 -239.914653) (xy 394.979898 -239.96323) (xy 394.964314 -240.009911)
			(xy 394.941443 -240.053488) (xy 394.911878 -240.092832) (xy 394.876385 -240.126924) (xy 394.835882 -240.15488)
			(xy 394.79142 -240.175978) (xy 394.744149 -240.18967) (xy 394.695294 -240.195602) (xy 394.646119 -240.193621)
			(xy 394.5979 -240.183777) (xy 394.551884 -240.166325) (xy 394.509263 -240.141718) (xy 394.471142 -240.110593)
			(xy 394.438507 -240.073756) (xy 394.412204 -240.03216) (xy 394.392913 -239.986884) (xy 394.381136 -239.9391)
			(xy 394.377176 -239.890046) (xy 390.904411 -239.890046) (xy 390.892922 -239.897976) (xy 390.846943 -239.919793)
			(xy 390.798059 -239.933953) (xy 390.747538 -239.940087) (xy 390.696686 -239.938038) (xy 390.646822 -239.927858)
			(xy 390.599236 -239.909811) (xy 390.555162 -239.884365) (xy 390.51574 -239.852178) (xy 390.481992 -239.814084)
			(xy 390.454791 -239.77107) (xy 390.434843 -239.72425) (xy 390.422664 -239.674836) (xy 390.418569 -239.624108)
			(xy 390.100058 -239.624108) (xy 390.099563 -239.648715) (xy 390.091668 -239.697292) (xy 390.076084 -239.743973)
			(xy 390.053213 -239.78755) (xy 390.023648 -239.826894) (xy 389.988155 -239.860986) (xy 389.947652 -239.888942)
			(xy 389.90319 -239.91004) (xy 389.855919 -239.923732) (xy 389.807064 -239.929664) (xy 389.757889 -239.927683)
			(xy 389.70967 -239.917839) (xy 389.663654 -239.900387) (xy 389.621033 -239.87578) (xy 389.582912 -239.844655)
			(xy 389.550277 -239.807818) (xy 389.523974 -239.766222) (xy 389.504683 -239.720946) (xy 389.492906 -239.673162)
			(xy 389.488946 -239.624108) (xy 389.170672 -239.624108) (xy 389.17016 -239.649554) (xy 389.161996 -239.699788)
			(xy 389.14588 -239.748062) (xy 389.122229 -239.793125) (xy 389.091656 -239.833811) (xy 389.054952 -239.869066)
			(xy 389.013068 -239.897976) (xy 388.967089 -239.919793) (xy 388.918205 -239.933953) (xy 388.867684 -239.940087)
			(xy 388.816832 -239.938038) (xy 388.766968 -239.927858) (xy 388.719382 -239.909811) (xy 388.675308 -239.884365)
			(xy 388.635886 -239.852178) (xy 388.602138 -239.814084) (xy 388.574937 -239.77107) (xy 388.554989 -239.72425)
			(xy 388.54281 -239.674836) (xy 388.538715 -239.624108) (xy 388.220204 -239.624108) (xy 388.219709 -239.648715)
			(xy 388.211814 -239.697292) (xy 388.19623 -239.743973) (xy 388.173359 -239.78755) (xy 388.143794 -239.826894)
			(xy 388.108301 -239.860986) (xy 388.067798 -239.888942) (xy 388.023336 -239.91004) (xy 387.976065 -239.923732)
			(xy 387.92721 -239.929664) (xy 387.878035 -239.927683) (xy 387.829816 -239.917839) (xy 387.7838 -239.900387)
			(xy 387.741179 -239.87578) (xy 387.703058 -239.844655) (xy 387.670423 -239.807818) (xy 387.64412 -239.766222)
			(xy 387.624829 -239.720946) (xy 387.613052 -239.673162) (xy 387.609092 -239.624108) (xy 387.290564 -239.624108)
			(xy 387.290052 -239.649554) (xy 387.281888 -239.699788) (xy 387.265772 -239.748062) (xy 387.242121 -239.793125)
			(xy 387.211548 -239.833811) (xy 387.174844 -239.869066) (xy 387.13296 -239.897976) (xy 387.086981 -239.919793)
			(xy 387.038097 -239.933953) (xy 386.987576 -239.940087) (xy 386.936724 -239.938038) (xy 386.88686 -239.927858)
			(xy 386.839274 -239.909811) (xy 386.7952 -239.884365) (xy 386.755778 -239.852178) (xy 386.72203 -239.814084)
			(xy 386.694829 -239.77107) (xy 386.674881 -239.72425) (xy 386.662702 -239.674836) (xy 386.658607 -239.624108)
			(xy 386.35051 -239.624108) (xy 386.349998 -239.649554) (xy 386.341834 -239.699788) (xy 386.325718 -239.748062)
			(xy 386.302067 -239.793125) (xy 386.271494 -239.833811) (xy 386.23479 -239.869066) (xy 386.192906 -239.897976)
			(xy 386.146927 -239.919793) (xy 386.098043 -239.933953) (xy 386.047522 -239.940087) (xy 385.99667 -239.938038)
			(xy 385.946806 -239.927858) (xy 385.89922 -239.909811) (xy 385.855146 -239.884365) (xy 385.815724 -239.852178)
			(xy 385.781976 -239.814084) (xy 385.754775 -239.77107) (xy 385.734827 -239.72425) (xy 385.722648 -239.674836)
			(xy 385.718553 -239.624108) (xy 384.470656 -239.624108) (xy 384.470144 -239.649554) (xy 384.46198 -239.699788)
			(xy 384.445864 -239.748062) (xy 384.422213 -239.793125) (xy 384.39164 -239.833811) (xy 384.354936 -239.869066)
			(xy 384.313052 -239.897976) (xy 384.267073 -239.919793) (xy 384.218189 -239.933953) (xy 384.167668 -239.940087)
			(xy 384.116816 -239.938038) (xy 384.066952 -239.927858) (xy 384.019366 -239.909811) (xy 383.975292 -239.884365)
			(xy 383.93587 -239.852178) (xy 383.902122 -239.814084) (xy 383.874921 -239.77107) (xy 383.854973 -239.72425)
			(xy 383.842794 -239.674836) (xy 383.838699 -239.624108) (xy 383.520188 -239.624108) (xy 383.519693 -239.648715)
			(xy 383.511798 -239.697292) (xy 383.496214 -239.743973) (xy 383.473343 -239.78755) (xy 383.443778 -239.826894)
			(xy 383.408285 -239.860986) (xy 383.367782 -239.888942) (xy 383.32332 -239.91004) (xy 383.276049 -239.923732)
			(xy 383.227194 -239.929664) (xy 383.178019 -239.927683) (xy 383.1298 -239.917839) (xy 383.083784 -239.900387)
			(xy 383.041163 -239.87578) (xy 383.003042 -239.844655) (xy 382.970407 -239.807818) (xy 382.944104 -239.766222)
			(xy 382.924813 -239.720946) (xy 382.913036 -239.673162) (xy 382.909076 -239.624108) (xy 382.590548 -239.624108)
			(xy 382.590036 -239.649554) (xy 382.581872 -239.699788) (xy 382.565756 -239.748062) (xy 382.542105 -239.793125)
			(xy 382.511532 -239.833811) (xy 382.474828 -239.869066) (xy 382.432944 -239.897976) (xy 382.386965 -239.919793)
			(xy 382.338081 -239.933953) (xy 382.28756 -239.940087) (xy 382.236708 -239.938038) (xy 382.186844 -239.927858)
			(xy 382.139258 -239.909811) (xy 382.095184 -239.884365) (xy 382.055762 -239.852178) (xy 382.022014 -239.814084)
			(xy 381.994813 -239.77107) (xy 381.974865 -239.72425) (xy 381.962686 -239.674836) (xy 381.958591 -239.624108)
			(xy 381.64008 -239.624108) (xy 381.639585 -239.648715) (xy 381.63169 -239.697292) (xy 381.616106 -239.743973)
			(xy 381.593235 -239.78755) (xy 381.56367 -239.826894) (xy 381.528177 -239.860986) (xy 381.487674 -239.888942)
			(xy 381.443212 -239.91004) (xy 381.395941 -239.923732) (xy 381.347086 -239.929664) (xy 381.297911 -239.927683)
			(xy 381.249692 -239.917839) (xy 381.203676 -239.900387) (xy 381.161055 -239.87578) (xy 381.122934 -239.844655)
			(xy 381.090299 -239.807818) (xy 381.063996 -239.766222) (xy 381.044705 -239.720946) (xy 381.032928 -239.673162)
			(xy 381.028968 -239.624108) (xy 380.71044 -239.624108) (xy 380.709928 -239.649554) (xy 380.701764 -239.699788)
			(xy 380.685648 -239.748062) (xy 380.661997 -239.793125) (xy 380.631424 -239.833811) (xy 380.59472 -239.869066)
			(xy 380.552836 -239.897976) (xy 380.506857 -239.919793) (xy 380.457973 -239.933953) (xy 380.407452 -239.940087)
			(xy 380.3566 -239.938038) (xy 380.306736 -239.927858) (xy 380.25915 -239.909811) (xy 380.215076 -239.884365)
			(xy 380.175654 -239.852178) (xy 380.141906 -239.814084) (xy 380.114705 -239.77107) (xy 380.094757 -239.72425)
			(xy 380.082578 -239.674836) (xy 380.078483 -239.624108) (xy 379.77064 -239.624108) (xy 379.770128 -239.649554)
			(xy 379.761964 -239.699788) (xy 379.745848 -239.748062) (xy 379.722197 -239.793125) (xy 379.691624 -239.833811)
			(xy 379.65492 -239.869066) (xy 379.613036 -239.897976) (xy 379.567057 -239.919793) (xy 379.518173 -239.933953)
			(xy 379.467652 -239.940087) (xy 379.4168 -239.938038) (xy 379.366936 -239.927858) (xy 379.31935 -239.909811)
			(xy 379.275276 -239.884365) (xy 379.235854 -239.852178) (xy 379.202106 -239.814084) (xy 379.174905 -239.77107)
			(xy 379.154957 -239.72425) (xy 379.142778 -239.674836) (xy 379.138683 -239.624108) (xy 377.890532 -239.624108)
			(xy 377.89002 -239.649554) (xy 377.881856 -239.699788) (xy 377.86574 -239.748062) (xy 377.842089 -239.793125)
			(xy 377.811516 -239.833811) (xy 377.774812 -239.869066) (xy 377.732928 -239.897976) (xy 377.686949 -239.919793)
			(xy 377.638065 -239.933953) (xy 377.587544 -239.940087) (xy 377.536692 -239.938038) (xy 377.486828 -239.927858)
			(xy 377.439242 -239.909811) (xy 377.395168 -239.884365) (xy 377.355746 -239.852178) (xy 377.321998 -239.814084)
			(xy 377.294797 -239.77107) (xy 377.274849 -239.72425) (xy 377.26267 -239.674836) (xy 377.258575 -239.624108)
			(xy 376.940064 -239.624108) (xy 376.939569 -239.648715) (xy 376.931674 -239.697292) (xy 376.91609 -239.743973)
			(xy 376.893219 -239.78755) (xy 376.863654 -239.826894) (xy 376.828161 -239.860986) (xy 376.787658 -239.888942)
			(xy 376.743196 -239.91004) (xy 376.695925 -239.923732) (xy 376.64707 -239.929664) (xy 376.597895 -239.927683)
			(xy 376.549676 -239.917839) (xy 376.50366 -239.900387) (xy 376.461039 -239.87578) (xy 376.422918 -239.844655)
			(xy 376.390283 -239.807818) (xy 376.36398 -239.766222) (xy 376.344689 -239.720946) (xy 376.332912 -239.673162)
			(xy 376.328952 -239.624108) (xy 376.010424 -239.624108) (xy 376.009912 -239.649554) (xy 376.001748 -239.699788)
			(xy 375.985632 -239.748062) (xy 375.961981 -239.793125) (xy 375.931408 -239.833811) (xy 375.894704 -239.869066)
			(xy 375.85282 -239.897976) (xy 375.806841 -239.919793) (xy 375.757957 -239.933953) (xy 375.707436 -239.940087)
			(xy 375.656584 -239.938038) (xy 375.60672 -239.927858) (xy 375.559134 -239.909811) (xy 375.51506 -239.884365)
			(xy 375.475638 -239.852178) (xy 375.44189 -239.814084) (xy 375.414689 -239.77107) (xy 375.394741 -239.72425)
			(xy 375.382562 -239.674836) (xy 375.378467 -239.624108) (xy 375.059686 -239.624108) (xy 375.059686 -239.64839)
			(xy 375.052003 -239.696346) (xy 375.036829 -239.742482) (xy 375.014549 -239.785637) (xy 375.00052 -239.805464)
			(xy 374.995948 -239.811814) (xy 374.988074 -239.834674) (xy 374.98679 -239.838681) (xy 374.985385 -239.846977)
			(xy 374.98528 -239.851184) (xy 374.98528 -240.434114) (xy 375.848621 -240.434114) (xy 375.852716 -240.383386)
			(xy 375.864895 -240.333972) (xy 375.884843 -240.287152) (xy 375.912044 -240.244138) (xy 375.945792 -240.206044)
			(xy 375.985214 -240.173857) (xy 376.029288 -240.148411) (xy 376.076874 -240.130364) (xy 376.126738 -240.120184)
			(xy 376.17759 -240.118135) (xy 376.228111 -240.124269) (xy 376.276995 -240.138429) (xy 376.322974 -240.160246)
			(xy 376.364858 -240.189156) (xy 376.401562 -240.224411) (xy 376.432135 -240.265097) (xy 376.455786 -240.31016)
			(xy 376.471902 -240.358434) (xy 376.480066 -240.408668) (xy 376.480578 -240.434114) (xy 376.788675 -240.434114)
			(xy 376.79277 -240.383386) (xy 376.804949 -240.333972) (xy 376.824897 -240.287152) (xy 376.852098 -240.244138)
			(xy 376.885846 -240.206044) (xy 376.925268 -240.173857) (xy 376.969342 -240.148411) (xy 377.016928 -240.130364)
			(xy 377.066792 -240.120184) (xy 377.117644 -240.118135) (xy 377.168165 -240.124269) (xy 377.217049 -240.138429)
			(xy 377.263028 -240.160246) (xy 377.304912 -240.189156) (xy 377.341616 -240.224411) (xy 377.372189 -240.265097)
			(xy 377.39584 -240.31016) (xy 377.411956 -240.358434) (xy 377.42012 -240.408668) (xy 377.420632 -240.434114)
			(xy 377.738906 -240.434114) (xy 377.742866 -240.38506) (xy 377.754643 -240.337276) (xy 377.773934 -240.292)
			(xy 377.800237 -240.250404) (xy 377.832872 -240.213567) (xy 377.870993 -240.182442) (xy 377.913614 -240.157835)
			(xy 377.95963 -240.140383) (xy 378.007849 -240.130539) (xy 378.057024 -240.128558) (xy 378.105879 -240.13449)
			(xy 378.15315 -240.148182) (xy 378.197612 -240.16928) (xy 378.238115 -240.197236) (xy 378.273608 -240.231328)
			(xy 378.303173 -240.270672) (xy 378.326044 -240.314249) (xy 378.341628 -240.36093) (xy 378.349523 -240.409507)
			(xy 378.350018 -240.434114) (xy 378.668529 -240.434114) (xy 378.672624 -240.383386) (xy 378.684803 -240.333972)
			(xy 378.704751 -240.287152) (xy 378.731952 -240.244138) (xy 378.7657 -240.206044) (xy 378.805122 -240.173857)
			(xy 378.849196 -240.148411) (xy 378.896782 -240.130364) (xy 378.946646 -240.120184) (xy 378.997498 -240.118135)
			(xy 379.048019 -240.124269) (xy 379.096903 -240.138429) (xy 379.142882 -240.160246) (xy 379.184766 -240.189156)
			(xy 379.22147 -240.224411) (xy 379.252043 -240.265097) (xy 379.275694 -240.31016) (xy 379.29181 -240.358434)
			(xy 379.299974 -240.408668) (xy 379.300486 -240.434114) (xy 379.619014 -240.434114) (xy 379.622974 -240.38506)
			(xy 379.634751 -240.337276) (xy 379.654042 -240.292) (xy 379.680345 -240.250404) (xy 379.71298 -240.213567)
			(xy 379.751101 -240.182442) (xy 379.793722 -240.157835) (xy 379.839738 -240.140383) (xy 379.887957 -240.130539)
			(xy 379.937132 -240.128558) (xy 379.985987 -240.13449) (xy 380.033258 -240.148182) (xy 380.07772 -240.16928)
			(xy 380.118223 -240.197236) (xy 380.153716 -240.231328) (xy 380.183281 -240.270672) (xy 380.206152 -240.314249)
			(xy 380.221736 -240.36093) (xy 380.229631 -240.409507) (xy 380.230126 -240.434114) (xy 380.548637 -240.434114)
			(xy 380.552732 -240.383386) (xy 380.564911 -240.333972) (xy 380.584859 -240.287152) (xy 380.61206 -240.244138)
			(xy 380.645808 -240.206044) (xy 380.68523 -240.173857) (xy 380.729304 -240.148411) (xy 380.77689 -240.130364)
			(xy 380.826754 -240.120184) (xy 380.877606 -240.118135) (xy 380.928127 -240.124269) (xy 380.977011 -240.138429)
			(xy 381.02299 -240.160246) (xy 381.064874 -240.189156) (xy 381.101578 -240.224411) (xy 381.132151 -240.265097)
			(xy 381.155802 -240.31016) (xy 381.171918 -240.358434) (xy 381.180082 -240.408668) (xy 381.180594 -240.434114)
			(xy 381.499122 -240.434114) (xy 381.503082 -240.38506) (xy 381.514859 -240.337276) (xy 381.53415 -240.292)
			(xy 381.560453 -240.250404) (xy 381.593088 -240.213567) (xy 381.631209 -240.182442) (xy 381.67383 -240.157835)
			(xy 381.719846 -240.140383) (xy 381.768065 -240.130539) (xy 381.81724 -240.128558) (xy 381.866095 -240.13449)
			(xy 381.913366 -240.148182) (xy 381.957828 -240.16928) (xy 381.998331 -240.197236) (xy 382.033824 -240.231328)
			(xy 382.063389 -240.270672) (xy 382.08626 -240.314249) (xy 382.101844 -240.36093) (xy 382.109739 -240.409507)
			(xy 382.110234 -240.434114) (xy 382.428491 -240.434114) (xy 382.432586 -240.383386) (xy 382.444765 -240.333972)
			(xy 382.464713 -240.287152) (xy 382.491914 -240.244138) (xy 382.525662 -240.206044) (xy 382.565084 -240.173857)
			(xy 382.609158 -240.148411) (xy 382.656744 -240.130364) (xy 382.706608 -240.120184) (xy 382.75746 -240.118135)
			(xy 382.807981 -240.124269) (xy 382.856865 -240.138429) (xy 382.902844 -240.160246) (xy 382.944728 -240.189156)
			(xy 382.981432 -240.224411) (xy 383.012005 -240.265097) (xy 383.035656 -240.31016) (xy 383.051772 -240.358434)
			(xy 383.059936 -240.408668) (xy 383.060448 -240.434114) (xy 383.368545 -240.434114) (xy 383.37264 -240.383386)
			(xy 383.384819 -240.333972) (xy 383.404767 -240.287152) (xy 383.431968 -240.244138) (xy 383.465716 -240.206044)
			(xy 383.505138 -240.173857) (xy 383.549212 -240.148411) (xy 383.596798 -240.130364) (xy 383.646662 -240.120184)
			(xy 383.697514 -240.118135) (xy 383.748035 -240.124269) (xy 383.796919 -240.138429) (xy 383.842898 -240.160246)
			(xy 383.884782 -240.189156) (xy 383.921486 -240.224411) (xy 383.952059 -240.265097) (xy 383.97571 -240.31016)
			(xy 383.991826 -240.358434) (xy 383.99999 -240.408668) (xy 384.000502 -240.434114) (xy 384.31903 -240.434114)
			(xy 384.32299 -240.38506) (xy 384.334767 -240.337276) (xy 384.354058 -240.292) (xy 384.380361 -240.250404)
			(xy 384.412996 -240.213567) (xy 384.451117 -240.182442) (xy 384.493738 -240.157835) (xy 384.539754 -240.140383)
			(xy 384.587973 -240.130539) (xy 384.637148 -240.128558) (xy 384.686003 -240.13449) (xy 384.733274 -240.148182)
			(xy 384.777736 -240.16928) (xy 384.818239 -240.197236) (xy 384.853732 -240.231328) (xy 384.883297 -240.270672)
			(xy 384.906168 -240.314249) (xy 384.921752 -240.36093) (xy 384.929647 -240.409507) (xy 384.930142 -240.434114)
			(xy 385.248653 -240.434114) (xy 385.252748 -240.383386) (xy 385.264927 -240.333972) (xy 385.284875 -240.287152)
			(xy 385.312076 -240.244138) (xy 385.345824 -240.206044) (xy 385.385246 -240.173857) (xy 385.42932 -240.148411)
			(xy 385.476906 -240.130364) (xy 385.52677 -240.120184) (xy 385.577622 -240.118135) (xy 385.628143 -240.124269)
			(xy 385.677027 -240.138429) (xy 385.723006 -240.160246) (xy 385.76489 -240.189156) (xy 385.801594 -240.224411)
			(xy 385.832167 -240.265097) (xy 385.855818 -240.31016) (xy 385.871934 -240.358434) (xy 385.880098 -240.408668)
			(xy 385.88061 -240.434114) (xy 386.199138 -240.434114) (xy 386.203098 -240.38506) (xy 386.214875 -240.337276)
			(xy 386.234166 -240.292) (xy 386.260469 -240.250404) (xy 386.293104 -240.213567) (xy 386.331225 -240.182442)
			(xy 386.373846 -240.157835) (xy 386.419862 -240.140383) (xy 386.468081 -240.130539) (xy 386.517256 -240.128558)
			(xy 386.566111 -240.13449) (xy 386.613382 -240.148182) (xy 386.657844 -240.16928) (xy 386.698347 -240.197236)
			(xy 386.73384 -240.231328) (xy 386.763405 -240.270672) (xy 386.786276 -240.314249) (xy 386.80186 -240.36093)
			(xy 386.809755 -240.409507) (xy 386.81025 -240.434114) (xy 387.128507 -240.434114) (xy 387.132602 -240.383386)
			(xy 387.144781 -240.333972) (xy 387.164729 -240.287152) (xy 387.19193 -240.244138) (xy 387.225678 -240.206044)
			(xy 387.2651 -240.173857) (xy 387.309174 -240.148411) (xy 387.35676 -240.130364) (xy 387.406624 -240.120184)
			(xy 387.457476 -240.118135) (xy 387.507997 -240.124269) (xy 387.556881 -240.138429) (xy 387.60286 -240.160246)
			(xy 387.644744 -240.189156) (xy 387.681448 -240.224411) (xy 387.712021 -240.265097) (xy 387.735672 -240.31016)
			(xy 387.751788 -240.358434) (xy 387.759952 -240.408668) (xy 387.760464 -240.434114) (xy 388.078992 -240.434114)
			(xy 388.082952 -240.38506) (xy 388.094729 -240.337276) (xy 388.11402 -240.292) (xy 388.140323 -240.250404)
			(xy 388.172958 -240.213567) (xy 388.211079 -240.182442) (xy 388.2537 -240.157835) (xy 388.299716 -240.140383)
			(xy 388.347935 -240.130539) (xy 388.39711 -240.128558) (xy 388.445965 -240.13449) (xy 388.493236 -240.148182)
			(xy 388.537698 -240.16928) (xy 388.578201 -240.197236) (xy 388.613694 -240.231328) (xy 388.643259 -240.270672)
			(xy 388.66613 -240.314249) (xy 388.681714 -240.36093) (xy 388.689609 -240.409507) (xy 388.690104 -240.434114)
			(xy 389.008615 -240.434114) (xy 389.01271 -240.383386) (xy 389.024889 -240.333972) (xy 389.044837 -240.287152)
			(xy 389.072038 -240.244138) (xy 389.105786 -240.206044) (xy 389.145208 -240.173857) (xy 389.189282 -240.148411)
			(xy 389.236868 -240.130364) (xy 389.286732 -240.120184) (xy 389.337584 -240.118135) (xy 389.388105 -240.124269)
			(xy 389.436989 -240.138429) (xy 389.482968 -240.160246) (xy 389.524852 -240.189156) (xy 389.561556 -240.224411)
			(xy 389.592129 -240.265097) (xy 389.61578 -240.31016) (xy 389.631896 -240.358434) (xy 389.64006 -240.408668)
			(xy 389.640572 -240.434114) (xy 389.948669 -240.434114) (xy 389.952764 -240.383386) (xy 389.964943 -240.333972)
			(xy 389.984891 -240.287152) (xy 390.012092 -240.244138) (xy 390.04584 -240.206044) (xy 390.085262 -240.173857)
			(xy 390.129336 -240.148411) (xy 390.176922 -240.130364) (xy 390.226786 -240.120184) (xy 390.277638 -240.118135)
			(xy 390.328159 -240.124269) (xy 390.377043 -240.138429) (xy 390.423022 -240.160246) (xy 390.464906 -240.189156)
			(xy 390.50161 -240.224411) (xy 390.532183 -240.265097) (xy 390.555834 -240.31016) (xy 390.57195 -240.358434)
			(xy 390.580114 -240.408668) (xy 390.580626 -240.434114) (xy 390.8989 -240.434114) (xy 390.90286 -240.38506)
			(xy 390.914637 -240.337276) (xy 390.933928 -240.292) (xy 390.960231 -240.250404) (xy 390.992866 -240.213567)
			(xy 391.030987 -240.182442) (xy 391.073608 -240.157835) (xy 391.119624 -240.140383) (xy 391.167843 -240.130539)
			(xy 391.217018 -240.128558) (xy 391.265873 -240.13449) (xy 391.313144 -240.148182) (xy 391.357606 -240.16928)
			(xy 391.398109 -240.197236) (xy 391.433602 -240.231328) (xy 391.463167 -240.270672) (xy 391.486038 -240.314249)
			(xy 391.501622 -240.36093) (xy 391.509517 -240.409507) (xy 391.510012 -240.434114) (xy 392.779008 -240.434114)
			(xy 392.782968 -240.38506) (xy 392.794745 -240.337276) (xy 392.814036 -240.292) (xy 392.840339 -240.250404)
			(xy 392.872974 -240.213567) (xy 392.911095 -240.182442) (xy 392.953716 -240.157835) (xy 392.999732 -240.140383)
			(xy 393.047951 -240.130539) (xy 393.097126 -240.128558) (xy 393.145981 -240.13449) (xy 393.193252 -240.148182)
			(xy 393.237714 -240.16928) (xy 393.278217 -240.197236) (xy 393.31371 -240.231328) (xy 393.343275 -240.270672)
			(xy 393.366146 -240.314249) (xy 393.38173 -240.36093) (xy 393.389625 -240.409507) (xy 393.39012 -240.434114)
			(xy 393.389625 -240.458721) (xy 393.38173 -240.507298) (xy 393.366146 -240.553979) (xy 393.343275 -240.597556)
			(xy 393.31371 -240.6369) (xy 393.278217 -240.670992) (xy 393.237714 -240.698948) (xy 393.193252 -240.720046)
			(xy 393.145981 -240.733738) (xy 393.097126 -240.73967) (xy 393.047951 -240.737689) (xy 392.999732 -240.727845)
			(xy 392.953716 -240.710393) (xy 392.911095 -240.685786) (xy 392.872974 -240.654661) (xy 392.840339 -240.617824)
			(xy 392.814036 -240.576228) (xy 392.794745 -240.530952) (xy 392.782968 -240.483168) (xy 392.779008 -240.434114)
			(xy 391.510012 -240.434114) (xy 391.509517 -240.458721) (xy 391.501622 -240.507298) (xy 391.486038 -240.553979)
			(xy 391.463167 -240.597556) (xy 391.433602 -240.6369) (xy 391.398109 -240.670992) (xy 391.357606 -240.698948)
			(xy 391.313144 -240.720046) (xy 391.265873 -240.733738) (xy 391.217018 -240.73967) (xy 391.167843 -240.737689)
			(xy 391.119624 -240.727845) (xy 391.073608 -240.710393) (xy 391.030987 -240.685786) (xy 390.992866 -240.654661)
			(xy 390.960231 -240.617824) (xy 390.933928 -240.576228) (xy 390.914637 -240.530952) (xy 390.90286 -240.483168)
			(xy 390.8989 -240.434114) (xy 390.580626 -240.434114) (xy 390.580114 -240.45956) (xy 390.57195 -240.509794)
			(xy 390.555834 -240.558068) (xy 390.532183 -240.603131) (xy 390.50161 -240.643817) (xy 390.464906 -240.679072)
			(xy 390.423022 -240.707982) (xy 390.377043 -240.729799) (xy 390.328159 -240.743959) (xy 390.277638 -240.750093)
			(xy 390.226786 -240.748044) (xy 390.176922 -240.737864) (xy 390.129336 -240.719817) (xy 390.085262 -240.694371)
			(xy 390.04584 -240.662184) (xy 390.012092 -240.62409) (xy 389.984891 -240.581076) (xy 389.964943 -240.534256)
			(xy 389.952764 -240.484842) (xy 389.948669 -240.434114) (xy 389.640572 -240.434114) (xy 389.64006 -240.45956)
			(xy 389.631896 -240.509794) (xy 389.61578 -240.558068) (xy 389.592129 -240.603131) (xy 389.561556 -240.643817)
			(xy 389.524852 -240.679072) (xy 389.482968 -240.707982) (xy 389.436989 -240.729799) (xy 389.388105 -240.743959)
			(xy 389.337584 -240.750093) (xy 389.286732 -240.748044) (xy 389.236868 -240.737864) (xy 389.189282 -240.719817)
			(xy 389.145208 -240.694371) (xy 389.105786 -240.662184) (xy 389.072038 -240.62409) (xy 389.044837 -240.581076)
			(xy 389.024889 -240.534256) (xy 389.01271 -240.484842) (xy 389.008615 -240.434114) (xy 388.690104 -240.434114)
			(xy 388.689609 -240.458721) (xy 388.681714 -240.507298) (xy 388.66613 -240.553979) (xy 388.643259 -240.597556)
			(xy 388.613694 -240.6369) (xy 388.578201 -240.670992) (xy 388.537698 -240.698948) (xy 388.493236 -240.720046)
			(xy 388.445965 -240.733738) (xy 388.39711 -240.73967) (xy 388.347935 -240.737689) (xy 388.299716 -240.727845)
			(xy 388.2537 -240.710393) (xy 388.211079 -240.685786) (xy 388.172958 -240.654661) (xy 388.140323 -240.617824)
			(xy 388.11402 -240.576228) (xy 388.094729 -240.530952) (xy 388.082952 -240.483168) (xy 388.078992 -240.434114)
			(xy 387.760464 -240.434114) (xy 387.759952 -240.45956) (xy 387.751788 -240.509794) (xy 387.735672 -240.558068)
			(xy 387.712021 -240.603131) (xy 387.681448 -240.643817) (xy 387.644744 -240.679072) (xy 387.60286 -240.707982)
			(xy 387.556881 -240.729799) (xy 387.507997 -240.743959) (xy 387.457476 -240.750093) (xy 387.406624 -240.748044)
			(xy 387.35676 -240.737864) (xy 387.309174 -240.719817) (xy 387.2651 -240.694371) (xy 387.225678 -240.662184)
			(xy 387.19193 -240.62409) (xy 387.164729 -240.581076) (xy 387.144781 -240.534256) (xy 387.132602 -240.484842)
			(xy 387.128507 -240.434114) (xy 386.81025 -240.434114) (xy 386.809755 -240.458721) (xy 386.80186 -240.507298)
			(xy 386.786276 -240.553979) (xy 386.763405 -240.597556) (xy 386.73384 -240.6369) (xy 386.698347 -240.670992)
			(xy 386.657844 -240.698948) (xy 386.613382 -240.720046) (xy 386.566111 -240.733738) (xy 386.517256 -240.73967)
			(xy 386.468081 -240.737689) (xy 386.419862 -240.727845) (xy 386.373846 -240.710393) (xy 386.331225 -240.685786)
			(xy 386.293104 -240.654661) (xy 386.260469 -240.617824) (xy 386.234166 -240.576228) (xy 386.214875 -240.530952)
			(xy 386.203098 -240.483168) (xy 386.199138 -240.434114) (xy 385.88061 -240.434114) (xy 385.880098 -240.45956)
			(xy 385.871934 -240.509794) (xy 385.855818 -240.558068) (xy 385.832167 -240.603131) (xy 385.801594 -240.643817)
			(xy 385.76489 -240.679072) (xy 385.723006 -240.707982) (xy 385.677027 -240.729799) (xy 385.628143 -240.743959)
			(xy 385.577622 -240.750093) (xy 385.52677 -240.748044) (xy 385.476906 -240.737864) (xy 385.42932 -240.719817)
			(xy 385.385246 -240.694371) (xy 385.345824 -240.662184) (xy 385.312076 -240.62409) (xy 385.284875 -240.581076)
			(xy 385.264927 -240.534256) (xy 385.252748 -240.484842) (xy 385.248653 -240.434114) (xy 384.930142 -240.434114)
			(xy 384.929647 -240.458721) (xy 384.921752 -240.507298) (xy 384.906168 -240.553979) (xy 384.883297 -240.597556)
			(xy 384.853732 -240.6369) (xy 384.818239 -240.670992) (xy 384.777736 -240.698948) (xy 384.733274 -240.720046)
			(xy 384.686003 -240.733738) (xy 384.637148 -240.73967) (xy 384.587973 -240.737689) (xy 384.539754 -240.727845)
			(xy 384.493738 -240.710393) (xy 384.451117 -240.685786) (xy 384.412996 -240.654661) (xy 384.380361 -240.617824)
			(xy 384.354058 -240.576228) (xy 384.334767 -240.530952) (xy 384.32299 -240.483168) (xy 384.31903 -240.434114)
			(xy 384.000502 -240.434114) (xy 383.99999 -240.45956) (xy 383.991826 -240.509794) (xy 383.97571 -240.558068)
			(xy 383.952059 -240.603131) (xy 383.921486 -240.643817) (xy 383.884782 -240.679072) (xy 383.842898 -240.707982)
			(xy 383.796919 -240.729799) (xy 383.748035 -240.743959) (xy 383.697514 -240.750093) (xy 383.646662 -240.748044)
			(xy 383.596798 -240.737864) (xy 383.549212 -240.719817) (xy 383.505138 -240.694371) (xy 383.465716 -240.662184)
			(xy 383.431968 -240.62409) (xy 383.404767 -240.581076) (xy 383.384819 -240.534256) (xy 383.37264 -240.484842)
			(xy 383.368545 -240.434114) (xy 383.060448 -240.434114) (xy 383.059936 -240.45956) (xy 383.051772 -240.509794)
			(xy 383.035656 -240.558068) (xy 383.012005 -240.603131) (xy 382.981432 -240.643817) (xy 382.944728 -240.679072)
			(xy 382.902844 -240.707982) (xy 382.856865 -240.729799) (xy 382.807981 -240.743959) (xy 382.75746 -240.750093)
			(xy 382.706608 -240.748044) (xy 382.656744 -240.737864) (xy 382.609158 -240.719817) (xy 382.565084 -240.694371)
			(xy 382.525662 -240.662184) (xy 382.491914 -240.62409) (xy 382.464713 -240.581076) (xy 382.444765 -240.534256)
			(xy 382.432586 -240.484842) (xy 382.428491 -240.434114) (xy 382.110234 -240.434114) (xy 382.109739 -240.458721)
			(xy 382.101844 -240.507298) (xy 382.08626 -240.553979) (xy 382.063389 -240.597556) (xy 382.033824 -240.6369)
			(xy 381.998331 -240.670992) (xy 381.957828 -240.698948) (xy 381.913366 -240.720046) (xy 381.866095 -240.733738)
			(xy 381.81724 -240.73967) (xy 381.768065 -240.737689) (xy 381.719846 -240.727845) (xy 381.67383 -240.710393)
			(xy 381.631209 -240.685786) (xy 381.593088 -240.654661) (xy 381.560453 -240.617824) (xy 381.53415 -240.576228)
			(xy 381.514859 -240.530952) (xy 381.503082 -240.483168) (xy 381.499122 -240.434114) (xy 381.180594 -240.434114)
			(xy 381.180082 -240.45956) (xy 381.171918 -240.509794) (xy 381.155802 -240.558068) (xy 381.132151 -240.603131)
			(xy 381.101578 -240.643817) (xy 381.064874 -240.679072) (xy 381.02299 -240.707982) (xy 380.977011 -240.729799)
			(xy 380.928127 -240.743959) (xy 380.877606 -240.750093) (xy 380.826754 -240.748044) (xy 380.77689 -240.737864)
			(xy 380.729304 -240.719817) (xy 380.68523 -240.694371) (xy 380.645808 -240.662184) (xy 380.61206 -240.62409)
			(xy 380.584859 -240.581076) (xy 380.564911 -240.534256) (xy 380.552732 -240.484842) (xy 380.548637 -240.434114)
			(xy 380.230126 -240.434114) (xy 380.229631 -240.458721) (xy 380.221736 -240.507298) (xy 380.206152 -240.553979)
			(xy 380.183281 -240.597556) (xy 380.153716 -240.6369) (xy 380.118223 -240.670992) (xy 380.07772 -240.698948)
			(xy 380.033258 -240.720046) (xy 379.985987 -240.733738) (xy 379.937132 -240.73967) (xy 379.887957 -240.737689)
			(xy 379.839738 -240.727845) (xy 379.793722 -240.710393) (xy 379.751101 -240.685786) (xy 379.71298 -240.654661)
			(xy 379.680345 -240.617824) (xy 379.654042 -240.576228) (xy 379.634751 -240.530952) (xy 379.622974 -240.483168)
			(xy 379.619014 -240.434114) (xy 379.300486 -240.434114) (xy 379.299974 -240.45956) (xy 379.29181 -240.509794)
			(xy 379.275694 -240.558068) (xy 379.252043 -240.603131) (xy 379.22147 -240.643817) (xy 379.184766 -240.679072)
			(xy 379.142882 -240.707982) (xy 379.096903 -240.729799) (xy 379.048019 -240.743959) (xy 378.997498 -240.750093)
			(xy 378.946646 -240.748044) (xy 378.896782 -240.737864) (xy 378.849196 -240.719817) (xy 378.805122 -240.694371)
			(xy 378.7657 -240.662184) (xy 378.731952 -240.62409) (xy 378.704751 -240.581076) (xy 378.684803 -240.534256)
			(xy 378.672624 -240.484842) (xy 378.668529 -240.434114) (xy 378.350018 -240.434114) (xy 378.349523 -240.458721)
			(xy 378.341628 -240.507298) (xy 378.326044 -240.553979) (xy 378.303173 -240.597556) (xy 378.273608 -240.6369)
			(xy 378.238115 -240.670992) (xy 378.197612 -240.698948) (xy 378.15315 -240.720046) (xy 378.105879 -240.733738)
			(xy 378.057024 -240.73967) (xy 378.007849 -240.737689) (xy 377.95963 -240.727845) (xy 377.913614 -240.710393)
			(xy 377.870993 -240.685786) (xy 377.832872 -240.654661) (xy 377.800237 -240.617824) (xy 377.773934 -240.576228)
			(xy 377.754643 -240.530952) (xy 377.742866 -240.483168) (xy 377.738906 -240.434114) (xy 377.420632 -240.434114)
			(xy 377.42012 -240.45956) (xy 377.411956 -240.509794) (xy 377.39584 -240.558068) (xy 377.372189 -240.603131)
			(xy 377.341616 -240.643817) (xy 377.304912 -240.679072) (xy 377.263028 -240.707982) (xy 377.217049 -240.729799)
			(xy 377.168165 -240.743959) (xy 377.117644 -240.750093) (xy 377.066792 -240.748044) (xy 377.016928 -240.737864)
			(xy 376.969342 -240.719817) (xy 376.925268 -240.694371) (xy 376.885846 -240.662184) (xy 376.852098 -240.62409)
			(xy 376.824897 -240.581076) (xy 376.804949 -240.534256) (xy 376.79277 -240.484842) (xy 376.788675 -240.434114)
			(xy 376.480578 -240.434114) (xy 376.480066 -240.45956) (xy 376.471902 -240.509794) (xy 376.455786 -240.558068)
			(xy 376.432135 -240.603131) (xy 376.401562 -240.643817) (xy 376.364858 -240.679072) (xy 376.322974 -240.707982)
			(xy 376.276995 -240.729799) (xy 376.228111 -240.743959) (xy 376.17759 -240.750093) (xy 376.126738 -240.748044)
			(xy 376.076874 -240.737864) (xy 376.029288 -240.719817) (xy 375.985214 -240.694371) (xy 375.945792 -240.662184)
			(xy 375.912044 -240.62409) (xy 375.884843 -240.581076) (xy 375.864895 -240.534256) (xy 375.852716 -240.484842)
			(xy 375.848621 -240.434114) (xy 374.98528 -240.434114) (xy 374.98528 -241.017044) (xy 374.98536 -241.021253)
			(xy 374.986773 -241.02955) (xy 374.988074 -241.033554) (xy 374.995948 -241.056414) (xy 375.00052 -241.062764)
			(xy 375.014555 -241.082586) (xy 375.036832 -241.125742) (xy 375.052001 -241.171878) (xy 375.059681 -241.219833)
			(xy 375.05968 -241.24412) (xy 375.378467 -241.24412) (xy 375.382562 -241.193392) (xy 375.394741 -241.143978)
			(xy 375.414689 -241.097158) (xy 375.44189 -241.054144) (xy 375.475638 -241.01605) (xy 375.51506 -240.983863)
			(xy 375.559134 -240.958417) (xy 375.60672 -240.94037) (xy 375.656584 -240.93019) (xy 375.707436 -240.928141)
			(xy 375.757957 -240.934275) (xy 375.806841 -240.948435) (xy 375.85282 -240.970252) (xy 375.894704 -240.999162)
			(xy 375.931408 -241.034417) (xy 375.961981 -241.075103) (xy 375.985632 -241.120166) (xy 376.001748 -241.16844)
			(xy 376.009912 -241.218674) (xy 376.010424 -241.24412) (xy 376.328952 -241.24412) (xy 376.332912 -241.195066)
			(xy 376.344689 -241.147282) (xy 376.36398 -241.102006) (xy 376.390283 -241.06041) (xy 376.422918 -241.023573)
			(xy 376.461039 -240.992448) (xy 376.50366 -240.967841) (xy 376.549676 -240.950389) (xy 376.597895 -240.940545)
			(xy 376.64707 -240.938564) (xy 376.695925 -240.944496) (xy 376.743196 -240.958188) (xy 376.787658 -240.979286)
			(xy 376.828161 -241.007242) (xy 376.863654 -241.041334) (xy 376.893219 -241.080678) (xy 376.91609 -241.124255)
			(xy 376.931674 -241.170936) (xy 376.939569 -241.219513) (xy 376.940064 -241.24412) (xy 377.258575 -241.24412)
			(xy 377.26267 -241.193392) (xy 377.274849 -241.143978) (xy 377.294797 -241.097158) (xy 377.321998 -241.054144)
			(xy 377.355746 -241.01605) (xy 377.395168 -240.983863) (xy 377.439242 -240.958417) (xy 377.486828 -240.94037)
			(xy 377.536692 -240.93019) (xy 377.587544 -240.928141) (xy 377.638065 -240.934275) (xy 377.686949 -240.948435)
			(xy 377.732928 -240.970252) (xy 377.774812 -240.999162) (xy 377.811516 -241.034417) (xy 377.842089 -241.075103)
			(xy 377.86574 -241.120166) (xy 377.881856 -241.16844) (xy 377.89002 -241.218674) (xy 377.890532 -241.24412)
			(xy 378.20906 -241.24412) (xy 378.21302 -241.195066) (xy 378.224797 -241.147282) (xy 378.244088 -241.102006)
			(xy 378.270391 -241.06041) (xy 378.303026 -241.023573) (xy 378.341147 -240.992448) (xy 378.383768 -240.967841)
			(xy 378.429784 -240.950389) (xy 378.478003 -240.940545) (xy 378.527178 -240.938564) (xy 378.576033 -240.944496)
			(xy 378.623304 -240.958188) (xy 378.667766 -240.979286) (xy 378.708269 -241.007242) (xy 378.743762 -241.041334)
			(xy 378.773327 -241.080678) (xy 378.796198 -241.124255) (xy 378.811782 -241.170936) (xy 378.819677 -241.219513)
			(xy 378.820172 -241.24412) (xy 379.138683 -241.24412) (xy 379.142778 -241.193392) (xy 379.154957 -241.143978)
			(xy 379.174905 -241.097158) (xy 379.202106 -241.054144) (xy 379.235854 -241.01605) (xy 379.275276 -240.983863)
			(xy 379.31935 -240.958417) (xy 379.366936 -240.94037) (xy 379.4168 -240.93019) (xy 379.467652 -240.928141)
			(xy 379.518173 -240.934275) (xy 379.567057 -240.948435) (xy 379.613036 -240.970252) (xy 379.65492 -240.999162)
			(xy 379.691624 -241.034417) (xy 379.722197 -241.075103) (xy 379.745848 -241.120166) (xy 379.761964 -241.16844)
			(xy 379.770128 -241.218674) (xy 379.77064 -241.24412) (xy 380.078483 -241.24412) (xy 380.082578 -241.193392)
			(xy 380.094757 -241.143978) (xy 380.114705 -241.097158) (xy 380.141906 -241.054144) (xy 380.175654 -241.01605)
			(xy 380.215076 -240.983863) (xy 380.25915 -240.958417) (xy 380.306736 -240.94037) (xy 380.3566 -240.93019)
			(xy 380.407452 -240.928141) (xy 380.457973 -240.934275) (xy 380.506857 -240.948435) (xy 380.552836 -240.970252)
			(xy 380.59472 -240.999162) (xy 380.631424 -241.034417) (xy 380.661997 -241.075103) (xy 380.685648 -241.120166)
			(xy 380.701764 -241.16844) (xy 380.709928 -241.218674) (xy 380.71044 -241.24412) (xy 381.028968 -241.24412)
			(xy 381.032928 -241.195066) (xy 381.044705 -241.147282) (xy 381.063996 -241.102006) (xy 381.090299 -241.06041)
			(xy 381.122934 -241.023573) (xy 381.161055 -240.992448) (xy 381.203676 -240.967841) (xy 381.249692 -240.950389)
			(xy 381.297911 -240.940545) (xy 381.347086 -240.938564) (xy 381.395941 -240.944496) (xy 381.443212 -240.958188)
			(xy 381.487674 -240.979286) (xy 381.528177 -241.007242) (xy 381.56367 -241.041334) (xy 381.593235 -241.080678)
			(xy 381.616106 -241.124255) (xy 381.63169 -241.170936) (xy 381.639585 -241.219513) (xy 381.64008 -241.24412)
			(xy 381.958591 -241.24412) (xy 381.962686 -241.193392) (xy 381.974865 -241.143978) (xy 381.994813 -241.097158)
			(xy 382.022014 -241.054144) (xy 382.055762 -241.01605) (xy 382.095184 -240.983863) (xy 382.139258 -240.958417)
			(xy 382.186844 -240.94037) (xy 382.236708 -240.93019) (xy 382.28756 -240.928141) (xy 382.338081 -240.934275)
			(xy 382.386965 -240.948435) (xy 382.432944 -240.970252) (xy 382.474828 -240.999162) (xy 382.511532 -241.034417)
			(xy 382.542105 -241.075103) (xy 382.565756 -241.120166) (xy 382.581872 -241.16844) (xy 382.590036 -241.218674)
			(xy 382.590548 -241.24412) (xy 382.909076 -241.24412) (xy 382.913036 -241.195066) (xy 382.924813 -241.147282)
			(xy 382.944104 -241.102006) (xy 382.970407 -241.06041) (xy 383.003042 -241.023573) (xy 383.041163 -240.992448)
			(xy 383.083784 -240.967841) (xy 383.1298 -240.950389) (xy 383.178019 -240.940545) (xy 383.227194 -240.938564)
			(xy 383.276049 -240.944496) (xy 383.32332 -240.958188) (xy 383.367782 -240.979286) (xy 383.408285 -241.007242)
			(xy 383.443778 -241.041334) (xy 383.473343 -241.080678) (xy 383.496214 -241.124255) (xy 383.511798 -241.170936)
			(xy 383.519693 -241.219513) (xy 383.520188 -241.24412) (xy 383.838699 -241.24412) (xy 383.842794 -241.193392)
			(xy 383.854973 -241.143978) (xy 383.874921 -241.097158) (xy 383.902122 -241.054144) (xy 383.93587 -241.01605)
			(xy 383.975292 -240.983863) (xy 384.019366 -240.958417) (xy 384.066952 -240.94037) (xy 384.116816 -240.93019)
			(xy 384.167668 -240.928141) (xy 384.218189 -240.934275) (xy 384.267073 -240.948435) (xy 384.313052 -240.970252)
			(xy 384.354936 -240.999162) (xy 384.39164 -241.034417) (xy 384.422213 -241.075103) (xy 384.445864 -241.120166)
			(xy 384.46198 -241.16844) (xy 384.470144 -241.218674) (xy 384.470656 -241.24412) (xy 384.78893 -241.24412)
			(xy 384.79289 -241.195066) (xy 384.804667 -241.147282) (xy 384.823958 -241.102006) (xy 384.850261 -241.06041)
			(xy 384.882896 -241.023573) (xy 384.921017 -240.992448) (xy 384.963638 -240.967841) (xy 385.009654 -240.950389)
			(xy 385.057873 -240.940545) (xy 385.107048 -240.938564) (xy 385.155903 -240.944496) (xy 385.203174 -240.958188)
			(xy 385.247636 -240.979286) (xy 385.288139 -241.007242) (xy 385.323632 -241.041334) (xy 385.353197 -241.080678)
			(xy 385.376068 -241.124255) (xy 385.391652 -241.170936) (xy 385.399547 -241.219513) (xy 385.400042 -241.24412)
			(xy 385.718553 -241.24412) (xy 385.722648 -241.193392) (xy 385.734827 -241.143978) (xy 385.754775 -241.097158)
			(xy 385.781976 -241.054144) (xy 385.815724 -241.01605) (xy 385.855146 -240.983863) (xy 385.89922 -240.958417)
			(xy 385.946806 -240.94037) (xy 385.99667 -240.93019) (xy 386.047522 -240.928141) (xy 386.098043 -240.934275)
			(xy 386.146927 -240.948435) (xy 386.192906 -240.970252) (xy 386.23479 -240.999162) (xy 386.271494 -241.034417)
			(xy 386.302067 -241.075103) (xy 386.325718 -241.120166) (xy 386.341834 -241.16844) (xy 386.349998 -241.218674)
			(xy 386.35051 -241.24412) (xy 386.658607 -241.24412) (xy 386.662702 -241.193392) (xy 386.674881 -241.143978)
			(xy 386.694829 -241.097158) (xy 386.72203 -241.054144) (xy 386.755778 -241.01605) (xy 386.7952 -240.983863)
			(xy 386.839274 -240.958417) (xy 386.88686 -240.94037) (xy 386.936724 -240.93019) (xy 386.987576 -240.928141)
			(xy 387.038097 -240.934275) (xy 387.086981 -240.948435) (xy 387.13296 -240.970252) (xy 387.174844 -240.999162)
			(xy 387.211548 -241.034417) (xy 387.242121 -241.075103) (xy 387.265772 -241.120166) (xy 387.281888 -241.16844)
			(xy 387.290052 -241.218674) (xy 387.290564 -241.24412) (xy 387.609092 -241.24412) (xy 387.613052 -241.195066)
			(xy 387.624829 -241.147282) (xy 387.64412 -241.102006) (xy 387.670423 -241.06041) (xy 387.703058 -241.023573)
			(xy 387.741179 -240.992448) (xy 387.7838 -240.967841) (xy 387.829816 -240.950389) (xy 387.878035 -240.940545)
			(xy 387.92721 -240.938564) (xy 387.976065 -240.944496) (xy 388.023336 -240.958188) (xy 388.067798 -240.979286)
			(xy 388.108301 -241.007242) (xy 388.143794 -241.041334) (xy 388.173359 -241.080678) (xy 388.19623 -241.124255)
			(xy 388.211814 -241.170936) (xy 388.219709 -241.219513) (xy 388.220204 -241.24412) (xy 388.538715 -241.24412)
			(xy 388.54281 -241.193392) (xy 388.554989 -241.143978) (xy 388.574937 -241.097158) (xy 388.602138 -241.054144)
			(xy 388.635886 -241.01605) (xy 388.675308 -240.983863) (xy 388.719382 -240.958417) (xy 388.766968 -240.94037)
			(xy 388.816832 -240.93019) (xy 388.867684 -240.928141) (xy 388.918205 -240.934275) (xy 388.967089 -240.948435)
			(xy 389.013068 -240.970252) (xy 389.054952 -240.999162) (xy 389.091656 -241.034417) (xy 389.122229 -241.075103)
			(xy 389.14588 -241.120166) (xy 389.161996 -241.16844) (xy 389.17016 -241.218674) (xy 389.170672 -241.24412)
			(xy 389.488946 -241.24412) (xy 389.492906 -241.195066) (xy 389.504683 -241.147282) (xy 389.523974 -241.102006)
			(xy 389.550277 -241.06041) (xy 389.582912 -241.023573) (xy 389.621033 -240.992448) (xy 389.663654 -240.967841)
			(xy 389.70967 -240.950389) (xy 389.757889 -240.940545) (xy 389.807064 -240.938564) (xy 389.855919 -240.944496)
			(xy 389.90319 -240.958188) (xy 389.947652 -240.979286) (xy 389.988155 -241.007242) (xy 390.023648 -241.041334)
			(xy 390.053213 -241.080678) (xy 390.076084 -241.124255) (xy 390.091668 -241.170936) (xy 390.099563 -241.219513)
			(xy 390.100058 -241.24412) (xy 390.418569 -241.24412) (xy 390.422664 -241.193392) (xy 390.434843 -241.143978)
			(xy 390.454791 -241.097158) (xy 390.481992 -241.054144) (xy 390.51574 -241.01605) (xy 390.555162 -240.983863)
			(xy 390.599236 -240.958417) (xy 390.646822 -240.94037) (xy 390.696686 -240.93019) (xy 390.747538 -240.928141)
			(xy 390.798059 -240.934275) (xy 390.846943 -240.948435) (xy 390.892922 -240.970252) (xy 390.934806 -240.999162)
			(xy 390.97151 -241.034417) (xy 391.002083 -241.075103) (xy 391.025734 -241.120166) (xy 391.04185 -241.16844)
			(xy 391.050014 -241.218674) (xy 391.050526 -241.24412) (xy 391.369054 -241.24412) (xy 391.373014 -241.195066)
			(xy 391.384791 -241.147282) (xy 391.404082 -241.102006) (xy 391.430385 -241.06041) (xy 391.46302 -241.023573)
			(xy 391.501141 -240.992448) (xy 391.543762 -240.967841) (xy 391.589778 -240.950389) (xy 391.637997 -240.940545)
			(xy 391.687172 -240.938564) (xy 391.736027 -240.944496) (xy 391.783298 -240.958188) (xy 391.82776 -240.979286)
			(xy 391.868263 -241.007242) (xy 391.903756 -241.041334) (xy 391.933321 -241.080678) (xy 391.956192 -241.124255)
			(xy 391.971776 -241.170936) (xy 391.979671 -241.219513) (xy 391.980166 -241.24412) (xy 391.979671 -241.268727)
			(xy 391.971776 -241.317304) (xy 391.956192 -241.363985) (xy 391.933321 -241.407562) (xy 391.903756 -241.446906)
			(xy 391.868263 -241.480998) (xy 391.82776 -241.508954) (xy 391.825433 -241.510058) (xy 394.377176 -241.510058)
			(xy 394.381136 -241.461004) (xy 394.392913 -241.41322) (xy 394.412204 -241.367944) (xy 394.438507 -241.326348)
			(xy 394.471142 -241.289511) (xy 394.509263 -241.258386) (xy 394.551884 -241.233779) (xy 394.5979 -241.216327)
			(xy 394.646119 -241.206483) (xy 394.695294 -241.204502) (xy 394.744149 -241.210434) (xy 394.79142 -241.224126)
			(xy 394.835882 -241.245224) (xy 394.876385 -241.27318) (xy 394.911878 -241.307272) (xy 394.941443 -241.346616)
			(xy 394.964314 -241.390193) (xy 394.979898 -241.436874) (xy 394.987793 -241.485451) (xy 394.988288 -241.510058)
			(xy 394.987793 -241.534665) (xy 394.979898 -241.583242) (xy 394.964314 -241.629923) (xy 394.941443 -241.6735)
			(xy 394.911878 -241.712844) (xy 394.876385 -241.746936) (xy 394.835882 -241.774892) (xy 394.79142 -241.79599)
			(xy 394.744149 -241.809682) (xy 394.695294 -241.815614) (xy 394.646119 -241.813633) (xy 394.5979 -241.803789)
			(xy 394.551884 -241.786337) (xy 394.509263 -241.76173) (xy 394.471142 -241.730605) (xy 394.438507 -241.693768)
			(xy 394.412204 -241.652172) (xy 394.392913 -241.606896) (xy 394.381136 -241.559112) (xy 394.377176 -241.510058)
			(xy 391.825433 -241.510058) (xy 391.783298 -241.530052) (xy 391.736027 -241.543744) (xy 391.687172 -241.549676)
			(xy 391.637997 -241.547695) (xy 391.589778 -241.537851) (xy 391.543762 -241.520399) (xy 391.501141 -241.495792)
			(xy 391.46302 -241.464667) (xy 391.430385 -241.42783) (xy 391.404082 -241.386234) (xy 391.384791 -241.340958)
			(xy 391.373014 -241.293174) (xy 391.369054 -241.24412) (xy 391.050526 -241.24412) (xy 391.050014 -241.269566)
			(xy 391.04185 -241.3198) (xy 391.025734 -241.368074) (xy 391.002083 -241.413137) (xy 390.97151 -241.453823)
			(xy 390.934806 -241.489078) (xy 390.892922 -241.517988) (xy 390.846943 -241.539805) (xy 390.798059 -241.553965)
			(xy 390.747538 -241.560099) (xy 390.696686 -241.55805) (xy 390.646822 -241.54787) (xy 390.599236 -241.529823)
			(xy 390.555162 -241.504377) (xy 390.51574 -241.47219) (xy 390.481992 -241.434096) (xy 390.454791 -241.391082)
			(xy 390.434843 -241.344262) (xy 390.422664 -241.294848) (xy 390.418569 -241.24412) (xy 390.100058 -241.24412)
			(xy 390.099563 -241.268727) (xy 390.091668 -241.317304) (xy 390.076084 -241.363985) (xy 390.053213 -241.407562)
			(xy 390.023648 -241.446906) (xy 389.988155 -241.480998) (xy 389.947652 -241.508954) (xy 389.90319 -241.530052)
			(xy 389.855919 -241.543744) (xy 389.807064 -241.549676) (xy 389.757889 -241.547695) (xy 389.70967 -241.537851)
			(xy 389.663654 -241.520399) (xy 389.621033 -241.495792) (xy 389.582912 -241.464667) (xy 389.550277 -241.42783)
			(xy 389.523974 -241.386234) (xy 389.504683 -241.340958) (xy 389.492906 -241.293174) (xy 389.488946 -241.24412)
			(xy 389.170672 -241.24412) (xy 389.17016 -241.269566) (xy 389.161996 -241.3198) (xy 389.14588 -241.368074)
			(xy 389.122229 -241.413137) (xy 389.091656 -241.453823) (xy 389.054952 -241.489078) (xy 389.013068 -241.517988)
			(xy 388.967089 -241.539805) (xy 388.918205 -241.553965) (xy 388.867684 -241.560099) (xy 388.816832 -241.55805)
			(xy 388.766968 -241.54787) (xy 388.719382 -241.529823) (xy 388.675308 -241.504377) (xy 388.635886 -241.47219)
			(xy 388.602138 -241.434096) (xy 388.574937 -241.391082) (xy 388.554989 -241.344262) (xy 388.54281 -241.294848)
			(xy 388.538715 -241.24412) (xy 388.220204 -241.24412) (xy 388.219709 -241.268727) (xy 388.211814 -241.317304)
			(xy 388.19623 -241.363985) (xy 388.173359 -241.407562) (xy 388.143794 -241.446906) (xy 388.108301 -241.480998)
			(xy 388.067798 -241.508954) (xy 388.023336 -241.530052) (xy 387.976065 -241.543744) (xy 387.92721 -241.549676)
			(xy 387.878035 -241.547695) (xy 387.829816 -241.537851) (xy 387.7838 -241.520399) (xy 387.741179 -241.495792)
			(xy 387.703058 -241.464667) (xy 387.670423 -241.42783) (xy 387.64412 -241.386234) (xy 387.624829 -241.340958)
			(xy 387.613052 -241.293174) (xy 387.609092 -241.24412) (xy 387.290564 -241.24412) (xy 387.290052 -241.269566)
			(xy 387.281888 -241.3198) (xy 387.265772 -241.368074) (xy 387.242121 -241.413137) (xy 387.211548 -241.453823)
			(xy 387.174844 -241.489078) (xy 387.13296 -241.517988) (xy 387.086981 -241.539805) (xy 387.038097 -241.553965)
			(xy 386.987576 -241.560099) (xy 386.936724 -241.55805) (xy 386.88686 -241.54787) (xy 386.839274 -241.529823)
			(xy 386.7952 -241.504377) (xy 386.755778 -241.47219) (xy 386.72203 -241.434096) (xy 386.694829 -241.391082)
			(xy 386.674881 -241.344262) (xy 386.662702 -241.294848) (xy 386.658607 -241.24412) (xy 386.35051 -241.24412)
			(xy 386.349998 -241.269566) (xy 386.341834 -241.3198) (xy 386.325718 -241.368074) (xy 386.302067 -241.413137)
			(xy 386.271494 -241.453823) (xy 386.23479 -241.489078) (xy 386.192906 -241.517988) (xy 386.146927 -241.539805)
			(xy 386.098043 -241.553965) (xy 386.047522 -241.560099) (xy 385.99667 -241.55805) (xy 385.946806 -241.54787)
			(xy 385.89922 -241.529823) (xy 385.855146 -241.504377) (xy 385.815724 -241.47219) (xy 385.781976 -241.434096)
			(xy 385.754775 -241.391082) (xy 385.734827 -241.344262) (xy 385.722648 -241.294848) (xy 385.718553 -241.24412)
			(xy 385.400042 -241.24412) (xy 385.399547 -241.268727) (xy 385.391652 -241.317304) (xy 385.376068 -241.363985)
			(xy 385.353197 -241.407562) (xy 385.323632 -241.446906) (xy 385.288139 -241.480998) (xy 385.247636 -241.508954)
			(xy 385.203174 -241.530052) (xy 385.155903 -241.543744) (xy 385.107048 -241.549676) (xy 385.057873 -241.547695)
			(xy 385.009654 -241.537851) (xy 384.963638 -241.520399) (xy 384.921017 -241.495792) (xy 384.882896 -241.464667)
			(xy 384.850261 -241.42783) (xy 384.823958 -241.386234) (xy 384.804667 -241.340958) (xy 384.79289 -241.293174)
			(xy 384.78893 -241.24412) (xy 384.470656 -241.24412) (xy 384.470144 -241.269566) (xy 384.46198 -241.3198)
			(xy 384.445864 -241.368074) (xy 384.422213 -241.413137) (xy 384.39164 -241.453823) (xy 384.354936 -241.489078)
			(xy 384.313052 -241.517988) (xy 384.267073 -241.539805) (xy 384.218189 -241.553965) (xy 384.167668 -241.560099)
			(xy 384.116816 -241.55805) (xy 384.066952 -241.54787) (xy 384.019366 -241.529823) (xy 383.975292 -241.504377)
			(xy 383.93587 -241.47219) (xy 383.902122 -241.434096) (xy 383.874921 -241.391082) (xy 383.854973 -241.344262)
			(xy 383.842794 -241.294848) (xy 383.838699 -241.24412) (xy 383.520188 -241.24412) (xy 383.519693 -241.268727)
			(xy 383.511798 -241.317304) (xy 383.496214 -241.363985) (xy 383.473343 -241.407562) (xy 383.443778 -241.446906)
			(xy 383.408285 -241.480998) (xy 383.367782 -241.508954) (xy 383.32332 -241.530052) (xy 383.276049 -241.543744)
			(xy 383.227194 -241.549676) (xy 383.178019 -241.547695) (xy 383.1298 -241.537851) (xy 383.083784 -241.520399)
			(xy 383.041163 -241.495792) (xy 383.003042 -241.464667) (xy 382.970407 -241.42783) (xy 382.944104 -241.386234)
			(xy 382.924813 -241.340958) (xy 382.913036 -241.293174) (xy 382.909076 -241.24412) (xy 382.590548 -241.24412)
			(xy 382.590036 -241.269566) (xy 382.581872 -241.3198) (xy 382.565756 -241.368074) (xy 382.542105 -241.413137)
			(xy 382.511532 -241.453823) (xy 382.474828 -241.489078) (xy 382.432944 -241.517988) (xy 382.386965 -241.539805)
			(xy 382.338081 -241.553965) (xy 382.28756 -241.560099) (xy 382.236708 -241.55805) (xy 382.186844 -241.54787)
			(xy 382.139258 -241.529823) (xy 382.095184 -241.504377) (xy 382.055762 -241.47219) (xy 382.022014 -241.434096)
			(xy 381.994813 -241.391082) (xy 381.974865 -241.344262) (xy 381.962686 -241.294848) (xy 381.958591 -241.24412)
			(xy 381.64008 -241.24412) (xy 381.639585 -241.268727) (xy 381.63169 -241.317304) (xy 381.616106 -241.363985)
			(xy 381.593235 -241.407562) (xy 381.56367 -241.446906) (xy 381.528177 -241.480998) (xy 381.487674 -241.508954)
			(xy 381.443212 -241.530052) (xy 381.395941 -241.543744) (xy 381.347086 -241.549676) (xy 381.297911 -241.547695)
			(xy 381.249692 -241.537851) (xy 381.203676 -241.520399) (xy 381.161055 -241.495792) (xy 381.122934 -241.464667)
			(xy 381.090299 -241.42783) (xy 381.063996 -241.386234) (xy 381.044705 -241.340958) (xy 381.032928 -241.293174)
			(xy 381.028968 -241.24412) (xy 380.71044 -241.24412) (xy 380.709928 -241.269566) (xy 380.701764 -241.3198)
			(xy 380.685648 -241.368074) (xy 380.661997 -241.413137) (xy 380.631424 -241.453823) (xy 380.59472 -241.489078)
			(xy 380.552836 -241.517988) (xy 380.506857 -241.539805) (xy 380.457973 -241.553965) (xy 380.407452 -241.560099)
			(xy 380.3566 -241.55805) (xy 380.306736 -241.54787) (xy 380.25915 -241.529823) (xy 380.215076 -241.504377)
			(xy 380.175654 -241.47219) (xy 380.141906 -241.434096) (xy 380.114705 -241.391082) (xy 380.094757 -241.344262)
			(xy 380.082578 -241.294848) (xy 380.078483 -241.24412) (xy 379.77064 -241.24412) (xy 379.770128 -241.269566)
			(xy 379.761964 -241.3198) (xy 379.745848 -241.368074) (xy 379.722197 -241.413137) (xy 379.691624 -241.453823)
			(xy 379.65492 -241.489078) (xy 379.613036 -241.517988) (xy 379.567057 -241.539805) (xy 379.518173 -241.553965)
			(xy 379.467652 -241.560099) (xy 379.4168 -241.55805) (xy 379.366936 -241.54787) (xy 379.31935 -241.529823)
			(xy 379.275276 -241.504377) (xy 379.235854 -241.47219) (xy 379.202106 -241.434096) (xy 379.174905 -241.391082)
			(xy 379.154957 -241.344262) (xy 379.142778 -241.294848) (xy 379.138683 -241.24412) (xy 378.820172 -241.24412)
			(xy 378.819677 -241.268727) (xy 378.811782 -241.317304) (xy 378.796198 -241.363985) (xy 378.773327 -241.407562)
			(xy 378.743762 -241.446906) (xy 378.708269 -241.480998) (xy 378.667766 -241.508954) (xy 378.623304 -241.530052)
			(xy 378.576033 -241.543744) (xy 378.527178 -241.549676) (xy 378.478003 -241.547695) (xy 378.429784 -241.537851)
			(xy 378.383768 -241.520399) (xy 378.341147 -241.495792) (xy 378.303026 -241.464667) (xy 378.270391 -241.42783)
			(xy 378.244088 -241.386234) (xy 378.224797 -241.340958) (xy 378.21302 -241.293174) (xy 378.20906 -241.24412)
			(xy 377.890532 -241.24412) (xy 377.89002 -241.269566) (xy 377.881856 -241.3198) (xy 377.86574 -241.368074)
			(xy 377.842089 -241.413137) (xy 377.811516 -241.453823) (xy 377.774812 -241.489078) (xy 377.732928 -241.517988)
			(xy 377.686949 -241.539805) (xy 377.638065 -241.553965) (xy 377.587544 -241.560099) (xy 377.536692 -241.55805)
			(xy 377.486828 -241.54787) (xy 377.439242 -241.529823) (xy 377.395168 -241.504377) (xy 377.355746 -241.47219)
			(xy 377.321998 -241.434096) (xy 377.294797 -241.391082) (xy 377.274849 -241.344262) (xy 377.26267 -241.294848)
			(xy 377.258575 -241.24412) (xy 376.940064 -241.24412) (xy 376.939569 -241.268727) (xy 376.931674 -241.317304)
			(xy 376.91609 -241.363985) (xy 376.893219 -241.407562) (xy 376.863654 -241.446906) (xy 376.828161 -241.480998)
			(xy 376.787658 -241.508954) (xy 376.743196 -241.530052) (xy 376.695925 -241.543744) (xy 376.64707 -241.549676)
			(xy 376.597895 -241.547695) (xy 376.549676 -241.537851) (xy 376.50366 -241.520399) (xy 376.461039 -241.495792)
			(xy 376.422918 -241.464667) (xy 376.390283 -241.42783) (xy 376.36398 -241.386234) (xy 376.344689 -241.340958)
			(xy 376.332912 -241.293174) (xy 376.328952 -241.24412) (xy 376.010424 -241.24412) (xy 376.009912 -241.269566)
			(xy 376.001748 -241.3198) (xy 375.985632 -241.368074) (xy 375.961981 -241.413137) (xy 375.931408 -241.453823)
			(xy 375.894704 -241.489078) (xy 375.85282 -241.517988) (xy 375.806841 -241.539805) (xy 375.757957 -241.553965)
			(xy 375.707436 -241.560099) (xy 375.656584 -241.55805) (xy 375.60672 -241.54787) (xy 375.559134 -241.529823)
			(xy 375.51506 -241.504377) (xy 375.475638 -241.47219) (xy 375.44189 -241.434096) (xy 375.414689 -241.391082)
			(xy 375.394741 -241.344262) (xy 375.382562 -241.294848) (xy 375.378467 -241.24412) (xy 375.05968 -241.24412)
			(xy 375.059679 -241.268399) (xy 375.051993 -241.316353) (xy 375.036819 -241.362488) (xy 375.014538 -241.405641)
			(xy 375.00052 -241.425476) (xy 374.995948 -241.431826) (xy 374.988074 -241.454686) (xy 374.986791 -241.458693)
			(xy 374.985388 -241.46699) (xy 374.98528 -241.471196) (xy 374.98528 -241.671348) (xy 374.98528 -241.67465)
			(xy 374.986471 -241.685395) (xy 374.99661 -241.704466) (xy 375.004838 -241.71148) (xy 375.00687 -241.713004)
			(xy 375.074688 -241.760756) (xy 375.085127 -241.767202) (xy 375.109414 -241.77037) (xy 375.12117 -241.766852)
			(xy 375.121932 -241.766598) (xy 375.12879 -241.764312) (xy 375.152133 -241.757087) (xy 375.200371 -241.749307)
			(xy 375.224802 -241.748818) (xy 375.250055 -241.74934) (xy 375.299872 -241.757653) (xy 375.347642 -241.774053)
			(xy 375.392061 -241.798091) (xy 375.431917 -241.829113) (xy 375.466124 -241.866271) (xy 375.493748 -241.908553)
			(xy 375.514036 -241.954806) (xy 375.526434 -242.003766) (xy 375.530605 -242.0541) (xy 375.530603 -242.054126)
			(xy 375.848621 -242.054126) (xy 375.852716 -242.003398) (xy 375.864895 -241.953984) (xy 375.884843 -241.907164)
			(xy 375.912044 -241.86415) (xy 375.945792 -241.826056) (xy 375.985214 -241.793869) (xy 376.029288 -241.768423)
			(xy 376.076874 -241.750376) (xy 376.126738 -241.740196) (xy 376.17759 -241.738147) (xy 376.228111 -241.744281)
			(xy 376.276995 -241.758441) (xy 376.322974 -241.780258) (xy 376.364858 -241.809168) (xy 376.401562 -241.844423)
			(xy 376.432135 -241.885109) (xy 376.455786 -241.930172) (xy 376.471902 -241.978446) (xy 376.480066 -242.02868)
			(xy 376.480578 -242.054126) (xy 376.788675 -242.054126) (xy 376.79277 -242.003398) (xy 376.804949 -241.953984)
			(xy 376.824897 -241.907164) (xy 376.852098 -241.86415) (xy 376.885846 -241.826056) (xy 376.925268 -241.793869)
			(xy 376.969342 -241.768423) (xy 377.016928 -241.750376) (xy 377.066792 -241.740196) (xy 377.117644 -241.738147)
			(xy 377.168165 -241.744281) (xy 377.217049 -241.758441) (xy 377.263028 -241.780258) (xy 377.304912 -241.809168)
			(xy 377.341616 -241.844423) (xy 377.372189 -241.885109) (xy 377.39584 -241.930172) (xy 377.411956 -241.978446)
			(xy 377.42012 -242.02868) (xy 377.420632 -242.054126) (xy 378.668529 -242.054126) (xy 378.672624 -242.003398)
			(xy 378.684803 -241.953984) (xy 378.704751 -241.907164) (xy 378.731952 -241.86415) (xy 378.7657 -241.826056)
			(xy 378.805122 -241.793869) (xy 378.849196 -241.768423) (xy 378.896782 -241.750376) (xy 378.946646 -241.740196)
			(xy 378.997498 -241.738147) (xy 379.048019 -241.744281) (xy 379.096903 -241.758441) (xy 379.142882 -241.780258)
			(xy 379.184766 -241.809168) (xy 379.22147 -241.844423) (xy 379.252043 -241.885109) (xy 379.275694 -241.930172)
			(xy 379.29181 -241.978446) (xy 379.299974 -242.02868) (xy 379.300486 -242.054126) (xy 379.619014 -242.054126)
			(xy 379.622974 -242.005072) (xy 379.634751 -241.957288) (xy 379.654042 -241.912012) (xy 379.680345 -241.870416)
			(xy 379.71298 -241.833579) (xy 379.751101 -241.802454) (xy 379.793722 -241.777847) (xy 379.839738 -241.760395)
			(xy 379.887957 -241.750551) (xy 379.937132 -241.74857) (xy 379.985987 -241.754502) (xy 380.033258 -241.768194)
			(xy 380.07772 -241.789292) (xy 380.118223 -241.817248) (xy 380.153716 -241.85134) (xy 380.183281 -241.890684)
			(xy 380.206152 -241.934261) (xy 380.221736 -241.980942) (xy 380.229631 -242.029519) (xy 380.230126 -242.054126)
			(xy 380.548637 -242.054126) (xy 380.552732 -242.003398) (xy 380.564911 -241.953984) (xy 380.584859 -241.907164)
			(xy 380.61206 -241.86415) (xy 380.645808 -241.826056) (xy 380.68523 -241.793869) (xy 380.729304 -241.768423)
			(xy 380.77689 -241.750376) (xy 380.826754 -241.740196) (xy 380.877606 -241.738147) (xy 380.928127 -241.744281)
			(xy 380.977011 -241.758441) (xy 381.02299 -241.780258) (xy 381.064874 -241.809168) (xy 381.101578 -241.844423)
			(xy 381.132151 -241.885109) (xy 381.155802 -241.930172) (xy 381.171918 -241.978446) (xy 381.180082 -242.02868)
			(xy 381.180594 -242.054126) (xy 381.499122 -242.054126) (xy 381.503082 -242.005072) (xy 381.514859 -241.957288)
			(xy 381.53415 -241.912012) (xy 381.560453 -241.870416) (xy 381.593088 -241.833579) (xy 381.631209 -241.802454)
			(xy 381.67383 -241.777847) (xy 381.719846 -241.760395) (xy 381.768065 -241.750551) (xy 381.81724 -241.74857)
			(xy 381.866095 -241.754502) (xy 381.913366 -241.768194) (xy 381.957828 -241.789292) (xy 381.998331 -241.817248)
			(xy 382.033824 -241.85134) (xy 382.063389 -241.890684) (xy 382.08626 -241.934261) (xy 382.101844 -241.980942)
			(xy 382.109739 -242.029519) (xy 382.110234 -242.054126) (xy 382.428491 -242.054126) (xy 382.432586 -242.003398)
			(xy 382.444765 -241.953984) (xy 382.464713 -241.907164) (xy 382.491914 -241.86415) (xy 382.525662 -241.826056)
			(xy 382.565084 -241.793869) (xy 382.609158 -241.768423) (xy 382.656744 -241.750376) (xy 382.706608 -241.740196)
			(xy 382.75746 -241.738147) (xy 382.807981 -241.744281) (xy 382.856865 -241.758441) (xy 382.902844 -241.780258)
			(xy 382.944728 -241.809168) (xy 382.981432 -241.844423) (xy 383.012005 -241.885109) (xy 383.035656 -241.930172)
			(xy 383.051772 -241.978446) (xy 383.059936 -242.02868) (xy 383.060448 -242.054126) (xy 383.368545 -242.054126)
			(xy 383.37264 -242.003398) (xy 383.384819 -241.953984) (xy 383.404767 -241.907164) (xy 383.431968 -241.86415)
			(xy 383.465716 -241.826056) (xy 383.505138 -241.793869) (xy 383.549212 -241.768423) (xy 383.596798 -241.750376)
			(xy 383.646662 -241.740196) (xy 383.697514 -241.738147) (xy 383.748035 -241.744281) (xy 383.796919 -241.758441)
			(xy 383.842898 -241.780258) (xy 383.884782 -241.809168) (xy 383.921486 -241.844423) (xy 383.952059 -241.885109)
			(xy 383.97571 -241.930172) (xy 383.991826 -241.978446) (xy 383.99999 -242.02868) (xy 384.000502 -242.054126)
			(xy 385.248653 -242.054126) (xy 385.252748 -242.003398) (xy 385.264927 -241.953984) (xy 385.284875 -241.907164)
			(xy 385.312076 -241.86415) (xy 385.345824 -241.826056) (xy 385.385246 -241.793869) (xy 385.42932 -241.768423)
			(xy 385.476906 -241.750376) (xy 385.52677 -241.740196) (xy 385.577622 -241.738147) (xy 385.628143 -241.744281)
			(xy 385.677027 -241.758441) (xy 385.723006 -241.780258) (xy 385.76489 -241.809168) (xy 385.801594 -241.844423)
			(xy 385.832167 -241.885109) (xy 385.855818 -241.930172) (xy 385.871934 -241.978446) (xy 385.880098 -242.02868)
			(xy 385.88061 -242.054126) (xy 386.199138 -242.054126) (xy 386.203098 -242.005072) (xy 386.214875 -241.957288)
			(xy 386.234166 -241.912012) (xy 386.260469 -241.870416) (xy 386.293104 -241.833579) (xy 386.331225 -241.802454)
			(xy 386.373846 -241.777847) (xy 386.419862 -241.760395) (xy 386.468081 -241.750551) (xy 386.517256 -241.74857)
			(xy 386.566111 -241.754502) (xy 386.613382 -241.768194) (xy 386.657844 -241.789292) (xy 386.698347 -241.817248)
			(xy 386.73384 -241.85134) (xy 386.763405 -241.890684) (xy 386.786276 -241.934261) (xy 386.80186 -241.980942)
			(xy 386.809755 -242.029519) (xy 386.81025 -242.054126) (xy 387.128507 -242.054126) (xy 387.132602 -242.003398)
			(xy 387.144781 -241.953984) (xy 387.164729 -241.907164) (xy 387.19193 -241.86415) (xy 387.225678 -241.826056)
			(xy 387.2651 -241.793869) (xy 387.309174 -241.768423) (xy 387.35676 -241.750376) (xy 387.406624 -241.740196)
			(xy 387.457476 -241.738147) (xy 387.507997 -241.744281) (xy 387.556881 -241.758441) (xy 387.60286 -241.780258)
			(xy 387.644744 -241.809168) (xy 387.681448 -241.844423) (xy 387.712021 -241.885109) (xy 387.735672 -241.930172)
			(xy 387.751788 -241.978446) (xy 387.759952 -242.02868) (xy 387.760464 -242.054126) (xy 388.078992 -242.054126)
			(xy 388.082952 -242.005072) (xy 388.094729 -241.957288) (xy 388.11402 -241.912012) (xy 388.140323 -241.870416)
			(xy 388.172958 -241.833579) (xy 388.211079 -241.802454) (xy 388.2537 -241.777847) (xy 388.299716 -241.760395)
			(xy 388.347935 -241.750551) (xy 388.39711 -241.74857) (xy 388.445965 -241.754502) (xy 388.493236 -241.768194)
			(xy 388.537698 -241.789292) (xy 388.578201 -241.817248) (xy 388.613694 -241.85134) (xy 388.643259 -241.890684)
			(xy 388.66613 -241.934261) (xy 388.681714 -241.980942) (xy 388.689609 -242.029519) (xy 388.690104 -242.054126)
			(xy 389.008615 -242.054126) (xy 389.01271 -242.003398) (xy 389.024889 -241.953984) (xy 389.044837 -241.907164)
			(xy 389.072038 -241.86415) (xy 389.105786 -241.826056) (xy 389.145208 -241.793869) (xy 389.189282 -241.768423)
			(xy 389.236868 -241.750376) (xy 389.286732 -241.740196) (xy 389.337584 -241.738147) (xy 389.388105 -241.744281)
			(xy 389.436989 -241.758441) (xy 389.482968 -241.780258) (xy 389.524852 -241.809168) (xy 389.561556 -241.844423)
			(xy 389.592129 -241.885109) (xy 389.61578 -241.930172) (xy 389.631896 -241.978446) (xy 389.64006 -242.02868)
			(xy 389.640572 -242.054126) (xy 389.948669 -242.054126) (xy 389.952764 -242.003398) (xy 389.964943 -241.953984)
			(xy 389.984891 -241.907164) (xy 390.012092 -241.86415) (xy 390.04584 -241.826056) (xy 390.085262 -241.793869)
			(xy 390.129336 -241.768423) (xy 390.176922 -241.750376) (xy 390.226786 -241.740196) (xy 390.277638 -241.738147)
			(xy 390.328159 -241.744281) (xy 390.377043 -241.758441) (xy 390.423022 -241.780258) (xy 390.464906 -241.809168)
			(xy 390.50161 -241.844423) (xy 390.532183 -241.885109) (xy 390.555834 -241.930172) (xy 390.57195 -241.978446)
			(xy 390.580114 -242.02868) (xy 390.580626 -242.054126) (xy 392.779008 -242.054126) (xy 392.782968 -242.005072)
			(xy 392.794745 -241.957288) (xy 392.814036 -241.912012) (xy 392.840339 -241.870416) (xy 392.872974 -241.833579)
			(xy 392.911095 -241.802454) (xy 392.953716 -241.777847) (xy 392.999732 -241.760395) (xy 393.047951 -241.750551)
			(xy 393.097126 -241.74857) (xy 393.145981 -241.754502) (xy 393.193252 -241.768194) (xy 393.237714 -241.789292)
			(xy 393.278217 -241.817248) (xy 393.31371 -241.85134) (xy 393.343275 -241.890684) (xy 393.366146 -241.934261)
			(xy 393.38173 -241.980942) (xy 393.389625 -242.029519) (xy 393.39012 -242.054126) (xy 393.389625 -242.078733)
			(xy 393.38173 -242.12731) (xy 393.366146 -242.173991) (xy 393.343275 -242.217568) (xy 393.31371 -242.256912)
			(xy 393.278217 -242.291004) (xy 393.237714 -242.31896) (xy 393.193252 -242.340058) (xy 393.145981 -242.35375)
			(xy 393.097126 -242.359682) (xy 393.047951 -242.357701) (xy 392.999732 -242.347857) (xy 392.953716 -242.330405)
			(xy 392.911095 -242.305798) (xy 392.872974 -242.274673) (xy 392.840339 -242.237836) (xy 392.814036 -242.19624)
			(xy 392.794745 -242.150964) (xy 392.782968 -242.10318) (xy 392.779008 -242.054126) (xy 390.580626 -242.054126)
			(xy 390.580114 -242.079572) (xy 390.57195 -242.129806) (xy 390.555834 -242.17808) (xy 390.532183 -242.223143)
			(xy 390.50161 -242.263829) (xy 390.464906 -242.299084) (xy 390.423022 -242.327994) (xy 390.377043 -242.349811)
			(xy 390.328159 -242.363971) (xy 390.277638 -242.370105) (xy 390.226786 -242.368056) (xy 390.176922 -242.357876)
			(xy 390.129336 -242.339829) (xy 390.085262 -242.314383) (xy 390.04584 -242.282196) (xy 390.012092 -242.244102)
			(xy 389.984891 -242.201088) (xy 389.964943 -242.154268) (xy 389.952764 -242.104854) (xy 389.948669 -242.054126)
			(xy 389.640572 -242.054126) (xy 389.64006 -242.079572) (xy 389.631896 -242.129806) (xy 389.61578 -242.17808)
			(xy 389.592129 -242.223143) (xy 389.561556 -242.263829) (xy 389.524852 -242.299084) (xy 389.482968 -242.327994)
			(xy 389.436989 -242.349811) (xy 389.388105 -242.363971) (xy 389.337584 -242.370105) (xy 389.286732 -242.368056)
			(xy 389.236868 -242.357876) (xy 389.189282 -242.339829) (xy 389.145208 -242.314383) (xy 389.105786 -242.282196)
			(xy 389.072038 -242.244102) (xy 389.044837 -242.201088) (xy 389.024889 -242.154268) (xy 389.01271 -242.104854)
			(xy 389.008615 -242.054126) (xy 388.690104 -242.054126) (xy 388.689609 -242.078733) (xy 388.681714 -242.12731)
			(xy 388.66613 -242.173991) (xy 388.643259 -242.217568) (xy 388.613694 -242.256912) (xy 388.578201 -242.291004)
			(xy 388.537698 -242.31896) (xy 388.493236 -242.340058) (xy 388.445965 -242.35375) (xy 388.39711 -242.359682)
			(xy 388.347935 -242.357701) (xy 388.299716 -242.347857) (xy 388.2537 -242.330405) (xy 388.211079 -242.305798)
			(xy 388.172958 -242.274673) (xy 388.140323 -242.237836) (xy 388.11402 -242.19624) (xy 388.094729 -242.150964)
			(xy 388.082952 -242.10318) (xy 388.078992 -242.054126) (xy 387.760464 -242.054126) (xy 387.759952 -242.079572)
			(xy 387.751788 -242.129806) (xy 387.735672 -242.17808) (xy 387.712021 -242.223143) (xy 387.681448 -242.263829)
			(xy 387.644744 -242.299084) (xy 387.60286 -242.327994) (xy 387.556881 -242.349811) (xy 387.507997 -242.363971)
			(xy 387.457476 -242.370105) (xy 387.406624 -242.368056) (xy 387.35676 -242.357876) (xy 387.309174 -242.339829)
			(xy 387.2651 -242.314383) (xy 387.225678 -242.282196) (xy 387.19193 -242.244102) (xy 387.164729 -242.201088)
			(xy 387.144781 -242.154268) (xy 387.132602 -242.104854) (xy 387.128507 -242.054126) (xy 386.81025 -242.054126)
			(xy 386.809755 -242.078733) (xy 386.80186 -242.12731) (xy 386.786276 -242.173991) (xy 386.763405 -242.217568)
			(xy 386.73384 -242.256912) (xy 386.698347 -242.291004) (xy 386.657844 -242.31896) (xy 386.613382 -242.340058)
			(xy 386.566111 -242.35375) (xy 386.517256 -242.359682) (xy 386.468081 -242.357701) (xy 386.419862 -242.347857)
			(xy 386.373846 -242.330405) (xy 386.331225 -242.305798) (xy 386.293104 -242.274673) (xy 386.260469 -242.237836)
			(xy 386.234166 -242.19624) (xy 386.214875 -242.150964) (xy 386.203098 -242.10318) (xy 386.199138 -242.054126)
			(xy 385.88061 -242.054126) (xy 385.880098 -242.079572) (xy 385.871934 -242.129806) (xy 385.855818 -242.17808)
			(xy 385.832167 -242.223143) (xy 385.801594 -242.263829) (xy 385.76489 -242.299084) (xy 385.723006 -242.327994)
			(xy 385.677027 -242.349811) (xy 385.628143 -242.363971) (xy 385.577622 -242.370105) (xy 385.52677 -242.368056)
			(xy 385.476906 -242.357876) (xy 385.42932 -242.339829) (xy 385.385246 -242.314383) (xy 385.345824 -242.282196)
			(xy 385.312076 -242.244102) (xy 385.284875 -242.201088) (xy 385.264927 -242.154268) (xy 385.252748 -242.104854)
			(xy 385.248653 -242.054126) (xy 384.000502 -242.054126) (xy 383.99999 -242.079572) (xy 383.991826 -242.129806)
			(xy 383.97571 -242.17808) (xy 383.952059 -242.223143) (xy 383.921486 -242.263829) (xy 383.884782 -242.299084)
			(xy 383.842898 -242.327994) (xy 383.796919 -242.349811) (xy 383.748035 -242.363971) (xy 383.697514 -242.370105)
			(xy 383.646662 -242.368056) (xy 383.596798 -242.357876) (xy 383.549212 -242.339829) (xy 383.505138 -242.314383)
			(xy 383.465716 -242.282196) (xy 383.431968 -242.244102) (xy 383.404767 -242.201088) (xy 383.384819 -242.154268)
			(xy 383.37264 -242.104854) (xy 383.368545 -242.054126) (xy 383.060448 -242.054126) (xy 383.059936 -242.079572)
			(xy 383.051772 -242.129806) (xy 383.035656 -242.17808) (xy 383.012005 -242.223143) (xy 382.981432 -242.263829)
			(xy 382.944728 -242.299084) (xy 382.902844 -242.327994) (xy 382.856865 -242.349811) (xy 382.807981 -242.363971)
			(xy 382.75746 -242.370105) (xy 382.706608 -242.368056) (xy 382.656744 -242.357876) (xy 382.609158 -242.339829)
			(xy 382.565084 -242.314383) (xy 382.525662 -242.282196) (xy 382.491914 -242.244102) (xy 382.464713 -242.201088)
			(xy 382.444765 -242.154268) (xy 382.432586 -242.104854) (xy 382.428491 -242.054126) (xy 382.110234 -242.054126)
			(xy 382.109739 -242.078733) (xy 382.101844 -242.12731) (xy 382.08626 -242.173991) (xy 382.063389 -242.217568)
			(xy 382.033824 -242.256912) (xy 381.998331 -242.291004) (xy 381.957828 -242.31896) (xy 381.913366 -242.340058)
			(xy 381.866095 -242.35375) (xy 381.81724 -242.359682) (xy 381.768065 -242.357701) (xy 381.719846 -242.347857)
			(xy 381.67383 -242.330405) (xy 381.631209 -242.305798) (xy 381.593088 -242.274673) (xy 381.560453 -242.237836)
			(xy 381.53415 -242.19624) (xy 381.514859 -242.150964) (xy 381.503082 -242.10318) (xy 381.499122 -242.054126)
			(xy 381.180594 -242.054126) (xy 381.180082 -242.079572) (xy 381.171918 -242.129806) (xy 381.155802 -242.17808)
			(xy 381.132151 -242.223143) (xy 381.101578 -242.263829) (xy 381.064874 -242.299084) (xy 381.02299 -242.327994)
			(xy 380.977011 -242.349811) (xy 380.928127 -242.363971) (xy 380.877606 -242.370105) (xy 380.826754 -242.368056)
			(xy 380.77689 -242.357876) (xy 380.729304 -242.339829) (xy 380.68523 -242.314383) (xy 380.645808 -242.282196)
			(xy 380.61206 -242.244102) (xy 380.584859 -242.201088) (xy 380.564911 -242.154268) (xy 380.552732 -242.104854)
			(xy 380.548637 -242.054126) (xy 380.230126 -242.054126) (xy 380.229631 -242.078733) (xy 380.221736 -242.12731)
			(xy 380.206152 -242.173991) (xy 380.183281 -242.217568) (xy 380.153716 -242.256912) (xy 380.118223 -242.291004)
			(xy 380.07772 -242.31896) (xy 380.033258 -242.340058) (xy 379.985987 -242.35375) (xy 379.937132 -242.359682)
			(xy 379.887957 -242.357701) (xy 379.839738 -242.347857) (xy 379.793722 -242.330405) (xy 379.751101 -242.305798)
			(xy 379.71298 -242.274673) (xy 379.680345 -242.237836) (xy 379.654042 -242.19624) (xy 379.634751 -242.150964)
			(xy 379.622974 -242.10318) (xy 379.619014 -242.054126) (xy 379.300486 -242.054126) (xy 379.299974 -242.079572)
			(xy 379.29181 -242.129806) (xy 379.275694 -242.17808) (xy 379.252043 -242.223143) (xy 379.22147 -242.263829)
			(xy 379.184766 -242.299084) (xy 379.142882 -242.327994) (xy 379.096903 -242.349811) (xy 379.048019 -242.363971)
			(xy 378.997498 -242.370105) (xy 378.946646 -242.368056) (xy 378.896782 -242.357876) (xy 378.849196 -242.339829)
			(xy 378.805122 -242.314383) (xy 378.7657 -242.282196) (xy 378.731952 -242.244102) (xy 378.704751 -242.201088)
			(xy 378.684803 -242.154268) (xy 378.672624 -242.104854) (xy 378.668529 -242.054126) (xy 377.420632 -242.054126)
			(xy 377.42012 -242.079572) (xy 377.411956 -242.129806) (xy 377.39584 -242.17808) (xy 377.372189 -242.223143)
			(xy 377.341616 -242.263829) (xy 377.304912 -242.299084) (xy 377.263028 -242.327994) (xy 377.217049 -242.349811)
			(xy 377.168165 -242.363971) (xy 377.117644 -242.370105) (xy 377.066792 -242.368056) (xy 377.016928 -242.357876)
			(xy 376.969342 -242.339829) (xy 376.925268 -242.314383) (xy 376.885846 -242.282196) (xy 376.852098 -242.244102)
			(xy 376.824897 -242.201088) (xy 376.804949 -242.154268) (xy 376.79277 -242.104854) (xy 376.788675 -242.054126)
			(xy 376.480578 -242.054126) (xy 376.480066 -242.079572) (xy 376.471902 -242.129806) (xy 376.455786 -242.17808)
			(xy 376.432135 -242.223143) (xy 376.401562 -242.263829) (xy 376.364858 -242.299084) (xy 376.322974 -242.327994)
			(xy 376.276995 -242.349811) (xy 376.228111 -242.363971) (xy 376.17759 -242.370105) (xy 376.126738 -242.368056)
			(xy 376.076874 -242.357876) (xy 376.029288 -242.339829) (xy 375.985214 -242.314383) (xy 375.945792 -242.282196)
			(xy 375.912044 -242.244102) (xy 375.884843 -242.201088) (xy 375.864895 -242.154268) (xy 375.852716 -242.104854)
			(xy 375.848621 -242.054126) (xy 375.530603 -242.054126) (xy 375.526434 -242.104434) (xy 375.514036 -242.153394)
			(xy 375.493748 -242.199647) (xy 375.466124 -242.241929) (xy 375.431917 -242.279087) (xy 375.392061 -242.310109)
			(xy 375.347642 -242.334147) (xy 375.299872 -242.350547) (xy 375.250055 -242.35886) (xy 375.224802 -242.359434)
			(xy 375.200371 -242.358953) (xy 375.152133 -242.351166) (xy 375.12879 -242.34394) (xy 375.121932 -242.341654)
			(xy 375.12117 -242.3414) (xy 375.109419 -242.337927) (xy 375.085161 -242.34113) (xy 375.074688 -242.347496)
			(xy 375.00687 -242.395248) (xy 375.004838 -242.396772) (xy 374.99662 -242.403792) (xy 374.986489 -242.422862)
			(xy 374.98528 -242.433602) (xy 374.98528 -242.637056) (xy 374.985352 -242.641266) (xy 374.986752 -242.649569)
			(xy 374.988074 -242.653566) (xy 374.995948 -242.676426) (xy 375.00052 -242.682776) (xy 375.014554 -242.702598)
			(xy 375.036829 -242.745753) (xy 375.051996 -242.791889) (xy 375.059675 -242.839843) (xy 375.059673 -242.864132)
			(xy 375.378467 -242.864132) (xy 375.382562 -242.813404) (xy 375.394741 -242.76399) (xy 375.414689 -242.71717)
			(xy 375.44189 -242.674156) (xy 375.475638 -242.636062) (xy 375.51506 -242.603875) (xy 375.559134 -242.578429)
			(xy 375.60672 -242.560382) (xy 375.656584 -242.550202) (xy 375.707436 -242.548153) (xy 375.757957 -242.554287)
			(xy 375.806841 -242.568447) (xy 375.85282 -242.590264) (xy 375.894704 -242.619174) (xy 375.931408 -242.654429)
			(xy 375.961981 -242.695115) (xy 375.985632 -242.740178) (xy 376.001748 -242.788452) (xy 376.009912 -242.838686)
			(xy 376.010424 -242.864132) (xy 376.328952 -242.864132) (xy 376.332912 -242.815078) (xy 376.344689 -242.767294)
			(xy 376.36398 -242.722018) (xy 376.390283 -242.680422) (xy 376.422918 -242.643585) (xy 376.461039 -242.61246)
			(xy 376.50366 -242.587853) (xy 376.549676 -242.570401) (xy 376.597895 -242.560557) (xy 376.64707 -242.558576)
			(xy 376.695925 -242.564508) (xy 376.743196 -242.5782) (xy 376.787658 -242.599298) (xy 376.828161 -242.627254)
			(xy 376.863654 -242.661346) (xy 376.893219 -242.70069) (xy 376.91609 -242.744267) (xy 376.931674 -242.790948)
			(xy 376.939569 -242.839525) (xy 376.940064 -242.864132) (xy 377.258575 -242.864132) (xy 377.26267 -242.813404)
			(xy 377.274849 -242.76399) (xy 377.294797 -242.71717) (xy 377.321998 -242.674156) (xy 377.355746 -242.636062)
			(xy 377.395168 -242.603875) (xy 377.439242 -242.578429) (xy 377.486828 -242.560382) (xy 377.536692 -242.550202)
			(xy 377.587544 -242.548153) (xy 377.638065 -242.554287) (xy 377.686949 -242.568447) (xy 377.732928 -242.590264)
			(xy 377.774812 -242.619174) (xy 377.811516 -242.654429) (xy 377.842089 -242.695115) (xy 377.86574 -242.740178)
			(xy 377.881856 -242.788452) (xy 377.89002 -242.838686) (xy 377.890532 -242.864132) (xy 378.20906 -242.864132)
			(xy 378.21302 -242.815078) (xy 378.224797 -242.767294) (xy 378.244088 -242.722018) (xy 378.270391 -242.680422)
			(xy 378.303026 -242.643585) (xy 378.341147 -242.61246) (xy 378.383768 -242.587853) (xy 378.429784 -242.570401)
			(xy 378.478003 -242.560557) (xy 378.527178 -242.558576) (xy 378.576033 -242.564508) (xy 378.623304 -242.5782)
			(xy 378.667766 -242.599298) (xy 378.708269 -242.627254) (xy 378.743762 -242.661346) (xy 378.773327 -242.70069)
			(xy 378.796198 -242.744267) (xy 378.811782 -242.790948) (xy 378.819677 -242.839525) (xy 378.820172 -242.864132)
			(xy 379.138683 -242.864132) (xy 379.142778 -242.813404) (xy 379.154957 -242.76399) (xy 379.174905 -242.71717)
			(xy 379.202106 -242.674156) (xy 379.235854 -242.636062) (xy 379.275276 -242.603875) (xy 379.31935 -242.578429)
			(xy 379.366936 -242.560382) (xy 379.4168 -242.550202) (xy 379.467652 -242.548153) (xy 379.518173 -242.554287)
			(xy 379.567057 -242.568447) (xy 379.613036 -242.590264) (xy 379.65492 -242.619174) (xy 379.691624 -242.654429)
			(xy 379.722197 -242.695115) (xy 379.745848 -242.740178) (xy 379.761964 -242.788452) (xy 379.770128 -242.838686)
			(xy 379.77064 -242.864132) (xy 380.078483 -242.864132) (xy 380.082578 -242.813404) (xy 380.094757 -242.76399)
			(xy 380.114705 -242.71717) (xy 380.141906 -242.674156) (xy 380.175654 -242.636062) (xy 380.215076 -242.603875)
			(xy 380.25915 -242.578429) (xy 380.306736 -242.560382) (xy 380.3566 -242.550202) (xy 380.407452 -242.548153)
			(xy 380.457973 -242.554287) (xy 380.506857 -242.568447) (xy 380.552836 -242.590264) (xy 380.59472 -242.619174)
			(xy 380.631424 -242.654429) (xy 380.661997 -242.695115) (xy 380.685648 -242.740178) (xy 380.701764 -242.788452)
			(xy 380.709928 -242.838686) (xy 380.71044 -242.864132) (xy 381.028968 -242.864132) (xy 381.032928 -242.815078)
			(xy 381.044705 -242.767294) (xy 381.063996 -242.722018) (xy 381.090299 -242.680422) (xy 381.122934 -242.643585)
			(xy 381.161055 -242.61246) (xy 381.203676 -242.587853) (xy 381.249692 -242.570401) (xy 381.297911 -242.560557)
			(xy 381.347086 -242.558576) (xy 381.395941 -242.564508) (xy 381.443212 -242.5782) (xy 381.487674 -242.599298)
			(xy 381.528177 -242.627254) (xy 381.56367 -242.661346) (xy 381.593235 -242.70069) (xy 381.616106 -242.744267)
			(xy 381.63169 -242.790948) (xy 381.639585 -242.839525) (xy 381.64008 -242.864132) (xy 381.958591 -242.864132)
			(xy 381.962686 -242.813404) (xy 381.974865 -242.76399) (xy 381.994813 -242.71717) (xy 382.022014 -242.674156)
			(xy 382.055762 -242.636062) (xy 382.095184 -242.603875) (xy 382.139258 -242.578429) (xy 382.186844 -242.560382)
			(xy 382.236708 -242.550202) (xy 382.28756 -242.548153) (xy 382.338081 -242.554287) (xy 382.386965 -242.568447)
			(xy 382.432944 -242.590264) (xy 382.474828 -242.619174) (xy 382.511532 -242.654429) (xy 382.542105 -242.695115)
			(xy 382.565756 -242.740178) (xy 382.581872 -242.788452) (xy 382.590036 -242.838686) (xy 382.590548 -242.864132)
			(xy 382.909076 -242.864132) (xy 382.913036 -242.815078) (xy 382.924813 -242.767294) (xy 382.944104 -242.722018)
			(xy 382.970407 -242.680422) (xy 383.003042 -242.643585) (xy 383.041163 -242.61246) (xy 383.083784 -242.587853)
			(xy 383.1298 -242.570401) (xy 383.178019 -242.560557) (xy 383.227194 -242.558576) (xy 383.276049 -242.564508)
			(xy 383.32332 -242.5782) (xy 383.367782 -242.599298) (xy 383.408285 -242.627254) (xy 383.443778 -242.661346)
			(xy 383.473343 -242.70069) (xy 383.496214 -242.744267) (xy 383.511798 -242.790948) (xy 383.519693 -242.839525)
			(xy 383.520188 -242.864132) (xy 383.838699 -242.864132) (xy 383.842794 -242.813404) (xy 383.854973 -242.76399)
			(xy 383.874921 -242.71717) (xy 383.902122 -242.674156) (xy 383.93587 -242.636062) (xy 383.975292 -242.603875)
			(xy 384.019366 -242.578429) (xy 384.066952 -242.560382) (xy 384.116816 -242.550202) (xy 384.167668 -242.548153)
			(xy 384.218189 -242.554287) (xy 384.267073 -242.568447) (xy 384.313052 -242.590264) (xy 384.354936 -242.619174)
			(xy 384.39164 -242.654429) (xy 384.422213 -242.695115) (xy 384.445864 -242.740178) (xy 384.46198 -242.788452)
			(xy 384.470144 -242.838686) (xy 384.470656 -242.864132) (xy 384.78893 -242.864132) (xy 384.79289 -242.815078)
			(xy 384.804667 -242.767294) (xy 384.823958 -242.722018) (xy 384.850261 -242.680422) (xy 384.882896 -242.643585)
			(xy 384.921017 -242.61246) (xy 384.963638 -242.587853) (xy 385.009654 -242.570401) (xy 385.057873 -242.560557)
			(xy 385.107048 -242.558576) (xy 385.155903 -242.564508) (xy 385.203174 -242.5782) (xy 385.247636 -242.599298)
			(xy 385.288139 -242.627254) (xy 385.323632 -242.661346) (xy 385.353197 -242.70069) (xy 385.376068 -242.744267)
			(xy 385.391652 -242.790948) (xy 385.399547 -242.839525) (xy 385.400042 -242.864132) (xy 385.718553 -242.864132)
			(xy 385.722648 -242.813404) (xy 385.734827 -242.76399) (xy 385.754775 -242.71717) (xy 385.781976 -242.674156)
			(xy 385.815724 -242.636062) (xy 385.855146 -242.603875) (xy 385.89922 -242.578429) (xy 385.946806 -242.560382)
			(xy 385.99667 -242.550202) (xy 386.047522 -242.548153) (xy 386.098043 -242.554287) (xy 386.146927 -242.568447)
			(xy 386.192906 -242.590264) (xy 386.23479 -242.619174) (xy 386.271494 -242.654429) (xy 386.302067 -242.695115)
			(xy 386.325718 -242.740178) (xy 386.341834 -242.788452) (xy 386.349998 -242.838686) (xy 386.35051 -242.864132)
			(xy 386.658607 -242.864132) (xy 386.662702 -242.813404) (xy 386.674881 -242.76399) (xy 386.694829 -242.71717)
			(xy 386.72203 -242.674156) (xy 386.755778 -242.636062) (xy 386.7952 -242.603875) (xy 386.839274 -242.578429)
			(xy 386.88686 -242.560382) (xy 386.936724 -242.550202) (xy 386.987576 -242.548153) (xy 387.038097 -242.554287)
			(xy 387.086981 -242.568447) (xy 387.13296 -242.590264) (xy 387.174844 -242.619174) (xy 387.211548 -242.654429)
			(xy 387.242121 -242.695115) (xy 387.265772 -242.740178) (xy 387.281888 -242.788452) (xy 387.290052 -242.838686)
			(xy 387.290564 -242.864132) (xy 387.609092 -242.864132) (xy 387.613052 -242.815078) (xy 387.624829 -242.767294)
			(xy 387.64412 -242.722018) (xy 387.670423 -242.680422) (xy 387.703058 -242.643585) (xy 387.741179 -242.61246)
			(xy 387.7838 -242.587853) (xy 387.829816 -242.570401) (xy 387.878035 -242.560557) (xy 387.92721 -242.558576)
			(xy 387.976065 -242.564508) (xy 388.023336 -242.5782) (xy 388.067798 -242.599298) (xy 388.108301 -242.627254)
			(xy 388.143794 -242.661346) (xy 388.173359 -242.70069) (xy 388.19623 -242.744267) (xy 388.211814 -242.790948)
			(xy 388.219709 -242.839525) (xy 388.220204 -242.864132) (xy 388.538715 -242.864132) (xy 388.54281 -242.813404)
			(xy 388.554989 -242.76399) (xy 388.574937 -242.71717) (xy 388.602138 -242.674156) (xy 388.635886 -242.636062)
			(xy 388.675308 -242.603875) (xy 388.719382 -242.578429) (xy 388.766968 -242.560382) (xy 388.816832 -242.550202)
			(xy 388.867684 -242.548153) (xy 388.918205 -242.554287) (xy 388.967089 -242.568447) (xy 389.013068 -242.590264)
			(xy 389.054952 -242.619174) (xy 389.091656 -242.654429) (xy 389.122229 -242.695115) (xy 389.14588 -242.740178)
			(xy 389.161996 -242.788452) (xy 389.17016 -242.838686) (xy 389.170672 -242.864132) (xy 389.488946 -242.864132)
			(xy 389.492906 -242.815078) (xy 389.504683 -242.767294) (xy 389.523974 -242.722018) (xy 389.550277 -242.680422)
			(xy 389.582912 -242.643585) (xy 389.621033 -242.61246) (xy 389.663654 -242.587853) (xy 389.70967 -242.570401)
			(xy 389.757889 -242.560557) (xy 389.807064 -242.558576) (xy 389.855919 -242.564508) (xy 389.90319 -242.5782)
			(xy 389.947652 -242.599298) (xy 389.988155 -242.627254) (xy 390.023648 -242.661346) (xy 390.053213 -242.70069)
			(xy 390.076084 -242.744267) (xy 390.091668 -242.790948) (xy 390.099563 -242.839525) (xy 390.100058 -242.864132)
			(xy 390.418569 -242.864132) (xy 390.422664 -242.813404) (xy 390.434843 -242.76399) (xy 390.454791 -242.71717)
			(xy 390.481992 -242.674156) (xy 390.51574 -242.636062) (xy 390.555162 -242.603875) (xy 390.599236 -242.578429)
			(xy 390.646822 -242.560382) (xy 390.696686 -242.550202) (xy 390.747538 -242.548153) (xy 390.798059 -242.554287)
			(xy 390.846943 -242.568447) (xy 390.892922 -242.590264) (xy 390.934806 -242.619174) (xy 390.97151 -242.654429)
			(xy 391.002083 -242.695115) (xy 391.025734 -242.740178) (xy 391.04185 -242.788452) (xy 391.050014 -242.838686)
			(xy 391.050526 -242.864132) (xy 391.369054 -242.864132) (xy 391.373014 -242.815078) (xy 391.384791 -242.767294)
			(xy 391.404082 -242.722018) (xy 391.430385 -242.680422) (xy 391.46302 -242.643585) (xy 391.501141 -242.61246)
			(xy 391.543762 -242.587853) (xy 391.589778 -242.570401) (xy 391.637997 -242.560557) (xy 391.687172 -242.558576)
			(xy 391.736027 -242.564508) (xy 391.783298 -242.5782) (xy 391.82776 -242.599298) (xy 391.868263 -242.627254)
			(xy 391.903756 -242.661346) (xy 391.933321 -242.70069) (xy 391.956192 -242.744267) (xy 391.971776 -242.790948)
			(xy 391.979671 -242.839525) (xy 391.980166 -242.864132) (xy 391.979671 -242.888739) (xy 391.971776 -242.937316)
			(xy 391.956192 -242.983997) (xy 391.933321 -243.027574) (xy 391.903756 -243.066918) (xy 391.868263 -243.10101)
			(xy 391.82776 -243.128966) (xy 391.825433 -243.13007) (xy 394.377176 -243.13007) (xy 394.381136 -243.081016)
			(xy 394.392913 -243.033232) (xy 394.412204 -242.987956) (xy 394.438507 -242.94636) (xy 394.471142 -242.909523)
			(xy 394.509263 -242.878398) (xy 394.551884 -242.853791) (xy 394.5979 -242.836339) (xy 394.646119 -242.826495)
			(xy 394.695294 -242.824514) (xy 394.744149 -242.830446) (xy 394.79142 -242.844138) (xy 394.835882 -242.865236)
			(xy 394.876385 -242.893192) (xy 394.911878 -242.927284) (xy 394.941443 -242.966628) (xy 394.964314 -243.010205)
			(xy 394.979898 -243.056886) (xy 394.987793 -243.105463) (xy 394.988288 -243.13007) (xy 394.987793 -243.154677)
			(xy 394.979898 -243.203254) (xy 394.964314 -243.249935) (xy 394.941443 -243.293512) (xy 394.911878 -243.332856)
			(xy 394.876385 -243.366948) (xy 394.835882 -243.394904) (xy 394.79142 -243.416002) (xy 394.744149 -243.429694)
			(xy 394.695294 -243.435626) (xy 394.646119 -243.433645) (xy 394.5979 -243.423801) (xy 394.551884 -243.406349)
			(xy 394.509263 -243.381742) (xy 394.471142 -243.350617) (xy 394.438507 -243.31378) (xy 394.412204 -243.272184)
			(xy 394.392913 -243.226908) (xy 394.381136 -243.179124) (xy 394.377176 -243.13007) (xy 391.825433 -243.13007)
			(xy 391.783298 -243.150064) (xy 391.736027 -243.163756) (xy 391.687172 -243.169688) (xy 391.637997 -243.167707)
			(xy 391.589778 -243.157863) (xy 391.543762 -243.140411) (xy 391.501141 -243.115804) (xy 391.46302 -243.084679)
			(xy 391.430385 -243.047842) (xy 391.404082 -243.006246) (xy 391.384791 -242.96097) (xy 391.373014 -242.913186)
			(xy 391.369054 -242.864132) (xy 391.050526 -242.864132) (xy 391.050014 -242.889578) (xy 391.04185 -242.939812)
			(xy 391.025734 -242.988086) (xy 391.002083 -243.033149) (xy 390.97151 -243.073835) (xy 390.934806 -243.10909)
			(xy 390.892922 -243.138) (xy 390.846943 -243.159817) (xy 390.798059 -243.173977) (xy 390.747538 -243.180111)
			(xy 390.696686 -243.178062) (xy 390.646822 -243.167882) (xy 390.599236 -243.149835) (xy 390.555162 -243.124389)
			(xy 390.51574 -243.092202) (xy 390.481992 -243.054108) (xy 390.454791 -243.011094) (xy 390.434843 -242.964274)
			(xy 390.422664 -242.91486) (xy 390.418569 -242.864132) (xy 390.100058 -242.864132) (xy 390.099563 -242.888739)
			(xy 390.091668 -242.937316) (xy 390.076084 -242.983997) (xy 390.053213 -243.027574) (xy 390.023648 -243.066918)
			(xy 389.988155 -243.10101) (xy 389.947652 -243.128966) (xy 389.90319 -243.150064) (xy 389.855919 -243.163756)
			(xy 389.807064 -243.169688) (xy 389.757889 -243.167707) (xy 389.70967 -243.157863) (xy 389.663654 -243.140411)
			(xy 389.621033 -243.115804) (xy 389.582912 -243.084679) (xy 389.550277 -243.047842) (xy 389.523974 -243.006246)
			(xy 389.504683 -242.96097) (xy 389.492906 -242.913186) (xy 389.488946 -242.864132) (xy 389.170672 -242.864132)
			(xy 389.17016 -242.889578) (xy 389.161996 -242.939812) (xy 389.14588 -242.988086) (xy 389.122229 -243.033149)
			(xy 389.091656 -243.073835) (xy 389.054952 -243.10909) (xy 389.013068 -243.138) (xy 388.967089 -243.159817)
			(xy 388.918205 -243.173977) (xy 388.867684 -243.180111) (xy 388.816832 -243.178062) (xy 388.766968 -243.167882)
			(xy 388.719382 -243.149835) (xy 388.675308 -243.124389) (xy 388.635886 -243.092202) (xy 388.602138 -243.054108)
			(xy 388.574937 -243.011094) (xy 388.554989 -242.964274) (xy 388.54281 -242.91486) (xy 388.538715 -242.864132)
			(xy 388.220204 -242.864132) (xy 388.219709 -242.888739) (xy 388.211814 -242.937316) (xy 388.19623 -242.983997)
			(xy 388.173359 -243.027574) (xy 388.143794 -243.066918) (xy 388.108301 -243.10101) (xy 388.067798 -243.128966)
			(xy 388.023336 -243.150064) (xy 387.976065 -243.163756) (xy 387.92721 -243.169688) (xy 387.878035 -243.167707)
			(xy 387.829816 -243.157863) (xy 387.7838 -243.140411) (xy 387.741179 -243.115804) (xy 387.703058 -243.084679)
			(xy 387.670423 -243.047842) (xy 387.64412 -243.006246) (xy 387.624829 -242.96097) (xy 387.613052 -242.913186)
			(xy 387.609092 -242.864132) (xy 387.290564 -242.864132) (xy 387.290052 -242.889578) (xy 387.281888 -242.939812)
			(xy 387.265772 -242.988086) (xy 387.242121 -243.033149) (xy 387.211548 -243.073835) (xy 387.174844 -243.10909)
			(xy 387.13296 -243.138) (xy 387.086981 -243.159817) (xy 387.038097 -243.173977) (xy 386.987576 -243.180111)
			(xy 386.936724 -243.178062) (xy 386.88686 -243.167882) (xy 386.839274 -243.149835) (xy 386.7952 -243.124389)
			(xy 386.755778 -243.092202) (xy 386.72203 -243.054108) (xy 386.694829 -243.011094) (xy 386.674881 -242.964274)
			(xy 386.662702 -242.91486) (xy 386.658607 -242.864132) (xy 386.35051 -242.864132) (xy 386.349998 -242.889578)
			(xy 386.341834 -242.939812) (xy 386.325718 -242.988086) (xy 386.302067 -243.033149) (xy 386.271494 -243.073835)
			(xy 386.23479 -243.10909) (xy 386.192906 -243.138) (xy 386.146927 -243.159817) (xy 386.098043 -243.173977)
			(xy 386.047522 -243.180111) (xy 385.99667 -243.178062) (xy 385.946806 -243.167882) (xy 385.89922 -243.149835)
			(xy 385.855146 -243.124389) (xy 385.815724 -243.092202) (xy 385.781976 -243.054108) (xy 385.754775 -243.011094)
			(xy 385.734827 -242.964274) (xy 385.722648 -242.91486) (xy 385.718553 -242.864132) (xy 385.400042 -242.864132)
			(xy 385.399547 -242.888739) (xy 385.391652 -242.937316) (xy 385.376068 -242.983997) (xy 385.353197 -243.027574)
			(xy 385.323632 -243.066918) (xy 385.288139 -243.10101) (xy 385.247636 -243.128966) (xy 385.203174 -243.150064)
			(xy 385.155903 -243.163756) (xy 385.107048 -243.169688) (xy 385.057873 -243.167707) (xy 385.009654 -243.157863)
			(xy 384.963638 -243.140411) (xy 384.921017 -243.115804) (xy 384.882896 -243.084679) (xy 384.850261 -243.047842)
			(xy 384.823958 -243.006246) (xy 384.804667 -242.96097) (xy 384.79289 -242.913186) (xy 384.78893 -242.864132)
			(xy 384.470656 -242.864132) (xy 384.470144 -242.889578) (xy 384.46198 -242.939812) (xy 384.445864 -242.988086)
			(xy 384.422213 -243.033149) (xy 384.39164 -243.073835) (xy 384.354936 -243.10909) (xy 384.313052 -243.138)
			(xy 384.267073 -243.159817) (xy 384.218189 -243.173977) (xy 384.167668 -243.180111) (xy 384.116816 -243.178062)
			(xy 384.066952 -243.167882) (xy 384.019366 -243.149835) (xy 383.975292 -243.124389) (xy 383.93587 -243.092202)
			(xy 383.902122 -243.054108) (xy 383.874921 -243.011094) (xy 383.854973 -242.964274) (xy 383.842794 -242.91486)
			(xy 383.838699 -242.864132) (xy 383.520188 -242.864132) (xy 383.519693 -242.888739) (xy 383.511798 -242.937316)
			(xy 383.496214 -242.983997) (xy 383.473343 -243.027574) (xy 383.443778 -243.066918) (xy 383.408285 -243.10101)
			(xy 383.367782 -243.128966) (xy 383.32332 -243.150064) (xy 383.276049 -243.163756) (xy 383.227194 -243.169688)
			(xy 383.178019 -243.167707) (xy 383.1298 -243.157863) (xy 383.083784 -243.140411) (xy 383.041163 -243.115804)
			(xy 383.003042 -243.084679) (xy 382.970407 -243.047842) (xy 382.944104 -243.006246) (xy 382.924813 -242.96097)
			(xy 382.913036 -242.913186) (xy 382.909076 -242.864132) (xy 382.590548 -242.864132) (xy 382.590036 -242.889578)
			(xy 382.581872 -242.939812) (xy 382.565756 -242.988086) (xy 382.542105 -243.033149) (xy 382.511532 -243.073835)
			(xy 382.474828 -243.10909) (xy 382.432944 -243.138) (xy 382.386965 -243.159817) (xy 382.338081 -243.173977)
			(xy 382.28756 -243.180111) (xy 382.236708 -243.178062) (xy 382.186844 -243.167882) (xy 382.139258 -243.149835)
			(xy 382.095184 -243.124389) (xy 382.055762 -243.092202) (xy 382.022014 -243.054108) (xy 381.994813 -243.011094)
			(xy 381.974865 -242.964274) (xy 381.962686 -242.91486) (xy 381.958591 -242.864132) (xy 381.64008 -242.864132)
			(xy 381.639585 -242.888739) (xy 381.63169 -242.937316) (xy 381.616106 -242.983997) (xy 381.593235 -243.027574)
			(xy 381.56367 -243.066918) (xy 381.528177 -243.10101) (xy 381.487674 -243.128966) (xy 381.443212 -243.150064)
			(xy 381.395941 -243.163756) (xy 381.347086 -243.169688) (xy 381.297911 -243.167707) (xy 381.249692 -243.157863)
			(xy 381.203676 -243.140411) (xy 381.161055 -243.115804) (xy 381.122934 -243.084679) (xy 381.090299 -243.047842)
			(xy 381.063996 -243.006246) (xy 381.044705 -242.96097) (xy 381.032928 -242.913186) (xy 381.028968 -242.864132)
			(xy 380.71044 -242.864132) (xy 380.709928 -242.889578) (xy 380.701764 -242.939812) (xy 380.685648 -242.988086)
			(xy 380.661997 -243.033149) (xy 380.631424 -243.073835) (xy 380.59472 -243.10909) (xy 380.552836 -243.138)
			(xy 380.506857 -243.159817) (xy 380.457973 -243.173977) (xy 380.407452 -243.180111) (xy 380.3566 -243.178062)
			(xy 380.306736 -243.167882) (xy 380.25915 -243.149835) (xy 380.215076 -243.124389) (xy 380.175654 -243.092202)
			(xy 380.141906 -243.054108) (xy 380.114705 -243.011094) (xy 380.094757 -242.964274) (xy 380.082578 -242.91486)
			(xy 380.078483 -242.864132) (xy 379.77064 -242.864132) (xy 379.770128 -242.889578) (xy 379.761964 -242.939812)
			(xy 379.745848 -242.988086) (xy 379.722197 -243.033149) (xy 379.691624 -243.073835) (xy 379.65492 -243.10909)
			(xy 379.613036 -243.138) (xy 379.567057 -243.159817) (xy 379.518173 -243.173977) (xy 379.467652 -243.180111)
			(xy 379.4168 -243.178062) (xy 379.366936 -243.167882) (xy 379.31935 -243.149835) (xy 379.275276 -243.124389)
			(xy 379.235854 -243.092202) (xy 379.202106 -243.054108) (xy 379.174905 -243.011094) (xy 379.154957 -242.964274)
			(xy 379.142778 -242.91486) (xy 379.138683 -242.864132) (xy 378.820172 -242.864132) (xy 378.819677 -242.888739)
			(xy 378.811782 -242.937316) (xy 378.796198 -242.983997) (xy 378.773327 -243.027574) (xy 378.743762 -243.066918)
			(xy 378.708269 -243.10101) (xy 378.667766 -243.128966) (xy 378.623304 -243.150064) (xy 378.576033 -243.163756)
			(xy 378.527178 -243.169688) (xy 378.478003 -243.167707) (xy 378.429784 -243.157863) (xy 378.383768 -243.140411)
			(xy 378.341147 -243.115804) (xy 378.303026 -243.084679) (xy 378.270391 -243.047842) (xy 378.244088 -243.006246)
			(xy 378.224797 -242.96097) (xy 378.21302 -242.913186) (xy 378.20906 -242.864132) (xy 377.890532 -242.864132)
			(xy 377.89002 -242.889578) (xy 377.881856 -242.939812) (xy 377.86574 -242.988086) (xy 377.842089 -243.033149)
			(xy 377.811516 -243.073835) (xy 377.774812 -243.10909) (xy 377.732928 -243.138) (xy 377.686949 -243.159817)
			(xy 377.638065 -243.173977) (xy 377.587544 -243.180111) (xy 377.536692 -243.178062) (xy 377.486828 -243.167882)
			(xy 377.439242 -243.149835) (xy 377.395168 -243.124389) (xy 377.355746 -243.092202) (xy 377.321998 -243.054108)
			(xy 377.294797 -243.011094) (xy 377.274849 -242.964274) (xy 377.26267 -242.91486) (xy 377.258575 -242.864132)
			(xy 376.940064 -242.864132) (xy 376.939569 -242.888739) (xy 376.931674 -242.937316) (xy 376.91609 -242.983997)
			(xy 376.893219 -243.027574) (xy 376.863654 -243.066918) (xy 376.828161 -243.10101) (xy 376.787658 -243.128966)
			(xy 376.743196 -243.150064) (xy 376.695925 -243.163756) (xy 376.64707 -243.169688) (xy 376.597895 -243.167707)
			(xy 376.549676 -243.157863) (xy 376.50366 -243.140411) (xy 376.461039 -243.115804) (xy 376.422918 -243.084679)
			(xy 376.390283 -243.047842) (xy 376.36398 -243.006246) (xy 376.344689 -242.96097) (xy 376.332912 -242.913186)
			(xy 376.328952 -242.864132) (xy 376.010424 -242.864132) (xy 376.009912 -242.889578) (xy 376.001748 -242.939812)
			(xy 375.985632 -242.988086) (xy 375.961981 -243.033149) (xy 375.931408 -243.073835) (xy 375.894704 -243.10909)
			(xy 375.85282 -243.138) (xy 375.806841 -243.159817) (xy 375.757957 -243.173977) (xy 375.707436 -243.180111)
			(xy 375.656584 -243.178062) (xy 375.60672 -243.167882) (xy 375.559134 -243.149835) (xy 375.51506 -243.124389)
			(xy 375.475638 -243.092202) (xy 375.44189 -243.054108) (xy 375.414689 -243.011094) (xy 375.394741 -242.964274)
			(xy 375.382562 -242.91486) (xy 375.378467 -242.864132) (xy 375.059673 -242.864132) (xy 375.059671 -242.888408)
			(xy 375.051984 -242.936361) (xy 375.036809 -242.982494) (xy 375.014527 -243.025646) (xy 375.00052 -243.045488)
			(xy 374.995948 -243.051838) (xy 374.988074 -243.074698) (xy 374.986792 -243.078706) (xy 374.985391 -243.087002)
			(xy 374.98528 -243.091208) (xy 374.98528 -243.674138) (xy 375.848621 -243.674138) (xy 375.852716 -243.62341)
			(xy 375.864895 -243.573996) (xy 375.884843 -243.527176) (xy 375.912044 -243.484162) (xy 375.945792 -243.446068)
			(xy 375.985214 -243.413881) (xy 376.029288 -243.388435) (xy 376.076874 -243.370388) (xy 376.126738 -243.360208)
			(xy 376.17759 -243.358159) (xy 376.228111 -243.364293) (xy 376.276995 -243.378453) (xy 376.322974 -243.40027)
			(xy 376.364858 -243.42918) (xy 376.401562 -243.464435) (xy 376.432135 -243.505121) (xy 376.455786 -243.550184)
			(xy 376.471902 -243.598458) (xy 376.480066 -243.648692) (xy 376.480578 -243.674138) (xy 376.788675 -243.674138)
			(xy 376.79277 -243.62341) (xy 376.804949 -243.573996) (xy 376.824897 -243.527176) (xy 376.852098 -243.484162)
			(xy 376.885846 -243.446068) (xy 376.925268 -243.413881) (xy 376.969342 -243.388435) (xy 377.016928 -243.370388)
			(xy 377.066792 -243.360208) (xy 377.117644 -243.358159) (xy 377.168165 -243.364293) (xy 377.217049 -243.378453)
			(xy 377.263028 -243.40027) (xy 377.304912 -243.42918) (xy 377.341616 -243.464435) (xy 377.372189 -243.505121)
			(xy 377.39584 -243.550184) (xy 377.411956 -243.598458) (xy 377.42012 -243.648692) (xy 377.420632 -243.674138)
			(xy 377.738906 -243.674138) (xy 377.742866 -243.625084) (xy 377.754643 -243.5773) (xy 377.773934 -243.532024)
			(xy 377.800237 -243.490428) (xy 377.832872 -243.453591) (xy 377.870993 -243.422466) (xy 377.913614 -243.397859)
			(xy 377.95963 -243.380407) (xy 378.007849 -243.370563) (xy 378.057024 -243.368582) (xy 378.105879 -243.374514)
			(xy 378.15315 -243.388206) (xy 378.197612 -243.409304) (xy 378.238115 -243.43726) (xy 378.273608 -243.471352)
			(xy 378.303173 -243.510696) (xy 378.326044 -243.554273) (xy 378.341628 -243.600954) (xy 378.349523 -243.649531)
			(xy 378.350018 -243.674138) (xy 378.668529 -243.674138) (xy 378.672624 -243.62341) (xy 378.684803 -243.573996)
			(xy 378.704751 -243.527176) (xy 378.731952 -243.484162) (xy 378.7657 -243.446068) (xy 378.805122 -243.413881)
			(xy 378.849196 -243.388435) (xy 378.896782 -243.370388) (xy 378.946646 -243.360208) (xy 378.997498 -243.358159)
			(xy 379.048019 -243.364293) (xy 379.096903 -243.378453) (xy 379.142882 -243.40027) (xy 379.184766 -243.42918)
			(xy 379.22147 -243.464435) (xy 379.252043 -243.505121) (xy 379.275694 -243.550184) (xy 379.29181 -243.598458)
			(xy 379.299974 -243.648692) (xy 379.300486 -243.674138) (xy 379.619014 -243.674138) (xy 379.622974 -243.625084)
			(xy 379.634751 -243.5773) (xy 379.654042 -243.532024) (xy 379.680345 -243.490428) (xy 379.71298 -243.453591)
			(xy 379.751101 -243.422466) (xy 379.793722 -243.397859) (xy 379.839738 -243.380407) (xy 379.887957 -243.370563)
			(xy 379.937132 -243.368582) (xy 379.985987 -243.374514) (xy 380.033258 -243.388206) (xy 380.07772 -243.409304)
			(xy 380.118223 -243.43726) (xy 380.153716 -243.471352) (xy 380.183281 -243.510696) (xy 380.206152 -243.554273)
			(xy 380.221736 -243.600954) (xy 380.229631 -243.649531) (xy 380.230126 -243.674138) (xy 380.548637 -243.674138)
			(xy 380.552732 -243.62341) (xy 380.564911 -243.573996) (xy 380.584859 -243.527176) (xy 380.61206 -243.484162)
			(xy 380.645808 -243.446068) (xy 380.68523 -243.413881) (xy 380.729304 -243.388435) (xy 380.77689 -243.370388)
			(xy 380.826754 -243.360208) (xy 380.877606 -243.358159) (xy 380.928127 -243.364293) (xy 380.977011 -243.378453)
			(xy 381.02299 -243.40027) (xy 381.064874 -243.42918) (xy 381.101578 -243.464435) (xy 381.132151 -243.505121)
			(xy 381.155802 -243.550184) (xy 381.171918 -243.598458) (xy 381.180082 -243.648692) (xy 381.180594 -243.674138)
			(xy 381.499122 -243.674138) (xy 381.503082 -243.625084) (xy 381.514859 -243.5773) (xy 381.53415 -243.532024)
			(xy 381.560453 -243.490428) (xy 381.593088 -243.453591) (xy 381.631209 -243.422466) (xy 381.67383 -243.397859)
			(xy 381.719846 -243.380407) (xy 381.768065 -243.370563) (xy 381.81724 -243.368582) (xy 381.866095 -243.374514)
			(xy 381.913366 -243.388206) (xy 381.957828 -243.409304) (xy 381.998331 -243.43726) (xy 382.033824 -243.471352)
			(xy 382.063389 -243.510696) (xy 382.08626 -243.554273) (xy 382.101844 -243.600954) (xy 382.109739 -243.649531)
			(xy 382.110234 -243.674138) (xy 382.428491 -243.674138) (xy 382.432586 -243.62341) (xy 382.444765 -243.573996)
			(xy 382.464713 -243.527176) (xy 382.491914 -243.484162) (xy 382.525662 -243.446068) (xy 382.565084 -243.413881)
			(xy 382.609158 -243.388435) (xy 382.656744 -243.370388) (xy 382.706608 -243.360208) (xy 382.75746 -243.358159)
			(xy 382.807981 -243.364293) (xy 382.856865 -243.378453) (xy 382.902844 -243.40027) (xy 382.944728 -243.42918)
			(xy 382.981432 -243.464435) (xy 383.012005 -243.505121) (xy 383.035656 -243.550184) (xy 383.051772 -243.598458)
			(xy 383.059936 -243.648692) (xy 383.060448 -243.674138) (xy 383.368545 -243.674138) (xy 383.37264 -243.62341)
			(xy 383.384819 -243.573996) (xy 383.404767 -243.527176) (xy 383.431968 -243.484162) (xy 383.465716 -243.446068)
			(xy 383.505138 -243.413881) (xy 383.549212 -243.388435) (xy 383.596798 -243.370388) (xy 383.646662 -243.360208)
			(xy 383.697514 -243.358159) (xy 383.748035 -243.364293) (xy 383.796919 -243.378453) (xy 383.842898 -243.40027)
			(xy 383.884782 -243.42918) (xy 383.921486 -243.464435) (xy 383.952059 -243.505121) (xy 383.97571 -243.550184)
			(xy 383.991826 -243.598458) (xy 383.99999 -243.648692) (xy 384.000502 -243.674138) (xy 384.31903 -243.674138)
			(xy 384.32299 -243.625084) (xy 384.334767 -243.5773) (xy 384.354058 -243.532024) (xy 384.380361 -243.490428)
			(xy 384.412996 -243.453591) (xy 384.451117 -243.422466) (xy 384.493738 -243.397859) (xy 384.539754 -243.380407)
			(xy 384.587973 -243.370563) (xy 384.637148 -243.368582) (xy 384.686003 -243.374514) (xy 384.733274 -243.388206)
			(xy 384.777736 -243.409304) (xy 384.818239 -243.43726) (xy 384.853732 -243.471352) (xy 384.883297 -243.510696)
			(xy 384.906168 -243.554273) (xy 384.921752 -243.600954) (xy 384.929647 -243.649531) (xy 384.930142 -243.674138)
			(xy 385.248653 -243.674138) (xy 385.252748 -243.62341) (xy 385.264927 -243.573996) (xy 385.284875 -243.527176)
			(xy 385.312076 -243.484162) (xy 385.345824 -243.446068) (xy 385.385246 -243.413881) (xy 385.42932 -243.388435)
			(xy 385.476906 -243.370388) (xy 385.52677 -243.360208) (xy 385.577622 -243.358159) (xy 385.628143 -243.364293)
			(xy 385.677027 -243.378453) (xy 385.723006 -243.40027) (xy 385.76489 -243.42918) (xy 385.801594 -243.464435)
			(xy 385.832167 -243.505121) (xy 385.855818 -243.550184) (xy 385.871934 -243.598458) (xy 385.880098 -243.648692)
			(xy 385.88061 -243.674138) (xy 386.199138 -243.674138) (xy 386.203098 -243.625084) (xy 386.214875 -243.5773)
			(xy 386.234166 -243.532024) (xy 386.260469 -243.490428) (xy 386.293104 -243.453591) (xy 386.331225 -243.422466)
			(xy 386.373846 -243.397859) (xy 386.419862 -243.380407) (xy 386.468081 -243.370563) (xy 386.517256 -243.368582)
			(xy 386.566111 -243.374514) (xy 386.613382 -243.388206) (xy 386.657844 -243.409304) (xy 386.698347 -243.43726)
			(xy 386.73384 -243.471352) (xy 386.763405 -243.510696) (xy 386.786276 -243.554273) (xy 386.80186 -243.600954)
			(xy 386.809755 -243.649531) (xy 386.81025 -243.674138) (xy 387.128507 -243.674138) (xy 387.132602 -243.62341)
			(xy 387.144781 -243.573996) (xy 387.164729 -243.527176) (xy 387.19193 -243.484162) (xy 387.225678 -243.446068)
			(xy 387.2651 -243.413881) (xy 387.309174 -243.388435) (xy 387.35676 -243.370388) (xy 387.406624 -243.360208)
			(xy 387.457476 -243.358159) (xy 387.507997 -243.364293) (xy 387.556881 -243.378453) (xy 387.60286 -243.40027)
			(xy 387.644744 -243.42918) (xy 387.681448 -243.464435) (xy 387.712021 -243.505121) (xy 387.735672 -243.550184)
			(xy 387.751788 -243.598458) (xy 387.759952 -243.648692) (xy 387.760464 -243.674138) (xy 388.078992 -243.674138)
			(xy 388.082952 -243.625084) (xy 388.094729 -243.5773) (xy 388.11402 -243.532024) (xy 388.140323 -243.490428)
			(xy 388.172958 -243.453591) (xy 388.211079 -243.422466) (xy 388.2537 -243.397859) (xy 388.299716 -243.380407)
			(xy 388.347935 -243.370563) (xy 388.39711 -243.368582) (xy 388.445965 -243.374514) (xy 388.493236 -243.388206)
			(xy 388.537698 -243.409304) (xy 388.578201 -243.43726) (xy 388.613694 -243.471352) (xy 388.643259 -243.510696)
			(xy 388.66613 -243.554273) (xy 388.681714 -243.600954) (xy 388.689609 -243.649531) (xy 388.690104 -243.674138)
			(xy 389.008615 -243.674138) (xy 389.01271 -243.62341) (xy 389.024889 -243.573996) (xy 389.044837 -243.527176)
			(xy 389.072038 -243.484162) (xy 389.105786 -243.446068) (xy 389.145208 -243.413881) (xy 389.189282 -243.388435)
			(xy 389.236868 -243.370388) (xy 389.286732 -243.360208) (xy 389.337584 -243.358159) (xy 389.388105 -243.364293)
			(xy 389.436989 -243.378453) (xy 389.482968 -243.40027) (xy 389.524852 -243.42918) (xy 389.561556 -243.464435)
			(xy 389.592129 -243.505121) (xy 389.61578 -243.550184) (xy 389.631896 -243.598458) (xy 389.64006 -243.648692)
			(xy 389.640572 -243.674138) (xy 389.948669 -243.674138) (xy 389.952764 -243.62341) (xy 389.964943 -243.573996)
			(xy 389.984891 -243.527176) (xy 390.012092 -243.484162) (xy 390.04584 -243.446068) (xy 390.085262 -243.413881)
			(xy 390.129336 -243.388435) (xy 390.176922 -243.370388) (xy 390.226786 -243.360208) (xy 390.277638 -243.358159)
			(xy 390.328159 -243.364293) (xy 390.377043 -243.378453) (xy 390.423022 -243.40027) (xy 390.464906 -243.42918)
			(xy 390.50161 -243.464435) (xy 390.532183 -243.505121) (xy 390.555834 -243.550184) (xy 390.57195 -243.598458)
			(xy 390.580114 -243.648692) (xy 390.580626 -243.674138) (xy 390.8989 -243.674138) (xy 390.90286 -243.625084)
			(xy 390.914637 -243.5773) (xy 390.933928 -243.532024) (xy 390.960231 -243.490428) (xy 390.992866 -243.453591)
			(xy 391.030987 -243.422466) (xy 391.073608 -243.397859) (xy 391.119624 -243.380407) (xy 391.167843 -243.370563)
			(xy 391.217018 -243.368582) (xy 391.265873 -243.374514) (xy 391.313144 -243.388206) (xy 391.357606 -243.409304)
			(xy 391.398109 -243.43726) (xy 391.433602 -243.471352) (xy 391.463167 -243.510696) (xy 391.486038 -243.554273)
			(xy 391.501622 -243.600954) (xy 391.509517 -243.649531) (xy 391.510012 -243.674138) (xy 392.779008 -243.674138)
			(xy 392.782968 -243.625084) (xy 392.794745 -243.5773) (xy 392.814036 -243.532024) (xy 392.840339 -243.490428)
			(xy 392.872974 -243.453591) (xy 392.911095 -243.422466) (xy 392.953716 -243.397859) (xy 392.999732 -243.380407)
			(xy 393.047951 -243.370563) (xy 393.097126 -243.368582) (xy 393.145981 -243.374514) (xy 393.193252 -243.388206)
			(xy 393.237714 -243.409304) (xy 393.278217 -243.43726) (xy 393.31371 -243.471352) (xy 393.343275 -243.510696)
			(xy 393.366146 -243.554273) (xy 393.38173 -243.600954) (xy 393.389625 -243.649531) (xy 393.39012 -243.674138)
			(xy 393.389625 -243.698745) (xy 393.38173 -243.747322) (xy 393.366146 -243.794003) (xy 393.343275 -243.83758)
			(xy 393.31371 -243.876924) (xy 393.278217 -243.911016) (xy 393.237714 -243.938972) (xy 393.193252 -243.96007)
			(xy 393.145981 -243.973762) (xy 393.097126 -243.979694) (xy 393.047951 -243.977713) (xy 392.999732 -243.967869)
			(xy 392.953716 -243.950417) (xy 392.911095 -243.92581) (xy 392.872974 -243.894685) (xy 392.840339 -243.857848)
			(xy 392.814036 -243.816252) (xy 392.794745 -243.770976) (xy 392.782968 -243.723192) (xy 392.779008 -243.674138)
			(xy 391.510012 -243.674138) (xy 391.509517 -243.698745) (xy 391.501622 -243.747322) (xy 391.486038 -243.794003)
			(xy 391.463167 -243.83758) (xy 391.433602 -243.876924) (xy 391.398109 -243.911016) (xy 391.357606 -243.938972)
			(xy 391.313144 -243.96007) (xy 391.265873 -243.973762) (xy 391.217018 -243.979694) (xy 391.167843 -243.977713)
			(xy 391.119624 -243.967869) (xy 391.073608 -243.950417) (xy 391.030987 -243.92581) (xy 390.992866 -243.894685)
			(xy 390.960231 -243.857848) (xy 390.933928 -243.816252) (xy 390.914637 -243.770976) (xy 390.90286 -243.723192)
			(xy 390.8989 -243.674138) (xy 390.580626 -243.674138) (xy 390.580114 -243.699584) (xy 390.57195 -243.749818)
			(xy 390.555834 -243.798092) (xy 390.532183 -243.843155) (xy 390.50161 -243.883841) (xy 390.464906 -243.919096)
			(xy 390.423022 -243.948006) (xy 390.377043 -243.969823) (xy 390.328159 -243.983983) (xy 390.277638 -243.990117)
			(xy 390.226786 -243.988068) (xy 390.176922 -243.977888) (xy 390.129336 -243.959841) (xy 390.085262 -243.934395)
			(xy 390.04584 -243.902208) (xy 390.012092 -243.864114) (xy 389.984891 -243.8211) (xy 389.964943 -243.77428)
			(xy 389.952764 -243.724866) (xy 389.948669 -243.674138) (xy 389.640572 -243.674138) (xy 389.64006 -243.699584)
			(xy 389.631896 -243.749818) (xy 389.61578 -243.798092) (xy 389.592129 -243.843155) (xy 389.561556 -243.883841)
			(xy 389.524852 -243.919096) (xy 389.482968 -243.948006) (xy 389.436989 -243.969823) (xy 389.388105 -243.983983)
			(xy 389.337584 -243.990117) (xy 389.286732 -243.988068) (xy 389.236868 -243.977888) (xy 389.189282 -243.959841)
			(xy 389.145208 -243.934395) (xy 389.105786 -243.902208) (xy 389.072038 -243.864114) (xy 389.044837 -243.8211)
			(xy 389.024889 -243.77428) (xy 389.01271 -243.724866) (xy 389.008615 -243.674138) (xy 388.690104 -243.674138)
			(xy 388.689609 -243.698745) (xy 388.681714 -243.747322) (xy 388.66613 -243.794003) (xy 388.643259 -243.83758)
			(xy 388.613694 -243.876924) (xy 388.578201 -243.911016) (xy 388.537698 -243.938972) (xy 388.493236 -243.96007)
			(xy 388.445965 -243.973762) (xy 388.39711 -243.979694) (xy 388.347935 -243.977713) (xy 388.299716 -243.967869)
			(xy 388.2537 -243.950417) (xy 388.211079 -243.92581) (xy 388.172958 -243.894685) (xy 388.140323 -243.857848)
			(xy 388.11402 -243.816252) (xy 388.094729 -243.770976) (xy 388.082952 -243.723192) (xy 388.078992 -243.674138)
			(xy 387.760464 -243.674138) (xy 387.759952 -243.699584) (xy 387.751788 -243.749818) (xy 387.735672 -243.798092)
			(xy 387.712021 -243.843155) (xy 387.681448 -243.883841) (xy 387.644744 -243.919096) (xy 387.60286 -243.948006)
			(xy 387.556881 -243.969823) (xy 387.507997 -243.983983) (xy 387.457476 -243.990117) (xy 387.406624 -243.988068)
			(xy 387.35676 -243.977888) (xy 387.309174 -243.959841) (xy 387.2651 -243.934395) (xy 387.225678 -243.902208)
			(xy 387.19193 -243.864114) (xy 387.164729 -243.8211) (xy 387.144781 -243.77428) (xy 387.132602 -243.724866)
			(xy 387.128507 -243.674138) (xy 386.81025 -243.674138) (xy 386.809755 -243.698745) (xy 386.80186 -243.747322)
			(xy 386.786276 -243.794003) (xy 386.763405 -243.83758) (xy 386.73384 -243.876924) (xy 386.698347 -243.911016)
			(xy 386.657844 -243.938972) (xy 386.613382 -243.96007) (xy 386.566111 -243.973762) (xy 386.517256 -243.979694)
			(xy 386.468081 -243.977713) (xy 386.419862 -243.967869) (xy 386.373846 -243.950417) (xy 386.331225 -243.92581)
			(xy 386.293104 -243.894685) (xy 386.260469 -243.857848) (xy 386.234166 -243.816252) (xy 386.214875 -243.770976)
			(xy 386.203098 -243.723192) (xy 386.199138 -243.674138) (xy 385.88061 -243.674138) (xy 385.880098 -243.699584)
			(xy 385.871934 -243.749818) (xy 385.855818 -243.798092) (xy 385.832167 -243.843155) (xy 385.801594 -243.883841)
			(xy 385.76489 -243.919096) (xy 385.723006 -243.948006) (xy 385.677027 -243.969823) (xy 385.628143 -243.983983)
			(xy 385.577622 -243.990117) (xy 385.52677 -243.988068) (xy 385.476906 -243.977888) (xy 385.42932 -243.959841)
			(xy 385.385246 -243.934395) (xy 385.345824 -243.902208) (xy 385.312076 -243.864114) (xy 385.284875 -243.8211)
			(xy 385.264927 -243.77428) (xy 385.252748 -243.724866) (xy 385.248653 -243.674138) (xy 384.930142 -243.674138)
			(xy 384.929647 -243.698745) (xy 384.921752 -243.747322) (xy 384.906168 -243.794003) (xy 384.883297 -243.83758)
			(xy 384.853732 -243.876924) (xy 384.818239 -243.911016) (xy 384.777736 -243.938972) (xy 384.733274 -243.96007)
			(xy 384.686003 -243.973762) (xy 384.637148 -243.979694) (xy 384.587973 -243.977713) (xy 384.539754 -243.967869)
			(xy 384.493738 -243.950417) (xy 384.451117 -243.92581) (xy 384.412996 -243.894685) (xy 384.380361 -243.857848)
			(xy 384.354058 -243.816252) (xy 384.334767 -243.770976) (xy 384.32299 -243.723192) (xy 384.31903 -243.674138)
			(xy 384.000502 -243.674138) (xy 383.99999 -243.699584) (xy 383.991826 -243.749818) (xy 383.97571 -243.798092)
			(xy 383.952059 -243.843155) (xy 383.921486 -243.883841) (xy 383.884782 -243.919096) (xy 383.842898 -243.948006)
			(xy 383.796919 -243.969823) (xy 383.748035 -243.983983) (xy 383.697514 -243.990117) (xy 383.646662 -243.988068)
			(xy 383.596798 -243.977888) (xy 383.549212 -243.959841) (xy 383.505138 -243.934395) (xy 383.465716 -243.902208)
			(xy 383.431968 -243.864114) (xy 383.404767 -243.8211) (xy 383.384819 -243.77428) (xy 383.37264 -243.724866)
			(xy 383.368545 -243.674138) (xy 383.060448 -243.674138) (xy 383.059936 -243.699584) (xy 383.051772 -243.749818)
			(xy 383.035656 -243.798092) (xy 383.012005 -243.843155) (xy 382.981432 -243.883841) (xy 382.944728 -243.919096)
			(xy 382.902844 -243.948006) (xy 382.856865 -243.969823) (xy 382.807981 -243.983983) (xy 382.75746 -243.990117)
			(xy 382.706608 -243.988068) (xy 382.656744 -243.977888) (xy 382.609158 -243.959841) (xy 382.565084 -243.934395)
			(xy 382.525662 -243.902208) (xy 382.491914 -243.864114) (xy 382.464713 -243.8211) (xy 382.444765 -243.77428)
			(xy 382.432586 -243.724866) (xy 382.428491 -243.674138) (xy 382.110234 -243.674138) (xy 382.109739 -243.698745)
			(xy 382.101844 -243.747322) (xy 382.08626 -243.794003) (xy 382.063389 -243.83758) (xy 382.033824 -243.876924)
			(xy 381.998331 -243.911016) (xy 381.957828 -243.938972) (xy 381.913366 -243.96007) (xy 381.866095 -243.973762)
			(xy 381.81724 -243.979694) (xy 381.768065 -243.977713) (xy 381.719846 -243.967869) (xy 381.67383 -243.950417)
			(xy 381.631209 -243.92581) (xy 381.593088 -243.894685) (xy 381.560453 -243.857848) (xy 381.53415 -243.816252)
			(xy 381.514859 -243.770976) (xy 381.503082 -243.723192) (xy 381.499122 -243.674138) (xy 381.180594 -243.674138)
			(xy 381.180082 -243.699584) (xy 381.171918 -243.749818) (xy 381.155802 -243.798092) (xy 381.132151 -243.843155)
			(xy 381.101578 -243.883841) (xy 381.064874 -243.919096) (xy 381.02299 -243.948006) (xy 380.977011 -243.969823)
			(xy 380.928127 -243.983983) (xy 380.877606 -243.990117) (xy 380.826754 -243.988068) (xy 380.77689 -243.977888)
			(xy 380.729304 -243.959841) (xy 380.68523 -243.934395) (xy 380.645808 -243.902208) (xy 380.61206 -243.864114)
			(xy 380.584859 -243.8211) (xy 380.564911 -243.77428) (xy 380.552732 -243.724866) (xy 380.548637 -243.674138)
			(xy 380.230126 -243.674138) (xy 380.229631 -243.698745) (xy 380.221736 -243.747322) (xy 380.206152 -243.794003)
			(xy 380.183281 -243.83758) (xy 380.153716 -243.876924) (xy 380.118223 -243.911016) (xy 380.07772 -243.938972)
			(xy 380.033258 -243.96007) (xy 379.985987 -243.973762) (xy 379.937132 -243.979694) (xy 379.887957 -243.977713)
			(xy 379.839738 -243.967869) (xy 379.793722 -243.950417) (xy 379.751101 -243.92581) (xy 379.71298 -243.894685)
			(xy 379.680345 -243.857848) (xy 379.654042 -243.816252) (xy 379.634751 -243.770976) (xy 379.622974 -243.723192)
			(xy 379.619014 -243.674138) (xy 379.300486 -243.674138) (xy 379.299974 -243.699584) (xy 379.29181 -243.749818)
			(xy 379.275694 -243.798092) (xy 379.252043 -243.843155) (xy 379.22147 -243.883841) (xy 379.184766 -243.919096)
			(xy 379.142882 -243.948006) (xy 379.096903 -243.969823) (xy 379.048019 -243.983983) (xy 378.997498 -243.990117)
			(xy 378.946646 -243.988068) (xy 378.896782 -243.977888) (xy 378.849196 -243.959841) (xy 378.805122 -243.934395)
			(xy 378.7657 -243.902208) (xy 378.731952 -243.864114) (xy 378.704751 -243.8211) (xy 378.684803 -243.77428)
			(xy 378.672624 -243.724866) (xy 378.668529 -243.674138) (xy 378.350018 -243.674138) (xy 378.349523 -243.698745)
			(xy 378.341628 -243.747322) (xy 378.326044 -243.794003) (xy 378.303173 -243.83758) (xy 378.273608 -243.876924)
			(xy 378.238115 -243.911016) (xy 378.197612 -243.938972) (xy 378.15315 -243.96007) (xy 378.105879 -243.973762)
			(xy 378.057024 -243.979694) (xy 378.007849 -243.977713) (xy 377.95963 -243.967869) (xy 377.913614 -243.950417)
			(xy 377.870993 -243.92581) (xy 377.832872 -243.894685) (xy 377.800237 -243.857848) (xy 377.773934 -243.816252)
			(xy 377.754643 -243.770976) (xy 377.742866 -243.723192) (xy 377.738906 -243.674138) (xy 377.420632 -243.674138)
			(xy 377.42012 -243.699584) (xy 377.411956 -243.749818) (xy 377.39584 -243.798092) (xy 377.372189 -243.843155)
			(xy 377.341616 -243.883841) (xy 377.304912 -243.919096) (xy 377.263028 -243.948006) (xy 377.217049 -243.969823)
			(xy 377.168165 -243.983983) (xy 377.117644 -243.990117) (xy 377.066792 -243.988068) (xy 377.016928 -243.977888)
			(xy 376.969342 -243.959841) (xy 376.925268 -243.934395) (xy 376.885846 -243.902208) (xy 376.852098 -243.864114)
			(xy 376.824897 -243.8211) (xy 376.804949 -243.77428) (xy 376.79277 -243.724866) (xy 376.788675 -243.674138)
			(xy 376.480578 -243.674138) (xy 376.480066 -243.699584) (xy 376.471902 -243.749818) (xy 376.455786 -243.798092)
			(xy 376.432135 -243.843155) (xy 376.401562 -243.883841) (xy 376.364858 -243.919096) (xy 376.322974 -243.948006)
			(xy 376.276995 -243.969823) (xy 376.228111 -243.983983) (xy 376.17759 -243.990117) (xy 376.126738 -243.988068)
			(xy 376.076874 -243.977888) (xy 376.029288 -243.959841) (xy 375.985214 -243.934395) (xy 375.945792 -243.902208)
			(xy 375.912044 -243.864114) (xy 375.884843 -243.8211) (xy 375.864895 -243.77428) (xy 375.852716 -243.724866)
			(xy 375.848621 -243.674138) (xy 374.98528 -243.674138) (xy 374.98528 -244.257068) (xy 374.985353 -244.261278)
			(xy 374.986755 -244.26958) (xy 374.988074 -244.273578) (xy 374.995948 -244.296438) (xy 375.00052 -244.302788)
			(xy 375.014553 -244.32261) (xy 375.036826 -244.365765) (xy 375.051992 -244.4119) (xy 375.059668 -244.459853)
			(xy 375.059665 -244.484144) (xy 375.378467 -244.484144) (xy 375.382562 -244.433416) (xy 375.394741 -244.384002)
			(xy 375.414689 -244.337182) (xy 375.44189 -244.294168) (xy 375.475638 -244.256074) (xy 375.51506 -244.223887)
			(xy 375.559134 -244.198441) (xy 375.60672 -244.180394) (xy 375.656584 -244.170214) (xy 375.707436 -244.168165)
			(xy 375.757957 -244.174299) (xy 375.806841 -244.188459) (xy 375.85282 -244.210276) (xy 375.894704 -244.239186)
			(xy 375.931408 -244.274441) (xy 375.961981 -244.315127) (xy 375.985632 -244.36019) (xy 376.001748 -244.408464)
			(xy 376.009912 -244.458698) (xy 376.010424 -244.484144) (xy 376.328952 -244.484144) (xy 376.332912 -244.43509)
			(xy 376.344689 -244.387306) (xy 376.36398 -244.34203) (xy 376.390283 -244.300434) (xy 376.422918 -244.263597)
			(xy 376.461039 -244.232472) (xy 376.50366 -244.207865) (xy 376.549676 -244.190413) (xy 376.597895 -244.180569)
			(xy 376.64707 -244.178588) (xy 376.695925 -244.18452) (xy 376.743196 -244.198212) (xy 376.787658 -244.21931)
			(xy 376.828161 -244.247266) (xy 376.863654 -244.281358) (xy 376.893219 -244.320702) (xy 376.91609 -244.364279)
			(xy 376.931674 -244.41096) (xy 376.939569 -244.459537) (xy 376.940064 -244.484144) (xy 377.258575 -244.484144)
			(xy 377.26267 -244.433416) (xy 377.274849 -244.384002) (xy 377.294797 -244.337182) (xy 377.321998 -244.294168)
			(xy 377.355746 -244.256074) (xy 377.395168 -244.223887) (xy 377.439242 -244.198441) (xy 377.486828 -244.180394)
			(xy 377.536692 -244.170214) (xy 377.587544 -244.168165) (xy 377.638065 -244.174299) (xy 377.686949 -244.188459)
			(xy 377.732928 -244.210276) (xy 377.774812 -244.239186) (xy 377.811516 -244.274441) (xy 377.842089 -244.315127)
			(xy 377.86574 -244.36019) (xy 377.881856 -244.408464) (xy 377.89002 -244.458698) (xy 377.890532 -244.484144)
			(xy 379.138683 -244.484144) (xy 379.142778 -244.433416) (xy 379.154957 -244.384002) (xy 379.174905 -244.337182)
			(xy 379.202106 -244.294168) (xy 379.235854 -244.256074) (xy 379.275276 -244.223887) (xy 379.31935 -244.198441)
			(xy 379.366936 -244.180394) (xy 379.4168 -244.170214) (xy 379.467652 -244.168165) (xy 379.518173 -244.174299)
			(xy 379.567057 -244.188459) (xy 379.613036 -244.210276) (xy 379.65492 -244.239186) (xy 379.691624 -244.274441)
			(xy 379.722197 -244.315127) (xy 379.745848 -244.36019) (xy 379.761964 -244.408464) (xy 379.770128 -244.458698)
			(xy 379.77064 -244.484144) (xy 380.078483 -244.484144) (xy 380.082578 -244.433416) (xy 380.094757 -244.384002)
			(xy 380.114705 -244.337182) (xy 380.141906 -244.294168) (xy 380.175654 -244.256074) (xy 380.215076 -244.223887)
			(xy 380.25915 -244.198441) (xy 380.306736 -244.180394) (xy 380.3566 -244.170214) (xy 380.407452 -244.168165)
			(xy 380.457973 -244.174299) (xy 380.506857 -244.188459) (xy 380.552836 -244.210276) (xy 380.59472 -244.239186)
			(xy 380.631424 -244.274441) (xy 380.661997 -244.315127) (xy 380.685648 -244.36019) (xy 380.701764 -244.408464)
			(xy 380.709928 -244.458698) (xy 380.71044 -244.484144) (xy 381.028968 -244.484144) (xy 381.032928 -244.43509)
			(xy 381.044705 -244.387306) (xy 381.063996 -244.34203) (xy 381.090299 -244.300434) (xy 381.122934 -244.263597)
			(xy 381.161055 -244.232472) (xy 381.203676 -244.207865) (xy 381.249692 -244.190413) (xy 381.297911 -244.180569)
			(xy 381.347086 -244.178588) (xy 381.395941 -244.18452) (xy 381.443212 -244.198212) (xy 381.487674 -244.21931)
			(xy 381.528177 -244.247266) (xy 381.56367 -244.281358) (xy 381.593235 -244.320702) (xy 381.616106 -244.364279)
			(xy 381.63169 -244.41096) (xy 381.639585 -244.459537) (xy 381.64008 -244.484144) (xy 381.958591 -244.484144)
			(xy 381.962686 -244.433416) (xy 381.974865 -244.384002) (xy 381.994813 -244.337182) (xy 382.022014 -244.294168)
			(xy 382.055762 -244.256074) (xy 382.095184 -244.223887) (xy 382.139258 -244.198441) (xy 382.186844 -244.180394)
			(xy 382.236708 -244.170214) (xy 382.28756 -244.168165) (xy 382.338081 -244.174299) (xy 382.386965 -244.188459)
			(xy 382.432944 -244.210276) (xy 382.474828 -244.239186) (xy 382.511532 -244.274441) (xy 382.542105 -244.315127)
			(xy 382.565756 -244.36019) (xy 382.581872 -244.408464) (xy 382.590036 -244.458698) (xy 382.590548 -244.484144)
			(xy 382.909076 -244.484144) (xy 382.913036 -244.43509) (xy 382.924813 -244.387306) (xy 382.944104 -244.34203)
			(xy 382.970407 -244.300434) (xy 383.003042 -244.263597) (xy 383.041163 -244.232472) (xy 383.083784 -244.207865)
			(xy 383.1298 -244.190413) (xy 383.178019 -244.180569) (xy 383.227194 -244.178588) (xy 383.276049 -244.18452)
			(xy 383.32332 -244.198212) (xy 383.367782 -244.21931) (xy 383.408285 -244.247266) (xy 383.443778 -244.281358)
			(xy 383.473343 -244.320702) (xy 383.496214 -244.364279) (xy 383.511798 -244.41096) (xy 383.519693 -244.459537)
			(xy 383.520188 -244.484144) (xy 383.838699 -244.484144) (xy 383.842794 -244.433416) (xy 383.854973 -244.384002)
			(xy 383.874921 -244.337182) (xy 383.902122 -244.294168) (xy 383.93587 -244.256074) (xy 383.975292 -244.223887)
			(xy 384.019366 -244.198441) (xy 384.066952 -244.180394) (xy 384.116816 -244.170214) (xy 384.167668 -244.168165)
			(xy 384.218189 -244.174299) (xy 384.267073 -244.188459) (xy 384.313052 -244.210276) (xy 384.354936 -244.239186)
			(xy 384.39164 -244.274441) (xy 384.422213 -244.315127) (xy 384.445864 -244.36019) (xy 384.46198 -244.408464)
			(xy 384.470144 -244.458698) (xy 384.470656 -244.484144) (xy 385.718553 -244.484144) (xy 385.722648 -244.433416)
			(xy 385.734827 -244.384002) (xy 385.754775 -244.337182) (xy 385.781976 -244.294168) (xy 385.815724 -244.256074)
			(xy 385.855146 -244.223887) (xy 385.89922 -244.198441) (xy 385.946806 -244.180394) (xy 385.99667 -244.170214)
			(xy 386.047522 -244.168165) (xy 386.098043 -244.174299) (xy 386.146927 -244.188459) (xy 386.192906 -244.210276)
			(xy 386.23479 -244.239186) (xy 386.271494 -244.274441) (xy 386.302067 -244.315127) (xy 386.325718 -244.36019)
			(xy 386.341834 -244.408464) (xy 386.349998 -244.458698) (xy 386.35051 -244.484144) (xy 386.658607 -244.484144)
			(xy 386.662702 -244.433416) (xy 386.674881 -244.384002) (xy 386.694829 -244.337182) (xy 386.72203 -244.294168)
			(xy 386.755778 -244.256074) (xy 386.7952 -244.223887) (xy 386.839274 -244.198441) (xy 386.88686 -244.180394)
			(xy 386.936724 -244.170214) (xy 386.987576 -244.168165) (xy 387.038097 -244.174299) (xy 387.086981 -244.188459)
			(xy 387.13296 -244.210276) (xy 387.174844 -244.239186) (xy 387.211548 -244.274441) (xy 387.242121 -244.315127)
			(xy 387.265772 -244.36019) (xy 387.281888 -244.408464) (xy 387.290052 -244.458698) (xy 387.290564 -244.484144)
			(xy 387.609092 -244.484144) (xy 387.613052 -244.43509) (xy 387.624829 -244.387306) (xy 387.64412 -244.34203)
			(xy 387.670423 -244.300434) (xy 387.703058 -244.263597) (xy 387.741179 -244.232472) (xy 387.7838 -244.207865)
			(xy 387.829816 -244.190413) (xy 387.878035 -244.180569) (xy 387.92721 -244.178588) (xy 387.976065 -244.18452)
			(xy 388.023336 -244.198212) (xy 388.067798 -244.21931) (xy 388.108301 -244.247266) (xy 388.143794 -244.281358)
			(xy 388.173359 -244.320702) (xy 388.19623 -244.364279) (xy 388.211814 -244.41096) (xy 388.219709 -244.459537)
			(xy 388.220204 -244.484144) (xy 388.538715 -244.484144) (xy 388.54281 -244.433416) (xy 388.554989 -244.384002)
			(xy 388.574937 -244.337182) (xy 388.602138 -244.294168) (xy 388.635886 -244.256074) (xy 388.675308 -244.223887)
			(xy 388.719382 -244.198441) (xy 388.766968 -244.180394) (xy 388.816832 -244.170214) (xy 388.867684 -244.168165)
			(xy 388.918205 -244.174299) (xy 388.967089 -244.188459) (xy 389.013068 -244.210276) (xy 389.054952 -244.239186)
			(xy 389.091656 -244.274441) (xy 389.122229 -244.315127) (xy 389.14588 -244.36019) (xy 389.161996 -244.408464)
			(xy 389.17016 -244.458698) (xy 389.170672 -244.484144) (xy 389.488946 -244.484144) (xy 389.492906 -244.43509)
			(xy 389.504683 -244.387306) (xy 389.523974 -244.34203) (xy 389.550277 -244.300434) (xy 389.582912 -244.263597)
			(xy 389.621033 -244.232472) (xy 389.663654 -244.207865) (xy 389.70967 -244.190413) (xy 389.757889 -244.180569)
			(xy 389.807064 -244.178588) (xy 389.855919 -244.18452) (xy 389.90319 -244.198212) (xy 389.947652 -244.21931)
			(xy 389.988155 -244.247266) (xy 390.023648 -244.281358) (xy 390.053213 -244.320702) (xy 390.076084 -244.364279)
			(xy 390.091668 -244.41096) (xy 390.099563 -244.459537) (xy 390.100058 -244.484144) (xy 390.418569 -244.484144)
			(xy 390.422664 -244.433416) (xy 390.434843 -244.384002) (xy 390.454791 -244.337182) (xy 390.481992 -244.294168)
			(xy 390.51574 -244.256074) (xy 390.555162 -244.223887) (xy 390.599236 -244.198441) (xy 390.646822 -244.180394)
			(xy 390.696686 -244.170214) (xy 390.747538 -244.168165) (xy 390.798059 -244.174299) (xy 390.846943 -244.188459)
			(xy 390.892922 -244.210276) (xy 390.934806 -244.239186) (xy 390.97151 -244.274441) (xy 391.002083 -244.315127)
			(xy 391.025734 -244.36019) (xy 391.04185 -244.408464) (xy 391.050014 -244.458698) (xy 391.050526 -244.484144)
			(xy 391.050014 -244.50959) (xy 391.04185 -244.559824) (xy 391.025734 -244.608098) (xy 391.002083 -244.653161)
			(xy 390.97151 -244.693847) (xy 390.934806 -244.729102) (xy 390.904411 -244.750082) (xy 394.377176 -244.750082)
			(xy 394.381136 -244.701028) (xy 394.392913 -244.653244) (xy 394.412204 -244.607968) (xy 394.438507 -244.566372)
			(xy 394.471142 -244.529535) (xy 394.509263 -244.49841) (xy 394.551884 -244.473803) (xy 394.5979 -244.456351)
			(xy 394.646119 -244.446507) (xy 394.695294 -244.444526) (xy 394.744149 -244.450458) (xy 394.79142 -244.46415)
			(xy 394.835882 -244.485248) (xy 394.876385 -244.513204) (xy 394.911878 -244.547296) (xy 394.941443 -244.58664)
			(xy 394.964314 -244.630217) (xy 394.979898 -244.676898) (xy 394.987793 -244.725475) (xy 394.988288 -244.750082)
			(xy 394.987793 -244.774689) (xy 394.979898 -244.823266) (xy 394.964314 -244.869947) (xy 394.941443 -244.913524)
			(xy 394.911878 -244.952868) (xy 394.876385 -244.98696) (xy 394.835882 -245.014916) (xy 394.79142 -245.036014)
			(xy 394.744149 -245.049706) (xy 394.695294 -245.055638) (xy 394.646119 -245.053657) (xy 394.5979 -245.043813)
			(xy 394.551884 -245.026361) (xy 394.509263 -245.001754) (xy 394.471142 -244.970629) (xy 394.438507 -244.933792)
			(xy 394.412204 -244.892196) (xy 394.392913 -244.84692) (xy 394.381136 -244.799136) (xy 394.377176 -244.750082)
			(xy 390.904411 -244.750082) (xy 390.892922 -244.758012) (xy 390.846943 -244.779829) (xy 390.798059 -244.793989)
			(xy 390.747538 -244.800123) (xy 390.696686 -244.798074) (xy 390.646822 -244.787894) (xy 390.599236 -244.769847)
			(xy 390.555162 -244.744401) (xy 390.51574 -244.712214) (xy 390.481992 -244.67412) (xy 390.454791 -244.631106)
			(xy 390.434843 -244.584286) (xy 390.422664 -244.534872) (xy 390.418569 -244.484144) (xy 390.100058 -244.484144)
			(xy 390.099563 -244.508751) (xy 390.091668 -244.557328) (xy 390.076084 -244.604009) (xy 390.053213 -244.647586)
			(xy 390.023648 -244.68693) (xy 389.988155 -244.721022) (xy 389.947652 -244.748978) (xy 389.90319 -244.770076)
			(xy 389.855919 -244.783768) (xy 389.807064 -244.7897) (xy 389.757889 -244.787719) (xy 389.70967 -244.777875)
			(xy 389.663654 -244.760423) (xy 389.621033 -244.735816) (xy 389.582912 -244.704691) (xy 389.550277 -244.667854)
			(xy 389.523974 -244.626258) (xy 389.504683 -244.580982) (xy 389.492906 -244.533198) (xy 389.488946 -244.484144)
			(xy 389.170672 -244.484144) (xy 389.17016 -244.50959) (xy 389.161996 -244.559824) (xy 389.14588 -244.608098)
			(xy 389.122229 -244.653161) (xy 389.091656 -244.693847) (xy 389.054952 -244.729102) (xy 389.013068 -244.758012)
			(xy 388.967089 -244.779829) (xy 388.918205 -244.793989) (xy 388.867684 -244.800123) (xy 388.816832 -244.798074)
			(xy 388.766968 -244.787894) (xy 388.719382 -244.769847) (xy 388.675308 -244.744401) (xy 388.635886 -244.712214)
			(xy 388.602138 -244.67412) (xy 388.574937 -244.631106) (xy 388.554989 -244.584286) (xy 388.54281 -244.534872)
			(xy 388.538715 -244.484144) (xy 388.220204 -244.484144) (xy 388.219709 -244.508751) (xy 388.211814 -244.557328)
			(xy 388.19623 -244.604009) (xy 388.173359 -244.647586) (xy 388.143794 -244.68693) (xy 388.108301 -244.721022)
			(xy 388.067798 -244.748978) (xy 388.023336 -244.770076) (xy 387.976065 -244.783768) (xy 387.92721 -244.7897)
			(xy 387.878035 -244.787719) (xy 387.829816 -244.777875) (xy 387.7838 -244.760423) (xy 387.741179 -244.735816)
			(xy 387.703058 -244.704691) (xy 387.670423 -244.667854) (xy 387.64412 -244.626258) (xy 387.624829 -244.580982)
			(xy 387.613052 -244.533198) (xy 387.609092 -244.484144) (xy 387.290564 -244.484144) (xy 387.290052 -244.50959)
			(xy 387.281888 -244.559824) (xy 387.265772 -244.608098) (xy 387.242121 -244.653161) (xy 387.211548 -244.693847)
			(xy 387.174844 -244.729102) (xy 387.13296 -244.758012) (xy 387.086981 -244.779829) (xy 387.038097 -244.793989)
			(xy 386.987576 -244.800123) (xy 386.936724 -244.798074) (xy 386.88686 -244.787894) (xy 386.839274 -244.769847)
			(xy 386.7952 -244.744401) (xy 386.755778 -244.712214) (xy 386.72203 -244.67412) (xy 386.694829 -244.631106)
			(xy 386.674881 -244.584286) (xy 386.662702 -244.534872) (xy 386.658607 -244.484144) (xy 386.35051 -244.484144)
			(xy 386.349998 -244.50959) (xy 386.341834 -244.559824) (xy 386.325718 -244.608098) (xy 386.302067 -244.653161)
			(xy 386.271494 -244.693847) (xy 386.23479 -244.729102) (xy 386.192906 -244.758012) (xy 386.146927 -244.779829)
			(xy 386.098043 -244.793989) (xy 386.047522 -244.800123) (xy 385.99667 -244.798074) (xy 385.946806 -244.787894)
			(xy 385.89922 -244.769847) (xy 385.855146 -244.744401) (xy 385.815724 -244.712214) (xy 385.781976 -244.67412)
			(xy 385.754775 -244.631106) (xy 385.734827 -244.584286) (xy 385.722648 -244.534872) (xy 385.718553 -244.484144)
			(xy 384.470656 -244.484144) (xy 384.470144 -244.50959) (xy 384.46198 -244.559824) (xy 384.445864 -244.608098)
			(xy 384.422213 -244.653161) (xy 384.39164 -244.693847) (xy 384.354936 -244.729102) (xy 384.313052 -244.758012)
			(xy 384.267073 -244.779829) (xy 384.218189 -244.793989) (xy 384.167668 -244.800123) (xy 384.116816 -244.798074)
			(xy 384.066952 -244.787894) (xy 384.019366 -244.769847) (xy 383.975292 -244.744401) (xy 383.93587 -244.712214)
			(xy 383.902122 -244.67412) (xy 383.874921 -244.631106) (xy 383.854973 -244.584286) (xy 383.842794 -244.534872)
			(xy 383.838699 -244.484144) (xy 383.520188 -244.484144) (xy 383.519693 -244.508751) (xy 383.511798 -244.557328)
			(xy 383.496214 -244.604009) (xy 383.473343 -244.647586) (xy 383.443778 -244.68693) (xy 383.408285 -244.721022)
			(xy 383.367782 -244.748978) (xy 383.32332 -244.770076) (xy 383.276049 -244.783768) (xy 383.227194 -244.7897)
			(xy 383.178019 -244.787719) (xy 383.1298 -244.777875) (xy 383.083784 -244.760423) (xy 383.041163 -244.735816)
			(xy 383.003042 -244.704691) (xy 382.970407 -244.667854) (xy 382.944104 -244.626258) (xy 382.924813 -244.580982)
			(xy 382.913036 -244.533198) (xy 382.909076 -244.484144) (xy 382.590548 -244.484144) (xy 382.590036 -244.50959)
			(xy 382.581872 -244.559824) (xy 382.565756 -244.608098) (xy 382.542105 -244.653161) (xy 382.511532 -244.693847)
			(xy 382.474828 -244.729102) (xy 382.432944 -244.758012) (xy 382.386965 -244.779829) (xy 382.338081 -244.793989)
			(xy 382.28756 -244.800123) (xy 382.236708 -244.798074) (xy 382.186844 -244.787894) (xy 382.139258 -244.769847)
			(xy 382.095184 -244.744401) (xy 382.055762 -244.712214) (xy 382.022014 -244.67412) (xy 381.994813 -244.631106)
			(xy 381.974865 -244.584286) (xy 381.962686 -244.534872) (xy 381.958591 -244.484144) (xy 381.64008 -244.484144)
			(xy 381.639585 -244.508751) (xy 381.63169 -244.557328) (xy 381.616106 -244.604009) (xy 381.593235 -244.647586)
			(xy 381.56367 -244.68693) (xy 381.528177 -244.721022) (xy 381.487674 -244.748978) (xy 381.443212 -244.770076)
			(xy 381.395941 -244.783768) (xy 381.347086 -244.7897) (xy 381.297911 -244.787719) (xy 381.249692 -244.777875)
			(xy 381.203676 -244.760423) (xy 381.161055 -244.735816) (xy 381.122934 -244.704691) (xy 381.090299 -244.667854)
			(xy 381.063996 -244.626258) (xy 381.044705 -244.580982) (xy 381.032928 -244.533198) (xy 381.028968 -244.484144)
			(xy 380.71044 -244.484144) (xy 380.709928 -244.50959) (xy 380.701764 -244.559824) (xy 380.685648 -244.608098)
			(xy 380.661997 -244.653161) (xy 380.631424 -244.693847) (xy 380.59472 -244.729102) (xy 380.552836 -244.758012)
			(xy 380.506857 -244.779829) (xy 380.457973 -244.793989) (xy 380.407452 -244.800123) (xy 380.3566 -244.798074)
			(xy 380.306736 -244.787894) (xy 380.25915 -244.769847) (xy 380.215076 -244.744401) (xy 380.175654 -244.712214)
			(xy 380.141906 -244.67412) (xy 380.114705 -244.631106) (xy 380.094757 -244.584286) (xy 380.082578 -244.534872)
			(xy 380.078483 -244.484144) (xy 379.77064 -244.484144) (xy 379.770128 -244.50959) (xy 379.761964 -244.559824)
			(xy 379.745848 -244.608098) (xy 379.722197 -244.653161) (xy 379.691624 -244.693847) (xy 379.65492 -244.729102)
			(xy 379.613036 -244.758012) (xy 379.567057 -244.779829) (xy 379.518173 -244.793989) (xy 379.467652 -244.800123)
			(xy 379.4168 -244.798074) (xy 379.366936 -244.787894) (xy 379.31935 -244.769847) (xy 379.275276 -244.744401)
			(xy 379.235854 -244.712214) (xy 379.202106 -244.67412) (xy 379.174905 -244.631106) (xy 379.154957 -244.584286)
			(xy 379.142778 -244.534872) (xy 379.138683 -244.484144) (xy 377.890532 -244.484144) (xy 377.89002 -244.50959)
			(xy 377.881856 -244.559824) (xy 377.86574 -244.608098) (xy 377.842089 -244.653161) (xy 377.811516 -244.693847)
			(xy 377.774812 -244.729102) (xy 377.732928 -244.758012) (xy 377.686949 -244.779829) (xy 377.638065 -244.793989)
			(xy 377.587544 -244.800123) (xy 377.536692 -244.798074) (xy 377.486828 -244.787894) (xy 377.439242 -244.769847)
			(xy 377.395168 -244.744401) (xy 377.355746 -244.712214) (xy 377.321998 -244.67412) (xy 377.294797 -244.631106)
			(xy 377.274849 -244.584286) (xy 377.26267 -244.534872) (xy 377.258575 -244.484144) (xy 376.940064 -244.484144)
			(xy 376.939569 -244.508751) (xy 376.931674 -244.557328) (xy 376.91609 -244.604009) (xy 376.893219 -244.647586)
			(xy 376.863654 -244.68693) (xy 376.828161 -244.721022) (xy 376.787658 -244.748978) (xy 376.743196 -244.770076)
			(xy 376.695925 -244.783768) (xy 376.64707 -244.7897) (xy 376.597895 -244.787719) (xy 376.549676 -244.777875)
			(xy 376.50366 -244.760423) (xy 376.461039 -244.735816) (xy 376.422918 -244.704691) (xy 376.390283 -244.667854)
			(xy 376.36398 -244.626258) (xy 376.344689 -244.580982) (xy 376.332912 -244.533198) (xy 376.328952 -244.484144)
			(xy 376.010424 -244.484144) (xy 376.009912 -244.50959) (xy 376.001748 -244.559824) (xy 375.985632 -244.608098)
			(xy 375.961981 -244.653161) (xy 375.931408 -244.693847) (xy 375.894704 -244.729102) (xy 375.85282 -244.758012)
			(xy 375.806841 -244.779829) (xy 375.757957 -244.793989) (xy 375.707436 -244.800123) (xy 375.656584 -244.798074)
			(xy 375.60672 -244.787894) (xy 375.559134 -244.769847) (xy 375.51506 -244.744401) (xy 375.475638 -244.712214)
			(xy 375.44189 -244.67412) (xy 375.414689 -244.631106) (xy 375.394741 -244.584286) (xy 375.382562 -244.534872)
			(xy 375.378467 -244.484144) (xy 375.059665 -244.484144) (xy 375.059663 -244.508417) (xy 375.051975 -244.556369)
			(xy 375.036798 -244.6025) (xy 375.014516 -244.64565) (xy 375.00052 -244.6655) (xy 374.995948 -244.67185)
			(xy 374.988074 -244.69471) (xy 374.986793 -244.698718) (xy 374.985394 -244.707014) (xy 374.98528 -244.71122)
			(xy 374.98528 -244.911372) (xy 374.98528 -244.914674) (xy 374.986476 -244.925416) (xy 374.99662 -244.94448)
			(xy 375.004838 -244.951504) (xy 375.00687 -244.953028) (xy 375.074688 -245.00078) (xy 375.085127 -245.007224)
			(xy 375.109414 -245.010391) (xy 375.12117 -245.006876) (xy 375.121932 -245.006622) (xy 375.12879 -245.004336)
			(xy 375.152133 -244.997112) (xy 375.200371 -244.989334) (xy 375.224802 -244.988842) (xy 375.250053 -244.989364)
			(xy 375.299866 -244.997676) (xy 375.347632 -245.014075) (xy 375.392047 -245.038111) (xy 375.431901 -245.06913)
			(xy 375.466105 -245.106286) (xy 375.493727 -245.148565) (xy 375.514013 -245.194813) (xy 375.526411 -245.24377)
			(xy 375.530581 -245.2941) (xy 375.530577 -245.29415) (xy 375.848621 -245.29415) (xy 375.852716 -245.243422)
			(xy 375.864895 -245.194008) (xy 375.884843 -245.147188) (xy 375.912044 -245.104174) (xy 375.945792 -245.06608)
			(xy 375.985214 -245.033893) (xy 376.029288 -245.008447) (xy 376.076874 -244.9904) (xy 376.126738 -244.98022)
			(xy 376.17759 -244.978171) (xy 376.228111 -244.984305) (xy 376.276995 -244.998465) (xy 376.322974 -245.020282)
			(xy 376.364858 -245.049192) (xy 376.401562 -245.084447) (xy 376.432135 -245.125133) (xy 376.455786 -245.170196)
			(xy 376.471902 -245.21847) (xy 376.480066 -245.268704) (xy 376.480578 -245.29415) (xy 376.788675 -245.29415)
			(xy 376.79277 -245.243422) (xy 376.804949 -245.194008) (xy 376.824897 -245.147188) (xy 376.852098 -245.104174)
			(xy 376.885846 -245.06608) (xy 376.925268 -245.033893) (xy 376.969342 -245.008447) (xy 377.016928 -244.9904)
			(xy 377.066792 -244.98022) (xy 377.117644 -244.978171) (xy 377.168165 -244.984305) (xy 377.217049 -244.998465)
			(xy 377.263028 -245.020282) (xy 377.304912 -245.049192) (xy 377.341616 -245.084447) (xy 377.372189 -245.125133)
			(xy 377.39584 -245.170196) (xy 377.411956 -245.21847) (xy 377.42012 -245.268704) (xy 377.420632 -245.29415)
			(xy 377.738906 -245.29415) (xy 377.742866 -245.245096) (xy 377.754643 -245.197312) (xy 377.773934 -245.152036)
			(xy 377.800237 -245.11044) (xy 377.832872 -245.073603) (xy 377.870993 -245.042478) (xy 377.913614 -245.017871)
			(xy 377.95963 -245.000419) (xy 378.007849 -244.990575) (xy 378.057024 -244.988594) (xy 378.105879 -244.994526)
			(xy 378.15315 -245.008218) (xy 378.197612 -245.029316) (xy 378.238115 -245.057272) (xy 378.273608 -245.091364)
			(xy 378.303173 -245.130708) (xy 378.326044 -245.174285) (xy 378.341628 -245.220966) (xy 378.349523 -245.269543)
			(xy 378.350018 -245.29415) (xy 378.668529 -245.29415) (xy 378.672624 -245.243422) (xy 378.684803 -245.194008)
			(xy 378.704751 -245.147188) (xy 378.731952 -245.104174) (xy 378.7657 -245.06608) (xy 378.805122 -245.033893)
			(xy 378.849196 -245.008447) (xy 378.896782 -244.9904) (xy 378.946646 -244.98022) (xy 378.997498 -244.978171)
			(xy 379.048019 -244.984305) (xy 379.096903 -244.998465) (xy 379.142882 -245.020282) (xy 379.184766 -245.049192)
			(xy 379.22147 -245.084447) (xy 379.252043 -245.125133) (xy 379.275694 -245.170196) (xy 379.29181 -245.21847)
			(xy 379.299974 -245.268704) (xy 379.300486 -245.29415) (xy 379.619014 -245.29415) (xy 379.622974 -245.245096)
			(xy 379.634751 -245.197312) (xy 379.654042 -245.152036) (xy 379.680345 -245.11044) (xy 379.71298 -245.073603)
			(xy 379.751101 -245.042478) (xy 379.793722 -245.017871) (xy 379.839738 -245.000419) (xy 379.887957 -244.990575)
			(xy 379.937132 -244.988594) (xy 379.985987 -244.994526) (xy 380.033258 -245.008218) (xy 380.07772 -245.029316)
			(xy 380.118223 -245.057272) (xy 380.153716 -245.091364) (xy 380.183281 -245.130708) (xy 380.206152 -245.174285)
			(xy 380.221736 -245.220966) (xy 380.229631 -245.269543) (xy 380.230126 -245.29415) (xy 380.548637 -245.29415)
			(xy 380.552732 -245.243422) (xy 380.564911 -245.194008) (xy 380.584859 -245.147188) (xy 380.61206 -245.104174)
			(xy 380.645808 -245.06608) (xy 380.68523 -245.033893) (xy 380.729304 -245.008447) (xy 380.77689 -244.9904)
			(xy 380.826754 -244.98022) (xy 380.877606 -244.978171) (xy 380.928127 -244.984305) (xy 380.977011 -244.998465)
			(xy 381.02299 -245.020282) (xy 381.064874 -245.049192) (xy 381.101578 -245.084447) (xy 381.132151 -245.125133)
			(xy 381.155802 -245.170196) (xy 381.171918 -245.21847) (xy 381.180082 -245.268704) (xy 381.180594 -245.29415)
			(xy 381.499122 -245.29415) (xy 381.503082 -245.245096) (xy 381.514859 -245.197312) (xy 381.53415 -245.152036)
			(xy 381.560453 -245.11044) (xy 381.593088 -245.073603) (xy 381.631209 -245.042478) (xy 381.67383 -245.017871)
			(xy 381.719846 -245.000419) (xy 381.768065 -244.990575) (xy 381.81724 -244.988594) (xy 381.866095 -244.994526)
			(xy 381.913366 -245.008218) (xy 381.957828 -245.029316) (xy 381.998331 -245.057272) (xy 382.033824 -245.091364)
			(xy 382.063389 -245.130708) (xy 382.08626 -245.174285) (xy 382.101844 -245.220966) (xy 382.109739 -245.269543)
			(xy 382.110234 -245.29415) (xy 382.428491 -245.29415) (xy 382.432586 -245.243422) (xy 382.444765 -245.194008)
			(xy 382.464713 -245.147188) (xy 382.491914 -245.104174) (xy 382.525662 -245.06608) (xy 382.565084 -245.033893)
			(xy 382.609158 -245.008447) (xy 382.656744 -244.9904) (xy 382.706608 -244.98022) (xy 382.75746 -244.978171)
			(xy 382.807981 -244.984305) (xy 382.856865 -244.998465) (xy 382.902844 -245.020282) (xy 382.944728 -245.049192)
			(xy 382.981432 -245.084447) (xy 383.012005 -245.125133) (xy 383.035656 -245.170196) (xy 383.051772 -245.21847)
			(xy 383.059936 -245.268704) (xy 383.060448 -245.29415) (xy 383.368545 -245.29415) (xy 383.37264 -245.243422)
			(xy 383.384819 -245.194008) (xy 383.404767 -245.147188) (xy 383.431968 -245.104174) (xy 383.465716 -245.06608)
			(xy 383.505138 -245.033893) (xy 383.549212 -245.008447) (xy 383.596798 -244.9904) (xy 383.646662 -244.98022)
			(xy 383.697514 -244.978171) (xy 383.748035 -244.984305) (xy 383.796919 -244.998465) (xy 383.842898 -245.020282)
			(xy 383.884782 -245.049192) (xy 383.921486 -245.084447) (xy 383.952059 -245.125133) (xy 383.97571 -245.170196)
			(xy 383.991826 -245.21847) (xy 383.99999 -245.268704) (xy 384.000502 -245.29415) (xy 384.31903 -245.29415)
			(xy 384.32299 -245.245096) (xy 384.334767 -245.197312) (xy 384.354058 -245.152036) (xy 384.380361 -245.11044)
			(xy 384.412996 -245.073603) (xy 384.451117 -245.042478) (xy 384.493738 -245.017871) (xy 384.539754 -245.000419)
			(xy 384.587973 -244.990575) (xy 384.637148 -244.988594) (xy 384.686003 -244.994526) (xy 384.733274 -245.008218)
			(xy 384.777736 -245.029316) (xy 384.818239 -245.057272) (xy 384.853732 -245.091364) (xy 384.883297 -245.130708)
			(xy 384.906168 -245.174285) (xy 384.921752 -245.220966) (xy 384.929647 -245.269543) (xy 384.930142 -245.29415)
			(xy 385.248653 -245.29415) (xy 385.252748 -245.243422) (xy 385.264927 -245.194008) (xy 385.284875 -245.147188)
			(xy 385.312076 -245.104174) (xy 385.345824 -245.06608) (xy 385.385246 -245.033893) (xy 385.42932 -245.008447)
			(xy 385.476906 -244.9904) (xy 385.52677 -244.98022) (xy 385.577622 -244.978171) (xy 385.628143 -244.984305)
			(xy 385.677027 -244.998465) (xy 385.723006 -245.020282) (xy 385.76489 -245.049192) (xy 385.801594 -245.084447)
			(xy 385.832167 -245.125133) (xy 385.855818 -245.170196) (xy 385.871934 -245.21847) (xy 385.880098 -245.268704)
			(xy 385.88061 -245.29415) (xy 386.199138 -245.29415) (xy 386.203098 -245.245096) (xy 386.214875 -245.197312)
			(xy 386.234166 -245.152036) (xy 386.260469 -245.11044) (xy 386.293104 -245.073603) (xy 386.331225 -245.042478)
			(xy 386.373846 -245.017871) (xy 386.419862 -245.000419) (xy 386.468081 -244.990575) (xy 386.517256 -244.988594)
			(xy 386.566111 -244.994526) (xy 386.613382 -245.008218) (xy 386.657844 -245.029316) (xy 386.698347 -245.057272)
			(xy 386.73384 -245.091364) (xy 386.763405 -245.130708) (xy 386.786276 -245.174285) (xy 386.80186 -245.220966)
			(xy 386.809755 -245.269543) (xy 386.81025 -245.29415) (xy 387.128507 -245.29415) (xy 387.132602 -245.243422)
			(xy 387.144781 -245.194008) (xy 387.164729 -245.147188) (xy 387.19193 -245.104174) (xy 387.225678 -245.06608)
			(xy 387.2651 -245.033893) (xy 387.309174 -245.008447) (xy 387.35676 -244.9904) (xy 387.406624 -244.98022)
			(xy 387.457476 -244.978171) (xy 387.507997 -244.984305) (xy 387.556881 -244.998465) (xy 387.60286 -245.020282)
			(xy 387.644744 -245.049192) (xy 387.681448 -245.084447) (xy 387.712021 -245.125133) (xy 387.735672 -245.170196)
			(xy 387.751788 -245.21847) (xy 387.759952 -245.268704) (xy 387.760464 -245.29415) (xy 388.078992 -245.29415)
			(xy 388.082952 -245.245096) (xy 388.094729 -245.197312) (xy 388.11402 -245.152036) (xy 388.140323 -245.11044)
			(xy 388.172958 -245.073603) (xy 388.211079 -245.042478) (xy 388.2537 -245.017871) (xy 388.299716 -245.000419)
			(xy 388.347935 -244.990575) (xy 388.39711 -244.988594) (xy 388.445965 -244.994526) (xy 388.493236 -245.008218)
			(xy 388.537698 -245.029316) (xy 388.578201 -245.057272) (xy 388.613694 -245.091364) (xy 388.643259 -245.130708)
			(xy 388.66613 -245.174285) (xy 388.681714 -245.220966) (xy 388.689609 -245.269543) (xy 388.690104 -245.29415)
			(xy 389.008615 -245.29415) (xy 389.01271 -245.243422) (xy 389.024889 -245.194008) (xy 389.044837 -245.147188)
			(xy 389.072038 -245.104174) (xy 389.105786 -245.06608) (xy 389.145208 -245.033893) (xy 389.189282 -245.008447)
			(xy 389.236868 -244.9904) (xy 389.286732 -244.98022) (xy 389.337584 -244.978171) (xy 389.388105 -244.984305)
			(xy 389.436989 -244.998465) (xy 389.482968 -245.020282) (xy 389.524852 -245.049192) (xy 389.561556 -245.084447)
			(xy 389.592129 -245.125133) (xy 389.61578 -245.170196) (xy 389.631896 -245.21847) (xy 389.64006 -245.268704)
			(xy 389.640572 -245.29415) (xy 389.948669 -245.29415) (xy 389.952764 -245.243422) (xy 389.964943 -245.194008)
			(xy 389.984891 -245.147188) (xy 390.012092 -245.104174) (xy 390.04584 -245.06608) (xy 390.085262 -245.033893)
			(xy 390.129336 -245.008447) (xy 390.176922 -244.9904) (xy 390.226786 -244.98022) (xy 390.277638 -244.978171)
			(xy 390.328159 -244.984305) (xy 390.377043 -244.998465) (xy 390.423022 -245.020282) (xy 390.464906 -245.049192)
			(xy 390.50161 -245.084447) (xy 390.532183 -245.125133) (xy 390.555834 -245.170196) (xy 390.57195 -245.21847)
			(xy 390.580114 -245.268704) (xy 390.580626 -245.29415) (xy 390.8989 -245.29415) (xy 390.90286 -245.245096)
			(xy 390.914637 -245.197312) (xy 390.933928 -245.152036) (xy 390.960231 -245.11044) (xy 390.992866 -245.073603)
			(xy 391.030987 -245.042478) (xy 391.073608 -245.017871) (xy 391.119624 -245.000419) (xy 391.167843 -244.990575)
			(xy 391.217018 -244.988594) (xy 391.265873 -244.994526) (xy 391.313144 -245.008218) (xy 391.357606 -245.029316)
			(xy 391.398109 -245.057272) (xy 391.433602 -245.091364) (xy 391.463167 -245.130708) (xy 391.486038 -245.174285)
			(xy 391.501622 -245.220966) (xy 391.509517 -245.269543) (xy 391.510012 -245.29415) (xy 392.779008 -245.29415)
			(xy 392.782968 -245.245096) (xy 392.794745 -245.197312) (xy 392.814036 -245.152036) (xy 392.840339 -245.11044)
			(xy 392.872974 -245.073603) (xy 392.911095 -245.042478) (xy 392.953716 -245.017871) (xy 392.999732 -245.000419)
			(xy 393.047951 -244.990575) (xy 393.097126 -244.988594) (xy 393.145981 -244.994526) (xy 393.193252 -245.008218)
			(xy 393.237714 -245.029316) (xy 393.278217 -245.057272) (xy 393.31371 -245.091364) (xy 393.343275 -245.130708)
			(xy 393.366146 -245.174285) (xy 393.38173 -245.220966) (xy 393.389625 -245.269543) (xy 393.39012 -245.29415)
			(xy 393.389625 -245.318757) (xy 393.38173 -245.367334) (xy 393.366146 -245.414015) (xy 393.343275 -245.457592)
			(xy 393.31371 -245.496936) (xy 393.278217 -245.531028) (xy 393.237714 -245.558984) (xy 393.193252 -245.580082)
			(xy 393.145981 -245.593774) (xy 393.097126 -245.599706) (xy 393.047951 -245.597725) (xy 392.999732 -245.587881)
			(xy 392.953716 -245.570429) (xy 392.911095 -245.545822) (xy 392.872974 -245.514697) (xy 392.840339 -245.47786)
			(xy 392.814036 -245.436264) (xy 392.794745 -245.390988) (xy 392.782968 -245.343204) (xy 392.779008 -245.29415)
			(xy 391.510012 -245.29415) (xy 391.509517 -245.318757) (xy 391.501622 -245.367334) (xy 391.486038 -245.414015)
			(xy 391.463167 -245.457592) (xy 391.433602 -245.496936) (xy 391.398109 -245.531028) (xy 391.357606 -245.558984)
			(xy 391.313144 -245.580082) (xy 391.265873 -245.593774) (xy 391.217018 -245.599706) (xy 391.167843 -245.597725)
			(xy 391.119624 -245.587881) (xy 391.073608 -245.570429) (xy 391.030987 -245.545822) (xy 390.992866 -245.514697)
			(xy 390.960231 -245.47786) (xy 390.933928 -245.436264) (xy 390.914637 -245.390988) (xy 390.90286 -245.343204)
			(xy 390.8989 -245.29415) (xy 390.580626 -245.29415) (xy 390.580114 -245.319596) (xy 390.57195 -245.36983)
			(xy 390.555834 -245.418104) (xy 390.532183 -245.463167) (xy 390.50161 -245.503853) (xy 390.464906 -245.539108)
			(xy 390.423022 -245.568018) (xy 390.377043 -245.589835) (xy 390.328159 -245.603995) (xy 390.277638 -245.610129)
			(xy 390.226786 -245.60808) (xy 390.176922 -245.5979) (xy 390.129336 -245.579853) (xy 390.085262 -245.554407)
			(xy 390.04584 -245.52222) (xy 390.012092 -245.484126) (xy 389.984891 -245.441112) (xy 389.964943 -245.394292)
			(xy 389.952764 -245.344878) (xy 389.948669 -245.29415) (xy 389.640572 -245.29415) (xy 389.64006 -245.319596)
			(xy 389.631896 -245.36983) (xy 389.61578 -245.418104) (xy 389.592129 -245.463167) (xy 389.561556 -245.503853)
			(xy 389.524852 -245.539108) (xy 389.482968 -245.568018) (xy 389.436989 -245.589835) (xy 389.388105 -245.603995)
			(xy 389.337584 -245.610129) (xy 389.286732 -245.60808) (xy 389.236868 -245.5979) (xy 389.189282 -245.579853)
			(xy 389.145208 -245.554407) (xy 389.105786 -245.52222) (xy 389.072038 -245.484126) (xy 389.044837 -245.441112)
			(xy 389.024889 -245.394292) (xy 389.01271 -245.344878) (xy 389.008615 -245.29415) (xy 388.690104 -245.29415)
			(xy 388.689609 -245.318757) (xy 388.681714 -245.367334) (xy 388.66613 -245.414015) (xy 388.643259 -245.457592)
			(xy 388.613694 -245.496936) (xy 388.578201 -245.531028) (xy 388.537698 -245.558984) (xy 388.493236 -245.580082)
			(xy 388.445965 -245.593774) (xy 388.39711 -245.599706) (xy 388.347935 -245.597725) (xy 388.299716 -245.587881)
			(xy 388.2537 -245.570429) (xy 388.211079 -245.545822) (xy 388.172958 -245.514697) (xy 388.140323 -245.47786)
			(xy 388.11402 -245.436264) (xy 388.094729 -245.390988) (xy 388.082952 -245.343204) (xy 388.078992 -245.29415)
			(xy 387.760464 -245.29415) (xy 387.759952 -245.319596) (xy 387.751788 -245.36983) (xy 387.735672 -245.418104)
			(xy 387.712021 -245.463167) (xy 387.681448 -245.503853) (xy 387.644744 -245.539108) (xy 387.60286 -245.568018)
			(xy 387.556881 -245.589835) (xy 387.507997 -245.603995) (xy 387.457476 -245.610129) (xy 387.406624 -245.60808)
			(xy 387.35676 -245.5979) (xy 387.309174 -245.579853) (xy 387.2651 -245.554407) (xy 387.225678 -245.52222)
			(xy 387.19193 -245.484126) (xy 387.164729 -245.441112) (xy 387.144781 -245.394292) (xy 387.132602 -245.344878)
			(xy 387.128507 -245.29415) (xy 386.81025 -245.29415) (xy 386.809755 -245.318757) (xy 386.80186 -245.367334)
			(xy 386.786276 -245.414015) (xy 386.763405 -245.457592) (xy 386.73384 -245.496936) (xy 386.698347 -245.531028)
			(xy 386.657844 -245.558984) (xy 386.613382 -245.580082) (xy 386.566111 -245.593774) (xy 386.517256 -245.599706)
			(xy 386.468081 -245.597725) (xy 386.419862 -245.587881) (xy 386.373846 -245.570429) (xy 386.331225 -245.545822)
			(xy 386.293104 -245.514697) (xy 386.260469 -245.47786) (xy 386.234166 -245.436264) (xy 386.214875 -245.390988)
			(xy 386.203098 -245.343204) (xy 386.199138 -245.29415) (xy 385.88061 -245.29415) (xy 385.880098 -245.319596)
			(xy 385.871934 -245.36983) (xy 385.855818 -245.418104) (xy 385.832167 -245.463167) (xy 385.801594 -245.503853)
			(xy 385.76489 -245.539108) (xy 385.723006 -245.568018) (xy 385.677027 -245.589835) (xy 385.628143 -245.603995)
			(xy 385.577622 -245.610129) (xy 385.52677 -245.60808) (xy 385.476906 -245.5979) (xy 385.42932 -245.579853)
			(xy 385.385246 -245.554407) (xy 385.345824 -245.52222) (xy 385.312076 -245.484126) (xy 385.284875 -245.441112)
			(xy 385.264927 -245.394292) (xy 385.252748 -245.344878) (xy 385.248653 -245.29415) (xy 384.930142 -245.29415)
			(xy 384.929647 -245.318757) (xy 384.921752 -245.367334) (xy 384.906168 -245.414015) (xy 384.883297 -245.457592)
			(xy 384.853732 -245.496936) (xy 384.818239 -245.531028) (xy 384.777736 -245.558984) (xy 384.733274 -245.580082)
			(xy 384.686003 -245.593774) (xy 384.637148 -245.599706) (xy 384.587973 -245.597725) (xy 384.539754 -245.587881)
			(xy 384.493738 -245.570429) (xy 384.451117 -245.545822) (xy 384.412996 -245.514697) (xy 384.380361 -245.47786)
			(xy 384.354058 -245.436264) (xy 384.334767 -245.390988) (xy 384.32299 -245.343204) (xy 384.31903 -245.29415)
			(xy 384.000502 -245.29415) (xy 383.99999 -245.319596) (xy 383.991826 -245.36983) (xy 383.97571 -245.418104)
			(xy 383.952059 -245.463167) (xy 383.921486 -245.503853) (xy 383.884782 -245.539108) (xy 383.842898 -245.568018)
			(xy 383.796919 -245.589835) (xy 383.748035 -245.603995) (xy 383.697514 -245.610129) (xy 383.646662 -245.60808)
			(xy 383.596798 -245.5979) (xy 383.549212 -245.579853) (xy 383.505138 -245.554407) (xy 383.465716 -245.52222)
			(xy 383.431968 -245.484126) (xy 383.404767 -245.441112) (xy 383.384819 -245.394292) (xy 383.37264 -245.344878)
			(xy 383.368545 -245.29415) (xy 383.060448 -245.29415) (xy 383.059936 -245.319596) (xy 383.051772 -245.36983)
			(xy 383.035656 -245.418104) (xy 383.012005 -245.463167) (xy 382.981432 -245.503853) (xy 382.944728 -245.539108)
			(xy 382.902844 -245.568018) (xy 382.856865 -245.589835) (xy 382.807981 -245.603995) (xy 382.75746 -245.610129)
			(xy 382.706608 -245.60808) (xy 382.656744 -245.5979) (xy 382.609158 -245.579853) (xy 382.565084 -245.554407)
			(xy 382.525662 -245.52222) (xy 382.491914 -245.484126) (xy 382.464713 -245.441112) (xy 382.444765 -245.394292)
			(xy 382.432586 -245.344878) (xy 382.428491 -245.29415) (xy 382.110234 -245.29415) (xy 382.109739 -245.318757)
			(xy 382.101844 -245.367334) (xy 382.08626 -245.414015) (xy 382.063389 -245.457592) (xy 382.033824 -245.496936)
			(xy 381.998331 -245.531028) (xy 381.957828 -245.558984) (xy 381.913366 -245.580082) (xy 381.866095 -245.593774)
			(xy 381.81724 -245.599706) (xy 381.768065 -245.597725) (xy 381.719846 -245.587881) (xy 381.67383 -245.570429)
			(xy 381.631209 -245.545822) (xy 381.593088 -245.514697) (xy 381.560453 -245.47786) (xy 381.53415 -245.436264)
			(xy 381.514859 -245.390988) (xy 381.503082 -245.343204) (xy 381.499122 -245.29415) (xy 381.180594 -245.29415)
			(xy 381.180082 -245.319596) (xy 381.171918 -245.36983) (xy 381.155802 -245.418104) (xy 381.132151 -245.463167)
			(xy 381.101578 -245.503853) (xy 381.064874 -245.539108) (xy 381.02299 -245.568018) (xy 380.977011 -245.589835)
			(xy 380.928127 -245.603995) (xy 380.877606 -245.610129) (xy 380.826754 -245.60808) (xy 380.77689 -245.5979)
			(xy 380.729304 -245.579853) (xy 380.68523 -245.554407) (xy 380.645808 -245.52222) (xy 380.61206 -245.484126)
			(xy 380.584859 -245.441112) (xy 380.564911 -245.394292) (xy 380.552732 -245.344878) (xy 380.548637 -245.29415)
			(xy 380.230126 -245.29415) (xy 380.229631 -245.318757) (xy 380.221736 -245.367334) (xy 380.206152 -245.414015)
			(xy 380.183281 -245.457592) (xy 380.153716 -245.496936) (xy 380.118223 -245.531028) (xy 380.07772 -245.558984)
			(xy 380.033258 -245.580082) (xy 379.985987 -245.593774) (xy 379.937132 -245.599706) (xy 379.887957 -245.597725)
			(xy 379.839738 -245.587881) (xy 379.793722 -245.570429) (xy 379.751101 -245.545822) (xy 379.71298 -245.514697)
			(xy 379.680345 -245.47786) (xy 379.654042 -245.436264) (xy 379.634751 -245.390988) (xy 379.622974 -245.343204)
			(xy 379.619014 -245.29415) (xy 379.300486 -245.29415) (xy 379.299974 -245.319596) (xy 379.29181 -245.36983)
			(xy 379.275694 -245.418104) (xy 379.252043 -245.463167) (xy 379.22147 -245.503853) (xy 379.184766 -245.539108)
			(xy 379.142882 -245.568018) (xy 379.096903 -245.589835) (xy 379.048019 -245.603995) (xy 378.997498 -245.610129)
			(xy 378.946646 -245.60808) (xy 378.896782 -245.5979) (xy 378.849196 -245.579853) (xy 378.805122 -245.554407)
			(xy 378.7657 -245.52222) (xy 378.731952 -245.484126) (xy 378.704751 -245.441112) (xy 378.684803 -245.394292)
			(xy 378.672624 -245.344878) (xy 378.668529 -245.29415) (xy 378.350018 -245.29415) (xy 378.349523 -245.318757)
			(xy 378.341628 -245.367334) (xy 378.326044 -245.414015) (xy 378.303173 -245.457592) (xy 378.273608 -245.496936)
			(xy 378.238115 -245.531028) (xy 378.197612 -245.558984) (xy 378.15315 -245.580082) (xy 378.105879 -245.593774)
			(xy 378.057024 -245.599706) (xy 378.007849 -245.597725) (xy 377.95963 -245.587881) (xy 377.913614 -245.570429)
			(xy 377.870993 -245.545822) (xy 377.832872 -245.514697) (xy 377.800237 -245.47786) (xy 377.773934 -245.436264)
			(xy 377.754643 -245.390988) (xy 377.742866 -245.343204) (xy 377.738906 -245.29415) (xy 377.420632 -245.29415)
			(xy 377.42012 -245.319596) (xy 377.411956 -245.36983) (xy 377.39584 -245.418104) (xy 377.372189 -245.463167)
			(xy 377.341616 -245.503853) (xy 377.304912 -245.539108) (xy 377.263028 -245.568018) (xy 377.217049 -245.589835)
			(xy 377.168165 -245.603995) (xy 377.117644 -245.610129) (xy 377.066792 -245.60808) (xy 377.016928 -245.5979)
			(xy 376.969342 -245.579853) (xy 376.925268 -245.554407) (xy 376.885846 -245.52222) (xy 376.852098 -245.484126)
			(xy 376.824897 -245.441112) (xy 376.804949 -245.394292) (xy 376.79277 -245.344878) (xy 376.788675 -245.29415)
			(xy 376.480578 -245.29415) (xy 376.480066 -245.319596) (xy 376.471902 -245.36983) (xy 376.455786 -245.418104)
			(xy 376.432135 -245.463167) (xy 376.401562 -245.503853) (xy 376.364858 -245.539108) (xy 376.322974 -245.568018)
			(xy 376.276995 -245.589835) (xy 376.228111 -245.603995) (xy 376.17759 -245.610129) (xy 376.126738 -245.60808)
			(xy 376.076874 -245.5979) (xy 376.029288 -245.579853) (xy 375.985214 -245.554407) (xy 375.945792 -245.52222)
			(xy 375.912044 -245.484126) (xy 375.884843 -245.441112) (xy 375.864895 -245.394292) (xy 375.852716 -245.344878)
			(xy 375.848621 -245.29415) (xy 375.530577 -245.29415) (xy 375.526411 -245.34443) (xy 375.514013 -245.393387)
			(xy 375.493727 -245.439635) (xy 375.466105 -245.481914) (xy 375.431901 -245.51907) (xy 375.392047 -245.550089)
			(xy 375.347632 -245.574125) (xy 375.299866 -245.590524) (xy 375.250053 -245.598836) (xy 375.224802 -245.599458)
			(xy 375.200371 -245.598977) (xy 375.152133 -245.591191) (xy 375.12879 -245.583964) (xy 375.121932 -245.581678)
			(xy 375.12117 -245.581424) (xy 375.109419 -245.57795) (xy 375.085162 -245.581154) (xy 375.074688 -245.58752)
			(xy 375.00687 -245.635272) (xy 375.004838 -245.636796) (xy 374.996624 -245.643817) (xy 374.986501 -245.662889)
			(xy 374.98528 -245.673626) (xy 374.98528 -245.87708) (xy 374.985354 -245.88129) (xy 374.986758 -245.889591)
			(xy 374.988074 -245.89359) (xy 374.995948 -245.91645) (xy 375.00052 -245.9228) (xy 375.01456 -245.942622)
			(xy 375.036847 -245.985779) (xy 375.052026 -246.031919) (xy 375.059715 -246.079879) (xy 375.059717 -246.104156)
			(xy 375.378467 -246.104156) (xy 375.382562 -246.053428) (xy 375.394741 -246.004014) (xy 375.414689 -245.957194)
			(xy 375.44189 -245.91418) (xy 375.475638 -245.876086) (xy 375.51506 -245.843899) (xy 375.559134 -245.818453)
			(xy 375.60672 -245.800406) (xy 375.656584 -245.790226) (xy 375.707436 -245.788177) (xy 375.757957 -245.794311)
			(xy 375.806841 -245.808471) (xy 375.85282 -245.830288) (xy 375.894704 -245.859198) (xy 375.931408 -245.894453)
			(xy 375.961981 -245.935139) (xy 375.985632 -245.980202) (xy 376.001748 -246.028476) (xy 376.009912 -246.07871)
			(xy 376.010424 -246.104156) (xy 376.328952 -246.104156) (xy 376.332912 -246.055102) (xy 376.344689 -246.007318)
			(xy 376.36398 -245.962042) (xy 376.390283 -245.920446) (xy 376.422918 -245.883609) (xy 376.461039 -245.852484)
			(xy 376.50366 -245.827877) (xy 376.549676 -245.810425) (xy 376.597895 -245.800581) (xy 376.64707 -245.7986)
			(xy 376.695925 -245.804532) (xy 376.743196 -245.818224) (xy 376.787658 -245.839322) (xy 376.828161 -245.867278)
			(xy 376.863654 -245.90137) (xy 376.893219 -245.940714) (xy 376.91609 -245.984291) (xy 376.931674 -246.030972)
			(xy 376.939569 -246.079549) (xy 376.940064 -246.104156) (xy 377.258575 -246.104156) (xy 377.26267 -246.053428)
			(xy 377.274849 -246.004014) (xy 377.294797 -245.957194) (xy 377.321998 -245.91418) (xy 377.355746 -245.876086)
			(xy 377.395168 -245.843899) (xy 377.439242 -245.818453) (xy 377.486828 -245.800406) (xy 377.536692 -245.790226)
			(xy 377.587544 -245.788177) (xy 377.638065 -245.794311) (xy 377.686949 -245.808471) (xy 377.732928 -245.830288)
			(xy 377.774812 -245.859198) (xy 377.811516 -245.894453) (xy 377.842089 -245.935139) (xy 377.86574 -245.980202)
			(xy 377.881856 -246.028476) (xy 377.89002 -246.07871) (xy 377.890532 -246.104156) (xy 378.20906 -246.104156)
			(xy 378.21302 -246.055102) (xy 378.224797 -246.007318) (xy 378.244088 -245.962042) (xy 378.270391 -245.920446)
			(xy 378.303026 -245.883609) (xy 378.341147 -245.852484) (xy 378.383768 -245.827877) (xy 378.429784 -245.810425)
			(xy 378.478003 -245.800581) (xy 378.527178 -245.7986) (xy 378.576033 -245.804532) (xy 378.623304 -245.818224)
			(xy 378.667766 -245.839322) (xy 378.708269 -245.867278) (xy 378.743762 -245.90137) (xy 378.773327 -245.940714)
			(xy 378.796198 -245.984291) (xy 378.811782 -246.030972) (xy 378.819677 -246.079549) (xy 378.820172 -246.104156)
			(xy 379.138683 -246.104156) (xy 379.142778 -246.053428) (xy 379.154957 -246.004014) (xy 379.174905 -245.957194)
			(xy 379.202106 -245.91418) (xy 379.235854 -245.876086) (xy 379.275276 -245.843899) (xy 379.31935 -245.818453)
			(xy 379.366936 -245.800406) (xy 379.4168 -245.790226) (xy 379.467652 -245.788177) (xy 379.518173 -245.794311)
			(xy 379.567057 -245.808471) (xy 379.613036 -245.830288) (xy 379.65492 -245.859198) (xy 379.691624 -245.894453)
			(xy 379.722197 -245.935139) (xy 379.745848 -245.980202) (xy 379.761964 -246.028476) (xy 379.770128 -246.07871)
			(xy 379.77064 -246.104156) (xy 380.078483 -246.104156) (xy 380.082578 -246.053428) (xy 380.094757 -246.004014)
			(xy 380.114705 -245.957194) (xy 380.141906 -245.91418) (xy 380.175654 -245.876086) (xy 380.215076 -245.843899)
			(xy 380.25915 -245.818453) (xy 380.306736 -245.800406) (xy 380.3566 -245.790226) (xy 380.407452 -245.788177)
			(xy 380.457973 -245.794311) (xy 380.506857 -245.808471) (xy 380.552836 -245.830288) (xy 380.59472 -245.859198)
			(xy 380.631424 -245.894453) (xy 380.661997 -245.935139) (xy 380.685648 -245.980202) (xy 380.701764 -246.028476)
			(xy 380.709928 -246.07871) (xy 380.71044 -246.104156) (xy 381.028968 -246.104156) (xy 381.032928 -246.055102)
			(xy 381.044705 -246.007318) (xy 381.063996 -245.962042) (xy 381.090299 -245.920446) (xy 381.122934 -245.883609)
			(xy 381.161055 -245.852484) (xy 381.203676 -245.827877) (xy 381.249692 -245.810425) (xy 381.297911 -245.800581)
			(xy 381.347086 -245.7986) (xy 381.395941 -245.804532) (xy 381.443212 -245.818224) (xy 381.487674 -245.839322)
			(xy 381.528177 -245.867278) (xy 381.56367 -245.90137) (xy 381.593235 -245.940714) (xy 381.616106 -245.984291)
			(xy 381.63169 -246.030972) (xy 381.639585 -246.079549) (xy 381.64008 -246.104156) (xy 381.958591 -246.104156)
			(xy 381.962686 -246.053428) (xy 381.974865 -246.004014) (xy 381.994813 -245.957194) (xy 382.022014 -245.91418)
			(xy 382.055762 -245.876086) (xy 382.095184 -245.843899) (xy 382.139258 -245.818453) (xy 382.186844 -245.800406)
			(xy 382.236708 -245.790226) (xy 382.28756 -245.788177) (xy 382.338081 -245.794311) (xy 382.386965 -245.808471)
			(xy 382.432944 -245.830288) (xy 382.474828 -245.859198) (xy 382.511532 -245.894453) (xy 382.542105 -245.935139)
			(xy 382.565756 -245.980202) (xy 382.581872 -246.028476) (xy 382.590036 -246.07871) (xy 382.590548 -246.104156)
			(xy 382.909076 -246.104156) (xy 382.913036 -246.055102) (xy 382.924813 -246.007318) (xy 382.944104 -245.962042)
			(xy 382.970407 -245.920446) (xy 383.003042 -245.883609) (xy 383.041163 -245.852484) (xy 383.083784 -245.827877)
			(xy 383.1298 -245.810425) (xy 383.178019 -245.800581) (xy 383.227194 -245.7986) (xy 383.276049 -245.804532)
			(xy 383.32332 -245.818224) (xy 383.367782 -245.839322) (xy 383.408285 -245.867278) (xy 383.443778 -245.90137)
			(xy 383.473343 -245.940714) (xy 383.496214 -245.984291) (xy 383.511798 -246.030972) (xy 383.519693 -246.079549)
			(xy 383.520188 -246.104156) (xy 383.838699 -246.104156) (xy 383.842794 -246.053428) (xy 383.854973 -246.004014)
			(xy 383.874921 -245.957194) (xy 383.902122 -245.91418) (xy 383.93587 -245.876086) (xy 383.975292 -245.843899)
			(xy 384.019366 -245.818453) (xy 384.066952 -245.800406) (xy 384.116816 -245.790226) (xy 384.167668 -245.788177)
			(xy 384.218189 -245.794311) (xy 384.267073 -245.808471) (xy 384.313052 -245.830288) (xy 384.354936 -245.859198)
			(xy 384.39164 -245.894453) (xy 384.422213 -245.935139) (xy 384.445864 -245.980202) (xy 384.46198 -246.028476)
			(xy 384.470144 -246.07871) (xy 384.470656 -246.104156) (xy 384.78893 -246.104156) (xy 384.79289 -246.055102)
			(xy 384.804667 -246.007318) (xy 384.823958 -245.962042) (xy 384.850261 -245.920446) (xy 384.882896 -245.883609)
			(xy 384.921017 -245.852484) (xy 384.963638 -245.827877) (xy 385.009654 -245.810425) (xy 385.057873 -245.800581)
			(xy 385.107048 -245.7986) (xy 385.155903 -245.804532) (xy 385.203174 -245.818224) (xy 385.247636 -245.839322)
			(xy 385.288139 -245.867278) (xy 385.323632 -245.90137) (xy 385.353197 -245.940714) (xy 385.376068 -245.984291)
			(xy 385.391652 -246.030972) (xy 385.399547 -246.079549) (xy 385.400042 -246.104156) (xy 385.718553 -246.104156)
			(xy 385.722648 -246.053428) (xy 385.734827 -246.004014) (xy 385.754775 -245.957194) (xy 385.781976 -245.91418)
			(xy 385.815724 -245.876086) (xy 385.855146 -245.843899) (xy 385.89922 -245.818453) (xy 385.946806 -245.800406)
			(xy 385.99667 -245.790226) (xy 386.047522 -245.788177) (xy 386.098043 -245.794311) (xy 386.146927 -245.808471)
			(xy 386.192906 -245.830288) (xy 386.23479 -245.859198) (xy 386.271494 -245.894453) (xy 386.302067 -245.935139)
			(xy 386.325718 -245.980202) (xy 386.341834 -246.028476) (xy 386.349998 -246.07871) (xy 386.35051 -246.104156)
			(xy 386.658607 -246.104156) (xy 386.662702 -246.053428) (xy 386.674881 -246.004014) (xy 386.694829 -245.957194)
			(xy 386.72203 -245.91418) (xy 386.755778 -245.876086) (xy 386.7952 -245.843899) (xy 386.839274 -245.818453)
			(xy 386.88686 -245.800406) (xy 386.936724 -245.790226) (xy 386.987576 -245.788177) (xy 387.038097 -245.794311)
			(xy 387.086981 -245.808471) (xy 387.13296 -245.830288) (xy 387.174844 -245.859198) (xy 387.211548 -245.894453)
			(xy 387.242121 -245.935139) (xy 387.265772 -245.980202) (xy 387.281888 -246.028476) (xy 387.290052 -246.07871)
			(xy 387.290564 -246.104156) (xy 387.609092 -246.104156) (xy 387.613052 -246.055102) (xy 387.624829 -246.007318)
			(xy 387.64412 -245.962042) (xy 387.670423 -245.920446) (xy 387.703058 -245.883609) (xy 387.741179 -245.852484)
			(xy 387.7838 -245.827877) (xy 387.829816 -245.810425) (xy 387.878035 -245.800581) (xy 387.92721 -245.7986)
			(xy 387.976065 -245.804532) (xy 388.023336 -245.818224) (xy 388.067798 -245.839322) (xy 388.108301 -245.867278)
			(xy 388.143794 -245.90137) (xy 388.173359 -245.940714) (xy 388.19623 -245.984291) (xy 388.211814 -246.030972)
			(xy 388.219709 -246.079549) (xy 388.220204 -246.104156) (xy 388.538715 -246.104156) (xy 388.54281 -246.053428)
			(xy 388.554989 -246.004014) (xy 388.574937 -245.957194) (xy 388.602138 -245.91418) (xy 388.635886 -245.876086)
			(xy 388.675308 -245.843899) (xy 388.719382 -245.818453) (xy 388.766968 -245.800406) (xy 388.816832 -245.790226)
			(xy 388.867684 -245.788177) (xy 388.918205 -245.794311) (xy 388.967089 -245.808471) (xy 389.013068 -245.830288)
			(xy 389.054952 -245.859198) (xy 389.091656 -245.894453) (xy 389.122229 -245.935139) (xy 389.14588 -245.980202)
			(xy 389.161996 -246.028476) (xy 389.17016 -246.07871) (xy 389.170672 -246.104156) (xy 389.488946 -246.104156)
			(xy 389.492906 -246.055102) (xy 389.504683 -246.007318) (xy 389.523974 -245.962042) (xy 389.550277 -245.920446)
			(xy 389.582912 -245.883609) (xy 389.621033 -245.852484) (xy 389.663654 -245.827877) (xy 389.70967 -245.810425)
			(xy 389.757889 -245.800581) (xy 389.807064 -245.7986) (xy 389.855919 -245.804532) (xy 389.90319 -245.818224)
			(xy 389.947652 -245.839322) (xy 389.988155 -245.867278) (xy 390.023648 -245.90137) (xy 390.053213 -245.940714)
			(xy 390.076084 -245.984291) (xy 390.091668 -246.030972) (xy 390.099563 -246.079549) (xy 390.100058 -246.104156)
			(xy 390.418569 -246.104156) (xy 390.422664 -246.053428) (xy 390.434843 -246.004014) (xy 390.454791 -245.957194)
			(xy 390.481992 -245.91418) (xy 390.51574 -245.876086) (xy 390.555162 -245.843899) (xy 390.599236 -245.818453)
			(xy 390.646822 -245.800406) (xy 390.696686 -245.790226) (xy 390.747538 -245.788177) (xy 390.798059 -245.794311)
			(xy 390.846943 -245.808471) (xy 390.892922 -245.830288) (xy 390.934806 -245.859198) (xy 390.97151 -245.894453)
			(xy 391.002083 -245.935139) (xy 391.025734 -245.980202) (xy 391.04185 -246.028476) (xy 391.050014 -246.07871)
			(xy 391.050526 -246.104156) (xy 391.369054 -246.104156) (xy 391.373014 -246.055102) (xy 391.384791 -246.007318)
			(xy 391.404082 -245.962042) (xy 391.430385 -245.920446) (xy 391.46302 -245.883609) (xy 391.501141 -245.852484)
			(xy 391.543762 -245.827877) (xy 391.589778 -245.810425) (xy 391.637997 -245.800581) (xy 391.687172 -245.7986)
			(xy 391.736027 -245.804532) (xy 391.783298 -245.818224) (xy 391.82776 -245.839322) (xy 391.868263 -245.867278)
			(xy 391.903756 -245.90137) (xy 391.933321 -245.940714) (xy 391.956192 -245.984291) (xy 391.971776 -246.030972)
			(xy 391.979671 -246.079549) (xy 391.980166 -246.104156) (xy 391.979671 -246.128763) (xy 391.971776 -246.17734)
			(xy 391.956192 -246.224021) (xy 391.933321 -246.267598) (xy 391.903756 -246.306942) (xy 391.868263 -246.341034)
			(xy 391.82776 -246.36899) (xy 391.825433 -246.370094) (xy 394.377176 -246.370094) (xy 394.381136 -246.32104)
			(xy 394.392913 -246.273256) (xy 394.412204 -246.22798) (xy 394.438507 -246.186384) (xy 394.471142 -246.149547)
			(xy 394.509263 -246.118422) (xy 394.551884 -246.093815) (xy 394.5979 -246.076363) (xy 394.646119 -246.066519)
			(xy 394.695294 -246.064538) (xy 394.744149 -246.07047) (xy 394.79142 -246.084162) (xy 394.835882 -246.10526)
			(xy 394.876385 -246.133216) (xy 394.911878 -246.167308) (xy 394.941443 -246.206652) (xy 394.964314 -246.250229)
			(xy 394.979898 -246.29691) (xy 394.987793 -246.345487) (xy 394.988288 -246.370094) (xy 394.987793 -246.394701)
			(xy 394.979898 -246.443278) (xy 394.964314 -246.489959) (xy 394.941443 -246.533536) (xy 394.911878 -246.57288)
			(xy 394.876385 -246.606972) (xy 394.835882 -246.634928) (xy 394.79142 -246.656026) (xy 394.744149 -246.669718)
			(xy 394.695294 -246.67565) (xy 394.646119 -246.673669) (xy 394.5979 -246.663825) (xy 394.551884 -246.646373)
			(xy 394.509263 -246.621766) (xy 394.471142 -246.590641) (xy 394.438507 -246.553804) (xy 394.412204 -246.512208)
			(xy 394.392913 -246.466932) (xy 394.381136 -246.419148) (xy 394.377176 -246.370094) (xy 391.825433 -246.370094)
			(xy 391.783298 -246.390088) (xy 391.736027 -246.40378) (xy 391.687172 -246.409712) (xy 391.637997 -246.407731)
			(xy 391.589778 -246.397887) (xy 391.543762 -246.380435) (xy 391.501141 -246.355828) (xy 391.46302 -246.324703)
			(xy 391.430385 -246.287866) (xy 391.404082 -246.24627) (xy 391.384791 -246.200994) (xy 391.373014 -246.15321)
			(xy 391.369054 -246.104156) (xy 391.050526 -246.104156) (xy 391.050014 -246.129602) (xy 391.04185 -246.179836)
			(xy 391.025734 -246.22811) (xy 391.002083 -246.273173) (xy 390.97151 -246.313859) (xy 390.934806 -246.349114)
			(xy 390.892922 -246.378024) (xy 390.846943 -246.399841) (xy 390.798059 -246.414001) (xy 390.747538 -246.420135)
			(xy 390.696686 -246.418086) (xy 390.646822 -246.407906) (xy 390.599236 -246.389859) (xy 390.555162 -246.364413)
			(xy 390.51574 -246.332226) (xy 390.481992 -246.294132) (xy 390.454791 -246.251118) (xy 390.434843 -246.204298)
			(xy 390.422664 -246.154884) (xy 390.418569 -246.104156) (xy 390.100058 -246.104156) (xy 390.099563 -246.128763)
			(xy 390.091668 -246.17734) (xy 390.076084 -246.224021) (xy 390.053213 -246.267598) (xy 390.023648 -246.306942)
			(xy 389.988155 -246.341034) (xy 389.947652 -246.36899) (xy 389.90319 -246.390088) (xy 389.855919 -246.40378)
			(xy 389.807064 -246.409712) (xy 389.757889 -246.407731) (xy 389.70967 -246.397887) (xy 389.663654 -246.380435)
			(xy 389.621033 -246.355828) (xy 389.582912 -246.324703) (xy 389.550277 -246.287866) (xy 389.523974 -246.24627)
			(xy 389.504683 -246.200994) (xy 389.492906 -246.15321) (xy 389.488946 -246.104156) (xy 389.170672 -246.104156)
			(xy 389.17016 -246.129602) (xy 389.161996 -246.179836) (xy 389.14588 -246.22811) (xy 389.122229 -246.273173)
			(xy 389.091656 -246.313859) (xy 389.054952 -246.349114) (xy 389.013068 -246.378024) (xy 388.967089 -246.399841)
			(xy 388.918205 -246.414001) (xy 388.867684 -246.420135) (xy 388.816832 -246.418086) (xy 388.766968 -246.407906)
			(xy 388.719382 -246.389859) (xy 388.675308 -246.364413) (xy 388.635886 -246.332226) (xy 388.602138 -246.294132)
			(xy 388.574937 -246.251118) (xy 388.554989 -246.204298) (xy 388.54281 -246.154884) (xy 388.538715 -246.104156)
			(xy 388.220204 -246.104156) (xy 388.219709 -246.128763) (xy 388.211814 -246.17734) (xy 388.19623 -246.224021)
			(xy 388.173359 -246.267598) (xy 388.143794 -246.306942) (xy 388.108301 -246.341034) (xy 388.067798 -246.36899)
			(xy 388.023336 -246.390088) (xy 387.976065 -246.40378) (xy 387.92721 -246.409712) (xy 387.878035 -246.407731)
			(xy 387.829816 -246.397887) (xy 387.7838 -246.380435) (xy 387.741179 -246.355828) (xy 387.703058 -246.324703)
			(xy 387.670423 -246.287866) (xy 387.64412 -246.24627) (xy 387.624829 -246.200994) (xy 387.613052 -246.15321)
			(xy 387.609092 -246.104156) (xy 387.290564 -246.104156) (xy 387.290052 -246.129602) (xy 387.281888 -246.179836)
			(xy 387.265772 -246.22811) (xy 387.242121 -246.273173) (xy 387.211548 -246.313859) (xy 387.174844 -246.349114)
			(xy 387.13296 -246.378024) (xy 387.086981 -246.399841) (xy 387.038097 -246.414001) (xy 386.987576 -246.420135)
			(xy 386.936724 -246.418086) (xy 386.88686 -246.407906) (xy 386.839274 -246.389859) (xy 386.7952 -246.364413)
			(xy 386.755778 -246.332226) (xy 386.72203 -246.294132) (xy 386.694829 -246.251118) (xy 386.674881 -246.204298)
			(xy 386.662702 -246.154884) (xy 386.658607 -246.104156) (xy 386.35051 -246.104156) (xy 386.349998 -246.129602)
			(xy 386.341834 -246.179836) (xy 386.325718 -246.22811) (xy 386.302067 -246.273173) (xy 386.271494 -246.313859)
			(xy 386.23479 -246.349114) (xy 386.192906 -246.378024) (xy 386.146927 -246.399841) (xy 386.098043 -246.414001)
			(xy 386.047522 -246.420135) (xy 385.99667 -246.418086) (xy 385.946806 -246.407906) (xy 385.89922 -246.389859)
			(xy 385.855146 -246.364413) (xy 385.815724 -246.332226) (xy 385.781976 -246.294132) (xy 385.754775 -246.251118)
			(xy 385.734827 -246.204298) (xy 385.722648 -246.154884) (xy 385.718553 -246.104156) (xy 385.400042 -246.104156)
			(xy 385.399547 -246.128763) (xy 385.391652 -246.17734) (xy 385.376068 -246.224021) (xy 385.353197 -246.267598)
			(xy 385.323632 -246.306942) (xy 385.288139 -246.341034) (xy 385.247636 -246.36899) (xy 385.203174 -246.390088)
			(xy 385.155903 -246.40378) (xy 385.107048 -246.409712) (xy 385.057873 -246.407731) (xy 385.009654 -246.397887)
			(xy 384.963638 -246.380435) (xy 384.921017 -246.355828) (xy 384.882896 -246.324703) (xy 384.850261 -246.287866)
			(xy 384.823958 -246.24627) (xy 384.804667 -246.200994) (xy 384.79289 -246.15321) (xy 384.78893 -246.104156)
			(xy 384.470656 -246.104156) (xy 384.470144 -246.129602) (xy 384.46198 -246.179836) (xy 384.445864 -246.22811)
			(xy 384.422213 -246.273173) (xy 384.39164 -246.313859) (xy 384.354936 -246.349114) (xy 384.313052 -246.378024)
			(xy 384.267073 -246.399841) (xy 384.218189 -246.414001) (xy 384.167668 -246.420135) (xy 384.116816 -246.418086)
			(xy 384.066952 -246.407906) (xy 384.019366 -246.389859) (xy 383.975292 -246.364413) (xy 383.93587 -246.332226)
			(xy 383.902122 -246.294132) (xy 383.874921 -246.251118) (xy 383.854973 -246.204298) (xy 383.842794 -246.154884)
			(xy 383.838699 -246.104156) (xy 383.520188 -246.104156) (xy 383.519693 -246.128763) (xy 383.511798 -246.17734)
			(xy 383.496214 -246.224021) (xy 383.473343 -246.267598) (xy 383.443778 -246.306942) (xy 383.408285 -246.341034)
			(xy 383.367782 -246.36899) (xy 383.32332 -246.390088) (xy 383.276049 -246.40378) (xy 383.227194 -246.409712)
			(xy 383.178019 -246.407731) (xy 383.1298 -246.397887) (xy 383.083784 -246.380435) (xy 383.041163 -246.355828)
			(xy 383.003042 -246.324703) (xy 382.970407 -246.287866) (xy 382.944104 -246.24627) (xy 382.924813 -246.200994)
			(xy 382.913036 -246.15321) (xy 382.909076 -246.104156) (xy 382.590548 -246.104156) (xy 382.590036 -246.129602)
			(xy 382.581872 -246.179836) (xy 382.565756 -246.22811) (xy 382.542105 -246.273173) (xy 382.511532 -246.313859)
			(xy 382.474828 -246.349114) (xy 382.432944 -246.378024) (xy 382.386965 -246.399841) (xy 382.338081 -246.414001)
			(xy 382.28756 -246.420135) (xy 382.236708 -246.418086) (xy 382.186844 -246.407906) (xy 382.139258 -246.389859)
			(xy 382.095184 -246.364413) (xy 382.055762 -246.332226) (xy 382.022014 -246.294132) (xy 381.994813 -246.251118)
			(xy 381.974865 -246.204298) (xy 381.962686 -246.154884) (xy 381.958591 -246.104156) (xy 381.64008 -246.104156)
			(xy 381.639585 -246.128763) (xy 381.63169 -246.17734) (xy 381.616106 -246.224021) (xy 381.593235 -246.267598)
			(xy 381.56367 -246.306942) (xy 381.528177 -246.341034) (xy 381.487674 -246.36899) (xy 381.443212 -246.390088)
			(xy 381.395941 -246.40378) (xy 381.347086 -246.409712) (xy 381.297911 -246.407731) (xy 381.249692 -246.397887)
			(xy 381.203676 -246.380435) (xy 381.161055 -246.355828) (xy 381.122934 -246.324703) (xy 381.090299 -246.287866)
			(xy 381.063996 -246.24627) (xy 381.044705 -246.200994) (xy 381.032928 -246.15321) (xy 381.028968 -246.104156)
			(xy 380.71044 -246.104156) (xy 380.709928 -246.129602) (xy 380.701764 -246.179836) (xy 380.685648 -246.22811)
			(xy 380.661997 -246.273173) (xy 380.631424 -246.313859) (xy 380.59472 -246.349114) (xy 380.552836 -246.378024)
			(xy 380.506857 -246.399841) (xy 380.457973 -246.414001) (xy 380.407452 -246.420135) (xy 380.3566 -246.418086)
			(xy 380.306736 -246.407906) (xy 380.25915 -246.389859) (xy 380.215076 -246.364413) (xy 380.175654 -246.332226)
			(xy 380.141906 -246.294132) (xy 380.114705 -246.251118) (xy 380.094757 -246.204298) (xy 380.082578 -246.154884)
			(xy 380.078483 -246.104156) (xy 379.77064 -246.104156) (xy 379.770128 -246.129602) (xy 379.761964 -246.179836)
			(xy 379.745848 -246.22811) (xy 379.722197 -246.273173) (xy 379.691624 -246.313859) (xy 379.65492 -246.349114)
			(xy 379.613036 -246.378024) (xy 379.567057 -246.399841) (xy 379.518173 -246.414001) (xy 379.467652 -246.420135)
			(xy 379.4168 -246.418086) (xy 379.366936 -246.407906) (xy 379.31935 -246.389859) (xy 379.275276 -246.364413)
			(xy 379.235854 -246.332226) (xy 379.202106 -246.294132) (xy 379.174905 -246.251118) (xy 379.154957 -246.204298)
			(xy 379.142778 -246.154884) (xy 379.138683 -246.104156) (xy 378.820172 -246.104156) (xy 378.819677 -246.128763)
			(xy 378.811782 -246.17734) (xy 378.796198 -246.224021) (xy 378.773327 -246.267598) (xy 378.743762 -246.306942)
			(xy 378.708269 -246.341034) (xy 378.667766 -246.36899) (xy 378.623304 -246.390088) (xy 378.576033 -246.40378)
			(xy 378.527178 -246.409712) (xy 378.478003 -246.407731) (xy 378.429784 -246.397887) (xy 378.383768 -246.380435)
			(xy 378.341147 -246.355828) (xy 378.303026 -246.324703) (xy 378.270391 -246.287866) (xy 378.244088 -246.24627)
			(xy 378.224797 -246.200994) (xy 378.21302 -246.15321) (xy 378.20906 -246.104156) (xy 377.890532 -246.104156)
			(xy 377.89002 -246.129602) (xy 377.881856 -246.179836) (xy 377.86574 -246.22811) (xy 377.842089 -246.273173)
			(xy 377.811516 -246.313859) (xy 377.774812 -246.349114) (xy 377.732928 -246.378024) (xy 377.686949 -246.399841)
			(xy 377.638065 -246.414001) (xy 377.587544 -246.420135) (xy 377.536692 -246.418086) (xy 377.486828 -246.407906)
			(xy 377.439242 -246.389859) (xy 377.395168 -246.364413) (xy 377.355746 -246.332226) (xy 377.321998 -246.294132)
			(xy 377.294797 -246.251118) (xy 377.274849 -246.204298) (xy 377.26267 -246.154884) (xy 377.258575 -246.104156)
			(xy 376.940064 -246.104156) (xy 376.939569 -246.128763) (xy 376.931674 -246.17734) (xy 376.91609 -246.224021)
			(xy 376.893219 -246.267598) (xy 376.863654 -246.306942) (xy 376.828161 -246.341034) (xy 376.787658 -246.36899)
			(xy 376.743196 -246.390088) (xy 376.695925 -246.40378) (xy 376.64707 -246.409712) (xy 376.597895 -246.407731)
			(xy 376.549676 -246.397887) (xy 376.50366 -246.380435) (xy 376.461039 -246.355828) (xy 376.422918 -246.324703)
			(xy 376.390283 -246.287866) (xy 376.36398 -246.24627) (xy 376.344689 -246.200994) (xy 376.332912 -246.15321)
			(xy 376.328952 -246.104156) (xy 376.010424 -246.104156) (xy 376.009912 -246.129602) (xy 376.001748 -246.179836)
			(xy 375.985632 -246.22811) (xy 375.961981 -246.273173) (xy 375.931408 -246.313859) (xy 375.894704 -246.349114)
			(xy 375.85282 -246.378024) (xy 375.806841 -246.399841) (xy 375.757957 -246.414001) (xy 375.707436 -246.420135)
			(xy 375.656584 -246.418086) (xy 375.60672 -246.407906) (xy 375.559134 -246.389859) (xy 375.51506 -246.364413)
			(xy 375.475638 -246.332226) (xy 375.44189 -246.294132) (xy 375.414689 -246.251118) (xy 375.394741 -246.204298)
			(xy 375.382562 -246.154884) (xy 375.378467 -246.104156) (xy 375.059717 -246.104156) (xy 375.05972 -246.128451)
			(xy 375.052042 -246.176412) (xy 375.036874 -246.222555) (xy 375.014597 -246.265718) (xy 375.00052 -246.285512)
			(xy 374.995948 -246.291862) (xy 374.988074 -246.314722) (xy 374.986794 -246.31873) (xy 374.985397 -246.327026)
			(xy 374.98528 -246.331232) (xy 374.98528 -246.914162) (xy 375.848621 -246.914162) (xy 375.852716 -246.863434)
			(xy 375.864895 -246.81402) (xy 375.884843 -246.7672) (xy 375.912044 -246.724186) (xy 375.945792 -246.686092)
			(xy 375.985214 -246.653905) (xy 376.029288 -246.628459) (xy 376.076874 -246.610412) (xy 376.126738 -246.600232)
			(xy 376.17759 -246.598183) (xy 376.228111 -246.604317) (xy 376.276995 -246.618477) (xy 376.322974 -246.640294)
			(xy 376.364858 -246.669204) (xy 376.401562 -246.704459) (xy 376.432135 -246.745145) (xy 376.455786 -246.790208)
			(xy 376.471902 -246.838482) (xy 376.480066 -246.888716) (xy 376.480578 -246.914162) (xy 376.788675 -246.914162)
			(xy 376.79277 -246.863434) (xy 376.804949 -246.81402) (xy 376.824897 -246.7672) (xy 376.852098 -246.724186)
			(xy 376.885846 -246.686092) (xy 376.925268 -246.653905) (xy 376.969342 -246.628459) (xy 377.016928 -246.610412)
			(xy 377.066792 -246.600232) (xy 377.117644 -246.598183) (xy 377.168165 -246.604317) (xy 377.217049 -246.618477)
			(xy 377.263028 -246.640294) (xy 377.304912 -246.669204) (xy 377.341616 -246.704459) (xy 377.372189 -246.745145)
			(xy 377.39584 -246.790208) (xy 377.411956 -246.838482) (xy 377.42012 -246.888716) (xy 377.420632 -246.914162)
			(xy 378.668529 -246.914162) (xy 378.672624 -246.863434) (xy 378.684803 -246.81402) (xy 378.704751 -246.7672)
			(xy 378.731952 -246.724186) (xy 378.7657 -246.686092) (xy 378.805122 -246.653905) (xy 378.849196 -246.628459)
			(xy 378.896782 -246.610412) (xy 378.946646 -246.600232) (xy 378.997498 -246.598183) (xy 379.048019 -246.604317)
			(xy 379.096903 -246.618477) (xy 379.142882 -246.640294) (xy 379.184766 -246.669204) (xy 379.22147 -246.704459)
			(xy 379.252043 -246.745145) (xy 379.275694 -246.790208) (xy 379.29181 -246.838482) (xy 379.299974 -246.888716)
			(xy 379.300486 -246.914162) (xy 379.619014 -246.914162) (xy 379.622974 -246.865108) (xy 379.634751 -246.817324)
			(xy 379.654042 -246.772048) (xy 379.680345 -246.730452) (xy 379.71298 -246.693615) (xy 379.751101 -246.66249)
			(xy 379.793722 -246.637883) (xy 379.839738 -246.620431) (xy 379.887957 -246.610587) (xy 379.937132 -246.608606)
			(xy 379.985987 -246.614538) (xy 380.033258 -246.62823) (xy 380.07772 -246.649328) (xy 380.118223 -246.677284)
			(xy 380.153716 -246.711376) (xy 380.183281 -246.75072) (xy 380.206152 -246.794297) (xy 380.221736 -246.840978)
			(xy 380.229631 -246.889555) (xy 380.230126 -246.914162) (xy 380.548637 -246.914162) (xy 380.552732 -246.863434)
			(xy 380.564911 -246.81402) (xy 380.584859 -246.7672) (xy 380.61206 -246.724186) (xy 380.645808 -246.686092)
			(xy 380.68523 -246.653905) (xy 380.729304 -246.628459) (xy 380.77689 -246.610412) (xy 380.826754 -246.600232)
			(xy 380.877606 -246.598183) (xy 380.928127 -246.604317) (xy 380.977011 -246.618477) (xy 381.02299 -246.640294)
			(xy 381.064874 -246.669204) (xy 381.101578 -246.704459) (xy 381.132151 -246.745145) (xy 381.155802 -246.790208)
			(xy 381.171918 -246.838482) (xy 381.180082 -246.888716) (xy 381.180594 -246.914162) (xy 381.499122 -246.914162)
			(xy 381.503082 -246.865108) (xy 381.514859 -246.817324) (xy 381.53415 -246.772048) (xy 381.560453 -246.730452)
			(xy 381.593088 -246.693615) (xy 381.631209 -246.66249) (xy 381.67383 -246.637883) (xy 381.719846 -246.620431)
			(xy 381.768065 -246.610587) (xy 381.81724 -246.608606) (xy 381.866095 -246.614538) (xy 381.913366 -246.62823)
			(xy 381.957828 -246.649328) (xy 381.998331 -246.677284) (xy 382.033824 -246.711376) (xy 382.063389 -246.75072)
			(xy 382.08626 -246.794297) (xy 382.101844 -246.840978) (xy 382.109739 -246.889555) (xy 382.110234 -246.914162)
			(xy 382.428491 -246.914162) (xy 382.432586 -246.863434) (xy 382.444765 -246.81402) (xy 382.464713 -246.7672)
			(xy 382.491914 -246.724186) (xy 382.525662 -246.686092) (xy 382.565084 -246.653905) (xy 382.609158 -246.628459)
			(xy 382.656744 -246.610412) (xy 382.706608 -246.600232) (xy 382.75746 -246.598183) (xy 382.807981 -246.604317)
			(xy 382.856865 -246.618477) (xy 382.902844 -246.640294) (xy 382.944728 -246.669204) (xy 382.981432 -246.704459)
			(xy 383.012005 -246.745145) (xy 383.035656 -246.790208) (xy 383.051772 -246.838482) (xy 383.059936 -246.888716)
			(xy 383.060448 -246.914162) (xy 383.368545 -246.914162) (xy 383.37264 -246.863434) (xy 383.384819 -246.81402)
			(xy 383.404767 -246.7672) (xy 383.431968 -246.724186) (xy 383.465716 -246.686092) (xy 383.505138 -246.653905)
			(xy 383.549212 -246.628459) (xy 383.596798 -246.610412) (xy 383.646662 -246.600232) (xy 383.697514 -246.598183)
			(xy 383.748035 -246.604317) (xy 383.796919 -246.618477) (xy 383.842898 -246.640294) (xy 383.884782 -246.669204)
			(xy 383.921486 -246.704459) (xy 383.952059 -246.745145) (xy 383.97571 -246.790208) (xy 383.991826 -246.838482)
			(xy 383.99999 -246.888716) (xy 384.000502 -246.914162) (xy 385.248653 -246.914162) (xy 385.252748 -246.863434)
			(xy 385.264927 -246.81402) (xy 385.284875 -246.7672) (xy 385.312076 -246.724186) (xy 385.345824 -246.686092)
			(xy 385.385246 -246.653905) (xy 385.42932 -246.628459) (xy 385.476906 -246.610412) (xy 385.52677 -246.600232)
			(xy 385.577622 -246.598183) (xy 385.628143 -246.604317) (xy 385.677027 -246.618477) (xy 385.723006 -246.640294)
			(xy 385.76489 -246.669204) (xy 385.801594 -246.704459) (xy 385.832167 -246.745145) (xy 385.855818 -246.790208)
			(xy 385.871934 -246.838482) (xy 385.880098 -246.888716) (xy 385.88061 -246.914162) (xy 386.199138 -246.914162)
			(xy 386.203098 -246.865108) (xy 386.214875 -246.817324) (xy 386.234166 -246.772048) (xy 386.260469 -246.730452)
			(xy 386.293104 -246.693615) (xy 386.331225 -246.66249) (xy 386.373846 -246.637883) (xy 386.419862 -246.620431)
			(xy 386.468081 -246.610587) (xy 386.517256 -246.608606) (xy 386.566111 -246.614538) (xy 386.613382 -246.62823)
			(xy 386.657844 -246.649328) (xy 386.698347 -246.677284) (xy 386.73384 -246.711376) (xy 386.763405 -246.75072)
			(xy 386.786276 -246.794297) (xy 386.80186 -246.840978) (xy 386.809755 -246.889555) (xy 386.81025 -246.914162)
			(xy 387.128507 -246.914162) (xy 387.132602 -246.863434) (xy 387.144781 -246.81402) (xy 387.164729 -246.7672)
			(xy 387.19193 -246.724186) (xy 387.225678 -246.686092) (xy 387.2651 -246.653905) (xy 387.309174 -246.628459)
			(xy 387.35676 -246.610412) (xy 387.406624 -246.600232) (xy 387.457476 -246.598183) (xy 387.507997 -246.604317)
			(xy 387.556881 -246.618477) (xy 387.60286 -246.640294) (xy 387.644744 -246.669204) (xy 387.681448 -246.704459)
			(xy 387.712021 -246.745145) (xy 387.735672 -246.790208) (xy 387.751788 -246.838482) (xy 387.759952 -246.888716)
			(xy 387.760464 -246.914162) (xy 388.078992 -246.914162) (xy 388.082952 -246.865108) (xy 388.094729 -246.817324)
			(xy 388.11402 -246.772048) (xy 388.140323 -246.730452) (xy 388.172958 -246.693615) (xy 388.211079 -246.66249)
			(xy 388.2537 -246.637883) (xy 388.299716 -246.620431) (xy 388.347935 -246.610587) (xy 388.39711 -246.608606)
			(xy 388.445965 -246.614538) (xy 388.493236 -246.62823) (xy 388.537698 -246.649328) (xy 388.578201 -246.677284)
			(xy 388.613694 -246.711376) (xy 388.643259 -246.75072) (xy 388.66613 -246.794297) (xy 388.681714 -246.840978)
			(xy 388.689609 -246.889555) (xy 388.690104 -246.914162) (xy 389.008615 -246.914162) (xy 389.01271 -246.863434)
			(xy 389.024889 -246.81402) (xy 389.044837 -246.7672) (xy 389.072038 -246.724186) (xy 389.105786 -246.686092)
			(xy 389.145208 -246.653905) (xy 389.189282 -246.628459) (xy 389.236868 -246.610412) (xy 389.286732 -246.600232)
			(xy 389.337584 -246.598183) (xy 389.388105 -246.604317) (xy 389.436989 -246.618477) (xy 389.482968 -246.640294)
			(xy 389.524852 -246.669204) (xy 389.561556 -246.704459) (xy 389.592129 -246.745145) (xy 389.61578 -246.790208)
			(xy 389.631896 -246.838482) (xy 389.64006 -246.888716) (xy 389.640572 -246.914162) (xy 389.948669 -246.914162)
			(xy 389.952764 -246.863434) (xy 389.964943 -246.81402) (xy 389.984891 -246.7672) (xy 390.012092 -246.724186)
			(xy 390.04584 -246.686092) (xy 390.085262 -246.653905) (xy 390.129336 -246.628459) (xy 390.176922 -246.610412)
			(xy 390.226786 -246.600232) (xy 390.277638 -246.598183) (xy 390.328159 -246.604317) (xy 390.377043 -246.618477)
			(xy 390.423022 -246.640294) (xy 390.464906 -246.669204) (xy 390.50161 -246.704459) (xy 390.532183 -246.745145)
			(xy 390.555834 -246.790208) (xy 390.57195 -246.838482) (xy 390.580114 -246.888716) (xy 390.580626 -246.914162)
			(xy 392.779008 -246.914162) (xy 392.782968 -246.865108) (xy 392.794745 -246.817324) (xy 392.814036 -246.772048)
			(xy 392.840339 -246.730452) (xy 392.872974 -246.693615) (xy 392.911095 -246.66249) (xy 392.953716 -246.637883)
			(xy 392.999732 -246.620431) (xy 393.047951 -246.610587) (xy 393.097126 -246.608606) (xy 393.145981 -246.614538)
			(xy 393.193252 -246.62823) (xy 393.237714 -246.649328) (xy 393.278217 -246.677284) (xy 393.31371 -246.711376)
			(xy 393.343275 -246.75072) (xy 393.366146 -246.794297) (xy 393.38173 -246.840978) (xy 393.389625 -246.889555)
			(xy 393.39012 -246.914162) (xy 393.389625 -246.938769) (xy 393.38173 -246.987346) (xy 393.366146 -247.034027)
			(xy 393.343275 -247.077604) (xy 393.31371 -247.116948) (xy 393.278217 -247.15104) (xy 393.237714 -247.178996)
			(xy 393.193252 -247.200094) (xy 393.145981 -247.213786) (xy 393.097126 -247.219718) (xy 393.047951 -247.217737)
			(xy 392.999732 -247.207893) (xy 392.953716 -247.190441) (xy 392.911095 -247.165834) (xy 392.872974 -247.134709)
			(xy 392.840339 -247.097872) (xy 392.814036 -247.056276) (xy 392.794745 -247.011) (xy 392.782968 -246.963216)
			(xy 392.779008 -246.914162) (xy 390.580626 -246.914162) (xy 390.580114 -246.939608) (xy 390.57195 -246.989842)
			(xy 390.555834 -247.038116) (xy 390.532183 -247.083179) (xy 390.50161 -247.123865) (xy 390.464906 -247.15912)
			(xy 390.423022 -247.18803) (xy 390.377043 -247.209847) (xy 390.328159 -247.224007) (xy 390.277638 -247.230141)
			(xy 390.226786 -247.228092) (xy 390.176922 -247.217912) (xy 390.129336 -247.199865) (xy 390.085262 -247.174419)
			(xy 390.04584 -247.142232) (xy 390.012092 -247.104138) (xy 389.984891 -247.061124) (xy 389.964943 -247.014304)
			(xy 389.952764 -246.96489) (xy 389.948669 -246.914162) (xy 389.640572 -246.914162) (xy 389.64006 -246.939608)
			(xy 389.631896 -246.989842) (xy 389.61578 -247.038116) (xy 389.592129 -247.083179) (xy 389.561556 -247.123865)
			(xy 389.524852 -247.15912) (xy 389.482968 -247.18803) (xy 389.436989 -247.209847) (xy 389.388105 -247.224007)
			(xy 389.337584 -247.230141) (xy 389.286732 -247.228092) (xy 389.236868 -247.217912) (xy 389.189282 -247.199865)
			(xy 389.145208 -247.174419) (xy 389.105786 -247.142232) (xy 389.072038 -247.104138) (xy 389.044837 -247.061124)
			(xy 389.024889 -247.014304) (xy 389.01271 -246.96489) (xy 389.008615 -246.914162) (xy 388.690104 -246.914162)
			(xy 388.689609 -246.938769) (xy 388.681714 -246.987346) (xy 388.66613 -247.034027) (xy 388.643259 -247.077604)
			(xy 388.613694 -247.116948) (xy 388.578201 -247.15104) (xy 388.537698 -247.178996) (xy 388.493236 -247.200094)
			(xy 388.445965 -247.213786) (xy 388.39711 -247.219718) (xy 388.347935 -247.217737) (xy 388.299716 -247.207893)
			(xy 388.2537 -247.190441) (xy 388.211079 -247.165834) (xy 388.172958 -247.134709) (xy 388.140323 -247.097872)
			(xy 388.11402 -247.056276) (xy 388.094729 -247.011) (xy 388.082952 -246.963216) (xy 388.078992 -246.914162)
			(xy 387.760464 -246.914162) (xy 387.759952 -246.939608) (xy 387.751788 -246.989842) (xy 387.735672 -247.038116)
			(xy 387.712021 -247.083179) (xy 387.681448 -247.123865) (xy 387.644744 -247.15912) (xy 387.60286 -247.18803)
			(xy 387.556881 -247.209847) (xy 387.507997 -247.224007) (xy 387.457476 -247.230141) (xy 387.406624 -247.228092)
			(xy 387.35676 -247.217912) (xy 387.309174 -247.199865) (xy 387.2651 -247.174419) (xy 387.225678 -247.142232)
			(xy 387.19193 -247.104138) (xy 387.164729 -247.061124) (xy 387.144781 -247.014304) (xy 387.132602 -246.96489)
			(xy 387.128507 -246.914162) (xy 386.81025 -246.914162) (xy 386.809755 -246.938769) (xy 386.80186 -246.987346)
			(xy 386.786276 -247.034027) (xy 386.763405 -247.077604) (xy 386.73384 -247.116948) (xy 386.698347 -247.15104)
			(xy 386.657844 -247.178996) (xy 386.613382 -247.200094) (xy 386.566111 -247.213786) (xy 386.517256 -247.219718)
			(xy 386.468081 -247.217737) (xy 386.419862 -247.207893) (xy 386.373846 -247.190441) (xy 386.331225 -247.165834)
			(xy 386.293104 -247.134709) (xy 386.260469 -247.097872) (xy 386.234166 -247.056276) (xy 386.214875 -247.011)
			(xy 386.203098 -246.963216) (xy 386.199138 -246.914162) (xy 385.88061 -246.914162) (xy 385.880098 -246.939608)
			(xy 385.871934 -246.989842) (xy 385.855818 -247.038116) (xy 385.832167 -247.083179) (xy 385.801594 -247.123865)
			(xy 385.76489 -247.15912) (xy 385.723006 -247.18803) (xy 385.677027 -247.209847) (xy 385.628143 -247.224007)
			(xy 385.577622 -247.230141) (xy 385.52677 -247.228092) (xy 385.476906 -247.217912) (xy 385.42932 -247.199865)
			(xy 385.385246 -247.174419) (xy 385.345824 -247.142232) (xy 385.312076 -247.104138) (xy 385.284875 -247.061124)
			(xy 385.264927 -247.014304) (xy 385.252748 -246.96489) (xy 385.248653 -246.914162) (xy 384.000502 -246.914162)
			(xy 383.99999 -246.939608) (xy 383.991826 -246.989842) (xy 383.97571 -247.038116) (xy 383.952059 -247.083179)
			(xy 383.921486 -247.123865) (xy 383.884782 -247.15912) (xy 383.842898 -247.18803) (xy 383.796919 -247.209847)
			(xy 383.748035 -247.224007) (xy 383.697514 -247.230141) (xy 383.646662 -247.228092) (xy 383.596798 -247.217912)
			(xy 383.549212 -247.199865) (xy 383.505138 -247.174419) (xy 383.465716 -247.142232) (xy 383.431968 -247.104138)
			(xy 383.404767 -247.061124) (xy 383.384819 -247.014304) (xy 383.37264 -246.96489) (xy 383.368545 -246.914162)
			(xy 383.060448 -246.914162) (xy 383.059936 -246.939608) (xy 383.051772 -246.989842) (xy 383.035656 -247.038116)
			(xy 383.012005 -247.083179) (xy 382.981432 -247.123865) (xy 382.944728 -247.15912) (xy 382.902844 -247.18803)
			(xy 382.856865 -247.209847) (xy 382.807981 -247.224007) (xy 382.75746 -247.230141) (xy 382.706608 -247.228092)
			(xy 382.656744 -247.217912) (xy 382.609158 -247.199865) (xy 382.565084 -247.174419) (xy 382.525662 -247.142232)
			(xy 382.491914 -247.104138) (xy 382.464713 -247.061124) (xy 382.444765 -247.014304) (xy 382.432586 -246.96489)
			(xy 382.428491 -246.914162) (xy 382.110234 -246.914162) (xy 382.109739 -246.938769) (xy 382.101844 -246.987346)
			(xy 382.08626 -247.034027) (xy 382.063389 -247.077604) (xy 382.033824 -247.116948) (xy 381.998331 -247.15104)
			(xy 381.957828 -247.178996) (xy 381.913366 -247.200094) (xy 381.866095 -247.213786) (xy 381.81724 -247.219718)
			(xy 381.768065 -247.217737) (xy 381.719846 -247.207893) (xy 381.67383 -247.190441) (xy 381.631209 -247.165834)
			(xy 381.593088 -247.134709) (xy 381.560453 -247.097872) (xy 381.53415 -247.056276) (xy 381.514859 -247.011)
			(xy 381.503082 -246.963216) (xy 381.499122 -246.914162) (xy 381.180594 -246.914162) (xy 381.180082 -246.939608)
			(xy 381.171918 -246.989842) (xy 381.155802 -247.038116) (xy 381.132151 -247.083179) (xy 381.101578 -247.123865)
			(xy 381.064874 -247.15912) (xy 381.02299 -247.18803) (xy 380.977011 -247.209847) (xy 380.928127 -247.224007)
			(xy 380.877606 -247.230141) (xy 380.826754 -247.228092) (xy 380.77689 -247.217912) (xy 380.729304 -247.199865)
			(xy 380.68523 -247.174419) (xy 380.645808 -247.142232) (xy 380.61206 -247.104138) (xy 380.584859 -247.061124)
			(xy 380.564911 -247.014304) (xy 380.552732 -246.96489) (xy 380.548637 -246.914162) (xy 380.230126 -246.914162)
			(xy 380.229631 -246.938769) (xy 380.221736 -246.987346) (xy 380.206152 -247.034027) (xy 380.183281 -247.077604)
			(xy 380.153716 -247.116948) (xy 380.118223 -247.15104) (xy 380.07772 -247.178996) (xy 380.033258 -247.200094)
			(xy 379.985987 -247.213786) (xy 379.937132 -247.219718) (xy 379.887957 -247.217737) (xy 379.839738 -247.207893)
			(xy 379.793722 -247.190441) (xy 379.751101 -247.165834) (xy 379.71298 -247.134709) (xy 379.680345 -247.097872)
			(xy 379.654042 -247.056276) (xy 379.634751 -247.011) (xy 379.622974 -246.963216) (xy 379.619014 -246.914162)
			(xy 379.300486 -246.914162) (xy 379.299974 -246.939608) (xy 379.29181 -246.989842) (xy 379.275694 -247.038116)
			(xy 379.252043 -247.083179) (xy 379.22147 -247.123865) (xy 379.184766 -247.15912) (xy 379.142882 -247.18803)
			(xy 379.096903 -247.209847) (xy 379.048019 -247.224007) (xy 378.997498 -247.230141) (xy 378.946646 -247.228092)
			(xy 378.896782 -247.217912) (xy 378.849196 -247.199865) (xy 378.805122 -247.174419) (xy 378.7657 -247.142232)
			(xy 378.731952 -247.104138) (xy 378.704751 -247.061124) (xy 378.684803 -247.014304) (xy 378.672624 -246.96489)
			(xy 378.668529 -246.914162) (xy 377.420632 -246.914162) (xy 377.42012 -246.939608) (xy 377.411956 -246.989842)
			(xy 377.39584 -247.038116) (xy 377.372189 -247.083179) (xy 377.341616 -247.123865) (xy 377.304912 -247.15912)
			(xy 377.263028 -247.18803) (xy 377.217049 -247.209847) (xy 377.168165 -247.224007) (xy 377.117644 -247.230141)
			(xy 377.066792 -247.228092) (xy 377.016928 -247.217912) (xy 376.969342 -247.199865) (xy 376.925268 -247.174419)
			(xy 376.885846 -247.142232) (xy 376.852098 -247.104138) (xy 376.824897 -247.061124) (xy 376.804949 -247.014304)
			(xy 376.79277 -246.96489) (xy 376.788675 -246.914162) (xy 376.480578 -246.914162) (xy 376.480066 -246.939608)
			(xy 376.471902 -246.989842) (xy 376.455786 -247.038116) (xy 376.432135 -247.083179) (xy 376.401562 -247.123865)
			(xy 376.364858 -247.15912) (xy 376.322974 -247.18803) (xy 376.276995 -247.209847) (xy 376.228111 -247.224007)
			(xy 376.17759 -247.230141) (xy 376.126738 -247.228092) (xy 376.076874 -247.217912) (xy 376.029288 -247.199865)
			(xy 375.985214 -247.174419) (xy 375.945792 -247.142232) (xy 375.912044 -247.104138) (xy 375.884843 -247.061124)
			(xy 375.864895 -247.014304) (xy 375.852716 -246.96489) (xy 375.848621 -246.914162) (xy 374.98528 -246.914162)
			(xy 374.98528 -247.497092) (xy 374.985355 -247.501301) (xy 374.98676 -247.509602) (xy 374.988074 -247.513602)
			(xy 374.995948 -247.536462) (xy 375.00052 -247.542812) (xy 375.014559 -247.562634) (xy 375.036844 -247.605791)
			(xy 375.052021 -247.65193) (xy 375.059709 -247.699889) (xy 375.059711 -247.724168) (xy 375.378467 -247.724168)
			(xy 375.382562 -247.67344) (xy 375.394741 -247.624026) (xy 375.414689 -247.577206) (xy 375.44189 -247.534192)
			(xy 375.475638 -247.496098) (xy 375.51506 -247.463911) (xy 375.559134 -247.438465) (xy 375.60672 -247.420418)
			(xy 375.656584 -247.410238) (xy 375.707436 -247.408189) (xy 375.757957 -247.414323) (xy 375.806841 -247.428483)
			(xy 375.85282 -247.4503) (xy 375.894704 -247.47921) (xy 375.931408 -247.514465) (xy 375.961981 -247.555151)
			(xy 375.985632 -247.600214) (xy 376.001748 -247.648488) (xy 376.009912 -247.698722) (xy 376.010424 -247.724168)
			(xy 376.328952 -247.724168) (xy 376.332912 -247.675114) (xy 376.344689 -247.62733) (xy 376.36398 -247.582054)
			(xy 376.390283 -247.540458) (xy 376.422918 -247.503621) (xy 376.461039 -247.472496) (xy 376.50366 -247.447889)
			(xy 376.549676 -247.430437) (xy 376.597895 -247.420593) (xy 376.64707 -247.418612) (xy 376.695925 -247.424544)
			(xy 376.743196 -247.438236) (xy 376.787658 -247.459334) (xy 376.828161 -247.48729) (xy 376.863654 -247.521382)
			(xy 376.893219 -247.560726) (xy 376.91609 -247.604303) (xy 376.931674 -247.650984) (xy 376.939569 -247.699561)
			(xy 376.940064 -247.724168) (xy 377.258575 -247.724168) (xy 377.26267 -247.67344) (xy 377.274849 -247.624026)
			(xy 377.294797 -247.577206) (xy 377.321998 -247.534192) (xy 377.355746 -247.496098) (xy 377.395168 -247.463911)
			(xy 377.439242 -247.438465) (xy 377.486828 -247.420418) (xy 377.536692 -247.410238) (xy 377.587544 -247.408189)
			(xy 377.638065 -247.414323) (xy 377.686949 -247.428483) (xy 377.732928 -247.4503) (xy 377.774812 -247.47921)
			(xy 377.811516 -247.514465) (xy 377.842089 -247.555151) (xy 377.86574 -247.600214) (xy 377.881856 -247.648488)
			(xy 377.89002 -247.698722) (xy 377.890532 -247.724168) (xy 378.20906 -247.724168) (xy 378.21302 -247.675114)
			(xy 378.224797 -247.62733) (xy 378.244088 -247.582054) (xy 378.270391 -247.540458) (xy 378.303026 -247.503621)
			(xy 378.341147 -247.472496) (xy 378.383768 -247.447889) (xy 378.429784 -247.430437) (xy 378.478003 -247.420593)
			(xy 378.527178 -247.418612) (xy 378.576033 -247.424544) (xy 378.623304 -247.438236) (xy 378.667766 -247.459334)
			(xy 378.708269 -247.48729) (xy 378.743762 -247.521382) (xy 378.773327 -247.560726) (xy 378.796198 -247.604303)
			(xy 378.811782 -247.650984) (xy 378.819677 -247.699561) (xy 378.820172 -247.724168) (xy 379.138683 -247.724168)
			(xy 379.142778 -247.67344) (xy 379.154957 -247.624026) (xy 379.174905 -247.577206) (xy 379.202106 -247.534192)
			(xy 379.235854 -247.496098) (xy 379.275276 -247.463911) (xy 379.31935 -247.438465) (xy 379.366936 -247.420418)
			(xy 379.4168 -247.410238) (xy 379.467652 -247.408189) (xy 379.518173 -247.414323) (xy 379.567057 -247.428483)
			(xy 379.613036 -247.4503) (xy 379.65492 -247.47921) (xy 379.691624 -247.514465) (xy 379.722197 -247.555151)
			(xy 379.745848 -247.600214) (xy 379.761964 -247.648488) (xy 379.770128 -247.698722) (xy 379.77064 -247.724168)
			(xy 380.078483 -247.724168) (xy 380.082578 -247.67344) (xy 380.094757 -247.624026) (xy 380.114705 -247.577206)
			(xy 380.141906 -247.534192) (xy 380.175654 -247.496098) (xy 380.215076 -247.463911) (xy 380.25915 -247.438465)
			(xy 380.306736 -247.420418) (xy 380.3566 -247.410238) (xy 380.407452 -247.408189) (xy 380.457973 -247.414323)
			(xy 380.506857 -247.428483) (xy 380.552836 -247.4503) (xy 380.59472 -247.47921) (xy 380.631424 -247.514465)
			(xy 380.661997 -247.555151) (xy 380.685648 -247.600214) (xy 380.701764 -247.648488) (xy 380.709928 -247.698722)
			(xy 380.71044 -247.724168) (xy 381.028968 -247.724168) (xy 381.032928 -247.675114) (xy 381.044705 -247.62733)
			(xy 381.063996 -247.582054) (xy 381.090299 -247.540458) (xy 381.122934 -247.503621) (xy 381.161055 -247.472496)
			(xy 381.203676 -247.447889) (xy 381.249692 -247.430437) (xy 381.297911 -247.420593) (xy 381.347086 -247.418612)
			(xy 381.395941 -247.424544) (xy 381.443212 -247.438236) (xy 381.487674 -247.459334) (xy 381.528177 -247.48729)
			(xy 381.56367 -247.521382) (xy 381.593235 -247.560726) (xy 381.616106 -247.604303) (xy 381.63169 -247.650984)
			(xy 381.639585 -247.699561) (xy 381.64008 -247.724168) (xy 381.958591 -247.724168) (xy 381.962686 -247.67344)
			(xy 381.974865 -247.624026) (xy 381.994813 -247.577206) (xy 382.022014 -247.534192) (xy 382.055762 -247.496098)
			(xy 382.095184 -247.463911) (xy 382.139258 -247.438465) (xy 382.186844 -247.420418) (xy 382.236708 -247.410238)
			(xy 382.28756 -247.408189) (xy 382.338081 -247.414323) (xy 382.386965 -247.428483) (xy 382.432944 -247.4503)
			(xy 382.474828 -247.47921) (xy 382.511532 -247.514465) (xy 382.542105 -247.555151) (xy 382.565756 -247.600214)
			(xy 382.581872 -247.648488) (xy 382.590036 -247.698722) (xy 382.590548 -247.724168) (xy 382.909076 -247.724168)
			(xy 382.913036 -247.675114) (xy 382.924813 -247.62733) (xy 382.944104 -247.582054) (xy 382.970407 -247.540458)
			(xy 383.003042 -247.503621) (xy 383.041163 -247.472496) (xy 383.083784 -247.447889) (xy 383.1298 -247.430437)
			(xy 383.178019 -247.420593) (xy 383.227194 -247.418612) (xy 383.276049 -247.424544) (xy 383.32332 -247.438236)
			(xy 383.367782 -247.459334) (xy 383.408285 -247.48729) (xy 383.443778 -247.521382) (xy 383.473343 -247.560726)
			(xy 383.496214 -247.604303) (xy 383.511798 -247.650984) (xy 383.519693 -247.699561) (xy 383.520188 -247.724168)
			(xy 383.838699 -247.724168) (xy 383.842794 -247.67344) (xy 383.854973 -247.624026) (xy 383.874921 -247.577206)
			(xy 383.902122 -247.534192) (xy 383.93587 -247.496098) (xy 383.975292 -247.463911) (xy 384.019366 -247.438465)
			(xy 384.066952 -247.420418) (xy 384.116816 -247.410238) (xy 384.167668 -247.408189) (xy 384.218189 -247.414323)
			(xy 384.267073 -247.428483) (xy 384.313052 -247.4503) (xy 384.354936 -247.47921) (xy 384.39164 -247.514465)
			(xy 384.422213 -247.555151) (xy 384.445864 -247.600214) (xy 384.46198 -247.648488) (xy 384.470144 -247.698722)
			(xy 384.470656 -247.724168) (xy 384.78893 -247.724168) (xy 384.79289 -247.675114) (xy 384.804667 -247.62733)
			(xy 384.823958 -247.582054) (xy 384.850261 -247.540458) (xy 384.882896 -247.503621) (xy 384.921017 -247.472496)
			(xy 384.963638 -247.447889) (xy 385.009654 -247.430437) (xy 385.057873 -247.420593) (xy 385.107048 -247.418612)
			(xy 385.155903 -247.424544) (xy 385.203174 -247.438236) (xy 385.247636 -247.459334) (xy 385.288139 -247.48729)
			(xy 385.323632 -247.521382) (xy 385.353197 -247.560726) (xy 385.376068 -247.604303) (xy 385.391652 -247.650984)
			(xy 385.399547 -247.699561) (xy 385.400042 -247.724168) (xy 385.718553 -247.724168) (xy 385.722648 -247.67344)
			(xy 385.734827 -247.624026) (xy 385.754775 -247.577206) (xy 385.781976 -247.534192) (xy 385.815724 -247.496098)
			(xy 385.855146 -247.463911) (xy 385.89922 -247.438465) (xy 385.946806 -247.420418) (xy 385.99667 -247.410238)
			(xy 386.047522 -247.408189) (xy 386.098043 -247.414323) (xy 386.146927 -247.428483) (xy 386.192906 -247.4503)
			(xy 386.23479 -247.47921) (xy 386.271494 -247.514465) (xy 386.302067 -247.555151) (xy 386.325718 -247.600214)
			(xy 386.341834 -247.648488) (xy 386.349998 -247.698722) (xy 386.35051 -247.724168) (xy 386.658607 -247.724168)
			(xy 386.662702 -247.67344) (xy 386.674881 -247.624026) (xy 386.694829 -247.577206) (xy 386.72203 -247.534192)
			(xy 386.755778 -247.496098) (xy 386.7952 -247.463911) (xy 386.839274 -247.438465) (xy 386.88686 -247.420418)
			(xy 386.936724 -247.410238) (xy 386.987576 -247.408189) (xy 387.038097 -247.414323) (xy 387.086981 -247.428483)
			(xy 387.13296 -247.4503) (xy 387.174844 -247.47921) (xy 387.211548 -247.514465) (xy 387.242121 -247.555151)
			(xy 387.265772 -247.600214) (xy 387.281888 -247.648488) (xy 387.290052 -247.698722) (xy 387.290564 -247.724168)
			(xy 387.609092 -247.724168) (xy 387.613052 -247.675114) (xy 387.624829 -247.62733) (xy 387.64412 -247.582054)
			(xy 387.670423 -247.540458) (xy 387.703058 -247.503621) (xy 387.741179 -247.472496) (xy 387.7838 -247.447889)
			(xy 387.829816 -247.430437) (xy 387.878035 -247.420593) (xy 387.92721 -247.418612) (xy 387.976065 -247.424544)
			(xy 388.023336 -247.438236) (xy 388.067798 -247.459334) (xy 388.108301 -247.48729) (xy 388.143794 -247.521382)
			(xy 388.173359 -247.560726) (xy 388.19623 -247.604303) (xy 388.211814 -247.650984) (xy 388.219709 -247.699561)
			(xy 388.220204 -247.724168) (xy 388.538715 -247.724168) (xy 388.54281 -247.67344) (xy 388.554989 -247.624026)
			(xy 388.574937 -247.577206) (xy 388.602138 -247.534192) (xy 388.635886 -247.496098) (xy 388.675308 -247.463911)
			(xy 388.719382 -247.438465) (xy 388.766968 -247.420418) (xy 388.816832 -247.410238) (xy 388.867684 -247.408189)
			(xy 388.918205 -247.414323) (xy 388.967089 -247.428483) (xy 389.013068 -247.4503) (xy 389.054952 -247.47921)
			(xy 389.091656 -247.514465) (xy 389.122229 -247.555151) (xy 389.14588 -247.600214) (xy 389.161996 -247.648488)
			(xy 389.17016 -247.698722) (xy 389.170672 -247.724168) (xy 389.488946 -247.724168) (xy 389.492906 -247.675114)
			(xy 389.504683 -247.62733) (xy 389.523974 -247.582054) (xy 389.550277 -247.540458) (xy 389.582912 -247.503621)
			(xy 389.621033 -247.472496) (xy 389.663654 -247.447889) (xy 389.70967 -247.430437) (xy 389.757889 -247.420593)
			(xy 389.807064 -247.418612) (xy 389.855919 -247.424544) (xy 389.90319 -247.438236) (xy 389.947652 -247.459334)
			(xy 389.988155 -247.48729) (xy 390.023648 -247.521382) (xy 390.053213 -247.560726) (xy 390.076084 -247.604303)
			(xy 390.091668 -247.650984) (xy 390.099563 -247.699561) (xy 390.100058 -247.724168) (xy 390.418569 -247.724168)
			(xy 390.422664 -247.67344) (xy 390.434843 -247.624026) (xy 390.454791 -247.577206) (xy 390.481992 -247.534192)
			(xy 390.51574 -247.496098) (xy 390.555162 -247.463911) (xy 390.599236 -247.438465) (xy 390.646822 -247.420418)
			(xy 390.696686 -247.410238) (xy 390.747538 -247.408189) (xy 390.798059 -247.414323) (xy 390.846943 -247.428483)
			(xy 390.892922 -247.4503) (xy 390.934806 -247.47921) (xy 390.97151 -247.514465) (xy 391.002083 -247.555151)
			(xy 391.025734 -247.600214) (xy 391.04185 -247.648488) (xy 391.050014 -247.698722) (xy 391.050526 -247.724168)
			(xy 391.369054 -247.724168) (xy 391.373014 -247.675114) (xy 391.384791 -247.62733) (xy 391.404082 -247.582054)
			(xy 391.430385 -247.540458) (xy 391.46302 -247.503621) (xy 391.501141 -247.472496) (xy 391.543762 -247.447889)
			(xy 391.589778 -247.430437) (xy 391.637997 -247.420593) (xy 391.687172 -247.418612) (xy 391.736027 -247.424544)
			(xy 391.783298 -247.438236) (xy 391.82776 -247.459334) (xy 391.868263 -247.48729) (xy 391.903756 -247.521382)
			(xy 391.933321 -247.560726) (xy 391.956192 -247.604303) (xy 391.971776 -247.650984) (xy 391.979671 -247.699561)
			(xy 391.980166 -247.724168) (xy 391.979671 -247.748775) (xy 391.971776 -247.797352) (xy 391.956192 -247.844033)
			(xy 391.933321 -247.88761) (xy 391.903756 -247.926954) (xy 391.868263 -247.961046) (xy 391.82776 -247.989002)
			(xy 391.825433 -247.990106) (xy 394.377176 -247.990106) (xy 394.381136 -247.941052) (xy 394.392913 -247.893268)
			(xy 394.412204 -247.847992) (xy 394.438507 -247.806396) (xy 394.471142 -247.769559) (xy 394.509263 -247.738434)
			(xy 394.551884 -247.713827) (xy 394.5979 -247.696375) (xy 394.646119 -247.686531) (xy 394.695294 -247.68455)
			(xy 394.744149 -247.690482) (xy 394.79142 -247.704174) (xy 394.835882 -247.725272) (xy 394.876385 -247.753228)
			(xy 394.911878 -247.78732) (xy 394.941443 -247.826664) (xy 394.964314 -247.870241) (xy 394.979898 -247.916922)
			(xy 394.987793 -247.965499) (xy 394.988288 -247.990106) (xy 394.987793 -248.014713) (xy 394.979898 -248.06329)
			(xy 394.964314 -248.109971) (xy 394.941443 -248.153548) (xy 394.911878 -248.192892) (xy 394.876385 -248.226984)
			(xy 394.835882 -248.25494) (xy 394.79142 -248.276038) (xy 394.744149 -248.28973) (xy 394.695294 -248.295662)
			(xy 394.646119 -248.293681) (xy 394.5979 -248.283837) (xy 394.551884 -248.266385) (xy 394.509263 -248.241778)
			(xy 394.471142 -248.210653) (xy 394.438507 -248.173816) (xy 394.412204 -248.13222) (xy 394.392913 -248.086944)
			(xy 394.381136 -248.03916) (xy 394.377176 -247.990106) (xy 391.825433 -247.990106) (xy 391.783298 -248.0101)
			(xy 391.736027 -248.023792) (xy 391.687172 -248.029724) (xy 391.637997 -248.027743) (xy 391.589778 -248.017899)
			(xy 391.543762 -248.000447) (xy 391.501141 -247.97584) (xy 391.46302 -247.944715) (xy 391.430385 -247.907878)
			(xy 391.404082 -247.866282) (xy 391.384791 -247.821006) (xy 391.373014 -247.773222) (xy 391.369054 -247.724168)
			(xy 391.050526 -247.724168) (xy 391.050014 -247.749614) (xy 391.04185 -247.799848) (xy 391.025734 -247.848122)
			(xy 391.002083 -247.893185) (xy 390.97151 -247.933871) (xy 390.934806 -247.969126) (xy 390.892922 -247.998036)
			(xy 390.846943 -248.019853) (xy 390.798059 -248.034013) (xy 390.747538 -248.040147) (xy 390.696686 -248.038098)
			(xy 390.646822 -248.027918) (xy 390.599236 -248.009871) (xy 390.555162 -247.984425) (xy 390.51574 -247.952238)
			(xy 390.481992 -247.914144) (xy 390.454791 -247.87113) (xy 390.434843 -247.82431) (xy 390.422664 -247.774896)
			(xy 390.418569 -247.724168) (xy 390.100058 -247.724168) (xy 390.099563 -247.748775) (xy 390.091668 -247.797352)
			(xy 390.076084 -247.844033) (xy 390.053213 -247.88761) (xy 390.023648 -247.926954) (xy 389.988155 -247.961046)
			(xy 389.947652 -247.989002) (xy 389.90319 -248.0101) (xy 389.855919 -248.023792) (xy 389.807064 -248.029724)
			(xy 389.757889 -248.027743) (xy 389.70967 -248.017899) (xy 389.663654 -248.000447) (xy 389.621033 -247.97584)
			(xy 389.582912 -247.944715) (xy 389.550277 -247.907878) (xy 389.523974 -247.866282) (xy 389.504683 -247.821006)
			(xy 389.492906 -247.773222) (xy 389.488946 -247.724168) (xy 389.170672 -247.724168) (xy 389.17016 -247.749614)
			(xy 389.161996 -247.799848) (xy 389.14588 -247.848122) (xy 389.122229 -247.893185) (xy 389.091656 -247.933871)
			(xy 389.054952 -247.969126) (xy 389.013068 -247.998036) (xy 388.967089 -248.019853) (xy 388.918205 -248.034013)
			(xy 388.867684 -248.040147) (xy 388.816832 -248.038098) (xy 388.766968 -248.027918) (xy 388.719382 -248.009871)
			(xy 388.675308 -247.984425) (xy 388.635886 -247.952238) (xy 388.602138 -247.914144) (xy 388.574937 -247.87113)
			(xy 388.554989 -247.82431) (xy 388.54281 -247.774896) (xy 388.538715 -247.724168) (xy 388.220204 -247.724168)
			(xy 388.219709 -247.748775) (xy 388.211814 -247.797352) (xy 388.19623 -247.844033) (xy 388.173359 -247.88761)
			(xy 388.143794 -247.926954) (xy 388.108301 -247.961046) (xy 388.067798 -247.989002) (xy 388.023336 -248.0101)
			(xy 387.976065 -248.023792) (xy 387.92721 -248.029724) (xy 387.878035 -248.027743) (xy 387.829816 -248.017899)
			(xy 387.7838 -248.000447) (xy 387.741179 -247.97584) (xy 387.703058 -247.944715) (xy 387.670423 -247.907878)
			(xy 387.64412 -247.866282) (xy 387.624829 -247.821006) (xy 387.613052 -247.773222) (xy 387.609092 -247.724168)
			(xy 387.290564 -247.724168) (xy 387.290052 -247.749614) (xy 387.281888 -247.799848) (xy 387.265772 -247.848122)
			(xy 387.242121 -247.893185) (xy 387.211548 -247.933871) (xy 387.174844 -247.969126) (xy 387.13296 -247.998036)
			(xy 387.086981 -248.019853) (xy 387.038097 -248.034013) (xy 386.987576 -248.040147) (xy 386.936724 -248.038098)
			(xy 386.88686 -248.027918) (xy 386.839274 -248.009871) (xy 386.7952 -247.984425) (xy 386.755778 -247.952238)
			(xy 386.72203 -247.914144) (xy 386.694829 -247.87113) (xy 386.674881 -247.82431) (xy 386.662702 -247.774896)
			(xy 386.658607 -247.724168) (xy 386.35051 -247.724168) (xy 386.349998 -247.749614) (xy 386.341834 -247.799848)
			(xy 386.325718 -247.848122) (xy 386.302067 -247.893185) (xy 386.271494 -247.933871) (xy 386.23479 -247.969126)
			(xy 386.192906 -247.998036) (xy 386.146927 -248.019853) (xy 386.098043 -248.034013) (xy 386.047522 -248.040147)
			(xy 385.99667 -248.038098) (xy 385.946806 -248.027918) (xy 385.89922 -248.009871) (xy 385.855146 -247.984425)
			(xy 385.815724 -247.952238) (xy 385.781976 -247.914144) (xy 385.754775 -247.87113) (xy 385.734827 -247.82431)
			(xy 385.722648 -247.774896) (xy 385.718553 -247.724168) (xy 385.400042 -247.724168) (xy 385.399547 -247.748775)
			(xy 385.391652 -247.797352) (xy 385.376068 -247.844033) (xy 385.353197 -247.88761) (xy 385.323632 -247.926954)
			(xy 385.288139 -247.961046) (xy 385.247636 -247.989002) (xy 385.203174 -248.0101) (xy 385.155903 -248.023792)
			(xy 385.107048 -248.029724) (xy 385.057873 -248.027743) (xy 385.009654 -248.017899) (xy 384.963638 -248.000447)
			(xy 384.921017 -247.97584) (xy 384.882896 -247.944715) (xy 384.850261 -247.907878) (xy 384.823958 -247.866282)
			(xy 384.804667 -247.821006) (xy 384.79289 -247.773222) (xy 384.78893 -247.724168) (xy 384.470656 -247.724168)
			(xy 384.470144 -247.749614) (xy 384.46198 -247.799848) (xy 384.445864 -247.848122) (xy 384.422213 -247.893185)
			(xy 384.39164 -247.933871) (xy 384.354936 -247.969126) (xy 384.313052 -247.998036) (xy 384.267073 -248.019853)
			(xy 384.218189 -248.034013) (xy 384.167668 -248.040147) (xy 384.116816 -248.038098) (xy 384.066952 -248.027918)
			(xy 384.019366 -248.009871) (xy 383.975292 -247.984425) (xy 383.93587 -247.952238) (xy 383.902122 -247.914144)
			(xy 383.874921 -247.87113) (xy 383.854973 -247.82431) (xy 383.842794 -247.774896) (xy 383.838699 -247.724168)
			(xy 383.520188 -247.724168) (xy 383.519693 -247.748775) (xy 383.511798 -247.797352) (xy 383.496214 -247.844033)
			(xy 383.473343 -247.88761) (xy 383.443778 -247.926954) (xy 383.408285 -247.961046) (xy 383.367782 -247.989002)
			(xy 383.32332 -248.0101) (xy 383.276049 -248.023792) (xy 383.227194 -248.029724) (xy 383.178019 -248.027743)
			(xy 383.1298 -248.017899) (xy 383.083784 -248.000447) (xy 383.041163 -247.97584) (xy 383.003042 -247.944715)
			(xy 382.970407 -247.907878) (xy 382.944104 -247.866282) (xy 382.924813 -247.821006) (xy 382.913036 -247.773222)
			(xy 382.909076 -247.724168) (xy 382.590548 -247.724168) (xy 382.590036 -247.749614) (xy 382.581872 -247.799848)
			(xy 382.565756 -247.848122) (xy 382.542105 -247.893185) (xy 382.511532 -247.933871) (xy 382.474828 -247.969126)
			(xy 382.432944 -247.998036) (xy 382.386965 -248.019853) (xy 382.338081 -248.034013) (xy 382.28756 -248.040147)
			(xy 382.236708 -248.038098) (xy 382.186844 -248.027918) (xy 382.139258 -248.009871) (xy 382.095184 -247.984425)
			(xy 382.055762 -247.952238) (xy 382.022014 -247.914144) (xy 381.994813 -247.87113) (xy 381.974865 -247.82431)
			(xy 381.962686 -247.774896) (xy 381.958591 -247.724168) (xy 381.64008 -247.724168) (xy 381.639585 -247.748775)
			(xy 381.63169 -247.797352) (xy 381.616106 -247.844033) (xy 381.593235 -247.88761) (xy 381.56367 -247.926954)
			(xy 381.528177 -247.961046) (xy 381.487674 -247.989002) (xy 381.443212 -248.0101) (xy 381.395941 -248.023792)
			(xy 381.347086 -248.029724) (xy 381.297911 -248.027743) (xy 381.249692 -248.017899) (xy 381.203676 -248.000447)
			(xy 381.161055 -247.97584) (xy 381.122934 -247.944715) (xy 381.090299 -247.907878) (xy 381.063996 -247.866282)
			(xy 381.044705 -247.821006) (xy 381.032928 -247.773222) (xy 381.028968 -247.724168) (xy 380.71044 -247.724168)
			(xy 380.709928 -247.749614) (xy 380.701764 -247.799848) (xy 380.685648 -247.848122) (xy 380.661997 -247.893185)
			(xy 380.631424 -247.933871) (xy 380.59472 -247.969126) (xy 380.552836 -247.998036) (xy 380.506857 -248.019853)
			(xy 380.457973 -248.034013) (xy 380.407452 -248.040147) (xy 380.3566 -248.038098) (xy 380.306736 -248.027918)
			(xy 380.25915 -248.009871) (xy 380.215076 -247.984425) (xy 380.175654 -247.952238) (xy 380.141906 -247.914144)
			(xy 380.114705 -247.87113) (xy 380.094757 -247.82431) (xy 380.082578 -247.774896) (xy 380.078483 -247.724168)
			(xy 379.77064 -247.724168) (xy 379.770128 -247.749614) (xy 379.761964 -247.799848) (xy 379.745848 -247.848122)
			(xy 379.722197 -247.893185) (xy 379.691624 -247.933871) (xy 379.65492 -247.969126) (xy 379.613036 -247.998036)
			(xy 379.567057 -248.019853) (xy 379.518173 -248.034013) (xy 379.467652 -248.040147) (xy 379.4168 -248.038098)
			(xy 379.366936 -248.027918) (xy 379.31935 -248.009871) (xy 379.275276 -247.984425) (xy 379.235854 -247.952238)
			(xy 379.202106 -247.914144) (xy 379.174905 -247.87113) (xy 379.154957 -247.82431) (xy 379.142778 -247.774896)
			(xy 379.138683 -247.724168) (xy 378.820172 -247.724168) (xy 378.819677 -247.748775) (xy 378.811782 -247.797352)
			(xy 378.796198 -247.844033) (xy 378.773327 -247.88761) (xy 378.743762 -247.926954) (xy 378.708269 -247.961046)
			(xy 378.667766 -247.989002) (xy 378.623304 -248.0101) (xy 378.576033 -248.023792) (xy 378.527178 -248.029724)
			(xy 378.478003 -248.027743) (xy 378.429784 -248.017899) (xy 378.383768 -248.000447) (xy 378.341147 -247.97584)
			(xy 378.303026 -247.944715) (xy 378.270391 -247.907878) (xy 378.244088 -247.866282) (xy 378.224797 -247.821006)
			(xy 378.21302 -247.773222) (xy 378.20906 -247.724168) (xy 377.890532 -247.724168) (xy 377.89002 -247.749614)
			(xy 377.881856 -247.799848) (xy 377.86574 -247.848122) (xy 377.842089 -247.893185) (xy 377.811516 -247.933871)
			(xy 377.774812 -247.969126) (xy 377.732928 -247.998036) (xy 377.686949 -248.019853) (xy 377.638065 -248.034013)
			(xy 377.587544 -248.040147) (xy 377.536692 -248.038098) (xy 377.486828 -248.027918) (xy 377.439242 -248.009871)
			(xy 377.395168 -247.984425) (xy 377.355746 -247.952238) (xy 377.321998 -247.914144) (xy 377.294797 -247.87113)
			(xy 377.274849 -247.82431) (xy 377.26267 -247.774896) (xy 377.258575 -247.724168) (xy 376.940064 -247.724168)
			(xy 376.939569 -247.748775) (xy 376.931674 -247.797352) (xy 376.91609 -247.844033) (xy 376.893219 -247.88761)
			(xy 376.863654 -247.926954) (xy 376.828161 -247.961046) (xy 376.787658 -247.989002) (xy 376.743196 -248.0101)
			(xy 376.695925 -248.023792) (xy 376.64707 -248.029724) (xy 376.597895 -248.027743) (xy 376.549676 -248.017899)
			(xy 376.50366 -248.000447) (xy 376.461039 -247.97584) (xy 376.422918 -247.944715) (xy 376.390283 -247.907878)
			(xy 376.36398 -247.866282) (xy 376.344689 -247.821006) (xy 376.332912 -247.773222) (xy 376.328952 -247.724168)
			(xy 376.010424 -247.724168) (xy 376.009912 -247.749614) (xy 376.001748 -247.799848) (xy 375.985632 -247.848122)
			(xy 375.961981 -247.893185) (xy 375.931408 -247.933871) (xy 375.894704 -247.969126) (xy 375.85282 -247.998036)
			(xy 375.806841 -248.019853) (xy 375.757957 -248.034013) (xy 375.707436 -248.040147) (xy 375.656584 -248.038098)
			(xy 375.60672 -248.027918) (xy 375.559134 -248.009871) (xy 375.51506 -247.984425) (xy 375.475638 -247.952238)
			(xy 375.44189 -247.914144) (xy 375.414689 -247.87113) (xy 375.394741 -247.82431) (xy 375.382562 -247.774896)
			(xy 375.378467 -247.724168) (xy 375.059711 -247.724168) (xy 375.059713 -247.74846) (xy 375.052033 -247.79642)
			(xy 375.036864 -247.842561) (xy 375.014586 -247.885722) (xy 375.00052 -247.905524) (xy 374.995948 -247.911874)
			(xy 374.988074 -247.934734) (xy 374.986787 -247.938741) (xy 374.985376 -247.947037) (xy 374.98528 -247.951244)
			(xy 374.98528 -248.151396) (xy 374.98528 -248.154698) (xy 374.986462 -248.165448) (xy 374.996589 -248.184535)
			(xy 375.004838 -248.191528) (xy 375.00687 -248.193052) (xy 375.074688 -248.240804) (xy 375.085076 -248.247381)
			(xy 375.109431 -248.250561) (xy 375.12117 -248.2469) (xy 375.121932 -248.246646) (xy 375.12879 -248.24436)
			(xy 375.152133 -248.237136) (xy 375.200371 -248.229357) (xy 375.224802 -248.228866) (xy 375.250059 -248.229388)
			(xy 375.299885 -248.237703) (xy 375.347663 -248.254105) (xy 375.392089 -248.278147) (xy 375.431952 -248.309174)
			(xy 375.466165 -248.346339) (xy 375.493794 -248.388629) (xy 375.514085 -248.434889) (xy 375.526486 -248.483858)
			(xy 375.530655 -248.534174) (xy 375.848621 -248.534174) (xy 375.852716 -248.483446) (xy 375.864895 -248.434032)
			(xy 375.884843 -248.387212) (xy 375.912044 -248.344198) (xy 375.945792 -248.306104) (xy 375.985214 -248.273917)
			(xy 376.029288 -248.248471) (xy 376.076874 -248.230424) (xy 376.126738 -248.220244) (xy 376.17759 -248.218195)
			(xy 376.228111 -248.224329) (xy 376.276995 -248.238489) (xy 376.322974 -248.260306) (xy 376.364858 -248.289216)
			(xy 376.401562 -248.324471) (xy 376.432135 -248.365157) (xy 376.455786 -248.41022) (xy 376.471902 -248.458494)
			(xy 376.480066 -248.508728) (xy 376.480578 -248.534174) (xy 376.788675 -248.534174) (xy 376.79277 -248.483446)
			(xy 376.804949 -248.434032) (xy 376.824897 -248.387212) (xy 376.852098 -248.344198) (xy 376.885846 -248.306104)
			(xy 376.925268 -248.273917) (xy 376.969342 -248.248471) (xy 377.016928 -248.230424) (xy 377.066792 -248.220244)
			(xy 377.117644 -248.218195) (xy 377.168165 -248.224329) (xy 377.217049 -248.238489) (xy 377.263028 -248.260306)
			(xy 377.304912 -248.289216) (xy 377.341616 -248.324471) (xy 377.372189 -248.365157) (xy 377.39584 -248.41022)
			(xy 377.411956 -248.458494) (xy 377.42012 -248.508728) (xy 377.420632 -248.534174) (xy 377.738906 -248.534174)
			(xy 377.742866 -248.48512) (xy 377.754643 -248.437336) (xy 377.773934 -248.39206) (xy 377.800237 -248.350464)
			(xy 377.832872 -248.313627) (xy 377.870993 -248.282502) (xy 377.913614 -248.257895) (xy 377.95963 -248.240443)
			(xy 378.007849 -248.230599) (xy 378.057024 -248.228618) (xy 378.105879 -248.23455) (xy 378.15315 -248.248242)
			(xy 378.197612 -248.26934) (xy 378.238115 -248.297296) (xy 378.273608 -248.331388) (xy 378.303173 -248.370732)
			(xy 378.326044 -248.414309) (xy 378.341628 -248.46099) (xy 378.349523 -248.509567) (xy 378.350018 -248.534174)
			(xy 378.668529 -248.534174) (xy 378.672624 -248.483446) (xy 378.684803 -248.434032) (xy 378.704751 -248.387212)
			(xy 378.731952 -248.344198) (xy 378.7657 -248.306104) (xy 378.805122 -248.273917) (xy 378.849196 -248.248471)
			(xy 378.896782 -248.230424) (xy 378.946646 -248.220244) (xy 378.997498 -248.218195) (xy 379.048019 -248.224329)
			(xy 379.096903 -248.238489) (xy 379.142882 -248.260306) (xy 379.184766 -248.289216) (xy 379.22147 -248.324471)
			(xy 379.252043 -248.365157) (xy 379.275694 -248.41022) (xy 379.29181 -248.458494) (xy 379.299974 -248.508728)
			(xy 379.300486 -248.534174) (xy 379.619014 -248.534174) (xy 379.622974 -248.48512) (xy 379.634751 -248.437336)
			(xy 379.654042 -248.39206) (xy 379.680345 -248.350464) (xy 379.71298 -248.313627) (xy 379.751101 -248.282502)
			(xy 379.793722 -248.257895) (xy 379.839738 -248.240443) (xy 379.887957 -248.230599) (xy 379.937132 -248.228618)
			(xy 379.985987 -248.23455) (xy 380.033258 -248.248242) (xy 380.07772 -248.26934) (xy 380.118223 -248.297296)
			(xy 380.153716 -248.331388) (xy 380.183281 -248.370732) (xy 380.206152 -248.414309) (xy 380.221736 -248.46099)
			(xy 380.229631 -248.509567) (xy 380.230126 -248.534174) (xy 380.548637 -248.534174) (xy 380.552732 -248.483446)
			(xy 380.564911 -248.434032) (xy 380.584859 -248.387212) (xy 380.61206 -248.344198) (xy 380.645808 -248.306104)
			(xy 380.68523 -248.273917) (xy 380.729304 -248.248471) (xy 380.77689 -248.230424) (xy 380.826754 -248.220244)
			(xy 380.877606 -248.218195) (xy 380.928127 -248.224329) (xy 380.977011 -248.238489) (xy 381.02299 -248.260306)
			(xy 381.064874 -248.289216) (xy 381.101578 -248.324471) (xy 381.132151 -248.365157) (xy 381.155802 -248.41022)
			(xy 381.171918 -248.458494) (xy 381.180082 -248.508728) (xy 381.180594 -248.534174) (xy 381.499122 -248.534174)
			(xy 381.503082 -248.48512) (xy 381.514859 -248.437336) (xy 381.53415 -248.39206) (xy 381.560453 -248.350464)
			(xy 381.593088 -248.313627) (xy 381.631209 -248.282502) (xy 381.67383 -248.257895) (xy 381.719846 -248.240443)
			(xy 381.768065 -248.230599) (xy 381.81724 -248.228618) (xy 381.866095 -248.23455) (xy 381.913366 -248.248242)
			(xy 381.957828 -248.26934) (xy 381.998331 -248.297296) (xy 382.033824 -248.331388) (xy 382.063389 -248.370732)
			(xy 382.08626 -248.414309) (xy 382.101844 -248.46099) (xy 382.109739 -248.509567) (xy 382.110234 -248.534174)
			(xy 382.428491 -248.534174) (xy 382.432586 -248.483446) (xy 382.444765 -248.434032) (xy 382.464713 -248.387212)
			(xy 382.491914 -248.344198) (xy 382.525662 -248.306104) (xy 382.565084 -248.273917) (xy 382.609158 -248.248471)
			(xy 382.656744 -248.230424) (xy 382.706608 -248.220244) (xy 382.75746 -248.218195) (xy 382.807981 -248.224329)
			(xy 382.856865 -248.238489) (xy 382.902844 -248.260306) (xy 382.944728 -248.289216) (xy 382.981432 -248.324471)
			(xy 383.012005 -248.365157) (xy 383.035656 -248.41022) (xy 383.051772 -248.458494) (xy 383.059936 -248.508728)
			(xy 383.060448 -248.534174) (xy 383.368545 -248.534174) (xy 383.37264 -248.483446) (xy 383.384819 -248.434032)
			(xy 383.404767 -248.387212) (xy 383.431968 -248.344198) (xy 383.465716 -248.306104) (xy 383.505138 -248.273917)
			(xy 383.549212 -248.248471) (xy 383.596798 -248.230424) (xy 383.646662 -248.220244) (xy 383.697514 -248.218195)
			(xy 383.748035 -248.224329) (xy 383.796919 -248.238489) (xy 383.842898 -248.260306) (xy 383.884782 -248.289216)
			(xy 383.921486 -248.324471) (xy 383.952059 -248.365157) (xy 383.97571 -248.41022) (xy 383.991826 -248.458494)
			(xy 383.99999 -248.508728) (xy 384.000502 -248.534174) (xy 384.31903 -248.534174) (xy 384.32299 -248.48512)
			(xy 384.334767 -248.437336) (xy 384.354058 -248.39206) (xy 384.380361 -248.350464) (xy 384.412996 -248.313627)
			(xy 384.451117 -248.282502) (xy 384.493738 -248.257895) (xy 384.539754 -248.240443) (xy 384.587973 -248.230599)
			(xy 384.637148 -248.228618) (xy 384.686003 -248.23455) (xy 384.733274 -248.248242) (xy 384.777736 -248.26934)
			(xy 384.818239 -248.297296) (xy 384.853732 -248.331388) (xy 384.883297 -248.370732) (xy 384.906168 -248.414309)
			(xy 384.921752 -248.46099) (xy 384.929647 -248.509567) (xy 384.930142 -248.534174) (xy 385.248653 -248.534174)
			(xy 385.252748 -248.483446) (xy 385.264927 -248.434032) (xy 385.284875 -248.387212) (xy 385.312076 -248.344198)
			(xy 385.345824 -248.306104) (xy 385.385246 -248.273917) (xy 385.42932 -248.248471) (xy 385.476906 -248.230424)
			(xy 385.52677 -248.220244) (xy 385.577622 -248.218195) (xy 385.628143 -248.224329) (xy 385.677027 -248.238489)
			(xy 385.723006 -248.260306) (xy 385.76489 -248.289216) (xy 385.801594 -248.324471) (xy 385.832167 -248.365157)
			(xy 385.855818 -248.41022) (xy 385.871934 -248.458494) (xy 385.880098 -248.508728) (xy 385.88061 -248.534174)
			(xy 386.199138 -248.534174) (xy 386.203098 -248.48512) (xy 386.214875 -248.437336) (xy 386.234166 -248.39206)
			(xy 386.260469 -248.350464) (xy 386.293104 -248.313627) (xy 386.331225 -248.282502) (xy 386.373846 -248.257895)
			(xy 386.419862 -248.240443) (xy 386.468081 -248.230599) (xy 386.517256 -248.228618) (xy 386.566111 -248.23455)
			(xy 386.613382 -248.248242) (xy 386.657844 -248.26934) (xy 386.698347 -248.297296) (xy 386.73384 -248.331388)
			(xy 386.763405 -248.370732) (xy 386.786276 -248.414309) (xy 386.80186 -248.46099) (xy 386.809755 -248.509567)
			(xy 386.81025 -248.534174) (xy 387.128507 -248.534174) (xy 387.132602 -248.483446) (xy 387.144781 -248.434032)
			(xy 387.164729 -248.387212) (xy 387.19193 -248.344198) (xy 387.225678 -248.306104) (xy 387.2651 -248.273917)
			(xy 387.309174 -248.248471) (xy 387.35676 -248.230424) (xy 387.406624 -248.220244) (xy 387.457476 -248.218195)
			(xy 387.507997 -248.224329) (xy 387.556881 -248.238489) (xy 387.60286 -248.260306) (xy 387.644744 -248.289216)
			(xy 387.681448 -248.324471) (xy 387.712021 -248.365157) (xy 387.735672 -248.41022) (xy 387.751788 -248.458494)
			(xy 387.759952 -248.508728) (xy 387.760464 -248.534174) (xy 388.078992 -248.534174) (xy 388.082952 -248.48512)
			(xy 388.094729 -248.437336) (xy 388.11402 -248.39206) (xy 388.140323 -248.350464) (xy 388.172958 -248.313627)
			(xy 388.211079 -248.282502) (xy 388.2537 -248.257895) (xy 388.299716 -248.240443) (xy 388.347935 -248.230599)
			(xy 388.39711 -248.228618) (xy 388.445965 -248.23455) (xy 388.493236 -248.248242) (xy 388.537698 -248.26934)
			(xy 388.578201 -248.297296) (xy 388.613694 -248.331388) (xy 388.643259 -248.370732) (xy 388.66613 -248.414309)
			(xy 388.681714 -248.46099) (xy 388.689609 -248.509567) (xy 388.690104 -248.534174) (xy 389.008615 -248.534174)
			(xy 389.01271 -248.483446) (xy 389.024889 -248.434032) (xy 389.044837 -248.387212) (xy 389.072038 -248.344198)
			(xy 389.105786 -248.306104) (xy 389.145208 -248.273917) (xy 389.189282 -248.248471) (xy 389.236868 -248.230424)
			(xy 389.286732 -248.220244) (xy 389.337584 -248.218195) (xy 389.388105 -248.224329) (xy 389.436989 -248.238489)
			(xy 389.482968 -248.260306) (xy 389.524852 -248.289216) (xy 389.561556 -248.324471) (xy 389.592129 -248.365157)
			(xy 389.61578 -248.41022) (xy 389.631896 -248.458494) (xy 389.64006 -248.508728) (xy 389.640572 -248.534174)
			(xy 389.948669 -248.534174) (xy 389.952764 -248.483446) (xy 389.964943 -248.434032) (xy 389.984891 -248.387212)
			(xy 390.012092 -248.344198) (xy 390.04584 -248.306104) (xy 390.085262 -248.273917) (xy 390.129336 -248.248471)
			(xy 390.176922 -248.230424) (xy 390.226786 -248.220244) (xy 390.277638 -248.218195) (xy 390.328159 -248.224329)
			(xy 390.377043 -248.238489) (xy 390.423022 -248.260306) (xy 390.464906 -248.289216) (xy 390.50161 -248.324471)
			(xy 390.532183 -248.365157) (xy 390.555834 -248.41022) (xy 390.57195 -248.458494) (xy 390.580114 -248.508728)
			(xy 390.580626 -248.534174) (xy 390.8989 -248.534174) (xy 390.90286 -248.48512) (xy 390.914637 -248.437336)
			(xy 390.933928 -248.39206) (xy 390.960231 -248.350464) (xy 390.992866 -248.313627) (xy 391.030987 -248.282502)
			(xy 391.073608 -248.257895) (xy 391.119624 -248.240443) (xy 391.167843 -248.230599) (xy 391.217018 -248.228618)
			(xy 391.265873 -248.23455) (xy 391.313144 -248.248242) (xy 391.357606 -248.26934) (xy 391.398109 -248.297296)
			(xy 391.433602 -248.331388) (xy 391.463167 -248.370732) (xy 391.486038 -248.414309) (xy 391.501622 -248.46099)
			(xy 391.509517 -248.509567) (xy 391.510012 -248.534174) (xy 392.779008 -248.534174) (xy 392.782968 -248.48512)
			(xy 392.794745 -248.437336) (xy 392.814036 -248.39206) (xy 392.840339 -248.350464) (xy 392.872974 -248.313627)
			(xy 392.911095 -248.282502) (xy 392.953716 -248.257895) (xy 392.999732 -248.240443) (xy 393.047951 -248.230599)
			(xy 393.097126 -248.228618) (xy 393.145981 -248.23455) (xy 393.193252 -248.248242) (xy 393.237714 -248.26934)
			(xy 393.278217 -248.297296) (xy 393.31371 -248.331388) (xy 393.343275 -248.370732) (xy 393.366146 -248.414309)
			(xy 393.38173 -248.46099) (xy 393.389625 -248.509567) (xy 393.39012 -248.534174) (xy 393.389625 -248.558781)
			(xy 393.38173 -248.607358) (xy 393.366146 -248.654039) (xy 393.343275 -248.697616) (xy 393.31371 -248.73696)
			(xy 393.278217 -248.771052) (xy 393.237714 -248.799008) (xy 393.193252 -248.820106) (xy 393.145981 -248.833798)
			(xy 393.097126 -248.83973) (xy 393.047951 -248.837749) (xy 392.999732 -248.827905) (xy 392.953716 -248.810453)
			(xy 392.911095 -248.785846) (xy 392.872974 -248.754721) (xy 392.840339 -248.717884) (xy 392.814036 -248.676288)
			(xy 392.794745 -248.631012) (xy 392.782968 -248.583228) (xy 392.779008 -248.534174) (xy 391.510012 -248.534174)
			(xy 391.509517 -248.558781) (xy 391.501622 -248.607358) (xy 391.486038 -248.654039) (xy 391.463167 -248.697616)
			(xy 391.433602 -248.73696) (xy 391.398109 -248.771052) (xy 391.357606 -248.799008) (xy 391.313144 -248.820106)
			(xy 391.265873 -248.833798) (xy 391.217018 -248.83973) (xy 391.167843 -248.837749) (xy 391.119624 -248.827905)
			(xy 391.073608 -248.810453) (xy 391.030987 -248.785846) (xy 390.992866 -248.754721) (xy 390.960231 -248.717884)
			(xy 390.933928 -248.676288) (xy 390.914637 -248.631012) (xy 390.90286 -248.583228) (xy 390.8989 -248.534174)
			(xy 390.580626 -248.534174) (xy 390.580114 -248.55962) (xy 390.57195 -248.609854) (xy 390.555834 -248.658128)
			(xy 390.532183 -248.703191) (xy 390.50161 -248.743877) (xy 390.464906 -248.779132) (xy 390.423022 -248.808042)
			(xy 390.377043 -248.829859) (xy 390.328159 -248.844019) (xy 390.277638 -248.850153) (xy 390.226786 -248.848104)
			(xy 390.176922 -248.837924) (xy 390.129336 -248.819877) (xy 390.085262 -248.794431) (xy 390.04584 -248.762244)
			(xy 390.012092 -248.72415) (xy 389.984891 -248.681136) (xy 389.964943 -248.634316) (xy 389.952764 -248.584902)
			(xy 389.948669 -248.534174) (xy 389.640572 -248.534174) (xy 389.64006 -248.55962) (xy 389.631896 -248.609854)
			(xy 389.61578 -248.658128) (xy 389.592129 -248.703191) (xy 389.561556 -248.743877) (xy 389.524852 -248.779132)
			(xy 389.482968 -248.808042) (xy 389.436989 -248.829859) (xy 389.388105 -248.844019) (xy 389.337584 -248.850153)
			(xy 389.286732 -248.848104) (xy 389.236868 -248.837924) (xy 389.189282 -248.819877) (xy 389.145208 -248.794431)
			(xy 389.105786 -248.762244) (xy 389.072038 -248.72415) (xy 389.044837 -248.681136) (xy 389.024889 -248.634316)
			(xy 389.01271 -248.584902) (xy 389.008615 -248.534174) (xy 388.690104 -248.534174) (xy 388.689609 -248.558781)
			(xy 388.681714 -248.607358) (xy 388.66613 -248.654039) (xy 388.643259 -248.697616) (xy 388.613694 -248.73696)
			(xy 388.578201 -248.771052) (xy 388.537698 -248.799008) (xy 388.493236 -248.820106) (xy 388.445965 -248.833798)
			(xy 388.39711 -248.83973) (xy 388.347935 -248.837749) (xy 388.299716 -248.827905) (xy 388.2537 -248.810453)
			(xy 388.211079 -248.785846) (xy 388.172958 -248.754721) (xy 388.140323 -248.717884) (xy 388.11402 -248.676288)
			(xy 388.094729 -248.631012) (xy 388.082952 -248.583228) (xy 388.078992 -248.534174) (xy 387.760464 -248.534174)
			(xy 387.759952 -248.55962) (xy 387.751788 -248.609854) (xy 387.735672 -248.658128) (xy 387.712021 -248.703191)
			(xy 387.681448 -248.743877) (xy 387.644744 -248.779132) (xy 387.60286 -248.808042) (xy 387.556881 -248.829859)
			(xy 387.507997 -248.844019) (xy 387.457476 -248.850153) (xy 387.406624 -248.848104) (xy 387.35676 -248.837924)
			(xy 387.309174 -248.819877) (xy 387.2651 -248.794431) (xy 387.225678 -248.762244) (xy 387.19193 -248.72415)
			(xy 387.164729 -248.681136) (xy 387.144781 -248.634316) (xy 387.132602 -248.584902) (xy 387.128507 -248.534174)
			(xy 386.81025 -248.534174) (xy 386.809755 -248.558781) (xy 386.80186 -248.607358) (xy 386.786276 -248.654039)
			(xy 386.763405 -248.697616) (xy 386.73384 -248.73696) (xy 386.698347 -248.771052) (xy 386.657844 -248.799008)
			(xy 386.613382 -248.820106) (xy 386.566111 -248.833798) (xy 386.517256 -248.83973) (xy 386.468081 -248.837749)
			(xy 386.419862 -248.827905) (xy 386.373846 -248.810453) (xy 386.331225 -248.785846) (xy 386.293104 -248.754721)
			(xy 386.260469 -248.717884) (xy 386.234166 -248.676288) (xy 386.214875 -248.631012) (xy 386.203098 -248.583228)
			(xy 386.199138 -248.534174) (xy 385.88061 -248.534174) (xy 385.880098 -248.55962) (xy 385.871934 -248.609854)
			(xy 385.855818 -248.658128) (xy 385.832167 -248.703191) (xy 385.801594 -248.743877) (xy 385.76489 -248.779132)
			(xy 385.723006 -248.808042) (xy 385.677027 -248.829859) (xy 385.628143 -248.844019) (xy 385.577622 -248.850153)
			(xy 385.52677 -248.848104) (xy 385.476906 -248.837924) (xy 385.42932 -248.819877) (xy 385.385246 -248.794431)
			(xy 385.345824 -248.762244) (xy 385.312076 -248.72415) (xy 385.284875 -248.681136) (xy 385.264927 -248.634316)
			(xy 385.252748 -248.584902) (xy 385.248653 -248.534174) (xy 384.930142 -248.534174) (xy 384.929647 -248.558781)
			(xy 384.921752 -248.607358) (xy 384.906168 -248.654039) (xy 384.883297 -248.697616) (xy 384.853732 -248.73696)
			(xy 384.818239 -248.771052) (xy 384.777736 -248.799008) (xy 384.733274 -248.820106) (xy 384.686003 -248.833798)
			(xy 384.637148 -248.83973) (xy 384.587973 -248.837749) (xy 384.539754 -248.827905) (xy 384.493738 -248.810453)
			(xy 384.451117 -248.785846) (xy 384.412996 -248.754721) (xy 384.380361 -248.717884) (xy 384.354058 -248.676288)
			(xy 384.334767 -248.631012) (xy 384.32299 -248.583228) (xy 384.31903 -248.534174) (xy 384.000502 -248.534174)
			(xy 383.99999 -248.55962) (xy 383.991826 -248.609854) (xy 383.97571 -248.658128) (xy 383.952059 -248.703191)
			(xy 383.921486 -248.743877) (xy 383.884782 -248.779132) (xy 383.842898 -248.808042) (xy 383.796919 -248.829859)
			(xy 383.748035 -248.844019) (xy 383.697514 -248.850153) (xy 383.646662 -248.848104) (xy 383.596798 -248.837924)
			(xy 383.549212 -248.819877) (xy 383.505138 -248.794431) (xy 383.465716 -248.762244) (xy 383.431968 -248.72415)
			(xy 383.404767 -248.681136) (xy 383.384819 -248.634316) (xy 383.37264 -248.584902) (xy 383.368545 -248.534174)
			(xy 383.060448 -248.534174) (xy 383.059936 -248.55962) (xy 383.051772 -248.609854) (xy 383.035656 -248.658128)
			(xy 383.012005 -248.703191) (xy 382.981432 -248.743877) (xy 382.944728 -248.779132) (xy 382.902844 -248.808042)
			(xy 382.856865 -248.829859) (xy 382.807981 -248.844019) (xy 382.75746 -248.850153) (xy 382.706608 -248.848104)
			(xy 382.656744 -248.837924) (xy 382.609158 -248.819877) (xy 382.565084 -248.794431) (xy 382.525662 -248.762244)
			(xy 382.491914 -248.72415) (xy 382.464713 -248.681136) (xy 382.444765 -248.634316) (xy 382.432586 -248.584902)
			(xy 382.428491 -248.534174) (xy 382.110234 -248.534174) (xy 382.109739 -248.558781) (xy 382.101844 -248.607358)
			(xy 382.08626 -248.654039) (xy 382.063389 -248.697616) (xy 382.033824 -248.73696) (xy 381.998331 -248.771052)
			(xy 381.957828 -248.799008) (xy 381.913366 -248.820106) (xy 381.866095 -248.833798) (xy 381.81724 -248.83973)
			(xy 381.768065 -248.837749) (xy 381.719846 -248.827905) (xy 381.67383 -248.810453) (xy 381.631209 -248.785846)
			(xy 381.593088 -248.754721) (xy 381.560453 -248.717884) (xy 381.53415 -248.676288) (xy 381.514859 -248.631012)
			(xy 381.503082 -248.583228) (xy 381.499122 -248.534174) (xy 381.180594 -248.534174) (xy 381.180082 -248.55962)
			(xy 381.171918 -248.609854) (xy 381.155802 -248.658128) (xy 381.132151 -248.703191) (xy 381.101578 -248.743877)
			(xy 381.064874 -248.779132) (xy 381.02299 -248.808042) (xy 380.977011 -248.829859) (xy 380.928127 -248.844019)
			(xy 380.877606 -248.850153) (xy 380.826754 -248.848104) (xy 380.77689 -248.837924) (xy 380.729304 -248.819877)
			(xy 380.68523 -248.794431) (xy 380.645808 -248.762244) (xy 380.61206 -248.72415) (xy 380.584859 -248.681136)
			(xy 380.564911 -248.634316) (xy 380.552732 -248.584902) (xy 380.548637 -248.534174) (xy 380.230126 -248.534174)
			(xy 380.229631 -248.558781) (xy 380.221736 -248.607358) (xy 380.206152 -248.654039) (xy 380.183281 -248.697616)
			(xy 380.153716 -248.73696) (xy 380.118223 -248.771052) (xy 380.07772 -248.799008) (xy 380.033258 -248.820106)
			(xy 379.985987 -248.833798) (xy 379.937132 -248.83973) (xy 379.887957 -248.837749) (xy 379.839738 -248.827905)
			(xy 379.793722 -248.810453) (xy 379.751101 -248.785846) (xy 379.71298 -248.754721) (xy 379.680345 -248.717884)
			(xy 379.654042 -248.676288) (xy 379.634751 -248.631012) (xy 379.622974 -248.583228) (xy 379.619014 -248.534174)
			(xy 379.300486 -248.534174) (xy 379.299974 -248.55962) (xy 379.29181 -248.609854) (xy 379.275694 -248.658128)
			(xy 379.252043 -248.703191) (xy 379.22147 -248.743877) (xy 379.184766 -248.779132) (xy 379.142882 -248.808042)
			(xy 379.096903 -248.829859) (xy 379.048019 -248.844019) (xy 378.997498 -248.850153) (xy 378.946646 -248.848104)
			(xy 378.896782 -248.837924) (xy 378.849196 -248.819877) (xy 378.805122 -248.794431) (xy 378.7657 -248.762244)
			(xy 378.731952 -248.72415) (xy 378.704751 -248.681136) (xy 378.684803 -248.634316) (xy 378.672624 -248.584902)
			(xy 378.668529 -248.534174) (xy 378.350018 -248.534174) (xy 378.349523 -248.558781) (xy 378.341628 -248.607358)
			(xy 378.326044 -248.654039) (xy 378.303173 -248.697616) (xy 378.273608 -248.73696) (xy 378.238115 -248.771052)
			(xy 378.197612 -248.799008) (xy 378.15315 -248.820106) (xy 378.105879 -248.833798) (xy 378.057024 -248.83973)
			(xy 378.007849 -248.837749) (xy 377.95963 -248.827905) (xy 377.913614 -248.810453) (xy 377.870993 -248.785846)
			(xy 377.832872 -248.754721) (xy 377.800237 -248.717884) (xy 377.773934 -248.676288) (xy 377.754643 -248.631012)
			(xy 377.742866 -248.583228) (xy 377.738906 -248.534174) (xy 377.420632 -248.534174) (xy 377.42012 -248.55962)
			(xy 377.411956 -248.609854) (xy 377.39584 -248.658128) (xy 377.372189 -248.703191) (xy 377.341616 -248.743877)
			(xy 377.304912 -248.779132) (xy 377.263028 -248.808042) (xy 377.217049 -248.829859) (xy 377.168165 -248.844019)
			(xy 377.117644 -248.850153) (xy 377.066792 -248.848104) (xy 377.016928 -248.837924) (xy 376.969342 -248.819877)
			(xy 376.925268 -248.794431) (xy 376.885846 -248.762244) (xy 376.852098 -248.72415) (xy 376.824897 -248.681136)
			(xy 376.804949 -248.634316) (xy 376.79277 -248.584902) (xy 376.788675 -248.534174) (xy 376.480578 -248.534174)
			(xy 376.480066 -248.55962) (xy 376.471902 -248.609854) (xy 376.455786 -248.658128) (xy 376.432135 -248.703191)
			(xy 376.401562 -248.743877) (xy 376.364858 -248.779132) (xy 376.322974 -248.808042) (xy 376.276995 -248.829859)
			(xy 376.228111 -248.844019) (xy 376.17759 -248.850153) (xy 376.126738 -248.848104) (xy 376.076874 -248.837924)
			(xy 376.029288 -248.819877) (xy 375.985214 -248.794431) (xy 375.945792 -248.762244) (xy 375.912044 -248.72415)
			(xy 375.884843 -248.681136) (xy 375.864895 -248.634316) (xy 375.852716 -248.584902) (xy 375.848621 -248.534174)
			(xy 375.530655 -248.534174) (xy 375.530657 -248.5342) (xy 375.526486 -248.584542) (xy 375.514085 -248.633511)
			(xy 375.493794 -248.679771) (xy 375.466165 -248.722061) (xy 375.431952 -248.759226) (xy 375.392089 -248.790253)
			(xy 375.347663 -248.814295) (xy 375.299885 -248.830697) (xy 375.250059 -248.839012) (xy 375.224802 -248.839482)
			(xy 375.200371 -248.839) (xy 375.152133 -248.831213) (xy 375.12879 -248.823988) (xy 375.121932 -248.821702)
			(xy 375.12117 -248.821448) (xy 375.109419 -248.817973) (xy 375.085162 -248.821178) (xy 375.074688 -248.827544)
			(xy 375.00687 -248.875296) (xy 375.004838 -248.87682) (xy 374.996627 -248.883843) (xy 374.986513 -248.902915)
			(xy 374.98528 -248.91365) (xy 374.98528 -249.117104) (xy 374.985356 -249.121313) (xy 374.986763 -249.129613)
			(xy 374.988074 -249.133614) (xy 374.995948 -249.156474) (xy 375.00052 -249.162824) (xy 375.014558 -249.182646)
			(xy 375.036841 -249.225803) (xy 375.052016 -249.271941) (xy 375.059702 -249.319899) (xy 375.059703 -249.34418)
			(xy 375.378467 -249.34418) (xy 375.382562 -249.293452) (xy 375.394741 -249.244038) (xy 375.414689 -249.197218)
			(xy 375.44189 -249.154204) (xy 375.475638 -249.11611) (xy 375.51506 -249.083923) (xy 375.559134 -249.058477)
			(xy 375.60672 -249.04043) (xy 375.656584 -249.03025) (xy 375.707436 -249.028201) (xy 375.757957 -249.034335)
			(xy 375.806841 -249.048495) (xy 375.85282 -249.070312) (xy 375.894704 -249.099222) (xy 375.931408 -249.134477)
			(xy 375.961981 -249.175163) (xy 375.985632 -249.220226) (xy 376.001748 -249.2685) (xy 376.009912 -249.318734)
			(xy 376.010424 -249.34418) (xy 376.328952 -249.34418) (xy 376.332912 -249.295126) (xy 376.344689 -249.247342)
			(xy 376.36398 -249.202066) (xy 376.390283 -249.16047) (xy 376.422918 -249.123633) (xy 376.461039 -249.092508)
			(xy 376.50366 -249.067901) (xy 376.549676 -249.050449) (xy 376.597895 -249.040605) (xy 376.64707 -249.038624)
			(xy 376.695925 -249.044556) (xy 376.743196 -249.058248) (xy 376.787658 -249.079346) (xy 376.828161 -249.107302)
			(xy 376.863654 -249.141394) (xy 376.893219 -249.180738) (xy 376.91609 -249.224315) (xy 376.931674 -249.270996)
			(xy 376.939569 -249.319573) (xy 376.940064 -249.34418) (xy 377.269006 -249.34418) (xy 377.272966 -249.295126)
			(xy 377.284743 -249.247342) (xy 377.304034 -249.202066) (xy 377.330337 -249.16047) (xy 377.362972 -249.123633)
			(xy 377.401093 -249.092508) (xy 377.443714 -249.067901) (xy 377.48973 -249.050449) (xy 377.537949 -249.040605)
			(xy 377.587124 -249.038624) (xy 377.635979 -249.044556) (xy 377.68325 -249.058248) (xy 377.727712 -249.079346)
			(xy 377.768215 -249.107302) (xy 377.803708 -249.141394) (xy 377.833273 -249.180738) (xy 377.856144 -249.224315)
			(xy 377.871728 -249.270996) (xy 377.879623 -249.319573) (xy 377.880118 -249.34418) (xy 379.138683 -249.34418)
			(xy 379.142778 -249.293452) (xy 379.154957 -249.244038) (xy 379.174905 -249.197218) (xy 379.202106 -249.154204)
			(xy 379.235854 -249.11611) (xy 379.275276 -249.083923) (xy 379.31935 -249.058477) (xy 379.366936 -249.04043)
			(xy 379.4168 -249.03025) (xy 379.467652 -249.028201) (xy 379.518173 -249.034335) (xy 379.567057 -249.048495)
			(xy 379.613036 -249.070312) (xy 379.65492 -249.099222) (xy 379.691624 -249.134477) (xy 379.722197 -249.175163)
			(xy 379.745848 -249.220226) (xy 379.761964 -249.2685) (xy 379.770128 -249.318734) (xy 379.77064 -249.34418)
			(xy 380.088914 -249.34418) (xy 380.092874 -249.295126) (xy 380.104651 -249.247342) (xy 380.123942 -249.202066)
			(xy 380.150245 -249.16047) (xy 380.18288 -249.123633) (xy 380.221001 -249.092508) (xy 380.263622 -249.067901)
			(xy 380.309638 -249.050449) (xy 380.357857 -249.040605) (xy 380.407032 -249.038624) (xy 380.455887 -249.044556)
			(xy 380.503158 -249.058248) (xy 380.54762 -249.079346) (xy 380.588123 -249.107302) (xy 380.623616 -249.141394)
			(xy 380.653181 -249.180738) (xy 380.676052 -249.224315) (xy 380.691636 -249.270996) (xy 380.699531 -249.319573)
			(xy 380.700026 -249.34418) (xy 381.028968 -249.34418) (xy 381.032928 -249.295126) (xy 381.044705 -249.247342)
			(xy 381.063996 -249.202066) (xy 381.090299 -249.16047) (xy 381.122934 -249.123633) (xy 381.161055 -249.092508)
			(xy 381.203676 -249.067901) (xy 381.249692 -249.050449) (xy 381.297911 -249.040605) (xy 381.347086 -249.038624)
			(xy 381.395941 -249.044556) (xy 381.443212 -249.058248) (xy 381.487674 -249.079346) (xy 381.528177 -249.107302)
			(xy 381.56367 -249.141394) (xy 381.593235 -249.180738) (xy 381.616106 -249.224315) (xy 381.63169 -249.270996)
			(xy 381.639585 -249.319573) (xy 381.64008 -249.34418) (xy 381.958591 -249.34418) (xy 381.962686 -249.293452)
			(xy 381.974865 -249.244038) (xy 381.994813 -249.197218) (xy 382.022014 -249.154204) (xy 382.055762 -249.11611)
			(xy 382.095184 -249.083923) (xy 382.139258 -249.058477) (xy 382.186844 -249.04043) (xy 382.236708 -249.03025)
			(xy 382.28756 -249.028201) (xy 382.338081 -249.034335) (xy 382.386965 -249.048495) (xy 382.432944 -249.070312)
			(xy 382.474828 -249.099222) (xy 382.511532 -249.134477) (xy 382.542105 -249.175163) (xy 382.565756 -249.220226)
			(xy 382.581872 -249.2685) (xy 382.590036 -249.318734) (xy 382.590548 -249.34418) (xy 382.909076 -249.34418)
			(xy 382.913036 -249.295126) (xy 382.924813 -249.247342) (xy 382.944104 -249.202066) (xy 382.970407 -249.16047)
			(xy 383.003042 -249.123633) (xy 383.041163 -249.092508) (xy 383.083784 -249.067901) (xy 383.1298 -249.050449)
			(xy 383.178019 -249.040605) (xy 383.227194 -249.038624) (xy 383.276049 -249.044556) (xy 383.32332 -249.058248)
			(xy 383.367782 -249.079346) (xy 383.408285 -249.107302) (xy 383.443778 -249.141394) (xy 383.473343 -249.180738)
			(xy 383.496214 -249.224315) (xy 383.511798 -249.270996) (xy 383.519693 -249.319573) (xy 383.520188 -249.34418)
			(xy 383.84913 -249.34418) (xy 383.85309 -249.295126) (xy 383.864867 -249.247342) (xy 383.884158 -249.202066)
			(xy 383.910461 -249.16047) (xy 383.943096 -249.123633) (xy 383.981217 -249.092508) (xy 384.023838 -249.067901)
			(xy 384.069854 -249.050449) (xy 384.118073 -249.040605) (xy 384.167248 -249.038624) (xy 384.216103 -249.044556)
			(xy 384.263374 -249.058248) (xy 384.307836 -249.079346) (xy 384.348339 -249.107302) (xy 384.383832 -249.141394)
			(xy 384.413397 -249.180738) (xy 384.436268 -249.224315) (xy 384.451852 -249.270996) (xy 384.459747 -249.319573)
			(xy 384.460242 -249.34418) (xy 385.718553 -249.34418) (xy 385.722648 -249.293452) (xy 385.734827 -249.244038)
			(xy 385.754775 -249.197218) (xy 385.781976 -249.154204) (xy 385.815724 -249.11611) (xy 385.855146 -249.083923)
			(xy 385.89922 -249.058477) (xy 385.946806 -249.04043) (xy 385.99667 -249.03025) (xy 386.047522 -249.028201)
			(xy 386.098043 -249.034335) (xy 386.146927 -249.048495) (xy 386.192906 -249.070312) (xy 386.23479 -249.099222)
			(xy 386.271494 -249.134477) (xy 386.302067 -249.175163) (xy 386.325718 -249.220226) (xy 386.341834 -249.2685)
			(xy 386.349998 -249.318734) (xy 386.35051 -249.34418) (xy 386.669038 -249.34418) (xy 386.672998 -249.295126)
			(xy 386.684775 -249.247342) (xy 386.704066 -249.202066) (xy 386.730369 -249.16047) (xy 386.763004 -249.123633)
			(xy 386.801125 -249.092508) (xy 386.843746 -249.067901) (xy 386.889762 -249.050449) (xy 386.937981 -249.040605)
			(xy 386.987156 -249.038624) (xy 387.036011 -249.044556) (xy 387.083282 -249.058248) (xy 387.127744 -249.079346)
			(xy 387.168247 -249.107302) (xy 387.20374 -249.141394) (xy 387.233305 -249.180738) (xy 387.256176 -249.224315)
			(xy 387.27176 -249.270996) (xy 387.279655 -249.319573) (xy 387.28015 -249.34418) (xy 387.609092 -249.34418)
			(xy 387.613052 -249.295126) (xy 387.624829 -249.247342) (xy 387.64412 -249.202066) (xy 387.670423 -249.16047)
			(xy 387.703058 -249.123633) (xy 387.741179 -249.092508) (xy 387.7838 -249.067901) (xy 387.829816 -249.050449)
			(xy 387.878035 -249.040605) (xy 387.92721 -249.038624) (xy 387.976065 -249.044556) (xy 388.023336 -249.058248)
			(xy 388.067798 -249.079346) (xy 388.108301 -249.107302) (xy 388.143794 -249.141394) (xy 388.173359 -249.180738)
			(xy 388.19623 -249.224315) (xy 388.211814 -249.270996) (xy 388.219709 -249.319573) (xy 388.220204 -249.34418)
			(xy 388.538715 -249.34418) (xy 388.54281 -249.293452) (xy 388.554989 -249.244038) (xy 388.574937 -249.197218)
			(xy 388.602138 -249.154204) (xy 388.635886 -249.11611) (xy 388.675308 -249.083923) (xy 388.719382 -249.058477)
			(xy 388.766968 -249.04043) (xy 388.816832 -249.03025) (xy 388.867684 -249.028201) (xy 388.918205 -249.034335)
			(xy 388.967089 -249.048495) (xy 389.013068 -249.070312) (xy 389.054952 -249.099222) (xy 389.091656 -249.134477)
			(xy 389.122229 -249.175163) (xy 389.14588 -249.220226) (xy 389.161996 -249.2685) (xy 389.17016 -249.318734)
			(xy 389.170672 -249.34418) (xy 389.488946 -249.34418) (xy 389.492906 -249.295126) (xy 389.504683 -249.247342)
			(xy 389.523974 -249.202066) (xy 389.550277 -249.16047) (xy 389.582912 -249.123633) (xy 389.621033 -249.092508)
			(xy 389.663654 -249.067901) (xy 389.70967 -249.050449) (xy 389.757889 -249.040605) (xy 389.807064 -249.038624)
			(xy 389.855919 -249.044556) (xy 389.90319 -249.058248) (xy 389.947652 -249.079346) (xy 389.988155 -249.107302)
			(xy 390.023648 -249.141394) (xy 390.053213 -249.180738) (xy 390.076084 -249.224315) (xy 390.091668 -249.270996)
			(xy 390.099563 -249.319573) (xy 390.100058 -249.34418) (xy 390.429 -249.34418) (xy 390.43296 -249.295126)
			(xy 390.444737 -249.247342) (xy 390.464028 -249.202066) (xy 390.490331 -249.16047) (xy 390.522966 -249.123633)
			(xy 390.561087 -249.092508) (xy 390.603708 -249.067901) (xy 390.649724 -249.050449) (xy 390.697943 -249.040605)
			(xy 390.747118 -249.038624) (xy 390.795973 -249.044556) (xy 390.843244 -249.058248) (xy 390.887706 -249.079346)
			(xy 390.928209 -249.107302) (xy 390.963702 -249.141394) (xy 390.993267 -249.180738) (xy 391.016138 -249.224315)
			(xy 391.031722 -249.270996) (xy 391.039617 -249.319573) (xy 391.040112 -249.34418) (xy 391.039617 -249.368787)
			(xy 391.031722 -249.417364) (xy 391.016138 -249.464045) (xy 390.993267 -249.507622) (xy 390.963702 -249.546966)
			(xy 390.928209 -249.581058) (xy 390.887706 -249.609014) (xy 390.885379 -249.610118) (xy 394.377176 -249.610118)
			(xy 394.381136 -249.561064) (xy 394.392913 -249.51328) (xy 394.412204 -249.468004) (xy 394.438507 -249.426408)
			(xy 394.471142 -249.389571) (xy 394.509263 -249.358446) (xy 394.551884 -249.333839) (xy 394.5979 -249.316387)
			(xy 394.646119 -249.306543) (xy 394.695294 -249.304562) (xy 394.744149 -249.310494) (xy 394.79142 -249.324186)
			(xy 394.835882 -249.345284) (xy 394.876385 -249.37324) (xy 394.911878 -249.407332) (xy 394.941443 -249.446676)
			(xy 394.964314 -249.490253) (xy 394.979898 -249.536934) (xy 394.987793 -249.585511) (xy 394.988288 -249.610118)
			(xy 394.987793 -249.634725) (xy 394.979898 -249.683302) (xy 394.964314 -249.729983) (xy 394.941443 -249.77356)
			(xy 394.911878 -249.812904) (xy 394.876385 -249.846996) (xy 394.835882 -249.874952) (xy 394.79142 -249.89605)
			(xy 394.744149 -249.909742) (xy 394.695294 -249.915674) (xy 394.646119 -249.913693) (xy 394.5979 -249.903849)
			(xy 394.551884 -249.886397) (xy 394.509263 -249.86179) (xy 394.471142 -249.830665) (xy 394.438507 -249.793828)
			(xy 394.412204 -249.752232) (xy 394.392913 -249.706956) (xy 394.381136 -249.659172) (xy 394.377176 -249.610118)
			(xy 390.885379 -249.610118) (xy 390.843244 -249.630112) (xy 390.795973 -249.643804) (xy 390.747118 -249.649736)
			(xy 390.697943 -249.647755) (xy 390.649724 -249.637911) (xy 390.603708 -249.620459) (xy 390.561087 -249.595852)
			(xy 390.522966 -249.564727) (xy 390.490331 -249.52789) (xy 390.464028 -249.486294) (xy 390.444737 -249.441018)
			(xy 390.43296 -249.393234) (xy 390.429 -249.34418) (xy 390.100058 -249.34418) (xy 390.099563 -249.368787)
			(xy 390.091668 -249.417364) (xy 390.076084 -249.464045) (xy 390.053213 -249.507622) (xy 390.023648 -249.546966)
			(xy 389.988155 -249.581058) (xy 389.947652 -249.609014) (xy 389.90319 -249.630112) (xy 389.855919 -249.643804)
			(xy 389.807064 -249.649736) (xy 389.757889 -249.647755) (xy 389.70967 -249.637911) (xy 389.663654 -249.620459)
			(xy 389.621033 -249.595852) (xy 389.582912 -249.564727) (xy 389.550277 -249.52789) (xy 389.523974 -249.486294)
			(xy 389.504683 -249.441018) (xy 389.492906 -249.393234) (xy 389.488946 -249.34418) (xy 389.170672 -249.34418)
			(xy 389.17016 -249.369626) (xy 389.161996 -249.41986) (xy 389.14588 -249.468134) (xy 389.122229 -249.513197)
			(xy 389.091656 -249.553883) (xy 389.054952 -249.589138) (xy 389.013068 -249.618048) (xy 388.967089 -249.639865)
			(xy 388.918205 -249.654025) (xy 388.867684 -249.660159) (xy 388.816832 -249.65811) (xy 388.766968 -249.64793)
			(xy 388.719382 -249.629883) (xy 388.675308 -249.604437) (xy 388.635886 -249.57225) (xy 388.602138 -249.534156)
			(xy 388.574937 -249.491142) (xy 388.554989 -249.444322) (xy 388.54281 -249.394908) (xy 388.538715 -249.34418)
			(xy 388.220204 -249.34418) (xy 388.219709 -249.368787) (xy 388.211814 -249.417364) (xy 388.19623 -249.464045)
			(xy 388.173359 -249.507622) (xy 388.143794 -249.546966) (xy 388.108301 -249.581058) (xy 388.067798 -249.609014)
			(xy 388.023336 -249.630112) (xy 387.976065 -249.643804) (xy 387.92721 -249.649736) (xy 387.878035 -249.647755)
			(xy 387.829816 -249.637911) (xy 387.7838 -249.620459) (xy 387.741179 -249.595852) (xy 387.703058 -249.564727)
			(xy 387.670423 -249.52789) (xy 387.64412 -249.486294) (xy 387.624829 -249.441018) (xy 387.613052 -249.393234)
			(xy 387.609092 -249.34418) (xy 387.28015 -249.34418) (xy 387.279655 -249.368787) (xy 387.27176 -249.417364)
			(xy 387.256176 -249.464045) (xy 387.233305 -249.507622) (xy 387.20374 -249.546966) (xy 387.168247 -249.581058)
			(xy 387.127744 -249.609014) (xy 387.083282 -249.630112) (xy 387.036011 -249.643804) (xy 386.987156 -249.649736)
			(xy 386.937981 -249.647755) (xy 386.889762 -249.637911) (xy 386.843746 -249.620459) (xy 386.801125 -249.595852)
			(xy 386.763004 -249.564727) (xy 386.730369 -249.52789) (xy 386.704066 -249.486294) (xy 386.684775 -249.441018)
			(xy 386.672998 -249.393234) (xy 386.669038 -249.34418) (xy 386.35051 -249.34418) (xy 386.349998 -249.369626)
			(xy 386.341834 -249.41986) (xy 386.325718 -249.468134) (xy 386.302067 -249.513197) (xy 386.271494 -249.553883)
			(xy 386.23479 -249.589138) (xy 386.192906 -249.618048) (xy 386.146927 -249.639865) (xy 386.098043 -249.654025)
			(xy 386.047522 -249.660159) (xy 385.99667 -249.65811) (xy 385.946806 -249.64793) (xy 385.89922 -249.629883)
			(xy 385.855146 -249.604437) (xy 385.815724 -249.57225) (xy 385.781976 -249.534156) (xy 385.754775 -249.491142)
			(xy 385.734827 -249.444322) (xy 385.722648 -249.394908) (xy 385.718553 -249.34418) (xy 384.460242 -249.34418)
			(xy 384.459747 -249.368787) (xy 384.451852 -249.417364) (xy 384.436268 -249.464045) (xy 384.413397 -249.507622)
			(xy 384.383832 -249.546966) (xy 384.348339 -249.581058) (xy 384.307836 -249.609014) (xy 384.263374 -249.630112)
			(xy 384.216103 -249.643804) (xy 384.167248 -249.649736) (xy 384.118073 -249.647755) (xy 384.069854 -249.637911)
			(xy 384.023838 -249.620459) (xy 383.981217 -249.595852) (xy 383.943096 -249.564727) (xy 383.910461 -249.52789)
			(xy 383.884158 -249.486294) (xy 383.864867 -249.441018) (xy 383.85309 -249.393234) (xy 383.84913 -249.34418)
			(xy 383.520188 -249.34418) (xy 383.519693 -249.368787) (xy 383.511798 -249.417364) (xy 383.496214 -249.464045)
			(xy 383.473343 -249.507622) (xy 383.443778 -249.546966) (xy 383.408285 -249.581058) (xy 383.367782 -249.609014)
			(xy 383.32332 -249.630112) (xy 383.276049 -249.643804) (xy 383.227194 -249.649736) (xy 383.178019 -249.647755)
			(xy 383.1298 -249.637911) (xy 383.083784 -249.620459) (xy 383.041163 -249.595852) (xy 383.003042 -249.564727)
			(xy 382.970407 -249.52789) (xy 382.944104 -249.486294) (xy 382.924813 -249.441018) (xy 382.913036 -249.393234)
			(xy 382.909076 -249.34418) (xy 382.590548 -249.34418) (xy 382.590036 -249.369626) (xy 382.581872 -249.41986)
			(xy 382.565756 -249.468134) (xy 382.542105 -249.513197) (xy 382.511532 -249.553883) (xy 382.474828 -249.589138)
			(xy 382.432944 -249.618048) (xy 382.386965 -249.639865) (xy 382.338081 -249.654025) (xy 382.28756 -249.660159)
			(xy 382.236708 -249.65811) (xy 382.186844 -249.64793) (xy 382.139258 -249.629883) (xy 382.095184 -249.604437)
			(xy 382.055762 -249.57225) (xy 382.022014 -249.534156) (xy 381.994813 -249.491142) (xy 381.974865 -249.444322)
			(xy 381.962686 -249.394908) (xy 381.958591 -249.34418) (xy 381.64008 -249.34418) (xy 381.639585 -249.368787)
			(xy 381.63169 -249.417364) (xy 381.616106 -249.464045) (xy 381.593235 -249.507622) (xy 381.56367 -249.546966)
			(xy 381.528177 -249.581058) (xy 381.487674 -249.609014) (xy 381.443212 -249.630112) (xy 381.395941 -249.643804)
			(xy 381.347086 -249.649736) (xy 381.297911 -249.647755) (xy 381.249692 -249.637911) (xy 381.203676 -249.620459)
			(xy 381.161055 -249.595852) (xy 381.122934 -249.564727) (xy 381.090299 -249.52789) (xy 381.063996 -249.486294)
			(xy 381.044705 -249.441018) (xy 381.032928 -249.393234) (xy 381.028968 -249.34418) (xy 380.700026 -249.34418)
			(xy 380.699531 -249.368787) (xy 380.691636 -249.417364) (xy 380.676052 -249.464045) (xy 380.653181 -249.507622)
			(xy 380.623616 -249.546966) (xy 380.588123 -249.581058) (xy 380.54762 -249.609014) (xy 380.503158 -249.630112)
			(xy 380.455887 -249.643804) (xy 380.407032 -249.649736) (xy 380.357857 -249.647755) (xy 380.309638 -249.637911)
			(xy 380.263622 -249.620459) (xy 380.221001 -249.595852) (xy 380.18288 -249.564727) (xy 380.150245 -249.52789)
			(xy 380.123942 -249.486294) (xy 380.104651 -249.441018) (xy 380.092874 -249.393234) (xy 380.088914 -249.34418)
			(xy 379.77064 -249.34418) (xy 379.770128 -249.369626) (xy 379.761964 -249.41986) (xy 379.745848 -249.468134)
			(xy 379.722197 -249.513197) (xy 379.691624 -249.553883) (xy 379.65492 -249.589138) (xy 379.613036 -249.618048)
			(xy 379.567057 -249.639865) (xy 379.518173 -249.654025) (xy 379.467652 -249.660159) (xy 379.4168 -249.65811)
			(xy 379.366936 -249.64793) (xy 379.31935 -249.629883) (xy 379.275276 -249.604437) (xy 379.235854 -249.57225)
			(xy 379.202106 -249.534156) (xy 379.174905 -249.491142) (xy 379.154957 -249.444322) (xy 379.142778 -249.394908)
			(xy 379.138683 -249.34418) (xy 377.880118 -249.34418) (xy 377.879623 -249.368787) (xy 377.871728 -249.417364)
			(xy 377.856144 -249.464045) (xy 377.833273 -249.507622) (xy 377.803708 -249.546966) (xy 377.768215 -249.581058)
			(xy 377.727712 -249.609014) (xy 377.68325 -249.630112) (xy 377.635979 -249.643804) (xy 377.587124 -249.649736)
			(xy 377.537949 -249.647755) (xy 377.48973 -249.637911) (xy 377.443714 -249.620459) (xy 377.401093 -249.595852)
			(xy 377.362972 -249.564727) (xy 377.330337 -249.52789) (xy 377.304034 -249.486294) (xy 377.284743 -249.441018)
			(xy 377.272966 -249.393234) (xy 377.269006 -249.34418) (xy 376.940064 -249.34418) (xy 376.939569 -249.368787)
			(xy 376.931674 -249.417364) (xy 376.91609 -249.464045) (xy 376.893219 -249.507622) (xy 376.863654 -249.546966)
			(xy 376.828161 -249.581058) (xy 376.787658 -249.609014) (xy 376.743196 -249.630112) (xy 376.695925 -249.643804)
			(xy 376.64707 -249.649736) (xy 376.597895 -249.647755) (xy 376.549676 -249.637911) (xy 376.50366 -249.620459)
			(xy 376.461039 -249.595852) (xy 376.422918 -249.564727) (xy 376.390283 -249.52789) (xy 376.36398 -249.486294)
			(xy 376.344689 -249.441018) (xy 376.332912 -249.393234) (xy 376.328952 -249.34418) (xy 376.010424 -249.34418)
			(xy 376.009912 -249.369626) (xy 376.001748 -249.41986) (xy 375.985632 -249.468134) (xy 375.961981 -249.513197)
			(xy 375.931408 -249.553883) (xy 375.894704 -249.589138) (xy 375.85282 -249.618048) (xy 375.806841 -249.639865)
			(xy 375.757957 -249.654025) (xy 375.707436 -249.660159) (xy 375.656584 -249.65811) (xy 375.60672 -249.64793)
			(xy 375.559134 -249.629883) (xy 375.51506 -249.604437) (xy 375.475638 -249.57225) (xy 375.44189 -249.534156)
			(xy 375.414689 -249.491142) (xy 375.394741 -249.444322) (xy 375.382562 -249.394908) (xy 375.378467 -249.34418)
			(xy 375.059703 -249.34418) (xy 375.059705 -249.368469) (xy 375.052024 -249.416428) (xy 375.036853 -249.462568)
			(xy 375.014575 -249.505727) (xy 375.00052 -249.525536) (xy 374.995948 -249.531886) (xy 374.988074 -249.554746)
			(xy 374.986788 -249.558753) (xy 374.985379 -249.567049) (xy 374.98528 -249.571256) (xy 374.98528 -250.154186)
			(xy 375.848621 -250.154186) (xy 375.852716 -250.103458) (xy 375.864895 -250.054044) (xy 375.884843 -250.007224)
			(xy 375.912044 -249.96421) (xy 375.945792 -249.926116) (xy 375.985214 -249.893929) (xy 376.029288 -249.868483)
			(xy 376.076874 -249.850436) (xy 376.126738 -249.840256) (xy 376.17759 -249.838207) (xy 376.228111 -249.844341)
			(xy 376.276995 -249.858501) (xy 376.322974 -249.880318) (xy 376.364858 -249.909228) (xy 376.401562 -249.944483)
			(xy 376.432135 -249.985169) (xy 376.455786 -250.030232) (xy 376.471902 -250.078506) (xy 376.480066 -250.12874)
			(xy 376.480578 -250.154186) (xy 376.799106 -250.154186) (xy 376.803066 -250.105132) (xy 376.814843 -250.057348)
			(xy 376.834134 -250.012072) (xy 376.860437 -249.970476) (xy 376.893072 -249.933639) (xy 376.931193 -249.902514)
			(xy 376.973814 -249.877907) (xy 377.01983 -249.860455) (xy 377.068049 -249.850611) (xy 377.117224 -249.84863)
			(xy 377.166079 -249.854562) (xy 377.21335 -249.868254) (xy 377.257812 -249.889352) (xy 377.298315 -249.917308)
			(xy 377.333808 -249.9514) (xy 377.363373 -249.990744) (xy 377.386244 -250.034321) (xy 377.401828 -250.081002)
			(xy 377.409723 -250.129579) (xy 377.410218 -250.154186) (xy 377.738906 -250.154186) (xy 377.742866 -250.105132)
			(xy 377.754643 -250.057348) (xy 377.773934 -250.012072) (xy 377.800237 -249.970476) (xy 377.832872 -249.933639)
			(xy 377.870993 -249.902514) (xy 377.913614 -249.877907) (xy 377.95963 -249.860455) (xy 378.007849 -249.850611)
			(xy 378.057024 -249.84863) (xy 378.105879 -249.854562) (xy 378.15315 -249.868254) (xy 378.197612 -249.889352)
			(xy 378.238115 -249.917308) (xy 378.273608 -249.9514) (xy 378.303173 -249.990744) (xy 378.326044 -250.034321)
			(xy 378.341628 -250.081002) (xy 378.349523 -250.129579) (xy 378.350018 -250.154186) (xy 378.668529 -250.154186)
			(xy 378.672624 -250.103458) (xy 378.684803 -250.054044) (xy 378.704751 -250.007224) (xy 378.731952 -249.96421)
			(xy 378.7657 -249.926116) (xy 378.805122 -249.893929) (xy 378.849196 -249.868483) (xy 378.896782 -249.850436)
			(xy 378.946646 -249.840256) (xy 378.997498 -249.838207) (xy 379.048019 -249.844341) (xy 379.096903 -249.858501)
			(xy 379.142882 -249.880318) (xy 379.184766 -249.909228) (xy 379.22147 -249.944483) (xy 379.252043 -249.985169)
			(xy 379.275694 -250.030232) (xy 379.29181 -250.078506) (xy 379.299974 -250.12874) (xy 379.300486 -250.154186)
			(xy 379.619014 -250.154186) (xy 379.622974 -250.105132) (xy 379.634751 -250.057348) (xy 379.654042 -250.012072)
			(xy 379.680345 -249.970476) (xy 379.71298 -249.933639) (xy 379.751101 -249.902514) (xy 379.793722 -249.877907)
			(xy 379.839738 -249.860455) (xy 379.887957 -249.850611) (xy 379.937132 -249.84863) (xy 379.985987 -249.854562)
			(xy 380.033258 -249.868254) (xy 380.07772 -249.889352) (xy 380.118223 -249.917308) (xy 380.153716 -249.9514)
			(xy 380.183281 -249.990744) (xy 380.206152 -250.034321) (xy 380.221736 -250.081002) (xy 380.229631 -250.129579)
			(xy 380.230126 -250.154186) (xy 380.559068 -250.154186) (xy 380.563028 -250.105132) (xy 380.574805 -250.057348)
			(xy 380.594096 -250.012072) (xy 380.620399 -249.970476) (xy 380.653034 -249.933639) (xy 380.691155 -249.902514)
			(xy 380.733776 -249.877907) (xy 380.779792 -249.860455) (xy 380.828011 -249.850611) (xy 380.877186 -249.84863)
			(xy 380.926041 -249.854562) (xy 380.973312 -249.868254) (xy 381.017774 -249.889352) (xy 381.058277 -249.917308)
			(xy 381.09377 -249.9514) (xy 381.123335 -249.990744) (xy 381.146206 -250.034321) (xy 381.16179 -250.081002)
			(xy 381.169685 -250.129579) (xy 381.17018 -250.154186) (xy 381.499122 -250.154186) (xy 381.503082 -250.105132)
			(xy 381.514859 -250.057348) (xy 381.53415 -250.012072) (xy 381.560453 -249.970476) (xy 381.593088 -249.933639)
			(xy 381.631209 -249.902514) (xy 381.67383 -249.877907) (xy 381.719846 -249.860455) (xy 381.768065 -249.850611)
			(xy 381.81724 -249.84863) (xy 381.866095 -249.854562) (xy 381.913366 -249.868254) (xy 381.957828 -249.889352)
			(xy 381.998331 -249.917308) (xy 382.033824 -249.9514) (xy 382.063389 -249.990744) (xy 382.08626 -250.034321)
			(xy 382.101844 -250.081002) (xy 382.109739 -250.129579) (xy 382.110234 -250.154186) (xy 382.428491 -250.154186)
			(xy 382.432586 -250.103458) (xy 382.444765 -250.054044) (xy 382.464713 -250.007224) (xy 382.491914 -249.96421)
			(xy 382.525662 -249.926116) (xy 382.565084 -249.893929) (xy 382.609158 -249.868483) (xy 382.656744 -249.850436)
			(xy 382.706608 -249.840256) (xy 382.75746 -249.838207) (xy 382.807981 -249.844341) (xy 382.856865 -249.858501)
			(xy 382.902844 -249.880318) (xy 382.944728 -249.909228) (xy 382.981432 -249.944483) (xy 383.012005 -249.985169)
			(xy 383.035656 -250.030232) (xy 383.051772 -250.078506) (xy 383.059936 -250.12874) (xy 383.060448 -250.154186)
			(xy 383.378976 -250.154186) (xy 383.382936 -250.105132) (xy 383.394713 -250.057348) (xy 383.414004 -250.012072)
			(xy 383.440307 -249.970476) (xy 383.472942 -249.933639) (xy 383.511063 -249.902514) (xy 383.553684 -249.877907)
			(xy 383.5997 -249.860455) (xy 383.647919 -249.850611) (xy 383.697094 -249.84863) (xy 383.745949 -249.854562)
			(xy 383.79322 -249.868254) (xy 383.837682 -249.889352) (xy 383.878185 -249.917308) (xy 383.913678 -249.9514)
			(xy 383.943243 -249.990744) (xy 383.966114 -250.034321) (xy 383.981698 -250.081002) (xy 383.989593 -250.129579)
			(xy 383.990088 -250.154186) (xy 384.31903 -250.154186) (xy 384.32299 -250.105132) (xy 384.334767 -250.057348)
			(xy 384.354058 -250.012072) (xy 384.380361 -249.970476) (xy 384.412996 -249.933639) (xy 384.451117 -249.902514)
			(xy 384.493738 -249.877907) (xy 384.539754 -249.860455) (xy 384.587973 -249.850611) (xy 384.637148 -249.84863)
			(xy 384.686003 -249.854562) (xy 384.733274 -249.868254) (xy 384.777736 -249.889352) (xy 384.818239 -249.917308)
			(xy 384.853732 -249.9514) (xy 384.883297 -249.990744) (xy 384.906168 -250.034321) (xy 384.921752 -250.081002)
			(xy 384.929647 -250.129579) (xy 384.930142 -250.154186) (xy 385.248653 -250.154186) (xy 385.252748 -250.103458)
			(xy 385.264927 -250.054044) (xy 385.284875 -250.007224) (xy 385.312076 -249.96421) (xy 385.345824 -249.926116)
			(xy 385.385246 -249.893929) (xy 385.42932 -249.868483) (xy 385.476906 -249.850436) (xy 385.52677 -249.840256)
			(xy 385.577622 -249.838207) (xy 385.628143 -249.844341) (xy 385.677027 -249.858501) (xy 385.723006 -249.880318)
			(xy 385.76489 -249.909228) (xy 385.801594 -249.944483) (xy 385.832167 -249.985169) (xy 385.855818 -250.030232)
			(xy 385.871934 -250.078506) (xy 385.880098 -250.12874) (xy 385.88061 -250.154186) (xy 386.199138 -250.154186)
			(xy 386.203098 -250.105132) (xy 386.214875 -250.057348) (xy 386.234166 -250.012072) (xy 386.260469 -249.970476)
			(xy 386.293104 -249.933639) (xy 386.331225 -249.902514) (xy 386.373846 -249.877907) (xy 386.419862 -249.860455)
			(xy 386.468081 -249.850611) (xy 386.517256 -249.84863) (xy 386.566111 -249.854562) (xy 386.613382 -249.868254)
			(xy 386.657844 -249.889352) (xy 386.698347 -249.917308) (xy 386.73384 -249.9514) (xy 386.763405 -249.990744)
			(xy 386.786276 -250.034321) (xy 386.80186 -250.081002) (xy 386.809755 -250.129579) (xy 386.81025 -250.154186)
			(xy 387.138938 -250.154186) (xy 387.142898 -250.105132) (xy 387.154675 -250.057348) (xy 387.173966 -250.012072)
			(xy 387.200269 -249.970476) (xy 387.232904 -249.933639) (xy 387.271025 -249.902514) (xy 387.313646 -249.877907)
			(xy 387.359662 -249.860455) (xy 387.407881 -249.850611) (xy 387.457056 -249.84863) (xy 387.505911 -249.854562)
			(xy 387.553182 -249.868254) (xy 387.597644 -249.889352) (xy 387.638147 -249.917308) (xy 387.67364 -249.9514)
			(xy 387.703205 -249.990744) (xy 387.726076 -250.034321) (xy 387.74166 -250.081002) (xy 387.749555 -250.129579)
			(xy 387.75005 -250.154186) (xy 388.078992 -250.154186) (xy 388.082952 -250.105132) (xy 388.094729 -250.057348)
			(xy 388.11402 -250.012072) (xy 388.140323 -249.970476) (xy 388.172958 -249.933639) (xy 388.211079 -249.902514)
			(xy 388.2537 -249.877907) (xy 388.299716 -249.860455) (xy 388.347935 -249.850611) (xy 388.39711 -249.84863)
			(xy 388.445965 -249.854562) (xy 388.493236 -249.868254) (xy 388.537698 -249.889352) (xy 388.578201 -249.917308)
			(xy 388.613694 -249.9514) (xy 388.643259 -249.990744) (xy 388.66613 -250.034321) (xy 388.681714 -250.081002)
			(xy 388.689609 -250.129579) (xy 388.690104 -250.154186) (xy 389.008615 -250.154186) (xy 389.01271 -250.103458)
			(xy 389.024889 -250.054044) (xy 389.044837 -250.007224) (xy 389.072038 -249.96421) (xy 389.105786 -249.926116)
			(xy 389.145208 -249.893929) (xy 389.189282 -249.868483) (xy 389.236868 -249.850436) (xy 389.286732 -249.840256)
			(xy 389.337584 -249.838207) (xy 389.388105 -249.844341) (xy 389.436989 -249.858501) (xy 389.482968 -249.880318)
			(xy 389.524852 -249.909228) (xy 389.561556 -249.944483) (xy 389.592129 -249.985169) (xy 389.61578 -250.030232)
			(xy 389.631896 -250.078506) (xy 389.64006 -250.12874) (xy 389.640572 -250.154186) (xy 389.9591 -250.154186)
			(xy 389.96306 -250.105132) (xy 389.974837 -250.057348) (xy 389.994128 -250.012072) (xy 390.020431 -249.970476)
			(xy 390.053066 -249.933639) (xy 390.091187 -249.902514) (xy 390.133808 -249.877907) (xy 390.179824 -249.860455)
			(xy 390.228043 -249.850611) (xy 390.277218 -249.84863) (xy 390.326073 -249.854562) (xy 390.373344 -249.868254)
			(xy 390.417806 -249.889352) (xy 390.458309 -249.917308) (xy 390.493802 -249.9514) (xy 390.523367 -249.990744)
			(xy 390.546238 -250.034321) (xy 390.561822 -250.081002) (xy 390.569717 -250.129579) (xy 390.570212 -250.154186)
			(xy 390.8989 -250.154186) (xy 390.90286 -250.105132) (xy 390.914637 -250.057348) (xy 390.933928 -250.012072)
			(xy 390.960231 -249.970476) (xy 390.992866 -249.933639) (xy 391.030987 -249.902514) (xy 391.073608 -249.877907)
			(xy 391.119624 -249.860455) (xy 391.167843 -249.850611) (xy 391.217018 -249.84863) (xy 391.265873 -249.854562)
			(xy 391.313144 -249.868254) (xy 391.357606 -249.889352) (xy 391.398109 -249.917308) (xy 391.433602 -249.9514)
			(xy 391.463167 -249.990744) (xy 391.486038 -250.034321) (xy 391.501622 -250.081002) (xy 391.509517 -250.129579)
			(xy 391.510012 -250.154186) (xy 391.838954 -250.154186) (xy 391.842914 -250.105132) (xy 391.854691 -250.057348)
			(xy 391.873982 -250.012072) (xy 391.900285 -249.970476) (xy 391.93292 -249.933639) (xy 391.971041 -249.902514)
			(xy 392.013662 -249.877907) (xy 392.059678 -249.860455) (xy 392.107897 -249.850611) (xy 392.157072 -249.84863)
			(xy 392.205927 -249.854562) (xy 392.253198 -249.868254) (xy 392.29766 -249.889352) (xy 392.338163 -249.917308)
			(xy 392.373656 -249.9514) (xy 392.403221 -249.990744) (xy 392.426092 -250.034321) (xy 392.441676 -250.081002)
			(xy 392.449571 -250.129579) (xy 392.450066 -250.154186) (xy 392.779008 -250.154186) (xy 392.782968 -250.105132)
			(xy 392.794745 -250.057348) (xy 392.814036 -250.012072) (xy 392.840339 -249.970476) (xy 392.872974 -249.933639)
			(xy 392.911095 -249.902514) (xy 392.953716 -249.877907) (xy 392.999732 -249.860455) (xy 393.047951 -249.850611)
			(xy 393.097126 -249.84863) (xy 393.145981 -249.854562) (xy 393.193252 -249.868254) (xy 393.237714 -249.889352)
			(xy 393.278217 -249.917308) (xy 393.31371 -249.9514) (xy 393.343275 -249.990744) (xy 393.366146 -250.034321)
			(xy 393.38173 -250.081002) (xy 393.389625 -250.129579) (xy 393.39012 -250.154186) (xy 393.389625 -250.178793)
			(xy 393.38173 -250.22737) (xy 393.366146 -250.274051) (xy 393.343275 -250.317628) (xy 393.31371 -250.356972)
			(xy 393.278217 -250.391064) (xy 393.237714 -250.41902) (xy 393.193252 -250.440118) (xy 393.145981 -250.45381)
			(xy 393.097126 -250.459742) (xy 393.047951 -250.457761) (xy 392.999732 -250.447917) (xy 392.953716 -250.430465)
			(xy 392.911095 -250.405858) (xy 392.872974 -250.374733) (xy 392.840339 -250.337896) (xy 392.814036 -250.2963)
			(xy 392.794745 -250.251024) (xy 392.782968 -250.20324) (xy 392.779008 -250.154186) (xy 392.450066 -250.154186)
			(xy 392.449571 -250.178793) (xy 392.441676 -250.22737) (xy 392.426092 -250.274051) (xy 392.403221 -250.317628)
			(xy 392.373656 -250.356972) (xy 392.338163 -250.391064) (xy 392.29766 -250.41902) (xy 392.253198 -250.440118)
			(xy 392.205927 -250.45381) (xy 392.157072 -250.459742) (xy 392.107897 -250.457761) (xy 392.059678 -250.447917)
			(xy 392.013662 -250.430465) (xy 391.971041 -250.405858) (xy 391.93292 -250.374733) (xy 391.900285 -250.337896)
			(xy 391.873982 -250.2963) (xy 391.854691 -250.251024) (xy 391.842914 -250.20324) (xy 391.838954 -250.154186)
			(xy 391.510012 -250.154186) (xy 391.509517 -250.178793) (xy 391.501622 -250.22737) (xy 391.486038 -250.274051)
			(xy 391.463167 -250.317628) (xy 391.433602 -250.356972) (xy 391.398109 -250.391064) (xy 391.357606 -250.41902)
			(xy 391.313144 -250.440118) (xy 391.265873 -250.45381) (xy 391.217018 -250.459742) (xy 391.167843 -250.457761)
			(xy 391.119624 -250.447917) (xy 391.073608 -250.430465) (xy 391.030987 -250.405858) (xy 390.992866 -250.374733)
			(xy 390.960231 -250.337896) (xy 390.933928 -250.2963) (xy 390.914637 -250.251024) (xy 390.90286 -250.20324)
			(xy 390.8989 -250.154186) (xy 390.570212 -250.154186) (xy 390.569717 -250.178793) (xy 390.561822 -250.22737)
			(xy 390.546238 -250.274051) (xy 390.523367 -250.317628) (xy 390.493802 -250.356972) (xy 390.458309 -250.391064)
			(xy 390.417806 -250.41902) (xy 390.373344 -250.440118) (xy 390.326073 -250.45381) (xy 390.277218 -250.459742)
			(xy 390.228043 -250.457761) (xy 390.179824 -250.447917) (xy 390.133808 -250.430465) (xy 390.091187 -250.405858)
			(xy 390.053066 -250.374733) (xy 390.020431 -250.337896) (xy 389.994128 -250.2963) (xy 389.974837 -250.251024)
			(xy 389.96306 -250.20324) (xy 389.9591 -250.154186) (xy 389.640572 -250.154186) (xy 389.64006 -250.179632)
			(xy 389.631896 -250.229866) (xy 389.61578 -250.27814) (xy 389.592129 -250.323203) (xy 389.561556 -250.363889)
			(xy 389.524852 -250.399144) (xy 389.482968 -250.428054) (xy 389.436989 -250.449871) (xy 389.388105 -250.464031)
			(xy 389.337584 -250.470165) (xy 389.286732 -250.468116) (xy 389.236868 -250.457936) (xy 389.189282 -250.439889)
			(xy 389.145208 -250.414443) (xy 389.105786 -250.382256) (xy 389.072038 -250.344162) (xy 389.044837 -250.301148)
			(xy 389.024889 -250.254328) (xy 389.01271 -250.204914) (xy 389.008615 -250.154186) (xy 388.690104 -250.154186)
			(xy 388.689609 -250.178793) (xy 388.681714 -250.22737) (xy 388.66613 -250.274051) (xy 388.643259 -250.317628)
			(xy 388.613694 -250.356972) (xy 388.578201 -250.391064) (xy 388.537698 -250.41902) (xy 388.493236 -250.440118)
			(xy 388.445965 -250.45381) (xy 388.39711 -250.459742) (xy 388.347935 -250.457761) (xy 388.299716 -250.447917)
			(xy 388.2537 -250.430465) (xy 388.211079 -250.405858) (xy 388.172958 -250.374733) (xy 388.140323 -250.337896)
			(xy 388.11402 -250.2963) (xy 388.094729 -250.251024) (xy 388.082952 -250.20324) (xy 388.078992 -250.154186)
			(xy 387.75005 -250.154186) (xy 387.749555 -250.178793) (xy 387.74166 -250.22737) (xy 387.726076 -250.274051)
			(xy 387.703205 -250.317628) (xy 387.67364 -250.356972) (xy 387.638147 -250.391064) (xy 387.597644 -250.41902)
			(xy 387.553182 -250.440118) (xy 387.505911 -250.45381) (xy 387.457056 -250.459742) (xy 387.407881 -250.457761)
			(xy 387.359662 -250.447917) (xy 387.313646 -250.430465) (xy 387.271025 -250.405858) (xy 387.232904 -250.374733)
			(xy 387.200269 -250.337896) (xy 387.173966 -250.2963) (xy 387.154675 -250.251024) (xy 387.142898 -250.20324)
			(xy 387.138938 -250.154186) (xy 386.81025 -250.154186) (xy 386.809755 -250.178793) (xy 386.80186 -250.22737)
			(xy 386.786276 -250.274051) (xy 386.763405 -250.317628) (xy 386.73384 -250.356972) (xy 386.698347 -250.391064)
			(xy 386.657844 -250.41902) (xy 386.613382 -250.440118) (xy 386.566111 -250.45381) (xy 386.517256 -250.459742)
			(xy 386.468081 -250.457761) (xy 386.419862 -250.447917) (xy 386.373846 -250.430465) (xy 386.331225 -250.405858)
			(xy 386.293104 -250.374733) (xy 386.260469 -250.337896) (xy 386.234166 -250.2963) (xy 386.214875 -250.251024)
			(xy 386.203098 -250.20324) (xy 386.199138 -250.154186) (xy 385.88061 -250.154186) (xy 385.880098 -250.179632)
			(xy 385.871934 -250.229866) (xy 385.855818 -250.27814) (xy 385.832167 -250.323203) (xy 385.801594 -250.363889)
			(xy 385.76489 -250.399144) (xy 385.723006 -250.428054) (xy 385.677027 -250.449871) (xy 385.628143 -250.464031)
			(xy 385.577622 -250.470165) (xy 385.52677 -250.468116) (xy 385.476906 -250.457936) (xy 385.42932 -250.439889)
			(xy 385.385246 -250.414443) (xy 385.345824 -250.382256) (xy 385.312076 -250.344162) (xy 385.284875 -250.301148)
			(xy 385.264927 -250.254328) (xy 385.252748 -250.204914) (xy 385.248653 -250.154186) (xy 384.930142 -250.154186)
			(xy 384.929647 -250.178793) (xy 384.921752 -250.22737) (xy 384.906168 -250.274051) (xy 384.883297 -250.317628)
			(xy 384.853732 -250.356972) (xy 384.818239 -250.391064) (xy 384.777736 -250.41902) (xy 384.733274 -250.440118)
			(xy 384.686003 -250.45381) (xy 384.637148 -250.459742) (xy 384.587973 -250.457761) (xy 384.539754 -250.447917)
			(xy 384.493738 -250.430465) (xy 384.451117 -250.405858) (xy 384.412996 -250.374733) (xy 384.380361 -250.337896)
			(xy 384.354058 -250.2963) (xy 384.334767 -250.251024) (xy 384.32299 -250.20324) (xy 384.31903 -250.154186)
			(xy 383.990088 -250.154186) (xy 383.989593 -250.178793) (xy 383.981698 -250.22737) (xy 383.966114 -250.274051)
			(xy 383.943243 -250.317628) (xy 383.913678 -250.356972) (xy 383.878185 -250.391064) (xy 383.837682 -250.41902)
			(xy 383.79322 -250.440118) (xy 383.745949 -250.45381) (xy 383.697094 -250.459742) (xy 383.647919 -250.457761)
			(xy 383.5997 -250.447917) (xy 383.553684 -250.430465) (xy 383.511063 -250.405858) (xy 383.472942 -250.374733)
			(xy 383.440307 -250.337896) (xy 383.414004 -250.2963) (xy 383.394713 -250.251024) (xy 383.382936 -250.20324)
			(xy 383.378976 -250.154186) (xy 383.060448 -250.154186) (xy 383.059936 -250.179632) (xy 383.051772 -250.229866)
			(xy 383.035656 -250.27814) (xy 383.012005 -250.323203) (xy 382.981432 -250.363889) (xy 382.944728 -250.399144)
			(xy 382.902844 -250.428054) (xy 382.856865 -250.449871) (xy 382.807981 -250.464031) (xy 382.75746 -250.470165)
			(xy 382.706608 -250.468116) (xy 382.656744 -250.457936) (xy 382.609158 -250.439889) (xy 382.565084 -250.414443)
			(xy 382.525662 -250.382256) (xy 382.491914 -250.344162) (xy 382.464713 -250.301148) (xy 382.444765 -250.254328)
			(xy 382.432586 -250.204914) (xy 382.428491 -250.154186) (xy 382.110234 -250.154186) (xy 382.109739 -250.178793)
			(xy 382.101844 -250.22737) (xy 382.08626 -250.274051) (xy 382.063389 -250.317628) (xy 382.033824 -250.356972)
			(xy 381.998331 -250.391064) (xy 381.957828 -250.41902) (xy 381.913366 -250.440118) (xy 381.866095 -250.45381)
			(xy 381.81724 -250.459742) (xy 381.768065 -250.457761) (xy 381.719846 -250.447917) (xy 381.67383 -250.430465)
			(xy 381.631209 -250.405858) (xy 381.593088 -250.374733) (xy 381.560453 -250.337896) (xy 381.53415 -250.2963)
			(xy 381.514859 -250.251024) (xy 381.503082 -250.20324) (xy 381.499122 -250.154186) (xy 381.17018 -250.154186)
			(xy 381.169685 -250.178793) (xy 381.16179 -250.22737) (xy 381.146206 -250.274051) (xy 381.123335 -250.317628)
			(xy 381.09377 -250.356972) (xy 381.058277 -250.391064) (xy 381.017774 -250.41902) (xy 380.973312 -250.440118)
			(xy 380.926041 -250.45381) (xy 380.877186 -250.459742) (xy 380.828011 -250.457761) (xy 380.779792 -250.447917)
			(xy 380.733776 -250.430465) (xy 380.691155 -250.405858) (xy 380.653034 -250.374733) (xy 380.620399 -250.337896)
			(xy 380.594096 -250.2963) (xy 380.574805 -250.251024) (xy 380.563028 -250.20324) (xy 380.559068 -250.154186)
			(xy 380.230126 -250.154186) (xy 380.229631 -250.178793) (xy 380.221736 -250.22737) (xy 380.206152 -250.274051)
			(xy 380.183281 -250.317628) (xy 380.153716 -250.356972) (xy 380.118223 -250.391064) (xy 380.07772 -250.41902)
			(xy 380.033258 -250.440118) (xy 379.985987 -250.45381) (xy 379.937132 -250.459742) (xy 379.887957 -250.457761)
			(xy 379.839738 -250.447917) (xy 379.793722 -250.430465) (xy 379.751101 -250.405858) (xy 379.71298 -250.374733)
			(xy 379.680345 -250.337896) (xy 379.654042 -250.2963) (xy 379.634751 -250.251024) (xy 379.622974 -250.20324)
			(xy 379.619014 -250.154186) (xy 379.300486 -250.154186) (xy 379.299974 -250.179632) (xy 379.29181 -250.229866)
			(xy 379.275694 -250.27814) (xy 379.252043 -250.323203) (xy 379.22147 -250.363889) (xy 379.184766 -250.399144)
			(xy 379.142882 -250.428054) (xy 379.096903 -250.449871) (xy 379.048019 -250.464031) (xy 378.997498 -250.470165)
			(xy 378.946646 -250.468116) (xy 378.896782 -250.457936) (xy 378.849196 -250.439889) (xy 378.805122 -250.414443)
			(xy 378.7657 -250.382256) (xy 378.731952 -250.344162) (xy 378.704751 -250.301148) (xy 378.684803 -250.254328)
			(xy 378.672624 -250.204914) (xy 378.668529 -250.154186) (xy 378.350018 -250.154186) (xy 378.349523 -250.178793)
			(xy 378.341628 -250.22737) (xy 378.326044 -250.274051) (xy 378.303173 -250.317628) (xy 378.273608 -250.356972)
			(xy 378.238115 -250.391064) (xy 378.197612 -250.41902) (xy 378.15315 -250.440118) (xy 378.105879 -250.45381)
			(xy 378.057024 -250.459742) (xy 378.007849 -250.457761) (xy 377.95963 -250.447917) (xy 377.913614 -250.430465)
			(xy 377.870993 -250.405858) (xy 377.832872 -250.374733) (xy 377.800237 -250.337896) (xy 377.773934 -250.2963)
			(xy 377.754643 -250.251024) (xy 377.742866 -250.20324) (xy 377.738906 -250.154186) (xy 377.410218 -250.154186)
			(xy 377.409723 -250.178793) (xy 377.401828 -250.22737) (xy 377.386244 -250.274051) (xy 377.363373 -250.317628)
			(xy 377.333808 -250.356972) (xy 377.298315 -250.391064) (xy 377.257812 -250.41902) (xy 377.21335 -250.440118)
			(xy 377.166079 -250.45381) (xy 377.117224 -250.459742) (xy 377.068049 -250.457761) (xy 377.01983 -250.447917)
			(xy 376.973814 -250.430465) (xy 376.931193 -250.405858) (xy 376.893072 -250.374733) (xy 376.860437 -250.337896)
			(xy 376.834134 -250.2963) (xy 376.814843 -250.251024) (xy 376.803066 -250.20324) (xy 376.799106 -250.154186)
			(xy 376.480578 -250.154186) (xy 376.480066 -250.179632) (xy 376.471902 -250.229866) (xy 376.455786 -250.27814)
			(xy 376.432135 -250.323203) (xy 376.401562 -250.363889) (xy 376.364858 -250.399144) (xy 376.322974 -250.428054)
			(xy 376.276995 -250.449871) (xy 376.228111 -250.464031) (xy 376.17759 -250.470165) (xy 376.126738 -250.468116)
			(xy 376.076874 -250.457936) (xy 376.029288 -250.439889) (xy 375.985214 -250.414443) (xy 375.945792 -250.382256)
			(xy 375.912044 -250.344162) (xy 375.884843 -250.301148) (xy 375.864895 -250.254328) (xy 375.852716 -250.204914)
			(xy 375.848621 -250.154186) (xy 374.98528 -250.154186) (xy 374.98528 -250.737116) (xy 374.985357 -250.741325)
			(xy 374.986766 -250.749624) (xy 374.988074 -250.753626) (xy 374.995948 -250.776486) (xy 375.00052 -250.782836)
			(xy 375.013849 -250.801616) (xy 375.03531 -250.842361) (xy 375.050419 -250.885864) (xy 375.058834 -250.93114)
			(xy 375.059933 -250.964192) (xy 375.378467 -250.964192) (xy 375.382562 -250.913464) (xy 375.394741 -250.86405)
			(xy 375.414689 -250.81723) (xy 375.44189 -250.774216) (xy 375.475638 -250.736122) (xy 375.51506 -250.703935)
			(xy 375.559134 -250.678489) (xy 375.60672 -250.660442) (xy 375.656584 -250.650262) (xy 375.707436 -250.648213)
			(xy 375.757957 -250.654347) (xy 375.806841 -250.668507) (xy 375.85282 -250.690324) (xy 375.894704 -250.719234)
			(xy 375.931408 -250.754489) (xy 375.961981 -250.795175) (xy 375.985632 -250.840238) (xy 376.001748 -250.888512)
			(xy 376.009912 -250.938746) (xy 376.010424 -250.964192) (xy 376.328952 -250.964192) (xy 376.332912 -250.915138)
			(xy 376.344689 -250.867354) (xy 376.36398 -250.822078) (xy 376.390283 -250.780482) (xy 376.422918 -250.743645)
			(xy 376.461039 -250.71252) (xy 376.50366 -250.687913) (xy 376.549676 -250.670461) (xy 376.597895 -250.660617)
			(xy 376.64707 -250.658636) (xy 376.695925 -250.664568) (xy 376.743196 -250.67826) (xy 376.787658 -250.699358)
			(xy 376.828161 -250.727314) (xy 376.863654 -250.761406) (xy 376.893219 -250.80075) (xy 376.91609 -250.844327)
			(xy 376.931674 -250.891008) (xy 376.939569 -250.939585) (xy 376.940064 -250.964192) (xy 377.258575 -250.964192)
			(xy 377.26267 -250.913464) (xy 377.274849 -250.86405) (xy 377.294797 -250.81723) (xy 377.321998 -250.774216)
			(xy 377.355746 -250.736122) (xy 377.395168 -250.703935) (xy 377.439242 -250.678489) (xy 377.486828 -250.660442)
			(xy 377.536692 -250.650262) (xy 377.587544 -250.648213) (xy 377.638065 -250.654347) (xy 377.686949 -250.668507)
			(xy 377.732928 -250.690324) (xy 377.774812 -250.719234) (xy 377.811516 -250.754489) (xy 377.842089 -250.795175)
			(xy 377.86574 -250.840238) (xy 377.881856 -250.888512) (xy 377.89002 -250.938746) (xy 377.890532 -250.964192)
			(xy 378.20906 -250.964192) (xy 378.21302 -250.915138) (xy 378.224797 -250.867354) (xy 378.244088 -250.822078)
			(xy 378.270391 -250.780482) (xy 378.303026 -250.743645) (xy 378.341147 -250.71252) (xy 378.383768 -250.687913)
			(xy 378.429784 -250.670461) (xy 378.478003 -250.660617) (xy 378.527178 -250.658636) (xy 378.576033 -250.664568)
			(xy 378.623304 -250.67826) (xy 378.667766 -250.699358) (xy 378.708269 -250.727314) (xy 378.743762 -250.761406)
			(xy 378.773327 -250.80075) (xy 378.796198 -250.844327) (xy 378.811782 -250.891008) (xy 378.819677 -250.939585)
			(xy 378.820172 -250.964192) (xy 379.138683 -250.964192) (xy 379.142778 -250.913464) (xy 379.154957 -250.86405)
			(xy 379.174905 -250.81723) (xy 379.202106 -250.774216) (xy 379.235854 -250.736122) (xy 379.275276 -250.703935)
			(xy 379.31935 -250.678489) (xy 379.366936 -250.660442) (xy 379.4168 -250.650262) (xy 379.467652 -250.648213)
			(xy 379.518173 -250.654347) (xy 379.567057 -250.668507) (xy 379.613036 -250.690324) (xy 379.65492 -250.719234)
			(xy 379.691624 -250.754489) (xy 379.722197 -250.795175) (xy 379.745848 -250.840238) (xy 379.761964 -250.888512)
			(xy 379.770128 -250.938746) (xy 379.77064 -250.964192) (xy 380.078483 -250.964192) (xy 380.082578 -250.913464)
			(xy 380.094757 -250.86405) (xy 380.114705 -250.81723) (xy 380.141906 -250.774216) (xy 380.175654 -250.736122)
			(xy 380.215076 -250.703935) (xy 380.25915 -250.678489) (xy 380.306736 -250.660442) (xy 380.3566 -250.650262)
			(xy 380.407452 -250.648213) (xy 380.457973 -250.654347) (xy 380.506857 -250.668507) (xy 380.552836 -250.690324)
			(xy 380.59472 -250.719234) (xy 380.631424 -250.754489) (xy 380.661997 -250.795175) (xy 380.685648 -250.840238)
			(xy 380.701764 -250.888512) (xy 380.709928 -250.938746) (xy 380.71044 -250.964192) (xy 381.028968 -250.964192)
			(xy 381.032928 -250.915138) (xy 381.044705 -250.867354) (xy 381.063996 -250.822078) (xy 381.090299 -250.780482)
			(xy 381.122934 -250.743645) (xy 381.161055 -250.71252) (xy 381.203676 -250.687913) (xy 381.249692 -250.670461)
			(xy 381.297911 -250.660617) (xy 381.347086 -250.658636) (xy 381.395941 -250.664568) (xy 381.443212 -250.67826)
			(xy 381.487674 -250.699358) (xy 381.528177 -250.727314) (xy 381.56367 -250.761406) (xy 381.593235 -250.80075)
			(xy 381.616106 -250.844327) (xy 381.63169 -250.891008) (xy 381.639585 -250.939585) (xy 381.64008 -250.964192)
			(xy 381.958591 -250.964192) (xy 381.962686 -250.913464) (xy 381.974865 -250.86405) (xy 381.994813 -250.81723)
			(xy 382.022014 -250.774216) (xy 382.055762 -250.736122) (xy 382.095184 -250.703935) (xy 382.139258 -250.678489)
			(xy 382.186844 -250.660442) (xy 382.236708 -250.650262) (xy 382.28756 -250.648213) (xy 382.338081 -250.654347)
			(xy 382.386965 -250.668507) (xy 382.432944 -250.690324) (xy 382.474828 -250.719234) (xy 382.511532 -250.754489)
			(xy 382.542105 -250.795175) (xy 382.565756 -250.840238) (xy 382.581872 -250.888512) (xy 382.590036 -250.938746)
			(xy 382.590548 -250.964192) (xy 382.909076 -250.964192) (xy 382.913036 -250.915138) (xy 382.924813 -250.867354)
			(xy 382.944104 -250.822078) (xy 382.970407 -250.780482) (xy 383.003042 -250.743645) (xy 383.041163 -250.71252)
			(xy 383.083784 -250.687913) (xy 383.1298 -250.670461) (xy 383.178019 -250.660617) (xy 383.227194 -250.658636)
			(xy 383.276049 -250.664568) (xy 383.32332 -250.67826) (xy 383.367782 -250.699358) (xy 383.408285 -250.727314)
			(xy 383.443778 -250.761406) (xy 383.473343 -250.80075) (xy 383.496214 -250.844327) (xy 383.511798 -250.891008)
			(xy 383.519693 -250.939585) (xy 383.520188 -250.964192) (xy 383.838699 -250.964192) (xy 383.842794 -250.913464)
			(xy 383.854973 -250.86405) (xy 383.874921 -250.81723) (xy 383.902122 -250.774216) (xy 383.93587 -250.736122)
			(xy 383.975292 -250.703935) (xy 384.019366 -250.678489) (xy 384.066952 -250.660442) (xy 384.116816 -250.650262)
			(xy 384.167668 -250.648213) (xy 384.218189 -250.654347) (xy 384.267073 -250.668507) (xy 384.313052 -250.690324)
			(xy 384.354936 -250.719234) (xy 384.39164 -250.754489) (xy 384.422213 -250.795175) (xy 384.445864 -250.840238)
			(xy 384.46198 -250.888512) (xy 384.470144 -250.938746) (xy 384.470656 -250.964192) (xy 384.78893 -250.964192)
			(xy 384.79289 -250.915138) (xy 384.804667 -250.867354) (xy 384.823958 -250.822078) (xy 384.850261 -250.780482)
			(xy 384.882896 -250.743645) (xy 384.921017 -250.71252) (xy 384.963638 -250.687913) (xy 385.009654 -250.670461)
			(xy 385.057873 -250.660617) (xy 385.107048 -250.658636) (xy 385.155903 -250.664568) (xy 385.203174 -250.67826)
			(xy 385.247636 -250.699358) (xy 385.288139 -250.727314) (xy 385.323632 -250.761406) (xy 385.353197 -250.80075)
			(xy 385.376068 -250.844327) (xy 385.391652 -250.891008) (xy 385.399547 -250.939585) (xy 385.400042 -250.964192)
			(xy 385.718553 -250.964192) (xy 385.722648 -250.913464) (xy 385.734827 -250.86405) (xy 385.754775 -250.81723)
			(xy 385.781976 -250.774216) (xy 385.815724 -250.736122) (xy 385.855146 -250.703935) (xy 385.89922 -250.678489)
			(xy 385.946806 -250.660442) (xy 385.99667 -250.650262) (xy 386.047522 -250.648213) (xy 386.098043 -250.654347)
			(xy 386.146927 -250.668507) (xy 386.192906 -250.690324) (xy 386.23479 -250.719234) (xy 386.271494 -250.754489)
			(xy 386.302067 -250.795175) (xy 386.325718 -250.840238) (xy 386.341834 -250.888512) (xy 386.349998 -250.938746)
			(xy 386.35051 -250.964192) (xy 386.658607 -250.964192) (xy 386.662702 -250.913464) (xy 386.674881 -250.86405)
			(xy 386.694829 -250.81723) (xy 386.72203 -250.774216) (xy 386.755778 -250.736122) (xy 386.7952 -250.703935)
			(xy 386.839274 -250.678489) (xy 386.88686 -250.660442) (xy 386.936724 -250.650262) (xy 386.987576 -250.648213)
			(xy 387.038097 -250.654347) (xy 387.086981 -250.668507) (xy 387.13296 -250.690324) (xy 387.174844 -250.719234)
			(xy 387.211548 -250.754489) (xy 387.242121 -250.795175) (xy 387.265772 -250.840238) (xy 387.281888 -250.888512)
			(xy 387.290052 -250.938746) (xy 387.290564 -250.964192) (xy 387.609092 -250.964192) (xy 387.613052 -250.915138)
			(xy 387.624829 -250.867354) (xy 387.64412 -250.822078) (xy 387.670423 -250.780482) (xy 387.703058 -250.743645)
			(xy 387.741179 -250.71252) (xy 387.7838 -250.687913) (xy 387.829816 -250.670461) (xy 387.878035 -250.660617)
			(xy 387.92721 -250.658636) (xy 387.976065 -250.664568) (xy 388.023336 -250.67826) (xy 388.067798 -250.699358)
			(xy 388.108301 -250.727314) (xy 388.143794 -250.761406) (xy 388.173359 -250.80075) (xy 388.19623 -250.844327)
			(xy 388.211814 -250.891008) (xy 388.219709 -250.939585) (xy 388.220204 -250.964192) (xy 388.538715 -250.964192)
			(xy 388.54281 -250.913464) (xy 388.554989 -250.86405) (xy 388.574937 -250.81723) (xy 388.602138 -250.774216)
			(xy 388.635886 -250.736122) (xy 388.675308 -250.703935) (xy 388.719382 -250.678489) (xy 388.766968 -250.660442)
			(xy 388.816832 -250.650262) (xy 388.867684 -250.648213) (xy 388.918205 -250.654347) (xy 388.967089 -250.668507)
			(xy 389.013068 -250.690324) (xy 389.054952 -250.719234) (xy 389.091656 -250.754489) (xy 389.122229 -250.795175)
			(xy 389.14588 -250.840238) (xy 389.161996 -250.888512) (xy 389.17016 -250.938746) (xy 389.170672 -250.964192)
			(xy 389.488946 -250.964192) (xy 389.492906 -250.915138) (xy 389.504683 -250.867354) (xy 389.523974 -250.822078)
			(xy 389.550277 -250.780482) (xy 389.582912 -250.743645) (xy 389.621033 -250.71252) (xy 389.663654 -250.687913)
			(xy 389.70967 -250.670461) (xy 389.757889 -250.660617) (xy 389.807064 -250.658636) (xy 389.855919 -250.664568)
			(xy 389.90319 -250.67826) (xy 389.947652 -250.699358) (xy 389.988155 -250.727314) (xy 390.023648 -250.761406)
			(xy 390.053213 -250.80075) (xy 390.076084 -250.844327) (xy 390.091668 -250.891008) (xy 390.099563 -250.939585)
			(xy 390.100058 -250.964192) (xy 390.418569 -250.964192) (xy 390.422664 -250.913464) (xy 390.434843 -250.86405)
			(xy 390.454791 -250.81723) (xy 390.481992 -250.774216) (xy 390.51574 -250.736122) (xy 390.555162 -250.703935)
			(xy 390.599236 -250.678489) (xy 390.646822 -250.660442) (xy 390.696686 -250.650262) (xy 390.747538 -250.648213)
			(xy 390.798059 -250.654347) (xy 390.846943 -250.668507) (xy 390.892922 -250.690324) (xy 390.934806 -250.719234)
			(xy 390.97151 -250.754489) (xy 391.002083 -250.795175) (xy 391.025734 -250.840238) (xy 391.04185 -250.888512)
			(xy 391.050014 -250.938746) (xy 391.050526 -250.964192) (xy 391.369054 -250.964192) (xy 391.373014 -250.915138)
			(xy 391.384791 -250.867354) (xy 391.404082 -250.822078) (xy 391.430385 -250.780482) (xy 391.46302 -250.743645)
			(xy 391.501141 -250.71252) (xy 391.543762 -250.687913) (xy 391.589778 -250.670461) (xy 391.637997 -250.660617)
			(xy 391.687172 -250.658636) (xy 391.736027 -250.664568) (xy 391.783298 -250.67826) (xy 391.82776 -250.699358)
			(xy 391.868263 -250.727314) (xy 391.903756 -250.761406) (xy 391.933321 -250.80075) (xy 391.956192 -250.844327)
			(xy 391.971776 -250.891008) (xy 391.979671 -250.939585) (xy 391.980166 -250.964192) (xy 392.309108 -250.964192)
			(xy 392.313068 -250.915138) (xy 392.324845 -250.867354) (xy 392.344136 -250.822078) (xy 392.370439 -250.780482)
			(xy 392.403074 -250.743645) (xy 392.441195 -250.71252) (xy 392.483816 -250.687913) (xy 392.529832 -250.670461)
			(xy 392.578051 -250.660617) (xy 392.627226 -250.658636) (xy 392.676081 -250.664568) (xy 392.723352 -250.67826)
			(xy 392.767814 -250.699358) (xy 392.808317 -250.727314) (xy 392.84381 -250.761406) (xy 392.873375 -250.80075)
			(xy 392.896246 -250.844327) (xy 392.91183 -250.891008) (xy 392.919725 -250.939585) (xy 392.92022 -250.964192)
			(xy 392.919725 -250.988799) (xy 392.91183 -251.037376) (xy 392.896246 -251.084057) (xy 392.873375 -251.127634)
			(xy 392.84381 -251.166978) (xy 392.808317 -251.20107) (xy 392.767814 -251.229026) (xy 392.765487 -251.23013)
			(xy 394.377176 -251.23013) (xy 394.381136 -251.181076) (xy 394.392913 -251.133292) (xy 394.412204 -251.088016)
			(xy 394.438507 -251.04642) (xy 394.471142 -251.009583) (xy 394.509263 -250.978458) (xy 394.551884 -250.953851)
			(xy 394.5979 -250.936399) (xy 394.646119 -250.926555) (xy 394.695294 -250.924574) (xy 394.744149 -250.930506)
			(xy 394.79142 -250.944198) (xy 394.835882 -250.965296) (xy 394.876385 -250.993252) (xy 394.911878 -251.027344)
			(xy 394.941443 -251.066688) (xy 394.964314 -251.110265) (xy 394.979898 -251.156946) (xy 394.987793 -251.205523)
			(xy 394.988288 -251.23013) (xy 394.987793 -251.254737) (xy 394.979898 -251.303314) (xy 394.964314 -251.349995)
			(xy 394.941443 -251.393572) (xy 394.911878 -251.432916) (xy 394.876385 -251.467008) (xy 394.835882 -251.494964)
			(xy 394.79142 -251.516062) (xy 394.744149 -251.529754) (xy 394.695294 -251.535686) (xy 394.646119 -251.533705)
			(xy 394.5979 -251.523861) (xy 394.551884 -251.506409) (xy 394.509263 -251.481802) (xy 394.471142 -251.450677)
			(xy 394.438507 -251.41384) (xy 394.412204 -251.372244) (xy 394.392913 -251.326968) (xy 394.381136 -251.279184)
			(xy 394.377176 -251.23013) (xy 392.765487 -251.23013) (xy 392.723352 -251.250124) (xy 392.676081 -251.263816)
			(xy 392.627226 -251.269748) (xy 392.578051 -251.267767) (xy 392.529832 -251.257923) (xy 392.483816 -251.240471)
			(xy 392.441195 -251.215864) (xy 392.403074 -251.184739) (xy 392.370439 -251.147902) (xy 392.344136 -251.106306)
			(xy 392.324845 -251.06103) (xy 392.313068 -251.013246) (xy 392.309108 -250.964192) (xy 391.980166 -250.964192)
			(xy 391.979671 -250.988799) (xy 391.971776 -251.037376) (xy 391.956192 -251.084057) (xy 391.933321 -251.127634)
			(xy 391.903756 -251.166978) (xy 391.868263 -251.20107) (xy 391.82776 -251.229026) (xy 391.783298 -251.250124)
			(xy 391.736027 -251.263816) (xy 391.687172 -251.269748) (xy 391.637997 -251.267767) (xy 391.589778 -251.257923)
			(xy 391.543762 -251.240471) (xy 391.501141 -251.215864) (xy 391.46302 -251.184739) (xy 391.430385 -251.147902)
			(xy 391.404082 -251.106306) (xy 391.384791 -251.06103) (xy 391.373014 -251.013246) (xy 391.369054 -250.964192)
			(xy 391.050526 -250.964192) (xy 391.050014 -250.989638) (xy 391.04185 -251.039872) (xy 391.025734 -251.088146)
			(xy 391.002083 -251.133209) (xy 390.97151 -251.173895) (xy 390.934806 -251.20915) (xy 390.892922 -251.23806)
			(xy 390.846943 -251.259877) (xy 390.798059 -251.274037) (xy 390.747538 -251.280171) (xy 390.696686 -251.278122)
			(xy 390.646822 -251.267942) (xy 390.599236 -251.249895) (xy 390.555162 -251.224449) (xy 390.51574 -251.192262)
			(xy 390.481992 -251.154168) (xy 390.454791 -251.111154) (xy 390.434843 -251.064334) (xy 390.422664 -251.01492)
			(xy 390.418569 -250.964192) (xy 390.100058 -250.964192) (xy 390.099563 -250.988799) (xy 390.091668 -251.037376)
			(xy 390.076084 -251.084057) (xy 390.053213 -251.127634) (xy 390.023648 -251.166978) (xy 389.988155 -251.20107)
			(xy 389.947652 -251.229026) (xy 389.90319 -251.250124) (xy 389.855919 -251.263816) (xy 389.807064 -251.269748)
			(xy 389.757889 -251.267767) (xy 389.70967 -251.257923) (xy 389.663654 -251.240471) (xy 389.621033 -251.215864)
			(xy 389.582912 -251.184739) (xy 389.550277 -251.147902) (xy 389.523974 -251.106306) (xy 389.504683 -251.06103)
			(xy 389.492906 -251.013246) (xy 389.488946 -250.964192) (xy 389.170672 -250.964192) (xy 389.17016 -250.989638)
			(xy 389.161996 -251.039872) (xy 389.14588 -251.088146) (xy 389.122229 -251.133209) (xy 389.091656 -251.173895)
			(xy 389.054952 -251.20915) (xy 389.013068 -251.23806) (xy 388.967089 -251.259877) (xy 388.918205 -251.274037)
			(xy 388.867684 -251.280171) (xy 388.816832 -251.278122) (xy 388.766968 -251.267942) (xy 388.719382 -251.249895)
			(xy 388.675308 -251.224449) (xy 388.635886 -251.192262) (xy 388.602138 -251.154168) (xy 388.574937 -251.111154)
			(xy 388.554989 -251.064334) (xy 388.54281 -251.01492) (xy 388.538715 -250.964192) (xy 388.220204 -250.964192)
			(xy 388.219709 -250.988799) (xy 388.211814 -251.037376) (xy 388.19623 -251.084057) (xy 388.173359 -251.127634)
			(xy 388.143794 -251.166978) (xy 388.108301 -251.20107) (xy 388.067798 -251.229026) (xy 388.023336 -251.250124)
			(xy 387.976065 -251.263816) (xy 387.92721 -251.269748) (xy 387.878035 -251.267767) (xy 387.829816 -251.257923)
			(xy 387.7838 -251.240471) (xy 387.741179 -251.215864) (xy 387.703058 -251.184739) (xy 387.670423 -251.147902)
			(xy 387.64412 -251.106306) (xy 387.624829 -251.06103) (xy 387.613052 -251.013246) (xy 387.609092 -250.964192)
			(xy 387.290564 -250.964192) (xy 387.290052 -250.989638) (xy 387.281888 -251.039872) (xy 387.265772 -251.088146)
			(xy 387.242121 -251.133209) (xy 387.211548 -251.173895) (xy 387.174844 -251.20915) (xy 387.13296 -251.23806)
			(xy 387.086981 -251.259877) (xy 387.038097 -251.274037) (xy 386.987576 -251.280171) (xy 386.936724 -251.278122)
			(xy 386.88686 -251.267942) (xy 386.839274 -251.249895) (xy 386.7952 -251.224449) (xy 386.755778 -251.192262)
			(xy 386.72203 -251.154168) (xy 386.694829 -251.111154) (xy 386.674881 -251.064334) (xy 386.662702 -251.01492)
			(xy 386.658607 -250.964192) (xy 386.35051 -250.964192) (xy 386.349998 -250.989638) (xy 386.341834 -251.039872)
			(xy 386.325718 -251.088146) (xy 386.302067 -251.133209) (xy 386.271494 -251.173895) (xy 386.23479 -251.20915)
			(xy 386.192906 -251.23806) (xy 386.146927 -251.259877) (xy 386.098043 -251.274037) (xy 386.047522 -251.280171)
			(xy 385.99667 -251.278122) (xy 385.946806 -251.267942) (xy 385.89922 -251.249895) (xy 385.855146 -251.224449)
			(xy 385.815724 -251.192262) (xy 385.781976 -251.154168) (xy 385.754775 -251.111154) (xy 385.734827 -251.064334)
			(xy 385.722648 -251.01492) (xy 385.718553 -250.964192) (xy 385.400042 -250.964192) (xy 385.399547 -250.988799)
			(xy 385.391652 -251.037376) (xy 385.376068 -251.084057) (xy 385.353197 -251.127634) (xy 385.323632 -251.166978)
			(xy 385.288139 -251.20107) (xy 385.247636 -251.229026) (xy 385.203174 -251.250124) (xy 385.155903 -251.263816)
			(xy 385.107048 -251.269748) (xy 385.057873 -251.267767) (xy 385.009654 -251.257923) (xy 384.963638 -251.240471)
			(xy 384.921017 -251.215864) (xy 384.882896 -251.184739) (xy 384.850261 -251.147902) (xy 384.823958 -251.106306)
			(xy 384.804667 -251.06103) (xy 384.79289 -251.013246) (xy 384.78893 -250.964192) (xy 384.470656 -250.964192)
			(xy 384.470144 -250.989638) (xy 384.46198 -251.039872) (xy 384.445864 -251.088146) (xy 384.422213 -251.133209)
			(xy 384.39164 -251.173895) (xy 384.354936 -251.20915) (xy 384.313052 -251.23806) (xy 384.267073 -251.259877)
			(xy 384.218189 -251.274037) (xy 384.167668 -251.280171) (xy 384.116816 -251.278122) (xy 384.066952 -251.267942)
			(xy 384.019366 -251.249895) (xy 383.975292 -251.224449) (xy 383.93587 -251.192262) (xy 383.902122 -251.154168)
			(xy 383.874921 -251.111154) (xy 383.854973 -251.064334) (xy 383.842794 -251.01492) (xy 383.838699 -250.964192)
			(xy 383.520188 -250.964192) (xy 383.519693 -250.988799) (xy 383.511798 -251.037376) (xy 383.496214 -251.084057)
			(xy 383.473343 -251.127634) (xy 383.443778 -251.166978) (xy 383.408285 -251.20107) (xy 383.367782 -251.229026)
			(xy 383.32332 -251.250124) (xy 383.276049 -251.263816) (xy 383.227194 -251.269748) (xy 383.178019 -251.267767)
			(xy 383.1298 -251.257923) (xy 383.083784 -251.240471) (xy 383.041163 -251.215864) (xy 383.003042 -251.184739)
			(xy 382.970407 -251.147902) (xy 382.944104 -251.106306) (xy 382.924813 -251.06103) (xy 382.913036 -251.013246)
			(xy 382.909076 -250.964192) (xy 382.590548 -250.964192) (xy 382.590036 -250.989638) (xy 382.581872 -251.039872)
			(xy 382.565756 -251.088146) (xy 382.542105 -251.133209) (xy 382.511532 -251.173895) (xy 382.474828 -251.20915)
			(xy 382.432944 -251.23806) (xy 382.386965 -251.259877) (xy 382.338081 -251.274037) (xy 382.28756 -251.280171)
			(xy 382.236708 -251.278122) (xy 382.186844 -251.267942) (xy 382.139258 -251.249895) (xy 382.095184 -251.224449)
			(xy 382.055762 -251.192262) (xy 382.022014 -251.154168) (xy 381.994813 -251.111154) (xy 381.974865 -251.064334)
			(xy 381.962686 -251.01492) (xy 381.958591 -250.964192) (xy 381.64008 -250.964192) (xy 381.639585 -250.988799)
			(xy 381.63169 -251.037376) (xy 381.616106 -251.084057) (xy 381.593235 -251.127634) (xy 381.56367 -251.166978)
			(xy 381.528177 -251.20107) (xy 381.487674 -251.229026) (xy 381.443212 -251.250124) (xy 381.395941 -251.263816)
			(xy 381.347086 -251.269748) (xy 381.297911 -251.267767) (xy 381.249692 -251.257923) (xy 381.203676 -251.240471)
			(xy 381.161055 -251.215864) (xy 381.122934 -251.184739) (xy 381.090299 -251.147902) (xy 381.063996 -251.106306)
			(xy 381.044705 -251.06103) (xy 381.032928 -251.013246) (xy 381.028968 -250.964192) (xy 380.71044 -250.964192)
			(xy 380.709928 -250.989638) (xy 380.701764 -251.039872) (xy 380.685648 -251.088146) (xy 380.661997 -251.133209)
			(xy 380.631424 -251.173895) (xy 380.59472 -251.20915) (xy 380.552836 -251.23806) (xy 380.506857 -251.259877)
			(xy 380.457973 -251.274037) (xy 380.407452 -251.280171) (xy 380.3566 -251.278122) (xy 380.306736 -251.267942)
			(xy 380.25915 -251.249895) (xy 380.215076 -251.224449) (xy 380.175654 -251.192262) (xy 380.141906 -251.154168)
			(xy 380.114705 -251.111154) (xy 380.094757 -251.064334) (xy 380.082578 -251.01492) (xy 380.078483 -250.964192)
			(xy 379.77064 -250.964192) (xy 379.770128 -250.989638) (xy 379.761964 -251.039872) (xy 379.745848 -251.088146)
			(xy 379.722197 -251.133209) (xy 379.691624 -251.173895) (xy 379.65492 -251.20915) (xy 379.613036 -251.23806)
			(xy 379.567057 -251.259877) (xy 379.518173 -251.274037) (xy 379.467652 -251.280171) (xy 379.4168 -251.278122)
			(xy 379.366936 -251.267942) (xy 379.31935 -251.249895) (xy 379.275276 -251.224449) (xy 379.235854 -251.192262)
			(xy 379.202106 -251.154168) (xy 379.174905 -251.111154) (xy 379.154957 -251.064334) (xy 379.142778 -251.01492)
			(xy 379.138683 -250.964192) (xy 378.820172 -250.964192) (xy 378.819677 -250.988799) (xy 378.811782 -251.037376)
			(xy 378.796198 -251.084057) (xy 378.773327 -251.127634) (xy 378.743762 -251.166978) (xy 378.708269 -251.20107)
			(xy 378.667766 -251.229026) (xy 378.623304 -251.250124) (xy 378.576033 -251.263816) (xy 378.527178 -251.269748)
			(xy 378.478003 -251.267767) (xy 378.429784 -251.257923) (xy 378.383768 -251.240471) (xy 378.341147 -251.215864)
			(xy 378.303026 -251.184739) (xy 378.270391 -251.147902) (xy 378.244088 -251.106306) (xy 378.224797 -251.06103)
			(xy 378.21302 -251.013246) (xy 378.20906 -250.964192) (xy 377.890532 -250.964192) (xy 377.89002 -250.989638)
			(xy 377.881856 -251.039872) (xy 377.86574 -251.088146) (xy 377.842089 -251.133209) (xy 377.811516 -251.173895)
			(xy 377.774812 -251.20915) (xy 377.732928 -251.23806) (xy 377.686949 -251.259877) (xy 377.638065 -251.274037)
			(xy 377.587544 -251.280171) (xy 377.536692 -251.278122) (xy 377.486828 -251.267942) (xy 377.439242 -251.249895)
			(xy 377.395168 -251.224449) (xy 377.355746 -251.192262) (xy 377.321998 -251.154168) (xy 377.294797 -251.111154)
			(xy 377.274849 -251.064334) (xy 377.26267 -251.01492) (xy 377.258575 -250.964192) (xy 376.940064 -250.964192)
			(xy 376.939569 -250.988799) (xy 376.931674 -251.037376) (xy 376.91609 -251.084057) (xy 376.893219 -251.127634)
			(xy 376.863654 -251.166978) (xy 376.828161 -251.20107) (xy 376.787658 -251.229026) (xy 376.743196 -251.250124)
			(xy 376.695925 -251.263816) (xy 376.64707 -251.269748) (xy 376.597895 -251.267767) (xy 376.549676 -251.257923)
			(xy 376.50366 -251.240471) (xy 376.461039 -251.215864) (xy 376.422918 -251.184739) (xy 376.390283 -251.147902)
			(xy 376.36398 -251.106306) (xy 376.344689 -251.06103) (xy 376.332912 -251.013246) (xy 376.328952 -250.964192)
			(xy 376.010424 -250.964192) (xy 376.009912 -250.989638) (xy 376.001748 -251.039872) (xy 375.985632 -251.088146)
			(xy 375.961981 -251.133209) (xy 375.931408 -251.173895) (xy 375.894704 -251.20915) (xy 375.85282 -251.23806)
			(xy 375.806841 -251.259877) (xy 375.757957 -251.274037) (xy 375.707436 -251.280171) (xy 375.656584 -251.278122)
			(xy 375.60672 -251.267942) (xy 375.559134 -251.249895) (xy 375.51506 -251.224449) (xy 375.475638 -251.192262)
			(xy 375.44189 -251.154168) (xy 375.414689 -251.111154) (xy 375.394741 -251.064334) (xy 375.382562 -251.01492)
			(xy 375.378467 -250.964192) (xy 375.059933 -250.964192) (xy 375.060364 -250.977166) (xy 375.054975 -251.022902)
			(xy 375.049288 -251.045218) (xy 375.042474 -251.068302) (xy 375.02259 -251.112131) (xy 374.996069 -251.152294)
			(xy 374.96357 -251.187792) (xy 374.925898 -251.217746) (xy 374.88399 -251.241411) (xy 374.861582 -251.250196)
			(xy 374.85066 -251.25426) (xy 374.540018 -251.564902) (xy 374.535954 -251.5997) (xy 374.545098 -251.614686)
			(xy 374.559176 -251.638888) (xy 374.579225 -251.69116) (xy 374.589429 -251.746206) (xy 374.590056 -251.774198)
			(xy 375.848621 -251.774198) (xy 375.852716 -251.72347) (xy 375.864895 -251.674056) (xy 375.884843 -251.627236)
			(xy 375.912044 -251.584222) (xy 375.945792 -251.546128) (xy 375.985214 -251.513941) (xy 376.029288 -251.488495)
			(xy 376.076874 -251.470448) (xy 376.126738 -251.460268) (xy 376.17759 -251.458219) (xy 376.228111 -251.464353)
			(xy 376.276995 -251.478513) (xy 376.322974 -251.50033) (xy 376.364858 -251.52924) (xy 376.401562 -251.564495)
			(xy 376.432135 -251.605181) (xy 376.455786 -251.650244) (xy 376.471902 -251.698518) (xy 376.480066 -251.748752)
			(xy 376.480578 -251.774198) (xy 376.799106 -251.774198) (xy 376.803066 -251.725144) (xy 376.814843 -251.67736)
			(xy 376.834134 -251.632084) (xy 376.860437 -251.590488) (xy 376.893072 -251.553651) (xy 376.931193 -251.522526)
			(xy 376.973814 -251.497919) (xy 377.01983 -251.480467) (xy 377.068049 -251.470623) (xy 377.117224 -251.468642)
			(xy 377.166079 -251.474574) (xy 377.21335 -251.488266) (xy 377.257812 -251.509364) (xy 377.298315 -251.53732)
			(xy 377.333808 -251.571412) (xy 377.363373 -251.610756) (xy 377.386244 -251.654333) (xy 377.401828 -251.701014)
			(xy 377.409723 -251.749591) (xy 377.410218 -251.774198) (xy 378.668529 -251.774198) (xy 378.672624 -251.72347)
			(xy 378.684803 -251.674056) (xy 378.704751 -251.627236) (xy 378.731952 -251.584222) (xy 378.7657 -251.546128)
			(xy 378.805122 -251.513941) (xy 378.849196 -251.488495) (xy 378.896782 -251.470448) (xy 378.946646 -251.460268)
			(xy 378.997498 -251.458219) (xy 379.048019 -251.464353) (xy 379.096903 -251.478513) (xy 379.142882 -251.50033)
			(xy 379.184766 -251.52924) (xy 379.22147 -251.564495) (xy 379.252043 -251.605181) (xy 379.275694 -251.650244)
			(xy 379.29181 -251.698518) (xy 379.299974 -251.748752) (xy 379.300486 -251.774198) (xy 379.619014 -251.774198)
			(xy 379.622974 -251.725144) (xy 379.634751 -251.67736) (xy 379.654042 -251.632084) (xy 379.680345 -251.590488)
			(xy 379.71298 -251.553651) (xy 379.751101 -251.522526) (xy 379.793722 -251.497919) (xy 379.839738 -251.480467)
			(xy 379.887957 -251.470623) (xy 379.937132 -251.468642) (xy 379.985987 -251.474574) (xy 380.033258 -251.488266)
			(xy 380.07772 -251.509364) (xy 380.118223 -251.53732) (xy 380.153716 -251.571412) (xy 380.183281 -251.610756)
			(xy 380.206152 -251.654333) (xy 380.221736 -251.701014) (xy 380.229631 -251.749591) (xy 380.230126 -251.774198)
			(xy 380.559068 -251.774198) (xy 380.563028 -251.725144) (xy 380.574805 -251.67736) (xy 380.594096 -251.632084)
			(xy 380.620399 -251.590488) (xy 380.653034 -251.553651) (xy 380.691155 -251.522526) (xy 380.733776 -251.497919)
			(xy 380.779792 -251.480467) (xy 380.828011 -251.470623) (xy 380.877186 -251.468642) (xy 380.926041 -251.474574)
			(xy 380.973312 -251.488266) (xy 381.017774 -251.509364) (xy 381.058277 -251.53732) (xy 381.09377 -251.571412)
			(xy 381.123335 -251.610756) (xy 381.146206 -251.654333) (xy 381.16179 -251.701014) (xy 381.169685 -251.749591)
			(xy 381.17018 -251.774198) (xy 381.499122 -251.774198) (xy 381.503082 -251.725144) (xy 381.514859 -251.67736)
			(xy 381.53415 -251.632084) (xy 381.560453 -251.590488) (xy 381.593088 -251.553651) (xy 381.631209 -251.522526)
			(xy 381.67383 -251.497919) (xy 381.719846 -251.480467) (xy 381.768065 -251.470623) (xy 381.81724 -251.468642)
			(xy 381.866095 -251.474574) (xy 381.913366 -251.488266) (xy 381.957828 -251.509364) (xy 381.998331 -251.53732)
			(xy 382.033824 -251.571412) (xy 382.063389 -251.610756) (xy 382.08626 -251.654333) (xy 382.101844 -251.701014)
			(xy 382.109739 -251.749591) (xy 382.110234 -251.774198) (xy 382.428491 -251.774198) (xy 382.432586 -251.72347)
			(xy 382.444765 -251.674056) (xy 382.464713 -251.627236) (xy 382.491914 -251.584222) (xy 382.525662 -251.546128)
			(xy 382.565084 -251.513941) (xy 382.609158 -251.488495) (xy 382.656744 -251.470448) (xy 382.706608 -251.460268)
			(xy 382.75746 -251.458219) (xy 382.807981 -251.464353) (xy 382.856865 -251.478513) (xy 382.902844 -251.50033)
			(xy 382.944728 -251.52924) (xy 382.981432 -251.564495) (xy 383.012005 -251.605181) (xy 383.035656 -251.650244)
			(xy 383.051772 -251.698518) (xy 383.059936 -251.748752) (xy 383.060448 -251.774198) (xy 383.378976 -251.774198)
			(xy 383.382936 -251.725144) (xy 383.394713 -251.67736) (xy 383.414004 -251.632084) (xy 383.440307 -251.590488)
			(xy 383.472942 -251.553651) (xy 383.511063 -251.522526) (xy 383.553684 -251.497919) (xy 383.5997 -251.480467)
			(xy 383.647919 -251.470623) (xy 383.697094 -251.468642) (xy 383.745949 -251.474574) (xy 383.79322 -251.488266)
			(xy 383.837682 -251.509364) (xy 383.878185 -251.53732) (xy 383.913678 -251.571412) (xy 383.943243 -251.610756)
			(xy 383.966114 -251.654333) (xy 383.981698 -251.701014) (xy 383.989593 -251.749591) (xy 383.990088 -251.774198)
			(xy 385.248653 -251.774198) (xy 385.252748 -251.72347) (xy 385.264927 -251.674056) (xy 385.284875 -251.627236)
			(xy 385.312076 -251.584222) (xy 385.345824 -251.546128) (xy 385.385246 -251.513941) (xy 385.42932 -251.488495)
			(xy 385.476906 -251.470448) (xy 385.52677 -251.460268) (xy 385.577622 -251.458219) (xy 385.628143 -251.464353)
			(xy 385.677027 -251.478513) (xy 385.723006 -251.50033) (xy 385.76489 -251.52924) (xy 385.801594 -251.564495)
			(xy 385.832167 -251.605181) (xy 385.855818 -251.650244) (xy 385.871934 -251.698518) (xy 385.880098 -251.748752)
			(xy 385.88061 -251.774198) (xy 386.199138 -251.774198) (xy 386.203098 -251.725144) (xy 386.214875 -251.67736)
			(xy 386.234166 -251.632084) (xy 386.260469 -251.590488) (xy 386.293104 -251.553651) (xy 386.331225 -251.522526)
			(xy 386.373846 -251.497919) (xy 386.419862 -251.480467) (xy 386.468081 -251.470623) (xy 386.517256 -251.468642)
			(xy 386.566111 -251.474574) (xy 386.613382 -251.488266) (xy 386.657844 -251.509364) (xy 386.698347 -251.53732)
			(xy 386.73384 -251.571412) (xy 386.763405 -251.610756) (xy 386.786276 -251.654333) (xy 386.80186 -251.701014)
			(xy 386.809755 -251.749591) (xy 386.81025 -251.774198) (xy 387.138938 -251.774198) (xy 387.142898 -251.725144)
			(xy 387.154675 -251.67736) (xy 387.173966 -251.632084) (xy 387.200269 -251.590488) (xy 387.232904 -251.553651)
			(xy 387.271025 -251.522526) (xy 387.313646 -251.497919) (xy 387.359662 -251.480467) (xy 387.407881 -251.470623)
			(xy 387.457056 -251.468642) (xy 387.505911 -251.474574) (xy 387.553182 -251.488266) (xy 387.597644 -251.509364)
			(xy 387.638147 -251.53732) (xy 387.67364 -251.571412) (xy 387.703205 -251.610756) (xy 387.726076 -251.654333)
			(xy 387.74166 -251.701014) (xy 387.749555 -251.749591) (xy 387.75005 -251.774198) (xy 388.078992 -251.774198)
			(xy 388.082952 -251.725144) (xy 388.094729 -251.67736) (xy 388.11402 -251.632084) (xy 388.140323 -251.590488)
			(xy 388.172958 -251.553651) (xy 388.211079 -251.522526) (xy 388.2537 -251.497919) (xy 388.299716 -251.480467)
			(xy 388.347935 -251.470623) (xy 388.39711 -251.468642) (xy 388.445965 -251.474574) (xy 388.493236 -251.488266)
			(xy 388.537698 -251.509364) (xy 388.578201 -251.53732) (xy 388.613694 -251.571412) (xy 388.643259 -251.610756)
			(xy 388.66613 -251.654333) (xy 388.681714 -251.701014) (xy 388.689609 -251.749591) (xy 388.690104 -251.774198)
			(xy 389.008615 -251.774198) (xy 389.01271 -251.72347) (xy 389.024889 -251.674056) (xy 389.044837 -251.627236)
			(xy 389.072038 -251.584222) (xy 389.105786 -251.546128) (xy 389.145208 -251.513941) (xy 389.189282 -251.488495)
			(xy 389.236868 -251.470448) (xy 389.286732 -251.460268) (xy 389.337584 -251.458219) (xy 389.388105 -251.464353)
			(xy 389.436989 -251.478513) (xy 389.482968 -251.50033) (xy 389.524852 -251.52924) (xy 389.561556 -251.564495)
			(xy 389.592129 -251.605181) (xy 389.61578 -251.650244) (xy 389.631896 -251.698518) (xy 389.64006 -251.748752)
			(xy 389.640572 -251.774198) (xy 389.9591 -251.774198) (xy 389.96306 -251.725144) (xy 389.974837 -251.67736)
			(xy 389.994128 -251.632084) (xy 390.020431 -251.590488) (xy 390.053066 -251.553651) (xy 390.091187 -251.522526)
			(xy 390.133808 -251.497919) (xy 390.179824 -251.480467) (xy 390.228043 -251.470623) (xy 390.277218 -251.468642)
			(xy 390.326073 -251.474574) (xy 390.373344 -251.488266) (xy 390.417806 -251.509364) (xy 390.458309 -251.53732)
			(xy 390.493802 -251.571412) (xy 390.523367 -251.610756) (xy 390.546238 -251.654333) (xy 390.561822 -251.701014)
			(xy 390.569717 -251.749591) (xy 390.570212 -251.774198) (xy 392.779008 -251.774198) (xy 392.782968 -251.725144)
			(xy 392.794745 -251.67736) (xy 392.814036 -251.632084) (xy 392.840339 -251.590488) (xy 392.872974 -251.553651)
			(xy 392.911095 -251.522526) (xy 392.953716 -251.497919) (xy 392.999732 -251.480467) (xy 393.047951 -251.470623)
			(xy 393.097126 -251.468642) (xy 393.145981 -251.474574) (xy 393.193252 -251.488266) (xy 393.237714 -251.509364)
			(xy 393.278217 -251.53732) (xy 393.31371 -251.571412) (xy 393.343275 -251.610756) (xy 393.366146 -251.654333)
			(xy 393.38173 -251.701014) (xy 393.389625 -251.749591) (xy 393.39012 -251.774198) (xy 393.389625 -251.798805)
			(xy 393.38173 -251.847382) (xy 393.366146 -251.894063) (xy 393.343275 -251.93764) (xy 393.31371 -251.976984)
			(xy 393.278217 -252.011076) (xy 393.237714 -252.039032) (xy 393.193252 -252.06013) (xy 393.145981 -252.073822)
			(xy 393.097126 -252.079754) (xy 393.047951 -252.077773) (xy 392.999732 -252.067929) (xy 392.953716 -252.050477)
			(xy 392.911095 -252.02587) (xy 392.872974 -251.994745) (xy 392.840339 -251.957908) (xy 392.814036 -251.916312)
			(xy 392.794745 -251.871036) (xy 392.782968 -251.823252) (xy 392.779008 -251.774198) (xy 390.570212 -251.774198)
			(xy 390.569717 -251.798805) (xy 390.561822 -251.847382) (xy 390.546238 -251.894063) (xy 390.523367 -251.93764)
			(xy 390.493802 -251.976984) (xy 390.458309 -252.011076) (xy 390.417806 -252.039032) (xy 390.373344 -252.06013)
			(xy 390.326073 -252.073822) (xy 390.277218 -252.079754) (xy 390.228043 -252.077773) (xy 390.179824 -252.067929)
			(xy 390.133808 -252.050477) (xy 390.091187 -252.02587) (xy 390.053066 -251.994745) (xy 390.020431 -251.957908)
			(xy 389.994128 -251.916312) (xy 389.974837 -251.871036) (xy 389.96306 -251.823252) (xy 389.9591 -251.774198)
			(xy 389.640572 -251.774198) (xy 389.64006 -251.799644) (xy 389.631896 -251.849878) (xy 389.61578 -251.898152)
			(xy 389.592129 -251.943215) (xy 389.561556 -251.983901) (xy 389.524852 -252.019156) (xy 389.482968 -252.048066)
			(xy 389.436989 -252.069883) (xy 389.388105 -252.084043) (xy 389.337584 -252.090177) (xy 389.286732 -252.088128)
			(xy 389.236868 -252.077948) (xy 389.189282 -252.059901) (xy 389.145208 -252.034455) (xy 389.105786 -252.002268)
			(xy 389.072038 -251.964174) (xy 389.044837 -251.92116) (xy 389.024889 -251.87434) (xy 389.01271 -251.824926)
			(xy 389.008615 -251.774198) (xy 388.690104 -251.774198) (xy 388.689609 -251.798805) (xy 388.681714 -251.847382)
			(xy 388.66613 -251.894063) (xy 388.643259 -251.93764) (xy 388.613694 -251.976984) (xy 388.578201 -252.011076)
			(xy 388.537698 -252.039032) (xy 388.493236 -252.06013) (xy 388.445965 -252.073822) (xy 388.39711 -252.079754)
			(xy 388.347935 -252.077773) (xy 388.299716 -252.067929) (xy 388.2537 -252.050477) (xy 388.211079 -252.02587)
			(xy 388.172958 -251.994745) (xy 388.140323 -251.957908) (xy 388.11402 -251.916312) (xy 388.094729 -251.871036)
			(xy 388.082952 -251.823252) (xy 388.078992 -251.774198) (xy 387.75005 -251.774198) (xy 387.749555 -251.798805)
			(xy 387.74166 -251.847382) (xy 387.726076 -251.894063) (xy 387.703205 -251.93764) (xy 387.67364 -251.976984)
			(xy 387.638147 -252.011076) (xy 387.597644 -252.039032) (xy 387.553182 -252.06013) (xy 387.505911 -252.073822)
			(xy 387.457056 -252.079754) (xy 387.407881 -252.077773) (xy 387.359662 -252.067929) (xy 387.313646 -252.050477)
			(xy 387.271025 -252.02587) (xy 387.232904 -251.994745) (xy 387.200269 -251.957908) (xy 387.173966 -251.916312)
			(xy 387.154675 -251.871036) (xy 387.142898 -251.823252) (xy 387.138938 -251.774198) (xy 386.81025 -251.774198)
			(xy 386.809755 -251.798805) (xy 386.80186 -251.847382) (xy 386.786276 -251.894063) (xy 386.763405 -251.93764)
			(xy 386.73384 -251.976984) (xy 386.698347 -252.011076) (xy 386.657844 -252.039032) (xy 386.613382 -252.06013)
			(xy 386.566111 -252.073822) (xy 386.517256 -252.079754) (xy 386.468081 -252.077773) (xy 386.419862 -252.067929)
			(xy 386.373846 -252.050477) (xy 386.331225 -252.02587) (xy 386.293104 -251.994745) (xy 386.260469 -251.957908)
			(xy 386.234166 -251.916312) (xy 386.214875 -251.871036) (xy 386.203098 -251.823252) (xy 386.199138 -251.774198)
			(xy 385.88061 -251.774198) (xy 385.880098 -251.799644) (xy 385.871934 -251.849878) (xy 385.855818 -251.898152)
			(xy 385.832167 -251.943215) (xy 385.801594 -251.983901) (xy 385.76489 -252.019156) (xy 385.723006 -252.048066)
			(xy 385.677027 -252.069883) (xy 385.628143 -252.084043) (xy 385.577622 -252.090177) (xy 385.52677 -252.088128)
			(xy 385.476906 -252.077948) (xy 385.42932 -252.059901) (xy 385.385246 -252.034455) (xy 385.345824 -252.002268)
			(xy 385.312076 -251.964174) (xy 385.284875 -251.92116) (xy 385.264927 -251.87434) (xy 385.252748 -251.824926)
			(xy 385.248653 -251.774198) (xy 383.990088 -251.774198) (xy 383.989593 -251.798805) (xy 383.981698 -251.847382)
			(xy 383.966114 -251.894063) (xy 383.943243 -251.93764) (xy 383.913678 -251.976984) (xy 383.878185 -252.011076)
			(xy 383.837682 -252.039032) (xy 383.79322 -252.06013) (xy 383.745949 -252.073822) (xy 383.697094 -252.079754)
			(xy 383.647919 -252.077773) (xy 383.5997 -252.067929) (xy 383.553684 -252.050477) (xy 383.511063 -252.02587)
			(xy 383.472942 -251.994745) (xy 383.440307 -251.957908) (xy 383.414004 -251.916312) (xy 383.394713 -251.871036)
			(xy 383.382936 -251.823252) (xy 383.378976 -251.774198) (xy 383.060448 -251.774198) (xy 383.059936 -251.799644)
			(xy 383.051772 -251.849878) (xy 383.035656 -251.898152) (xy 383.012005 -251.943215) (xy 382.981432 -251.983901)
			(xy 382.944728 -252.019156) (xy 382.902844 -252.048066) (xy 382.856865 -252.069883) (xy 382.807981 -252.084043)
			(xy 382.75746 -252.090177) (xy 382.706608 -252.088128) (xy 382.656744 -252.077948) (xy 382.609158 -252.059901)
			(xy 382.565084 -252.034455) (xy 382.525662 -252.002268) (xy 382.491914 -251.964174) (xy 382.464713 -251.92116)
			(xy 382.444765 -251.87434) (xy 382.432586 -251.824926) (xy 382.428491 -251.774198) (xy 382.110234 -251.774198)
			(xy 382.109739 -251.798805) (xy 382.101844 -251.847382) (xy 382.08626 -251.894063) (xy 382.063389 -251.93764)
			(xy 382.033824 -251.976984) (xy 381.998331 -252.011076) (xy 381.957828 -252.039032) (xy 381.913366 -252.06013)
			(xy 381.866095 -252.073822) (xy 381.81724 -252.079754) (xy 381.768065 -252.077773) (xy 381.719846 -252.067929)
			(xy 381.67383 -252.050477) (xy 381.631209 -252.02587) (xy 381.593088 -251.994745) (xy 381.560453 -251.957908)
			(xy 381.53415 -251.916312) (xy 381.514859 -251.871036) (xy 381.503082 -251.823252) (xy 381.499122 -251.774198)
			(xy 381.17018 -251.774198) (xy 381.169685 -251.798805) (xy 381.16179 -251.847382) (xy 381.146206 -251.894063)
			(xy 381.123335 -251.93764) (xy 381.09377 -251.976984) (xy 381.058277 -252.011076) (xy 381.017774 -252.039032)
			(xy 380.973312 -252.06013) (xy 380.926041 -252.073822) (xy 380.877186 -252.079754) (xy 380.828011 -252.077773)
			(xy 380.779792 -252.067929) (xy 380.733776 -252.050477) (xy 380.691155 -252.02587) (xy 380.653034 -251.994745)
			(xy 380.620399 -251.957908) (xy 380.594096 -251.916312) (xy 380.574805 -251.871036) (xy 380.563028 -251.823252)
			(xy 380.559068 -251.774198) (xy 380.230126 -251.774198) (xy 380.229631 -251.798805) (xy 380.221736 -251.847382)
			(xy 380.206152 -251.894063) (xy 380.183281 -251.93764) (xy 380.153716 -251.976984) (xy 380.118223 -252.011076)
			(xy 380.07772 -252.039032) (xy 380.033258 -252.06013) (xy 379.985987 -252.073822) (xy 379.937132 -252.079754)
			(xy 379.887957 -252.077773) (xy 379.839738 -252.067929) (xy 379.793722 -252.050477) (xy 379.751101 -252.02587)
			(xy 379.71298 -251.994745) (xy 379.680345 -251.957908) (xy 379.654042 -251.916312) (xy 379.634751 -251.871036)
			(xy 379.622974 -251.823252) (xy 379.619014 -251.774198) (xy 379.300486 -251.774198) (xy 379.299974 -251.799644)
			(xy 379.29181 -251.849878) (xy 379.275694 -251.898152) (xy 379.252043 -251.943215) (xy 379.22147 -251.983901)
			(xy 379.184766 -252.019156) (xy 379.142882 -252.048066) (xy 379.096903 -252.069883) (xy 379.048019 -252.084043)
			(xy 378.997498 -252.090177) (xy 378.946646 -252.088128) (xy 378.896782 -252.077948) (xy 378.849196 -252.059901)
			(xy 378.805122 -252.034455) (xy 378.7657 -252.002268) (xy 378.731952 -251.964174) (xy 378.704751 -251.92116)
			(xy 378.684803 -251.87434) (xy 378.672624 -251.824926) (xy 378.668529 -251.774198) (xy 377.410218 -251.774198)
			(xy 377.409723 -251.798805) (xy 377.401828 -251.847382) (xy 377.386244 -251.894063) (xy 377.363373 -251.93764)
			(xy 377.333808 -251.976984) (xy 377.298315 -252.011076) (xy 377.257812 -252.039032) (xy 377.21335 -252.06013)
			(xy 377.166079 -252.073822) (xy 377.117224 -252.079754) (xy 377.068049 -252.077773) (xy 377.01983 -252.067929)
			(xy 376.973814 -252.050477) (xy 376.931193 -252.02587) (xy 376.893072 -251.994745) (xy 376.860437 -251.957908)
			(xy 376.834134 -251.916312) (xy 376.814843 -251.871036) (xy 376.803066 -251.823252) (xy 376.799106 -251.774198)
			(xy 376.480578 -251.774198) (xy 376.480066 -251.799644) (xy 376.471902 -251.849878) (xy 376.455786 -251.898152)
			(xy 376.432135 -251.943215) (xy 376.401562 -251.983901) (xy 376.364858 -252.019156) (xy 376.322974 -252.048066)
			(xy 376.276995 -252.069883) (xy 376.228111 -252.084043) (xy 376.17759 -252.090177) (xy 376.126738 -252.088128)
			(xy 376.076874 -252.077948) (xy 376.029288 -252.059901) (xy 375.985214 -252.034455) (xy 375.945792 -252.002268)
			(xy 375.912044 -251.964174) (xy 375.884843 -251.92116) (xy 375.864895 -251.87434) (xy 375.852716 -251.824926)
			(xy 375.848621 -251.774198) (xy 374.590056 -251.774198) (xy 374.589534 -251.799453) (xy 374.581221 -251.849275)
			(xy 374.56482 -251.897049) (xy 374.540779 -251.941472) (xy 374.509755 -251.981332) (xy 374.472593 -252.015542)
			(xy 374.430307 -252.043168) (xy 374.384051 -252.063458) (xy 374.335086 -252.075858) (xy 374.284748 -252.080029)
			(xy 374.23441 -252.075858) (xy 374.185445 -252.063458) (xy 374.139189 -252.043168) (xy 374.096903 -252.015542)
			(xy 374.059741 -251.981332) (xy 374.028717 -251.941472) (xy 374.004676 -251.897049) (xy 373.988275 -251.849275)
			(xy 373.979962 -251.799453) (xy 373.97944 -251.774198) (xy 373.979879 -251.751097) (xy 373.986888 -251.705431)
			(xy 373.99341 -251.683266) (xy 373.996966 -251.671328) (xy 373.992902 -251.647706) (xy 373.937022 -251.572014)
			(xy 373.929455 -251.562838) (xy 373.908257 -251.552122) (xy 373.896382 -251.55144) (xy 372.79326 -251.55144)
			(xy 372.781392 -251.552133) (xy 372.760211 -251.562864) (xy 372.75262 -251.572014) (xy 372.69674 -251.647706)
			(xy 372.692676 -251.671328) (xy 372.696232 -251.683266) (xy 372.702725 -251.705438) (xy 372.709741 -251.7511)
			(xy 372.710202 -251.774198) (xy 372.70968 -251.799453) (xy 372.701367 -251.849275) (xy 372.684966 -251.897049)
			(xy 372.660925 -251.941472) (xy 372.629901 -251.981332) (xy 372.592739 -252.015542) (xy 372.550453 -252.043168)
			(xy 372.504197 -252.063458) (xy 372.455232 -252.075858) (xy 372.404894 -252.080029) (xy 372.354556 -252.075858)
			(xy 372.305591 -252.063458) (xy 372.259335 -252.043168) (xy 372.217049 -252.015542) (xy 372.179887 -251.981332)
			(xy 372.148863 -251.941472) (xy 372.124822 -251.897049) (xy 372.108421 -251.849275) (xy 372.100108 -251.799453)
			(xy 372.099586 -251.774198) (xy 372.100025 -251.751097) (xy 372.107033 -251.705431) (xy 372.113556 -251.683266)
			(xy 372.117112 -251.671328) (xy 372.113048 -251.647706) (xy 372.057168 -251.572014) (xy 372.049604 -251.562831)
			(xy 372.028407 -251.552096) (xy 372.016528 -251.55144) (xy 370.913152 -251.55144) (xy 370.901285 -251.552135)
			(xy 370.880107 -251.562868) (xy 370.872512 -251.572014) (xy 370.816632 -251.647706) (xy 370.812568 -251.671328)
			(xy 370.816124 -251.683266) (xy 370.822617 -251.705438) (xy 370.829633 -251.7511) (xy 370.830094 -251.774198)
			(xy 370.829572 -251.799453) (xy 370.821259 -251.849275) (xy 370.804858 -251.897049) (xy 370.780817 -251.941472)
			(xy 370.749793 -251.981332) (xy 370.712631 -252.015542) (xy 370.670345 -252.043168) (xy 370.624089 -252.063458)
			(xy 370.575124 -252.075858) (xy 370.524786 -252.080029) (xy 370.474448 -252.075858) (xy 370.425483 -252.063458)
			(xy 370.379227 -252.043168) (xy 370.336941 -252.015542) (xy 370.299779 -251.981332) (xy 370.268755 -251.941472)
			(xy 370.244714 -251.897049) (xy 370.228313 -251.849275) (xy 370.22 -251.799453) (xy 370.219478 -251.774198)
			(xy 370.219917 -251.751097) (xy 370.226925 -251.705431) (xy 370.233448 -251.683266) (xy 370.237004 -251.671328)
			(xy 370.23294 -251.647706) (xy 370.17706 -251.572014) (xy 370.169496 -251.562832) (xy 370.148298 -251.5521)
			(xy 370.13642 -251.55144) (xy 369.033044 -251.55144) (xy 369.021178 -251.552137) (xy 369.000002 -251.562871)
			(xy 368.992404 -251.572014) (xy 368.936524 -251.647706) (xy 368.93246 -251.671328) (xy 368.936016 -251.683266)
			(xy 368.942509 -251.705438) (xy 368.949525 -251.7511) (xy 368.949986 -251.774198) (xy 368.949464 -251.799453)
			(xy 368.941151 -251.849275) (xy 368.92475 -251.897049) (xy 368.900709 -251.941472) (xy 368.869685 -251.981332)
			(xy 368.832523 -252.015542) (xy 368.790237 -252.043168) (xy 368.743981 -252.063458) (xy 368.695016 -252.075858)
			(xy 368.644678 -252.080029) (xy 368.59434 -252.075858) (xy 368.545375 -252.063458) (xy 368.499119 -252.043168)
			(xy 368.456833 -252.015542) (xy 368.419671 -251.981332) (xy 368.388647 -251.941472) (xy 368.364606 -251.897049)
			(xy 368.348205 -251.849275) (xy 368.339892 -251.799453) (xy 368.33937 -251.774198) (xy 368.339809 -251.751098)
			(xy 368.346819 -251.705431) (xy 368.35334 -251.683266) (xy 368.356896 -251.671328) (xy 368.352832 -251.647706)
			(xy 368.296952 -251.572014) (xy 368.289387 -251.562833) (xy 368.26819 -251.552105) (xy 368.256312 -251.55144)
			(xy 367.15319 -251.55144) (xy 367.141319 -251.552127) (xy 367.120127 -251.56285) (xy 367.11255 -251.572014)
			(xy 367.05667 -251.647706) (xy 367.052606 -251.671328) (xy 367.056162 -251.683266) (xy 367.062656 -251.705437)
			(xy 367.069674 -251.7511) (xy 367.070132 -251.774198) (xy 367.06961 -251.799453) (xy 367.061297 -251.849275)
			(xy 367.044896 -251.897049) (xy 367.020855 -251.941472) (xy 366.989831 -251.981332) (xy 366.952669 -252.015542)
			(xy 366.910383 -252.043168) (xy 366.864127 -252.063458) (xy 366.815162 -252.075858) (xy 366.764824 -252.080029)
			(xy 366.714486 -252.075858) (xy 366.665521 -252.063458) (xy 366.619265 -252.043168) (xy 366.576979 -252.015542)
			(xy 366.539817 -251.981332) (xy 366.508793 -251.941472) (xy 366.484752 -251.897049) (xy 366.468351 -251.849275)
			(xy 366.460038 -251.799453) (xy 366.459516 -251.774198) (xy 366.459955 -251.751097) (xy 366.466964 -251.705431)
			(xy 366.473486 -251.683266) (xy 366.477042 -251.671328) (xy 366.472978 -251.647706) (xy 366.417098 -251.572014)
			(xy 366.40953 -251.562842) (xy 366.388331 -251.552136) (xy 366.376458 -251.55144) (xy 365.273082 -251.55144)
			(xy 365.261212 -251.552129) (xy 365.240023 -251.562854) (xy 365.232442 -251.572014) (xy 365.176562 -251.647706)
			(xy 365.172498 -251.671328) (xy 365.176054 -251.683266) (xy 365.182548 -251.705437) (xy 365.189566 -251.7511)
			(xy 365.190024 -251.774198) (xy 365.189502 -251.799453) (xy 365.181189 -251.849275) (xy 365.164788 -251.897049)
			(xy 365.140747 -251.941472) (xy 365.109723 -251.981332) (xy 365.072561 -252.015542) (xy 365.030275 -252.043168)
			(xy 364.984019 -252.063458) (xy 364.935054 -252.075858) (xy 364.884716 -252.080029) (xy 364.834378 -252.075858)
			(xy 364.785413 -252.063458) (xy 364.739157 -252.043168) (xy 364.696871 -252.015542) (xy 364.659709 -251.981332)
			(xy 364.628685 -251.941472) (xy 364.604644 -251.897049) (xy 364.588243 -251.849275) (xy 364.57993 -251.799453)
			(xy 364.579408 -251.774198) (xy 364.579847 -251.751097) (xy 364.586856 -251.705431) (xy 364.593378 -251.683266)
			(xy 364.596934 -251.671328) (xy 364.59287 -251.647706) (xy 364.53699 -251.572014) (xy 364.529421 -251.562844)
			(xy 364.508223 -251.552141) (xy 364.49635 -251.55144) (xy 363.393228 -251.55144) (xy 363.381353 -251.552119)
			(xy 363.360148 -251.562833) (xy 363.352588 -251.572014) (xy 363.296708 -251.647706) (xy 363.292644 -251.671328)
			(xy 363.2962 -251.683266) (xy 363.302693 -251.705438) (xy 363.30971 -251.7511) (xy 363.31017 -251.774198)
			(xy 363.309648 -251.799453) (xy 363.301335 -251.849275) (xy 363.284934 -251.897049) (xy 363.260893 -251.941472)
			(xy 363.229869 -251.981332) (xy 363.192707 -252.015542) (xy 363.150421 -252.043168) (xy 363.104165 -252.063458)
			(xy 363.0552 -252.075858) (xy 363.004862 -252.080029) (xy 362.954524 -252.075858) (xy 362.905559 -252.063458)
			(xy 362.859303 -252.043168) (xy 362.817017 -252.015542) (xy 362.779855 -251.981332) (xy 362.748831 -251.941472)
			(xy 362.72479 -251.897049) (xy 362.708389 -251.849275) (xy 362.700076 -251.799453) (xy 362.699554 -251.774198)
			(xy 362.699993 -251.751097) (xy 362.707003 -251.705431) (xy 362.713524 -251.683266) (xy 362.71708 -251.671328)
			(xy 362.713016 -251.647706) (xy 362.657136 -251.572014) (xy 362.64957 -251.562836) (xy 362.628372 -251.552114)
			(xy 362.616496 -251.55144) (xy 361.51312 -251.55144) (xy 361.501245 -251.552121) (xy 361.480044 -251.562837)
			(xy 361.47248 -251.572014) (xy 361.4166 -251.647706) (xy 361.412536 -251.671328) (xy 361.416092 -251.683266)
			(xy 361.422585 -251.705438) (xy 361.429602 -251.7511) (xy 361.430062 -251.774198) (xy 361.42954 -251.799453)
			(xy 361.421227 -251.849275) (xy 361.404826 -251.897049) (xy 361.380785 -251.941472) (xy 361.349761 -251.981332)
			(xy 361.312599 -252.015542) (xy 361.270313 -252.043168) (xy 361.224057 -252.063458) (xy 361.175092 -252.075858)
			(xy 361.124754 -252.080029) (xy 361.074416 -252.075858) (xy 361.025451 -252.063458) (xy 360.979195 -252.043168)
			(xy 360.936909 -252.015542) (xy 360.899747 -251.981332) (xy 360.868723 -251.941472) (xy 360.844682 -251.897049)
			(xy 360.828281 -251.849275) (xy 360.819968 -251.799453) (xy 360.819446 -251.774198) (xy 360.819885 -251.751097)
			(xy 360.826895 -251.705431) (xy 360.833416 -251.683266) (xy 360.836972 -251.671328) (xy 360.832908 -251.647706)
			(xy 360.777028 -251.572014) (xy 360.769461 -251.562838) (xy 360.748264 -251.552119) (xy 360.736388 -251.55144)
			(xy 360.568748 -251.55144) (xy 360.562166 -251.551644) (xy 360.549429 -251.554977) (xy 360.543602 -251.558044)
			(xy 360.517186 -251.57303) (xy 360.508804 -251.581158) (xy 360.505248 -251.586492) (xy 360.490546 -251.60839)
			(xy 360.45551 -251.647814) (xy 360.414859 -251.681417) (xy 360.369547 -251.70841) (xy 360.320641 -251.728157)
			(xy 360.269291 -251.740194) (xy 360.216704 -251.744238) (xy 360.164117 -251.740194) (xy 360.112767 -251.728157)
			(xy 360.063861 -251.70841) (xy 360.018549 -251.681417) (xy 359.977898 -251.647814) (xy 359.942862 -251.60839)
			(xy 359.92816 -251.586492) (xy 359.924604 -251.581158) (xy 359.916222 -251.57303) (xy 359.889806 -251.558044)
			(xy 359.883991 -251.554939) (xy 359.871249 -251.551579) (xy 359.86466 -251.55144) (xy 359.670096 -251.55144)
			(xy 359.661017 -251.551802) (xy 359.644004 -251.558143) (xy 359.630299 -251.570052) (xy 359.625646 -251.577856)
			(xy 359.612574 -251.600665) (xy 359.580961 -251.642669) (xy 359.543708 -251.679762) (xy 359.501567 -251.711192)
			(xy 359.455392 -251.736323) (xy 359.406118 -251.754646) (xy 359.354742 -251.765791) (xy 359.302304 -251.769531)
			(xy 359.249866 -251.765791) (xy 359.19849 -251.754646) (xy 359.149216 -251.736323) (xy 359.103041 -251.711192)
			(xy 359.0609 -251.679762) (xy 359.023647 -251.642669) (xy 358.992034 -251.600665) (xy 358.978962 -251.577856)
			(xy 358.974271 -251.570085) (xy 358.960558 -251.55821) (xy 358.94358 -251.551821) (xy 358.934512 -251.55144)
			(xy 357.759508 -251.55144) (xy 357.747635 -251.552123) (xy 357.726437 -251.562842) (xy 357.718868 -251.572014)
			(xy 357.662988 -251.647706) (xy 357.658924 -251.671328) (xy 357.66248 -251.683266) (xy 357.668974 -251.705438)
			(xy 357.675991 -251.7511) (xy 357.67645 -251.774198) (xy 357.675928 -251.799453) (xy 357.667615 -251.849275)
			(xy 357.651214 -251.897049) (xy 357.627173 -251.941472) (xy 357.596149 -251.981332) (xy 357.558987 -252.015542)
			(xy 357.516701 -252.043168) (xy 357.470445 -252.063458) (xy 357.42148 -252.075858) (xy 357.371142 -252.080029)
			(xy 357.320804 -252.075858) (xy 357.271839 -252.063458) (xy 357.225583 -252.043168) (xy 357.183297 -252.015542)
			(xy 357.146135 -251.981332) (xy 357.115111 -251.941472) (xy 357.09107 -251.897049) (xy 357.074669 -251.849275)
			(xy 357.066356 -251.799453) (xy 357.065834 -251.774198) (xy 357.066273 -251.751097) (xy 357.073282 -251.705431)
			(xy 357.079804 -251.683266) (xy 357.08336 -251.671328) (xy 357.079296 -251.647706) (xy 357.023416 -251.572014)
			(xy 357.015849 -251.562839) (xy 356.994651 -251.552126) (xy 356.982776 -251.55144) (xy 355.8794 -251.55144)
			(xy 355.867528 -251.552125) (xy 355.846333 -251.562846) (xy 355.83876 -251.572014) (xy 355.78288 -251.647706)
			(xy 355.778816 -251.671328) (xy 355.782372 -251.683266) (xy 355.788866 -251.705438) (xy 355.795883 -251.7511)
			(xy 355.796342 -251.774198) (xy 355.79582 -251.799453) (xy 355.787507 -251.849275) (xy 355.771106 -251.897049)
			(xy 355.747065 -251.941472) (xy 355.716041 -251.981332) (xy 355.678879 -252.015542) (xy 355.636593 -252.043168)
			(xy 355.590337 -252.063458) (xy 355.541372 -252.075858) (xy 355.491034 -252.080029) (xy 355.440696 -252.075858)
			(xy 355.391731 -252.063458) (xy 355.345475 -252.043168) (xy 355.303189 -252.015542) (xy 355.266027 -251.981332)
			(xy 355.235003 -251.941472) (xy 355.210962 -251.897049) (xy 355.194561 -251.849275) (xy 355.186248 -251.799453)
			(xy 355.185726 -251.774198) (xy 355.186165 -251.751097) (xy 355.193174 -251.705431) (xy 355.199696 -251.683266)
			(xy 355.203252 -251.671328) (xy 355.199188 -251.647706) (xy 355.143308 -251.572014) (xy 355.13574 -251.562841)
			(xy 355.114542 -251.55213) (xy 355.102668 -251.55144) (xy 353.999546 -251.55144) (xy 353.98768 -251.552136)
			(xy 353.966503 -251.56287) (xy 353.958906 -251.572014) (xy 353.903026 -251.647706) (xy 353.898962 -251.671328)
			(xy 353.902518 -251.683266) (xy 353.909011 -251.705438) (xy 353.916027 -251.7511) (xy 353.916488 -251.774198)
			(xy 353.915966 -251.799453) (xy 353.907653 -251.849275) (xy 353.891252 -251.897049) (xy 353.867211 -251.941472)
			(xy 353.836187 -251.981332) (xy 353.799025 -252.015542) (xy 353.756739 -252.043168) (xy 353.710483 -252.063458)
			(xy 353.661518 -252.075858) (xy 353.61118 -252.080029) (xy 353.560842 -252.075858) (xy 353.511877 -252.063458)
			(xy 353.465621 -252.043168) (xy 353.423335 -252.015542) (xy 353.386173 -251.981332) (xy 353.355149 -251.941472)
			(xy 353.331108 -251.897049) (xy 353.314707 -251.849275) (xy 353.306394 -251.799453) (xy 353.305872 -251.774198)
			(xy 353.306311 -251.751098) (xy 353.313321 -251.705431) (xy 353.319842 -251.683266) (xy 353.323398 -251.671328)
			(xy 353.319334 -251.647706) (xy 353.263454 -251.572014) (xy 353.255889 -251.562833) (xy 353.234692 -251.552104)
			(xy 353.222814 -251.55144) (xy 352.119438 -251.55144) (xy 352.107573 -251.552138) (xy 352.086399 -251.562874)
			(xy 352.078798 -251.572014) (xy 352.022918 -251.647706) (xy 352.018854 -251.671328) (xy 352.02241 -251.683266)
			(xy 352.028903 -251.705438) (xy 352.03592 -251.7511) (xy 352.03638 -251.774198) (xy 352.035858 -251.799453)
			(xy 352.027545 -251.849275) (xy 352.011144 -251.897049) (xy 351.987103 -251.941472) (xy 351.956079 -251.981332)
			(xy 351.918917 -252.015542) (xy 351.876631 -252.043168) (xy 351.830375 -252.063458) (xy 351.78141 -252.075858)
			(xy 351.731072 -252.080029) (xy 351.680734 -252.075858) (xy 351.631769 -252.063458) (xy 351.585513 -252.043168)
			(xy 351.543227 -252.015542) (xy 351.506065 -251.981332) (xy 351.475041 -251.941472) (xy 351.451 -251.897049)
			(xy 351.434599 -251.849275) (xy 351.426286 -251.799453) (xy 351.425764 -251.774198) (xy 351.426203 -251.751098)
			(xy 351.433213 -251.705431) (xy 351.439734 -251.683266) (xy 351.44329 -251.671328) (xy 351.439226 -251.647706)
			(xy 351.383346 -251.572014) (xy 351.375781 -251.562834) (xy 351.354583 -251.552108) (xy 351.342706 -251.55144)
			(xy 350.239584 -251.55144) (xy 350.227713 -251.552128) (xy 350.206524 -251.562853) (xy 350.198944 -251.572014)
			(xy 350.143064 -251.647706) (xy 350.139 -251.671328) (xy 350.142556 -251.683266) (xy 350.14905 -251.705437)
			(xy 350.156068 -251.7511) (xy 350.156526 -251.774198) (xy 350.156004 -251.799453) (xy 350.147691 -251.849275)
			(xy 350.13129 -251.897049) (xy 350.107249 -251.941472) (xy 350.076225 -251.981332) (xy 350.039063 -252.015542)
			(xy 349.996777 -252.043168) (xy 349.950521 -252.063458) (xy 349.901556 -252.075858) (xy 349.851218 -252.080029)
			(xy 349.80088 -252.075858) (xy 349.751915 -252.063458) (xy 349.705659 -252.043168) (xy 349.663373 -252.015542)
			(xy 349.626211 -251.981332) (xy 349.595187 -251.941472) (xy 349.571146 -251.897049) (xy 349.554745 -251.849275)
			(xy 349.546432 -251.799453) (xy 349.54591 -251.774198) (xy 349.546349 -251.751097) (xy 349.553358 -251.705431)
			(xy 349.55988 -251.683266) (xy 349.563436 -251.671328) (xy 349.559372 -251.647706) (xy 349.503492 -251.572014)
			(xy 349.495923 -251.562843) (xy 349.474725 -251.55214) (xy 349.462852 -251.55144) (xy 349.29953 -251.55144)
			(xy 349.287654 -251.552119) (xy 349.266449 -251.562832) (xy 349.25889 -251.572014) (xy 349.20301 -251.647706)
			(xy 349.198946 -251.671328) (xy 349.202502 -251.683266) (xy 349.208995 -251.705438) (xy 349.216012 -251.7511)
			(xy 349.216472 -251.774198) (xy 349.216026 -251.79819) (xy 349.208519 -251.845584) (xy 349.19369 -251.891219)
			(xy 349.171905 -251.933973) (xy 349.143698 -251.972792) (xy 349.109766 -252.00672) (xy 349.070944 -252.034922)
			(xy 349.028188 -252.056703) (xy 348.982551 -252.071527) (xy 348.935156 -252.079029) (xy 348.911164 -252.079506)
			(xy 348.884688 -252.07894) (xy 348.832527 -252.069814) (xy 348.782718 -252.051839) (xy 348.736749 -252.025555)
			(xy 348.695994 -251.991745) (xy 348.661672 -251.951421) (xy 348.647766 -251.928884) (xy 348.644972 -251.924058)
			(xy 348.637606 -251.91593) (xy 348.615 -251.900182) (xy 348.610096 -251.896949) (xy 348.59919 -251.892594)
			(xy 348.59341 -251.891546) (xy 348.52483 -251.881386) (xy 348.514161 -251.880395) (xy 348.493557 -251.886177)
			(xy 348.484952 -251.892562) (xy 348.483174 -251.894086) (xy 348.302326 -252.074934) (xy 348.29496 -252.082046)
			(xy 348.28734 -252.100842) (xy 348.28734 -252.180852) (xy 348.28784 -252.191691) (xy 348.296789 -252.211434)
			(xy 348.304612 -252.218952) (xy 348.361508 -252.268736) (xy 348.368668 -252.274503) (xy 348.385852 -252.281)
			(xy 348.395036 -252.281436) (xy 348.40164 -252.281436) (xy 348.404688 -252.281182) (xy 348.413732 -252.280134)
			(xy 348.431906 -252.278991) (xy 348.44101 -252.278896) (xy 348.466264 -252.279418) (xy 348.516084 -252.287733)
			(xy 348.563856 -252.304135) (xy 348.608277 -252.328175) (xy 348.648135 -252.359199) (xy 348.682343 -252.39636)
			(xy 348.709968 -252.438645) (xy 348.730257 -252.4849) (xy 348.742656 -252.533864) (xy 348.746827 -252.5842)
			(xy 348.746827 -252.584204) (xy 349.07526 -252.584204) (xy 349.07922 -252.53515) (xy 349.090997 -252.487366)
			(xy 349.110288 -252.44209) (xy 349.136591 -252.400494) (xy 349.169226 -252.363657) (xy 349.207347 -252.332532)
			(xy 349.249968 -252.307925) (xy 349.295984 -252.290473) (xy 349.344203 -252.280629) (xy 349.393378 -252.278648)
			(xy 349.442233 -252.28458) (xy 349.489504 -252.298272) (xy 349.533966 -252.31937) (xy 349.574469 -252.347326)
			(xy 349.609962 -252.381418) (xy 349.636182 -252.41631) (xy 359.853741 -252.41631) (xy 359.857771 -252.363812)
			(xy 359.869768 -252.312544) (xy 359.889451 -252.263709) (xy 359.916357 -252.21845) (xy 359.949857 -252.177829)
			(xy 359.989165 -252.142798) (xy 360.03336 -252.114178) (xy 360.081405 -252.092639) (xy 360.132176 -252.078687)
			(xy 360.184481 -252.072649) (xy 360.237095 -252.074666) (xy 360.288785 -252.08469) (xy 360.338338 -252.102488)
			(xy 360.384594 -252.127641) (xy 360.426468 -252.15956) (xy 360.46298 -252.197498) (xy 360.493272 -252.240564)
			(xy 360.516635 -252.287749) (xy 360.532521 -252.337948) (xy 360.540558 -252.389984) (xy 360.541062 -252.41631)
			(xy 360.540558 -252.442636) (xy 360.532521 -252.494672) (xy 360.516635 -252.544871) (xy 360.49716 -252.584204)
			(xy 368.809028 -252.584204) (xy 368.812988 -252.53515) (xy 368.824765 -252.487366) (xy 368.844056 -252.44209)
			(xy 368.870359 -252.400494) (xy 368.902994 -252.363657) (xy 368.941115 -252.332532) (xy 368.983736 -252.307925)
			(xy 369.029752 -252.290473) (xy 369.077971 -252.280629) (xy 369.127146 -252.278648) (xy 369.176001 -252.28458)
			(xy 369.223272 -252.298272) (xy 369.267734 -252.31937) (xy 369.308237 -252.347326) (xy 369.34373 -252.381418)
			(xy 369.373295 -252.420762) (xy 369.396166 -252.464339) (xy 369.41175 -252.51102) (xy 369.419645 -252.559597)
			(xy 369.42014 -252.584204) (xy 370.688882 -252.584204) (xy 370.692842 -252.53515) (xy 370.704619 -252.487366)
			(xy 370.72391 -252.44209) (xy 370.750213 -252.400494) (xy 370.782848 -252.363657) (xy 370.820969 -252.332532)
			(xy 370.86359 -252.307925) (xy 370.909606 -252.290473) (xy 370.957825 -252.280629) (xy 371.007 -252.278648)
			(xy 371.055855 -252.28458) (xy 371.103126 -252.298272) (xy 371.147588 -252.31937) (xy 371.188091 -252.347326)
			(xy 371.223584 -252.381418) (xy 371.253149 -252.420762) (xy 371.27602 -252.464339) (xy 371.291604 -252.51102)
			(xy 371.299499 -252.559597) (xy 371.299994 -252.584204) (xy 372.56899 -252.584204) (xy 372.57295 -252.53515)
			(xy 372.584727 -252.487366) (xy 372.604018 -252.44209) (xy 372.630321 -252.400494) (xy 372.662956 -252.363657)
			(xy 372.701077 -252.332532) (xy 372.743698 -252.307925) (xy 372.789714 -252.290473) (xy 372.837933 -252.280629)
			(xy 372.887108 -252.278648) (xy 372.935963 -252.28458) (xy 372.983234 -252.298272) (xy 373.027696 -252.31937)
			(xy 373.068199 -252.347326) (xy 373.103692 -252.381418) (xy 373.133257 -252.420762) (xy 373.156128 -252.464339)
			(xy 373.171712 -252.51102) (xy 373.179607 -252.559597) (xy 373.180102 -252.584204) (xy 374.449098 -252.584204)
			(xy 374.453058 -252.53515) (xy 374.464835 -252.487366) (xy 374.484126 -252.44209) (xy 374.510429 -252.400494)
			(xy 374.543064 -252.363657) (xy 374.581185 -252.332532) (xy 374.623806 -252.307925) (xy 374.669822 -252.290473)
			(xy 374.718041 -252.280629) (xy 374.767216 -252.278648) (xy 374.816071 -252.28458) (xy 374.863342 -252.298272)
			(xy 374.907804 -252.31937) (xy 374.948307 -252.347326) (xy 374.9838 -252.381418) (xy 375.013365 -252.420762)
			(xy 375.036236 -252.464339) (xy 375.05182 -252.51102) (xy 375.059715 -252.559597) (xy 375.06021 -252.584204)
			(xy 375.388898 -252.584204) (xy 375.392858 -252.53515) (xy 375.404635 -252.487366) (xy 375.423926 -252.44209)
			(xy 375.450229 -252.400494) (xy 375.482864 -252.363657) (xy 375.520985 -252.332532) (xy 375.563606 -252.307925)
			(xy 375.609622 -252.290473) (xy 375.657841 -252.280629) (xy 375.707016 -252.278648) (xy 375.755871 -252.28458)
			(xy 375.803142 -252.298272) (xy 375.847604 -252.31937) (xy 375.888107 -252.347326) (xy 375.9236 -252.381418)
			(xy 375.953165 -252.420762) (xy 375.976036 -252.464339) (xy 375.99162 -252.51102) (xy 375.999515 -252.559597)
			(xy 376.00001 -252.584204) (xy 376.328952 -252.584204) (xy 376.332912 -252.53515) (xy 376.344689 -252.487366)
			(xy 376.36398 -252.44209) (xy 376.390283 -252.400494) (xy 376.422918 -252.363657) (xy 376.461039 -252.332532)
			(xy 376.50366 -252.307925) (xy 376.549676 -252.290473) (xy 376.597895 -252.280629) (xy 376.64707 -252.278648)
			(xy 376.695925 -252.28458) (xy 376.743196 -252.298272) (xy 376.787658 -252.31937) (xy 376.828161 -252.347326)
			(xy 376.863654 -252.381418) (xy 376.893219 -252.420762) (xy 376.91609 -252.464339) (xy 376.931674 -252.51102)
			(xy 376.939569 -252.559597) (xy 376.940064 -252.584204) (xy 377.258575 -252.584204) (xy 377.26267 -252.533476)
			(xy 377.274849 -252.484062) (xy 377.294797 -252.437242) (xy 377.321998 -252.394228) (xy 377.355746 -252.356134)
			(xy 377.395168 -252.323947) (xy 377.439242 -252.298501) (xy 377.486828 -252.280454) (xy 377.536692 -252.270274)
			(xy 377.587544 -252.268225) (xy 377.638065 -252.274359) (xy 377.686949 -252.288519) (xy 377.732928 -252.310336)
			(xy 377.774812 -252.339246) (xy 377.811516 -252.374501) (xy 377.842089 -252.415187) (xy 377.86574 -252.46025)
			(xy 377.881856 -252.508524) (xy 377.89002 -252.558758) (xy 377.890532 -252.584204) (xy 378.20906 -252.584204)
			(xy 378.21302 -252.53515) (xy 378.224797 -252.487366) (xy 378.244088 -252.44209) (xy 378.270391 -252.400494)
			(xy 378.303026 -252.363657) (xy 378.341147 -252.332532) (xy 378.383768 -252.307925) (xy 378.429784 -252.290473)
			(xy 378.478003 -252.280629) (xy 378.527178 -252.278648) (xy 378.576033 -252.28458) (xy 378.623304 -252.298272)
			(xy 378.667766 -252.31937) (xy 378.708269 -252.347326) (xy 378.743762 -252.381418) (xy 378.773327 -252.420762)
			(xy 378.796198 -252.464339) (xy 378.811782 -252.51102) (xy 378.819677 -252.559597) (xy 378.820172 -252.584204)
			(xy 379.149114 -252.584204) (xy 379.153074 -252.53515) (xy 379.164851 -252.487366) (xy 379.184142 -252.44209)
			(xy 379.210445 -252.400494) (xy 379.24308 -252.363657) (xy 379.281201 -252.332532) (xy 379.323822 -252.307925)
			(xy 379.369838 -252.290473) (xy 379.418057 -252.280629) (xy 379.467232 -252.278648) (xy 379.516087 -252.28458)
			(xy 379.563358 -252.298272) (xy 379.60782 -252.31937) (xy 379.648323 -252.347326) (xy 379.683816 -252.381418)
			(xy 379.713381 -252.420762) (xy 379.736252 -252.464339) (xy 379.751836 -252.51102) (xy 379.759731 -252.559597)
			(xy 379.760226 -252.584204) (xy 380.078483 -252.584204) (xy 380.082578 -252.533476) (xy 380.094757 -252.484062)
			(xy 380.114705 -252.437242) (xy 380.141906 -252.394228) (xy 380.175654 -252.356134) (xy 380.215076 -252.323947)
			(xy 380.25915 -252.298501) (xy 380.306736 -252.280454) (xy 380.3566 -252.270274) (xy 380.407452 -252.268225)
			(xy 380.457973 -252.274359) (xy 380.506857 -252.288519) (xy 380.552836 -252.310336) (xy 380.59472 -252.339246)
			(xy 380.631424 -252.374501) (xy 380.661997 -252.415187) (xy 380.685648 -252.46025) (xy 380.701764 -252.508524)
			(xy 380.709928 -252.558758) (xy 380.71044 -252.584204) (xy 381.028968 -252.584204) (xy 381.032928 -252.53515)
			(xy 381.044705 -252.487366) (xy 381.063996 -252.44209) (xy 381.090299 -252.400494) (xy 381.122934 -252.363657)
			(xy 381.161055 -252.332532) (xy 381.203676 -252.307925) (xy 381.249692 -252.290473) (xy 381.297911 -252.280629)
			(xy 381.347086 -252.278648) (xy 381.395941 -252.28458) (xy 381.443212 -252.298272) (xy 381.487674 -252.31937)
			(xy 381.528177 -252.347326) (xy 381.56367 -252.381418) (xy 381.593235 -252.420762) (xy 381.616106 -252.464339)
			(xy 381.63169 -252.51102) (xy 381.639585 -252.559597) (xy 381.64008 -252.584204) (xy 381.969022 -252.584204)
			(xy 381.972982 -252.53515) (xy 381.984759 -252.487366) (xy 382.00405 -252.44209) (xy 382.030353 -252.400494)
			(xy 382.062988 -252.363657) (xy 382.101109 -252.332532) (xy 382.14373 -252.307925) (xy 382.189746 -252.290473)
			(xy 382.237965 -252.280629) (xy 382.28714 -252.278648) (xy 382.335995 -252.28458) (xy 382.383266 -252.298272)
			(xy 382.427728 -252.31937) (xy 382.468231 -252.347326) (xy 382.503724 -252.381418) (xy 382.533289 -252.420762)
			(xy 382.55616 -252.464339) (xy 382.571744 -252.51102) (xy 382.579639 -252.559597) (xy 382.580134 -252.584204)
			(xy 382.909076 -252.584204) (xy 382.913036 -252.53515) (xy 382.924813 -252.487366) (xy 382.944104 -252.44209)
			(xy 382.970407 -252.400494) (xy 383.003042 -252.363657) (xy 383.041163 -252.332532) (xy 383.083784 -252.307925)
			(xy 383.1298 -252.290473) (xy 383.178019 -252.280629) (xy 383.227194 -252.278648) (xy 383.276049 -252.28458)
			(xy 383.32332 -252.298272) (xy 383.367782 -252.31937) (xy 383.408285 -252.347326) (xy 383.443778 -252.381418)
			(xy 383.473343 -252.420762) (xy 383.496214 -252.464339) (xy 383.511798 -252.51102) (xy 383.519693 -252.559597)
			(xy 383.520188 -252.584204) (xy 383.838699 -252.584204) (xy 383.842794 -252.533476) (xy 383.854973 -252.484062)
			(xy 383.874921 -252.437242) (xy 383.902122 -252.394228) (xy 383.93587 -252.356134) (xy 383.975292 -252.323947)
			(xy 384.019366 -252.298501) (xy 384.066952 -252.280454) (xy 384.116816 -252.270274) (xy 384.167668 -252.268225)
			(xy 384.218189 -252.274359) (xy 384.267073 -252.288519) (xy 384.313052 -252.310336) (xy 384.354936 -252.339246)
			(xy 384.39164 -252.374501) (xy 384.422213 -252.415187) (xy 384.445864 -252.46025) (xy 384.46198 -252.508524)
			(xy 384.470144 -252.558758) (xy 384.470656 -252.584204) (xy 384.78893 -252.584204) (xy 384.79289 -252.53515)
			(xy 384.804667 -252.487366) (xy 384.823958 -252.44209) (xy 384.850261 -252.400494) (xy 384.882896 -252.363657)
			(xy 384.921017 -252.332532) (xy 384.963638 -252.307925) (xy 385.009654 -252.290473) (xy 385.057873 -252.280629)
			(xy 385.107048 -252.278648) (xy 385.155903 -252.28458) (xy 385.203174 -252.298272) (xy 385.247636 -252.31937)
			(xy 385.288139 -252.347326) (xy 385.323632 -252.381418) (xy 385.353197 -252.420762) (xy 385.376068 -252.464339)
			(xy 385.391652 -252.51102) (xy 385.399547 -252.559597) (xy 385.400042 -252.584204) (xy 385.728984 -252.584204)
			(xy 385.732944 -252.53515) (xy 385.744721 -252.487366) (xy 385.764012 -252.44209) (xy 385.790315 -252.400494)
			(xy 385.82295 -252.363657) (xy 385.861071 -252.332532) (xy 385.903692 -252.307925) (xy 385.949708 -252.290473)
			(xy 385.997927 -252.280629) (xy 386.047102 -252.278648) (xy 386.095957 -252.28458) (xy 386.143228 -252.298272)
			(xy 386.18769 -252.31937) (xy 386.228193 -252.347326) (xy 386.263686 -252.381418) (xy 386.293251 -252.420762)
			(xy 386.316122 -252.464339) (xy 386.331706 -252.51102) (xy 386.339601 -252.559597) (xy 386.340096 -252.584204)
			(xy 386.658607 -252.584204) (xy 386.662702 -252.533476) (xy 386.674881 -252.484062) (xy 386.694829 -252.437242)
			(xy 386.72203 -252.394228) (xy 386.755778 -252.356134) (xy 386.7952 -252.323947) (xy 386.839274 -252.298501)
			(xy 386.88686 -252.280454) (xy 386.936724 -252.270274) (xy 386.987576 -252.268225) (xy 387.038097 -252.274359)
			(xy 387.086981 -252.288519) (xy 387.13296 -252.310336) (xy 387.174844 -252.339246) (xy 387.211548 -252.374501)
			(xy 387.242121 -252.415187) (xy 387.265772 -252.46025) (xy 387.281888 -252.508524) (xy 387.290052 -252.558758)
			(xy 387.290564 -252.584204) (xy 387.609092 -252.584204) (xy 387.613052 -252.53515) (xy 387.624829 -252.487366)
			(xy 387.64412 -252.44209) (xy 387.670423 -252.400494) (xy 387.703058 -252.363657) (xy 387.741179 -252.332532)
			(xy 387.7838 -252.307925) (xy 387.829816 -252.290473) (xy 387.878035 -252.280629) (xy 387.92721 -252.278648)
			(xy 387.976065 -252.28458) (xy 388.023336 -252.298272) (xy 388.067798 -252.31937) (xy 388.108301 -252.347326)
			(xy 388.143794 -252.381418) (xy 388.173359 -252.420762) (xy 388.19623 -252.464339) (xy 388.211814 -252.51102)
			(xy 388.219709 -252.559597) (xy 388.220204 -252.584204) (xy 388.548892 -252.584204) (xy 388.552852 -252.53515)
			(xy 388.564629 -252.487366) (xy 388.58392 -252.44209) (xy 388.610223 -252.400494) (xy 388.642858 -252.363657)
			(xy 388.680979 -252.332532) (xy 388.7236 -252.307925) (xy 388.769616 -252.290473) (xy 388.817835 -252.280629)
			(xy 388.86701 -252.278648) (xy 388.915865 -252.28458) (xy 388.963136 -252.298272) (xy 389.007598 -252.31937)
			(xy 389.048101 -252.347326) (xy 389.083594 -252.381418) (xy 389.113159 -252.420762) (xy 389.13603 -252.464339)
			(xy 389.151614 -252.51102) (xy 389.159509 -252.559597) (xy 389.160004 -252.584204) (xy 389.488946 -252.584204)
			(xy 389.492906 -252.53515) (xy 389.504683 -252.487366) (xy 389.523974 -252.44209) (xy 389.550277 -252.400494)
			(xy 389.582912 -252.363657) (xy 389.621033 -252.332532) (xy 389.663654 -252.307925) (xy 389.70967 -252.290473)
			(xy 389.757889 -252.280629) (xy 389.807064 -252.278648) (xy 389.855919 -252.28458) (xy 389.90319 -252.298272)
			(xy 389.947652 -252.31937) (xy 389.988155 -252.347326) (xy 390.023648 -252.381418) (xy 390.053213 -252.420762)
			(xy 390.076084 -252.464339) (xy 390.091668 -252.51102) (xy 390.099563 -252.559597) (xy 390.100058 -252.584204)
			(xy 390.418569 -252.584204) (xy 390.422664 -252.533476) (xy 390.434843 -252.484062) (xy 390.454791 -252.437242)
			(xy 390.481992 -252.394228) (xy 390.51574 -252.356134) (xy 390.555162 -252.323947) (xy 390.599236 -252.298501)
			(xy 390.646822 -252.280454) (xy 390.696686 -252.270274) (xy 390.747538 -252.268225) (xy 390.798059 -252.274359)
			(xy 390.846943 -252.288519) (xy 390.892922 -252.310336) (xy 390.934806 -252.339246) (xy 390.97151 -252.374501)
			(xy 391.002083 -252.415187) (xy 391.025734 -252.46025) (xy 391.04185 -252.508524) (xy 391.050014 -252.558758)
			(xy 391.050526 -252.584204) (xy 391.369054 -252.584204) (xy 391.373014 -252.53515) (xy 391.384791 -252.487366)
			(xy 391.404082 -252.44209) (xy 391.430385 -252.400494) (xy 391.46302 -252.363657) (xy 391.501141 -252.332532)
			(xy 391.543762 -252.307925) (xy 391.589778 -252.290473) (xy 391.637997 -252.280629) (xy 391.687172 -252.278648)
			(xy 391.736027 -252.28458) (xy 391.783298 -252.298272) (xy 391.82776 -252.31937) (xy 391.868263 -252.347326)
			(xy 391.903756 -252.381418) (xy 391.933321 -252.420762) (xy 391.956192 -252.464339) (xy 391.971776 -252.51102)
			(xy 391.979671 -252.559597) (xy 391.980166 -252.584204) (xy 391.979671 -252.608811) (xy 391.971776 -252.657388)
			(xy 391.956192 -252.704069) (xy 391.933321 -252.747646) (xy 391.903756 -252.78699) (xy 391.868263 -252.821082)
			(xy 391.82776 -252.849038) (xy 391.825433 -252.850142) (xy 394.377176 -252.850142) (xy 394.381136 -252.801088)
			(xy 394.392913 -252.753304) (xy 394.412204 -252.708028) (xy 394.438507 -252.666432) (xy 394.471142 -252.629595)
			(xy 394.509263 -252.59847) (xy 394.551884 -252.573863) (xy 394.5979 -252.556411) (xy 394.646119 -252.546567)
			(xy 394.695294 -252.544586) (xy 394.744149 -252.550518) (xy 394.79142 -252.56421) (xy 394.835882 -252.585308)
			(xy 394.876385 -252.613264) (xy 394.911878 -252.647356) (xy 394.941443 -252.6867) (xy 394.964314 -252.730277)
			(xy 394.979898 -252.776958) (xy 394.987793 -252.825535) (xy 394.988288 -252.850142) (xy 394.987793 -252.874749)
			(xy 394.979898 -252.923326) (xy 394.964314 -252.970007) (xy 394.941443 -253.013584) (xy 394.911878 -253.052928)
			(xy 394.876385 -253.08702) (xy 394.835882 -253.114976) (xy 394.79142 -253.136074) (xy 394.744149 -253.149766)
			(xy 394.695294 -253.155698) (xy 394.646119 -253.153717) (xy 394.5979 -253.143873) (xy 394.551884 -253.126421)
			(xy 394.509263 -253.101814) (xy 394.471142 -253.070689) (xy 394.438507 -253.033852) (xy 394.412204 -252.992256)
			(xy 394.392913 -252.94698) (xy 394.381136 -252.899196) (xy 394.377176 -252.850142) (xy 391.825433 -252.850142)
			(xy 391.783298 -252.870136) (xy 391.736027 -252.883828) (xy 391.687172 -252.88976) (xy 391.637997 -252.887779)
			(xy 391.589778 -252.877935) (xy 391.543762 -252.860483) (xy 391.501141 -252.835876) (xy 391.46302 -252.804751)
			(xy 391.430385 -252.767914) (xy 391.404082 -252.726318) (xy 391.384791 -252.681042) (xy 391.373014 -252.633258)
			(xy 391.369054 -252.584204) (xy 391.050526 -252.584204) (xy 391.050014 -252.60965) (xy 391.04185 -252.659884)
			(xy 391.025734 -252.708158) (xy 391.002083 -252.753221) (xy 390.97151 -252.793907) (xy 390.934806 -252.829162)
			(xy 390.892922 -252.858072) (xy 390.846943 -252.879889) (xy 390.798059 -252.894049) (xy 390.747538 -252.900183)
			(xy 390.696686 -252.898134) (xy 390.646822 -252.887954) (xy 390.599236 -252.869907) (xy 390.555162 -252.844461)
			(xy 390.51574 -252.812274) (xy 390.481992 -252.77418) (xy 390.454791 -252.731166) (xy 390.434843 -252.684346)
			(xy 390.422664 -252.634932) (xy 390.418569 -252.584204) (xy 390.100058 -252.584204) (xy 390.099563 -252.608811)
			(xy 390.091668 -252.657388) (xy 390.076084 -252.704069) (xy 390.053213 -252.747646) (xy 390.023648 -252.78699)
			(xy 389.988155 -252.821082) (xy 389.947652 -252.849038) (xy 389.90319 -252.870136) (xy 389.855919 -252.883828)
			(xy 389.807064 -252.88976) (xy 389.757889 -252.887779) (xy 389.70967 -252.877935) (xy 389.663654 -252.860483)
			(xy 389.621033 -252.835876) (xy 389.582912 -252.804751) (xy 389.550277 -252.767914) (xy 389.523974 -252.726318)
			(xy 389.504683 -252.681042) (xy 389.492906 -252.633258) (xy 389.488946 -252.584204) (xy 389.160004 -252.584204)
			(xy 389.159509 -252.608811) (xy 389.151614 -252.657388) (xy 389.13603 -252.704069) (xy 389.113159 -252.747646)
			(xy 389.083594 -252.78699) (xy 389.048101 -252.821082) (xy 389.007598 -252.849038) (xy 388.963136 -252.870136)
			(xy 388.915865 -252.883828) (xy 388.86701 -252.88976) (xy 388.817835 -252.887779) (xy 388.769616 -252.877935)
			(xy 388.7236 -252.860483) (xy 388.680979 -252.835876) (xy 388.642858 -252.804751) (xy 388.610223 -252.767914)
			(xy 388.58392 -252.726318) (xy 388.564629 -252.681042) (xy 388.552852 -252.633258) (xy 388.548892 -252.584204)
			(xy 388.220204 -252.584204) (xy 388.219709 -252.608811) (xy 388.211814 -252.657388) (xy 388.19623 -252.704069)
			(xy 388.173359 -252.747646) (xy 388.143794 -252.78699) (xy 388.108301 -252.821082) (xy 388.067798 -252.849038)
			(xy 388.023336 -252.870136) (xy 387.976065 -252.883828) (xy 387.92721 -252.88976) (xy 387.878035 -252.887779)
			(xy 387.829816 -252.877935) (xy 387.7838 -252.860483) (xy 387.741179 -252.835876) (xy 387.703058 -252.804751)
			(xy 387.670423 -252.767914) (xy 387.64412 -252.726318) (xy 387.624829 -252.681042) (xy 387.613052 -252.633258)
			(xy 387.609092 -252.584204) (xy 387.290564 -252.584204) (xy 387.290052 -252.60965) (xy 387.281888 -252.659884)
			(xy 387.265772 -252.708158) (xy 387.242121 -252.753221) (xy 387.211548 -252.793907) (xy 387.174844 -252.829162)
			(xy 387.13296 -252.858072) (xy 387.086981 -252.879889) (xy 387.038097 -252.894049) (xy 386.987576 -252.900183)
			(xy 386.936724 -252.898134) (xy 386.88686 -252.887954) (xy 386.839274 -252.869907) (xy 386.7952 -252.844461)
			(xy 386.755778 -252.812274) (xy 386.72203 -252.77418) (xy 386.694829 -252.731166) (xy 386.674881 -252.684346)
			(xy 386.662702 -252.634932) (xy 386.658607 -252.584204) (xy 386.340096 -252.584204) (xy 386.339601 -252.608811)
			(xy 386.331706 -252.657388) (xy 386.316122 -252.704069) (xy 386.293251 -252.747646) (xy 386.263686 -252.78699)
			(xy 386.228193 -252.821082) (xy 386.18769 -252.849038) (xy 386.143228 -252.870136) (xy 386.095957 -252.883828)
			(xy 386.047102 -252.88976) (xy 385.997927 -252.887779) (xy 385.949708 -252.877935) (xy 385.903692 -252.860483)
			(xy 385.861071 -252.835876) (xy 385.82295 -252.804751) (xy 385.790315 -252.767914) (xy 385.764012 -252.726318)
			(xy 385.744721 -252.681042) (xy 385.732944 -252.633258) (xy 385.728984 -252.584204) (xy 385.400042 -252.584204)
			(xy 385.399547 -252.608811) (xy 385.391652 -252.657388) (xy 385.376068 -252.704069) (xy 385.353197 -252.747646)
			(xy 385.323632 -252.78699) (xy 385.288139 -252.821082) (xy 385.247636 -252.849038) (xy 385.203174 -252.870136)
			(xy 385.155903 -252.883828) (xy 385.107048 -252.88976) (xy 385.057873 -252.887779) (xy 385.009654 -252.877935)
			(xy 384.963638 -252.860483) (xy 384.921017 -252.835876) (xy 384.882896 -252.804751) (xy 384.850261 -252.767914)
			(xy 384.823958 -252.726318) (xy 384.804667 -252.681042) (xy 384.79289 -252.633258) (xy 384.78893 -252.584204)
			(xy 384.470656 -252.584204) (xy 384.470144 -252.60965) (xy 384.46198 -252.659884) (xy 384.445864 -252.708158)
			(xy 384.422213 -252.753221) (xy 384.39164 -252.793907) (xy 384.354936 -252.829162) (xy 384.313052 -252.858072)
			(xy 384.267073 -252.879889) (xy 384.218189 -252.894049) (xy 384.167668 -252.900183) (xy 384.116816 -252.898134)
			(xy 384.066952 -252.887954) (xy 384.019366 -252.869907) (xy 383.975292 -252.844461) (xy 383.93587 -252.812274)
			(xy 383.902122 -252.77418) (xy 383.874921 -252.731166) (xy 383.854973 -252.684346) (xy 383.842794 -252.634932)
			(xy 383.838699 -252.584204) (xy 383.520188 -252.584204) (xy 383.519693 -252.608811) (xy 383.511798 -252.657388)
			(xy 383.496214 -252.704069) (xy 383.473343 -252.747646) (xy 383.443778 -252.78699) (xy 383.408285 -252.821082)
			(xy 383.367782 -252.849038) (xy 383.32332 -252.870136) (xy 383.276049 -252.883828) (xy 383.227194 -252.88976)
			(xy 383.178019 -252.887779) (xy 383.1298 -252.877935) (xy 383.083784 -252.860483) (xy 383.041163 -252.835876)
			(xy 383.003042 -252.804751) (xy 382.970407 -252.767914) (xy 382.944104 -252.726318) (xy 382.924813 -252.681042)
			(xy 382.913036 -252.633258) (xy 382.909076 -252.584204) (xy 382.580134 -252.584204) (xy 382.579639 -252.608811)
			(xy 382.571744 -252.657388) (xy 382.55616 -252.704069) (xy 382.533289 -252.747646) (xy 382.503724 -252.78699)
			(xy 382.468231 -252.821082) (xy 382.427728 -252.849038) (xy 382.383266 -252.870136) (xy 382.335995 -252.883828)
			(xy 382.28714 -252.88976) (xy 382.237965 -252.887779) (xy 382.189746 -252.877935) (xy 382.14373 -252.860483)
			(xy 382.101109 -252.835876) (xy 382.062988 -252.804751) (xy 382.030353 -252.767914) (xy 382.00405 -252.726318)
			(xy 381.984759 -252.681042) (xy 381.972982 -252.633258) (xy 381.969022 -252.584204) (xy 381.64008 -252.584204)
			(xy 381.639585 -252.608811) (xy 381.63169 -252.657388) (xy 381.616106 -252.704069) (xy 381.593235 -252.747646)
			(xy 381.56367 -252.78699) (xy 381.528177 -252.821082) (xy 381.487674 -252.849038) (xy 381.443212 -252.870136)
			(xy 381.395941 -252.883828) (xy 381.347086 -252.88976) (xy 381.297911 -252.887779) (xy 381.249692 -252.877935)
			(xy 381.203676 -252.860483) (xy 381.161055 -252.835876) (xy 381.122934 -252.804751) (xy 381.090299 -252.767914)
			(xy 381.063996 -252.726318) (xy 381.044705 -252.681042) (xy 381.032928 -252.633258) (xy 381.028968 -252.584204)
			(xy 380.71044 -252.584204) (xy 380.709928 -252.60965) (xy 380.701764 -252.659884) (xy 380.685648 -252.708158)
			(xy 380.661997 -252.753221) (xy 380.631424 -252.793907) (xy 380.59472 -252.829162) (xy 380.552836 -252.858072)
			(xy 380.506857 -252.879889) (xy 380.457973 -252.894049) (xy 380.407452 -252.900183) (xy 380.3566 -252.898134)
			(xy 380.306736 -252.887954) (xy 380.25915 -252.869907) (xy 380.215076 -252.844461) (xy 380.175654 -252.812274)
			(xy 380.141906 -252.77418) (xy 380.114705 -252.731166) (xy 380.094757 -252.684346) (xy 380.082578 -252.634932)
			(xy 380.078483 -252.584204) (xy 379.760226 -252.584204) (xy 379.759731 -252.608811) (xy 379.751836 -252.657388)
			(xy 379.736252 -252.704069) (xy 379.713381 -252.747646) (xy 379.683816 -252.78699) (xy 379.648323 -252.821082)
			(xy 379.60782 -252.849038) (xy 379.563358 -252.870136) (xy 379.516087 -252.883828) (xy 379.467232 -252.88976)
			(xy 379.418057 -252.887779) (xy 379.369838 -252.877935) (xy 379.323822 -252.860483) (xy 379.281201 -252.835876)
			(xy 379.24308 -252.804751) (xy 379.210445 -252.767914) (xy 379.184142 -252.726318) (xy 379.164851 -252.681042)
			(xy 379.153074 -252.633258) (xy 379.149114 -252.584204) (xy 378.820172 -252.584204) (xy 378.819677 -252.608811)
			(xy 378.811782 -252.657388) (xy 378.796198 -252.704069) (xy 378.773327 -252.747646) (xy 378.743762 -252.78699)
			(xy 378.708269 -252.821082) (xy 378.667766 -252.849038) (xy 378.623304 -252.870136) (xy 378.576033 -252.883828)
			(xy 378.527178 -252.88976) (xy 378.478003 -252.887779) (xy 378.429784 -252.877935) (xy 378.383768 -252.860483)
			(xy 378.341147 -252.835876) (xy 378.303026 -252.804751) (xy 378.270391 -252.767914) (xy 378.244088 -252.726318)
			(xy 378.224797 -252.681042) (xy 378.21302 -252.633258) (xy 378.20906 -252.584204) (xy 377.890532 -252.584204)
			(xy 377.89002 -252.60965) (xy 377.881856 -252.659884) (xy 377.86574 -252.708158) (xy 377.842089 -252.753221)
			(xy 377.811516 -252.793907) (xy 377.774812 -252.829162) (xy 377.732928 -252.858072) (xy 377.686949 -252.879889)
			(xy 377.638065 -252.894049) (xy 377.587544 -252.900183) (xy 377.536692 -252.898134) (xy 377.486828 -252.887954)
			(xy 377.439242 -252.869907) (xy 377.395168 -252.844461) (xy 377.355746 -252.812274) (xy 377.321998 -252.77418)
			(xy 377.294797 -252.731166) (xy 377.274849 -252.684346) (xy 377.26267 -252.634932) (xy 377.258575 -252.584204)
			(xy 376.940064 -252.584204) (xy 376.939569 -252.608811) (xy 376.931674 -252.657388) (xy 376.91609 -252.704069)
			(xy 376.893219 -252.747646) (xy 376.863654 -252.78699) (xy 376.828161 -252.821082) (xy 376.787658 -252.849038)
			(xy 376.743196 -252.870136) (xy 376.695925 -252.883828) (xy 376.64707 -252.88976) (xy 376.597895 -252.887779)
			(xy 376.549676 -252.877935) (xy 376.50366 -252.860483) (xy 376.461039 -252.835876) (xy 376.422918 -252.804751)
			(xy 376.390283 -252.767914) (xy 376.36398 -252.726318) (xy 376.344689 -252.681042) (xy 376.332912 -252.633258)
			(xy 376.328952 -252.584204) (xy 376.00001 -252.584204) (xy 375.999515 -252.608811) (xy 375.99162 -252.657388)
			(xy 375.976036 -252.704069) (xy 375.953165 -252.747646) (xy 375.9236 -252.78699) (xy 375.888107 -252.821082)
			(xy 375.847604 -252.849038) (xy 375.803142 -252.870136) (xy 375.755871 -252.883828) (xy 375.707016 -252.88976)
			(xy 375.657841 -252.887779) (xy 375.609622 -252.877935) (xy 375.563606 -252.860483) (xy 375.520985 -252.835876)
			(xy 375.482864 -252.804751) (xy 375.450229 -252.767914) (xy 375.423926 -252.726318) (xy 375.404635 -252.681042)
			(xy 375.392858 -252.633258) (xy 375.388898 -252.584204) (xy 375.06021 -252.584204) (xy 375.059715 -252.608811)
			(xy 375.05182 -252.657388) (xy 375.036236 -252.704069) (xy 375.013365 -252.747646) (xy 374.9838 -252.78699)
			(xy 374.948307 -252.821082) (xy 374.907804 -252.849038) (xy 374.863342 -252.870136) (xy 374.816071 -252.883828)
			(xy 374.767216 -252.88976) (xy 374.718041 -252.887779) (xy 374.669822 -252.877935) (xy 374.623806 -252.860483)
			(xy 374.581185 -252.835876) (xy 374.543064 -252.804751) (xy 374.510429 -252.767914) (xy 374.484126 -252.726318)
			(xy 374.464835 -252.681042) (xy 374.453058 -252.633258) (xy 374.449098 -252.584204) (xy 373.180102 -252.584204)
			(xy 373.179607 -252.608811) (xy 373.171712 -252.657388) (xy 373.156128 -252.704069) (xy 373.133257 -252.747646)
			(xy 373.103692 -252.78699) (xy 373.068199 -252.821082) (xy 373.027696 -252.849038) (xy 372.983234 -252.870136)
			(xy 372.935963 -252.883828) (xy 372.887108 -252.88976) (xy 372.837933 -252.887779) (xy 372.789714 -252.877935)
			(xy 372.743698 -252.860483) (xy 372.701077 -252.835876) (xy 372.662956 -252.804751) (xy 372.630321 -252.767914)
			(xy 372.604018 -252.726318) (xy 372.584727 -252.681042) (xy 372.57295 -252.633258) (xy 372.56899 -252.584204)
			(xy 371.299994 -252.584204) (xy 371.299499 -252.608811) (xy 371.291604 -252.657388) (xy 371.27602 -252.704069)
			(xy 371.253149 -252.747646) (xy 371.223584 -252.78699) (xy 371.188091 -252.821082) (xy 371.147588 -252.849038)
			(xy 371.103126 -252.870136) (xy 371.055855 -252.883828) (xy 371.007 -252.88976) (xy 370.957825 -252.887779)
			(xy 370.909606 -252.877935) (xy 370.86359 -252.860483) (xy 370.820969 -252.835876) (xy 370.782848 -252.804751)
			(xy 370.750213 -252.767914) (xy 370.72391 -252.726318) (xy 370.704619 -252.681042) (xy 370.692842 -252.633258)
			(xy 370.688882 -252.584204) (xy 369.42014 -252.584204) (xy 369.419645 -252.608811) (xy 369.41175 -252.657388)
			(xy 369.396166 -252.704069) (xy 369.373295 -252.747646) (xy 369.34373 -252.78699) (xy 369.308237 -252.821082)
			(xy 369.267734 -252.849038) (xy 369.223272 -252.870136) (xy 369.176001 -252.883828) (xy 369.127146 -252.88976)
			(xy 369.077971 -252.887779) (xy 369.029752 -252.877935) (xy 368.983736 -252.860483) (xy 368.941115 -252.835876)
			(xy 368.902994 -252.804751) (xy 368.870359 -252.767914) (xy 368.844056 -252.726318) (xy 368.824765 -252.681042)
			(xy 368.812988 -252.633258) (xy 368.809028 -252.584204) (xy 360.49716 -252.584204) (xy 360.493272 -252.592056)
			(xy 360.46298 -252.635122) (xy 360.426468 -252.67306) (xy 360.384594 -252.704979) (xy 360.338338 -252.730132)
			(xy 360.288785 -252.74793) (xy 360.237095 -252.757954) (xy 360.184481 -252.759971) (xy 360.132176 -252.753933)
			(xy 360.081405 -252.739981) (xy 360.03336 -252.718442) (xy 359.989165 -252.689822) (xy 359.949857 -252.654791)
			(xy 359.916357 -252.61417) (xy 359.889451 -252.568911) (xy 359.869768 -252.520076) (xy 359.857771 -252.468808)
			(xy 359.853741 -252.41631) (xy 349.636182 -252.41631) (xy 349.639527 -252.420762) (xy 349.662398 -252.464339)
			(xy 349.677982 -252.51102) (xy 349.685877 -252.559597) (xy 349.686372 -252.584204) (xy 349.685877 -252.608811)
			(xy 349.677982 -252.657388) (xy 349.662398 -252.704069) (xy 349.639527 -252.747646) (xy 349.609962 -252.78699)
			(xy 349.574469 -252.821082) (xy 349.533966 -252.849038) (xy 349.489504 -252.870136) (xy 349.442233 -252.883828)
			(xy 349.393378 -252.88976) (xy 349.344203 -252.887779) (xy 349.295984 -252.877935) (xy 349.249968 -252.860483)
			(xy 349.207347 -252.835876) (xy 349.169226 -252.804751) (xy 349.136591 -252.767914) (xy 349.110288 -252.726318)
			(xy 349.090997 -252.681042) (xy 349.07922 -252.633258) (xy 349.07526 -252.584204) (xy 348.746827 -252.584204)
			(xy 348.742656 -252.634536) (xy 348.730257 -252.6835) (xy 348.709968 -252.729755) (xy 348.682343 -252.77204)
			(xy 348.648135 -252.809201) (xy 348.608277 -252.840225) (xy 348.563856 -252.864265) (xy 348.516084 -252.880667)
			(xy 348.466264 -252.888982) (xy 348.44101 -252.889512) (xy 348.431203 -252.889425) (xy 348.41163 -252.888157)
			(xy 348.401894 -252.886972) (xy 348.390972 -252.885702) (xy 348.370144 -252.892052) (xy 348.304612 -252.949456)
			(xy 348.296783 -252.957046) (xy 348.28785 -252.976916) (xy 348.28734 -252.98781) (xy 348.28734 -253.39421)
			(xy 349.545414 -253.39421) (xy 349.549374 -253.345156) (xy 349.561151 -253.297372) (xy 349.580442 -253.252096)
			(xy 349.606745 -253.2105) (xy 349.63938 -253.173663) (xy 349.677501 -253.142538) (xy 349.720122 -253.117931)
			(xy 349.766138 -253.100479) (xy 349.814357 -253.090635) (xy 349.863532 -253.088654) (xy 349.912387 -253.094586)
			(xy 349.959658 -253.108278) (xy 350.00412 -253.129376) (xy 350.044623 -253.157332) (xy 350.080116 -253.191424)
			(xy 350.109681 -253.230768) (xy 350.132552 -253.274345) (xy 350.148136 -253.321026) (xy 350.156031 -253.369603)
			(xy 350.156485 -253.392178) (xy 351.42222 -253.392178) (xy 351.42618 -253.343124) (xy 351.437957 -253.29534)
			(xy 351.457248 -253.250064) (xy 351.483551 -253.208468) (xy 351.516186 -253.171631) (xy 351.554307 -253.140506)
			(xy 351.596928 -253.115899) (xy 351.642944 -253.098447) (xy 351.691163 -253.088603) (xy 351.740338 -253.086622)
			(xy 351.789193 -253.092554) (xy 351.836464 -253.106246) (xy 351.880926 -253.127344) (xy 351.921429 -253.1553)
			(xy 351.956922 -253.189392) (xy 351.986487 -253.228736) (xy 352.009358 -253.272313) (xy 352.024942 -253.318994)
			(xy 352.032837 -253.367571) (xy 352.033332 -253.392178) (xy 353.302074 -253.392178) (xy 353.306034 -253.343124)
			(xy 353.317811 -253.29534) (xy 353.337102 -253.250064) (xy 353.363405 -253.208468) (xy 353.39604 -253.171631)
			(xy 353.434161 -253.140506) (xy 353.476782 -253.115899) (xy 353.522798 -253.098447) (xy 353.571017 -253.088603)
			(xy 353.620192 -253.086622) (xy 353.669047 -253.092554) (xy 353.716318 -253.106246) (xy 353.76078 -253.127344)
			(xy 353.801283 -253.1553) (xy 353.836776 -253.189392) (xy 353.866341 -253.228736) (xy 353.889212 -253.272313)
			(xy 353.904796 -253.318994) (xy 353.912691 -253.367571) (xy 353.913186 -253.392178) (xy 355.182182 -253.392178)
			(xy 355.186142 -253.343124) (xy 355.197919 -253.29534) (xy 355.21721 -253.250064) (xy 355.243513 -253.208468)
			(xy 355.276148 -253.171631) (xy 355.314269 -253.140506) (xy 355.35689 -253.115899) (xy 355.402906 -253.098447)
			(xy 355.451125 -253.088603) (xy 355.5003 -253.086622) (xy 355.549155 -253.092554) (xy 355.596426 -253.106246)
			(xy 355.640888 -253.127344) (xy 355.681391 -253.1553) (xy 355.716884 -253.189392) (xy 355.746449 -253.228736)
			(xy 355.76932 -253.272313) (xy 355.784904 -253.318994) (xy 355.792799 -253.367571) (xy 355.793294 -253.392178)
			(xy 357.06229 -253.392178) (xy 357.06625 -253.343124) (xy 357.078027 -253.29534) (xy 357.097318 -253.250064)
			(xy 357.123621 -253.208468) (xy 357.156256 -253.171631) (xy 357.194377 -253.140506) (xy 357.236998 -253.115899)
			(xy 357.283014 -253.098447) (xy 357.331233 -253.088603) (xy 357.380408 -253.086622) (xy 357.429263 -253.092554)
			(xy 357.476534 -253.106246) (xy 357.520996 -253.127344) (xy 357.561499 -253.1553) (xy 357.596992 -253.189392)
			(xy 357.626557 -253.228736) (xy 357.649428 -253.272313) (xy 357.665012 -253.318994) (xy 357.672907 -253.367571)
			(xy 357.673402 -253.392178) (xy 357.672907 -253.416785) (xy 357.670384 -253.43231) (xy 359.853741 -253.43231)
			(xy 359.857771 -253.379812) (xy 359.869768 -253.328544) (xy 359.889451 -253.279709) (xy 359.916357 -253.23445)
			(xy 359.949857 -253.193829) (xy 359.989165 -253.158798) (xy 360.03336 -253.130178) (xy 360.081405 -253.108639)
			(xy 360.132176 -253.094687) (xy 360.184481 -253.088649) (xy 360.237095 -253.090666) (xy 360.288785 -253.10069)
			(xy 360.338338 -253.118488) (xy 360.384594 -253.143641) (xy 360.426468 -253.17556) (xy 360.46298 -253.213498)
			(xy 360.493272 -253.256564) (xy 360.516635 -253.303749) (xy 360.532521 -253.353948) (xy 360.538426 -253.392178)
			(xy 360.822252 -253.392178) (xy 360.826212 -253.343124) (xy 360.837989 -253.29534) (xy 360.85728 -253.250064)
			(xy 360.883583 -253.208468) (xy 360.916218 -253.171631) (xy 360.954339 -253.140506) (xy 360.99696 -253.115899)
			(xy 361.042976 -253.098447) (xy 361.091195 -253.088603) (xy 361.14037 -253.086622) (xy 361.189225 -253.092554)
			(xy 361.236496 -253.106246) (xy 361.280958 -253.127344) (xy 361.321461 -253.1553) (xy 361.356954 -253.189392)
			(xy 361.386519 -253.228736) (xy 361.40939 -253.272313) (xy 361.424974 -253.318994) (xy 361.432869 -253.367571)
			(xy 361.433364 -253.392178) (xy 362.702106 -253.392178) (xy 362.706066 -253.343124) (xy 362.717843 -253.29534)
			(xy 362.737134 -253.250064) (xy 362.763437 -253.208468) (xy 362.796072 -253.171631) (xy 362.834193 -253.140506)
			(xy 362.876814 -253.115899) (xy 362.92283 -253.098447) (xy 362.971049 -253.088603) (xy 363.020224 -253.086622)
			(xy 363.069079 -253.092554) (xy 363.11635 -253.106246) (xy 363.160812 -253.127344) (xy 363.201315 -253.1553)
			(xy 363.236808 -253.189392) (xy 363.266373 -253.228736) (xy 363.289244 -253.272313) (xy 363.304828 -253.318994)
			(xy 363.312723 -253.367571) (xy 363.313218 -253.392178) (xy 364.582214 -253.392178) (xy 364.586174 -253.343124)
			(xy 364.597951 -253.29534) (xy 364.617242 -253.250064) (xy 364.643545 -253.208468) (xy 364.67618 -253.171631)
			(xy 364.714301 -253.140506) (xy 364.756922 -253.115899) (xy 364.802938 -253.098447) (xy 364.851157 -253.088603)
			(xy 364.900332 -253.086622) (xy 364.949187 -253.092554) (xy 364.996458 -253.106246) (xy 365.04092 -253.127344)
			(xy 365.081423 -253.1553) (xy 365.116916 -253.189392) (xy 365.146481 -253.228736) (xy 365.169352 -253.272313)
			(xy 365.184936 -253.318994) (xy 365.192831 -253.367571) (xy 365.193326 -253.392178) (xy 366.462068 -253.392178)
			(xy 366.466028 -253.343124) (xy 366.477805 -253.29534) (xy 366.497096 -253.250064) (xy 366.523399 -253.208468)
			(xy 366.556034 -253.171631) (xy 366.594155 -253.140506) (xy 366.636776 -253.115899) (xy 366.682792 -253.098447)
			(xy 366.731011 -253.088603) (xy 366.780186 -253.086622) (xy 366.829041 -253.092554) (xy 366.876312 -253.106246)
			(xy 366.920774 -253.127344) (xy 366.961277 -253.1553) (xy 366.99677 -253.189392) (xy 367.026335 -253.228736)
			(xy 367.049206 -253.272313) (xy 367.06479 -253.318994) (xy 367.072685 -253.367571) (xy 367.07318 -253.392178)
			(xy 367.073139 -253.39421) (xy 370.218982 -253.39421) (xy 370.222942 -253.345156) (xy 370.234719 -253.297372)
			(xy 370.25401 -253.252096) (xy 370.280313 -253.2105) (xy 370.312948 -253.173663) (xy 370.351069 -253.142538)
			(xy 370.39369 -253.117931) (xy 370.439706 -253.100479) (xy 370.487925 -253.090635) (xy 370.5371 -253.088654)
			(xy 370.585955 -253.094586) (xy 370.633226 -253.108278) (xy 370.677688 -253.129376) (xy 370.718191 -253.157332)
			(xy 370.753684 -253.191424) (xy 370.783249 -253.230768) (xy 370.80612 -253.274345) (xy 370.821704 -253.321026)
			(xy 370.829599 -253.369603) (xy 370.830094 -253.39421) (xy 372.09909 -253.39421) (xy 372.10305 -253.345156)
			(xy 372.114827 -253.297372) (xy 372.134118 -253.252096) (xy 372.160421 -253.2105) (xy 372.193056 -253.173663)
			(xy 372.231177 -253.142538) (xy 372.273798 -253.117931) (xy 372.319814 -253.100479) (xy 372.368033 -253.090635)
			(xy 372.417208 -253.088654) (xy 372.466063 -253.094586) (xy 372.513334 -253.108278) (xy 372.557796 -253.129376)
			(xy 372.598299 -253.157332) (xy 372.633792 -253.191424) (xy 372.663357 -253.230768) (xy 372.686228 -253.274345)
			(xy 372.701812 -253.321026) (xy 372.709707 -253.369603) (xy 372.710202 -253.39421) (xy 373.978944 -253.39421)
			(xy 373.982904 -253.345156) (xy 373.994681 -253.297372) (xy 374.013972 -253.252096) (xy 374.040275 -253.2105)
			(xy 374.07291 -253.173663) (xy 374.111031 -253.142538) (xy 374.153652 -253.117931) (xy 374.199668 -253.100479)
			(xy 374.247887 -253.090635) (xy 374.297062 -253.088654) (xy 374.345917 -253.094586) (xy 374.393188 -253.108278)
			(xy 374.43765 -253.129376) (xy 374.478153 -253.157332) (xy 374.513646 -253.191424) (xy 374.543211 -253.230768)
			(xy 374.566082 -253.274345) (xy 374.581666 -253.321026) (xy 374.589561 -253.369603) (xy 374.590056 -253.39421)
			(xy 375.848621 -253.39421) (xy 375.852716 -253.343482) (xy 375.864895 -253.294068) (xy 375.884843 -253.247248)
			(xy 375.912044 -253.204234) (xy 375.945792 -253.16614) (xy 375.985214 -253.133953) (xy 376.029288 -253.108507)
			(xy 376.076874 -253.09046) (xy 376.126738 -253.08028) (xy 376.17759 -253.078231) (xy 376.228111 -253.084365)
			(xy 376.276995 -253.098525) (xy 376.322974 -253.120342) (xy 376.364858 -253.149252) (xy 376.401562 -253.184507)
			(xy 376.432135 -253.225193) (xy 376.455786 -253.270256) (xy 376.471902 -253.31853) (xy 376.480066 -253.368764)
			(xy 376.480578 -253.39421) (xy 376.788675 -253.39421) (xy 376.79277 -253.343482) (xy 376.804949 -253.294068)
			(xy 376.824897 -253.247248) (xy 376.852098 -253.204234) (xy 376.885846 -253.16614) (xy 376.925268 -253.133953)
			(xy 376.969342 -253.108507) (xy 377.016928 -253.09046) (xy 377.066792 -253.08028) (xy 377.117644 -253.078231)
			(xy 377.168165 -253.084365) (xy 377.217049 -253.098525) (xy 377.263028 -253.120342) (xy 377.304912 -253.149252)
			(xy 377.341616 -253.184507) (xy 377.372189 -253.225193) (xy 377.39584 -253.270256) (xy 377.411956 -253.31853)
			(xy 377.42012 -253.368764) (xy 377.420632 -253.39421) (xy 377.738906 -253.39421) (xy 377.742866 -253.345156)
			(xy 377.754643 -253.297372) (xy 377.773934 -253.252096) (xy 377.800237 -253.2105) (xy 377.832872 -253.173663)
			(xy 377.870993 -253.142538) (xy 377.913614 -253.117931) (xy 377.95963 -253.100479) (xy 378.007849 -253.090635)
			(xy 378.057024 -253.088654) (xy 378.105879 -253.094586) (xy 378.15315 -253.108278) (xy 378.197612 -253.129376)
			(xy 378.238115 -253.157332) (xy 378.273608 -253.191424) (xy 378.303173 -253.230768) (xy 378.326044 -253.274345)
			(xy 378.341628 -253.321026) (xy 378.349523 -253.369603) (xy 378.350018 -253.39421) (xy 378.668529 -253.39421)
			(xy 378.672624 -253.343482) (xy 378.684803 -253.294068) (xy 378.704751 -253.247248) (xy 378.731952 -253.204234)
			(xy 378.7657 -253.16614) (xy 378.805122 -253.133953) (xy 378.849196 -253.108507) (xy 378.896782 -253.09046)
			(xy 378.946646 -253.08028) (xy 378.997498 -253.078231) (xy 379.048019 -253.084365) (xy 379.096903 -253.098525)
			(xy 379.142882 -253.120342) (xy 379.184766 -253.149252) (xy 379.22147 -253.184507) (xy 379.252043 -253.225193)
			(xy 379.275694 -253.270256) (xy 379.29181 -253.31853) (xy 379.299974 -253.368764) (xy 379.300486 -253.39421)
			(xy 379.619014 -253.39421) (xy 379.622974 -253.345156) (xy 379.634751 -253.297372) (xy 379.654042 -253.252096)
			(xy 379.680345 -253.2105) (xy 379.71298 -253.173663) (xy 379.751101 -253.142538) (xy 379.793722 -253.117931)
			(xy 379.839738 -253.100479) (xy 379.887957 -253.090635) (xy 379.937132 -253.088654) (xy 379.985987 -253.094586)
			(xy 380.033258 -253.108278) (xy 380.07772 -253.129376) (xy 380.118223 -253.157332) (xy 380.153716 -253.191424)
			(xy 380.183281 -253.230768) (xy 380.206152 -253.274345) (xy 380.221736 -253.321026) (xy 380.229631 -253.369603)
			(xy 380.230126 -253.39421) (xy 380.548637 -253.39421) (xy 380.552732 -253.343482) (xy 380.564911 -253.294068)
			(xy 380.584859 -253.247248) (xy 380.61206 -253.204234) (xy 380.645808 -253.16614) (xy 380.68523 -253.133953)
			(xy 380.729304 -253.108507) (xy 380.77689 -253.09046) (xy 380.826754 -253.08028) (xy 380.877606 -253.078231)
			(xy 380.928127 -253.084365) (xy 380.977011 -253.098525) (xy 381.02299 -253.120342) (xy 381.064874 -253.149252)
			(xy 381.101578 -253.184507) (xy 381.132151 -253.225193) (xy 381.155802 -253.270256) (xy 381.171918 -253.31853)
			(xy 381.180082 -253.368764) (xy 381.180594 -253.39421) (xy 381.499122 -253.39421) (xy 381.503082 -253.345156)
			(xy 381.514859 -253.297372) (xy 381.53415 -253.252096) (xy 381.560453 -253.2105) (xy 381.593088 -253.173663)
			(xy 381.631209 -253.142538) (xy 381.67383 -253.117931) (xy 381.719846 -253.100479) (xy 381.768065 -253.090635)
			(xy 381.81724 -253.088654) (xy 381.866095 -253.094586) (xy 381.913366 -253.108278) (xy 381.957828 -253.129376)
			(xy 381.998331 -253.157332) (xy 382.033824 -253.191424) (xy 382.063389 -253.230768) (xy 382.08626 -253.274345)
			(xy 382.101844 -253.321026) (xy 382.109739 -253.369603) (xy 382.110234 -253.39421) (xy 382.428491 -253.39421)
			(xy 382.432586 -253.343482) (xy 382.444765 -253.294068) (xy 382.464713 -253.247248) (xy 382.491914 -253.204234)
			(xy 382.525662 -253.16614) (xy 382.565084 -253.133953) (xy 382.609158 -253.108507) (xy 382.656744 -253.09046)
			(xy 382.706608 -253.08028) (xy 382.75746 -253.078231) (xy 382.807981 -253.084365) (xy 382.856865 -253.098525)
			(xy 382.902844 -253.120342) (xy 382.944728 -253.149252) (xy 382.981432 -253.184507) (xy 383.012005 -253.225193)
			(xy 383.035656 -253.270256) (xy 383.051772 -253.31853) (xy 383.059936 -253.368764) (xy 383.060448 -253.39421)
			(xy 383.368545 -253.39421) (xy 383.37264 -253.343482) (xy 383.384819 -253.294068) (xy 383.404767 -253.247248)
			(xy 383.431968 -253.204234) (xy 383.465716 -253.16614) (xy 383.505138 -253.133953) (xy 383.549212 -253.108507)
			(xy 383.596798 -253.09046) (xy 383.646662 -253.08028) (xy 383.697514 -253.078231) (xy 383.748035 -253.084365)
			(xy 383.796919 -253.098525) (xy 383.842898 -253.120342) (xy 383.884782 -253.149252) (xy 383.921486 -253.184507)
			(xy 383.952059 -253.225193) (xy 383.97571 -253.270256) (xy 383.991826 -253.31853) (xy 383.99999 -253.368764)
			(xy 384.000502 -253.39421) (xy 384.31903 -253.39421) (xy 384.32299 -253.345156) (xy 384.334767 -253.297372)
			(xy 384.354058 -253.252096) (xy 384.380361 -253.2105) (xy 384.412996 -253.173663) (xy 384.451117 -253.142538)
			(xy 384.493738 -253.117931) (xy 384.539754 -253.100479) (xy 384.587973 -253.090635) (xy 384.637148 -253.088654)
			(xy 384.686003 -253.094586) (xy 384.733274 -253.108278) (xy 384.777736 -253.129376) (xy 384.818239 -253.157332)
			(xy 384.853732 -253.191424) (xy 384.883297 -253.230768) (xy 384.906168 -253.274345) (xy 384.921752 -253.321026)
			(xy 384.929647 -253.369603) (xy 384.930142 -253.39421) (xy 385.248653 -253.39421) (xy 385.252748 -253.343482)
			(xy 385.264927 -253.294068) (xy 385.284875 -253.247248) (xy 385.312076 -253.204234) (xy 385.345824 -253.16614)
			(xy 385.385246 -253.133953) (xy 385.42932 -253.108507) (xy 385.476906 -253.09046) (xy 385.52677 -253.08028)
			(xy 385.577622 -253.078231) (xy 385.628143 -253.084365) (xy 385.677027 -253.098525) (xy 385.723006 -253.120342)
			(xy 385.76489 -253.149252) (xy 385.801594 -253.184507) (xy 385.832167 -253.225193) (xy 385.855818 -253.270256)
			(xy 385.871934 -253.31853) (xy 385.880098 -253.368764) (xy 385.88061 -253.39421) (xy 386.199138 -253.39421)
			(xy 386.203098 -253.345156) (xy 386.214875 -253.297372) (xy 386.234166 -253.252096) (xy 386.260469 -253.2105)
			(xy 386.293104 -253.173663) (xy 386.331225 -253.142538) (xy 386.373846 -253.117931) (xy 386.419862 -253.100479)
			(xy 386.468081 -253.090635) (xy 386.517256 -253.088654) (xy 386.566111 -253.094586) (xy 386.613382 -253.108278)
			(xy 386.657844 -253.129376) (xy 386.698347 -253.157332) (xy 386.73384 -253.191424) (xy 386.763405 -253.230768)
			(xy 386.786276 -253.274345) (xy 386.80186 -253.321026) (xy 386.809755 -253.369603) (xy 386.81025 -253.39421)
			(xy 387.128507 -253.39421) (xy 387.132602 -253.343482) (xy 387.144781 -253.294068) (xy 387.164729 -253.247248)
			(xy 387.19193 -253.204234) (xy 387.225678 -253.16614) (xy 387.2651 -253.133953) (xy 387.309174 -253.108507)
			(xy 387.35676 -253.09046) (xy 387.406624 -253.08028) (xy 387.457476 -253.078231) (xy 387.507997 -253.084365)
			(xy 387.556881 -253.098525) (xy 387.60286 -253.120342) (xy 387.644744 -253.149252) (xy 387.681448 -253.184507)
			(xy 387.712021 -253.225193) (xy 387.735672 -253.270256) (xy 387.751788 -253.31853) (xy 387.759952 -253.368764)
			(xy 387.760464 -253.39421) (xy 388.078992 -253.39421) (xy 388.082952 -253.345156) (xy 388.094729 -253.297372)
			(xy 388.11402 -253.252096) (xy 388.140323 -253.2105) (xy 388.172958 -253.173663) (xy 388.211079 -253.142538)
			(xy 388.2537 -253.117931) (xy 388.299716 -253.100479) (xy 388.347935 -253.090635) (xy 388.39711 -253.088654)
			(xy 388.445965 -253.094586) (xy 388.493236 -253.108278) (xy 388.537698 -253.129376) (xy 388.578201 -253.157332)
			(xy 388.613694 -253.191424) (xy 388.643259 -253.230768) (xy 388.66613 -253.274345) (xy 388.681714 -253.321026)
			(xy 388.689609 -253.369603) (xy 388.690104 -253.39421) (xy 389.008615 -253.39421) (xy 389.01271 -253.343482)
			(xy 389.024889 -253.294068) (xy 389.044837 -253.247248) (xy 389.072038 -253.204234) (xy 389.105786 -253.16614)
			(xy 389.145208 -253.133953) (xy 389.189282 -253.108507) (xy 389.236868 -253.09046) (xy 389.286732 -253.08028)
			(xy 389.337584 -253.078231) (xy 389.388105 -253.084365) (xy 389.436989 -253.098525) (xy 389.482968 -253.120342)
			(xy 389.524852 -253.149252) (xy 389.561556 -253.184507) (xy 389.592129 -253.225193) (xy 389.61578 -253.270256)
			(xy 389.631896 -253.31853) (xy 389.64006 -253.368764) (xy 389.640572 -253.39421) (xy 389.948669 -253.39421)
			(xy 389.952764 -253.343482) (xy 389.964943 -253.294068) (xy 389.984891 -253.247248) (xy 390.012092 -253.204234)
			(xy 390.04584 -253.16614) (xy 390.085262 -253.133953) (xy 390.129336 -253.108507) (xy 390.176922 -253.09046)
			(xy 390.226786 -253.08028) (xy 390.277638 -253.078231) (xy 390.328159 -253.084365) (xy 390.377043 -253.098525)
			(xy 390.423022 -253.120342) (xy 390.464906 -253.149252) (xy 390.50161 -253.184507) (xy 390.532183 -253.225193)
			(xy 390.555834 -253.270256) (xy 390.57195 -253.31853) (xy 390.580114 -253.368764) (xy 390.580626 -253.39421)
			(xy 390.8989 -253.39421) (xy 390.90286 -253.345156) (xy 390.914637 -253.297372) (xy 390.933928 -253.252096)
			(xy 390.960231 -253.2105) (xy 390.992866 -253.173663) (xy 391.030987 -253.142538) (xy 391.073608 -253.117931)
			(xy 391.119624 -253.100479) (xy 391.167843 -253.090635) (xy 391.217018 -253.088654) (xy 391.265873 -253.094586)
			(xy 391.313144 -253.108278) (xy 391.357606 -253.129376) (xy 391.398109 -253.157332) (xy 391.433602 -253.191424)
			(xy 391.463167 -253.230768) (xy 391.486038 -253.274345) (xy 391.501622 -253.321026) (xy 391.509517 -253.369603)
			(xy 391.510012 -253.39421) (xy 392.779008 -253.39421) (xy 392.782968 -253.345156) (xy 392.794745 -253.297372)
			(xy 392.814036 -253.252096) (xy 392.840339 -253.2105) (xy 392.872974 -253.173663) (xy 392.911095 -253.142538)
			(xy 392.953716 -253.117931) (xy 392.999732 -253.100479) (xy 393.047951 -253.090635) (xy 393.097126 -253.088654)
			(xy 393.145981 -253.094586) (xy 393.193252 -253.108278) (xy 393.237714 -253.129376) (xy 393.278217 -253.157332)
			(xy 393.31371 -253.191424) (xy 393.343275 -253.230768) (xy 393.366146 -253.274345) (xy 393.38173 -253.321026)
			(xy 393.389625 -253.369603) (xy 393.39012 -253.39421) (xy 393.389625 -253.418817) (xy 393.38173 -253.467394)
			(xy 393.366146 -253.514075) (xy 393.343275 -253.557652) (xy 393.31371 -253.596996) (xy 393.278217 -253.631088)
			(xy 393.237714 -253.659044) (xy 393.193252 -253.680142) (xy 393.145981 -253.693834) (xy 393.097126 -253.699766)
			(xy 393.047951 -253.697785) (xy 392.999732 -253.687941) (xy 392.953716 -253.670489) (xy 392.911095 -253.645882)
			(xy 392.872974 -253.614757) (xy 392.840339 -253.57792) (xy 392.814036 -253.536324) (xy 392.794745 -253.491048)
			(xy 392.782968 -253.443264) (xy 392.779008 -253.39421) (xy 391.510012 -253.39421) (xy 391.509517 -253.418817)
			(xy 391.501622 -253.467394) (xy 391.486038 -253.514075) (xy 391.463167 -253.557652) (xy 391.433602 -253.596996)
			(xy 391.398109 -253.631088) (xy 391.357606 -253.659044) (xy 391.313144 -253.680142) (xy 391.265873 -253.693834)
			(xy 391.217018 -253.699766) (xy 391.167843 -253.697785) (xy 391.119624 -253.687941) (xy 391.073608 -253.670489)
			(xy 391.030987 -253.645882) (xy 390.992866 -253.614757) (xy 390.960231 -253.57792) (xy 390.933928 -253.536324)
			(xy 390.914637 -253.491048) (xy 390.90286 -253.443264) (xy 390.8989 -253.39421) (xy 390.580626 -253.39421)
			(xy 390.580114 -253.419656) (xy 390.57195 -253.46989) (xy 390.555834 -253.518164) (xy 390.532183 -253.563227)
			(xy 390.50161 -253.603913) (xy 390.464906 -253.639168) (xy 390.423022 -253.668078) (xy 390.377043 -253.689895)
			(xy 390.328159 -253.704055) (xy 390.277638 -253.710189) (xy 390.226786 -253.70814) (xy 390.176922 -253.69796)
			(xy 390.129336 -253.679913) (xy 390.085262 -253.654467) (xy 390.04584 -253.62228) (xy 390.012092 -253.584186)
			(xy 389.984891 -253.541172) (xy 389.964943 -253.494352) (xy 389.952764 -253.444938) (xy 389.948669 -253.39421)
			(xy 389.640572 -253.39421) (xy 389.64006 -253.419656) (xy 389.631896 -253.46989) (xy 389.61578 -253.518164)
			(xy 389.592129 -253.563227) (xy 389.561556 -253.603913) (xy 389.524852 -253.639168) (xy 389.482968 -253.668078)
			(xy 389.436989 -253.689895) (xy 389.388105 -253.704055) (xy 389.337584 -253.710189) (xy 389.286732 -253.70814)
			(xy 389.236868 -253.69796) (xy 389.189282 -253.679913) (xy 389.145208 -253.654467) (xy 389.105786 -253.62228)
			(xy 389.072038 -253.584186) (xy 389.044837 -253.541172) (xy 389.024889 -253.494352) (xy 389.01271 -253.444938)
			(xy 389.008615 -253.39421) (xy 388.690104 -253.39421) (xy 388.689609 -253.418817) (xy 388.681714 -253.467394)
			(xy 388.66613 -253.514075) (xy 388.643259 -253.557652) (xy 388.613694 -253.596996) (xy 388.578201 -253.631088)
			(xy 388.537698 -253.659044) (xy 388.493236 -253.680142) (xy 388.445965 -253.693834) (xy 388.39711 -253.699766)
			(xy 388.347935 -253.697785) (xy 388.299716 -253.687941) (xy 388.2537 -253.670489) (xy 388.211079 -253.645882)
			(xy 388.172958 -253.614757) (xy 388.140323 -253.57792) (xy 388.11402 -253.536324) (xy 388.094729 -253.491048)
			(xy 388.082952 -253.443264) (xy 388.078992 -253.39421) (xy 387.760464 -253.39421) (xy 387.759952 -253.419656)
			(xy 387.751788 -253.46989) (xy 387.735672 -253.518164) (xy 387.712021 -253.563227) (xy 387.681448 -253.603913)
			(xy 387.644744 -253.639168) (xy 387.60286 -253.668078) (xy 387.556881 -253.689895) (xy 387.507997 -253.704055)
			(xy 387.457476 -253.710189) (xy 387.406624 -253.70814) (xy 387.35676 -253.69796) (xy 387.309174 -253.679913)
			(xy 387.2651 -253.654467) (xy 387.225678 -253.62228) (xy 387.19193 -253.584186) (xy 387.164729 -253.541172)
			(xy 387.144781 -253.494352) (xy 387.132602 -253.444938) (xy 387.128507 -253.39421) (xy 386.81025 -253.39421)
			(xy 386.809755 -253.418817) (xy 386.80186 -253.467394) (xy 386.786276 -253.514075) (xy 386.763405 -253.557652)
			(xy 386.73384 -253.596996) (xy 386.698347 -253.631088) (xy 386.657844 -253.659044) (xy 386.613382 -253.680142)
			(xy 386.566111 -253.693834) (xy 386.517256 -253.699766) (xy 386.468081 -253.697785) (xy 386.419862 -253.687941)
			(xy 386.373846 -253.670489) (xy 386.331225 -253.645882) (xy 386.293104 -253.614757) (xy 386.260469 -253.57792)
			(xy 386.234166 -253.536324) (xy 386.214875 -253.491048) (xy 386.203098 -253.443264) (xy 386.199138 -253.39421)
			(xy 385.88061 -253.39421) (xy 385.880098 -253.419656) (xy 385.871934 -253.46989) (xy 385.855818 -253.518164)
			(xy 385.832167 -253.563227) (xy 385.801594 -253.603913) (xy 385.76489 -253.639168) (xy 385.723006 -253.668078)
			(xy 385.677027 -253.689895) (xy 385.628143 -253.704055) (xy 385.577622 -253.710189) (xy 385.52677 -253.70814)
			(xy 385.476906 -253.69796) (xy 385.42932 -253.679913) (xy 385.385246 -253.654467) (xy 385.345824 -253.62228)
			(xy 385.312076 -253.584186) (xy 385.284875 -253.541172) (xy 385.264927 -253.494352) (xy 385.252748 -253.444938)
			(xy 385.248653 -253.39421) (xy 384.930142 -253.39421) (xy 384.929647 -253.418817) (xy 384.921752 -253.467394)
			(xy 384.906168 -253.514075) (xy 384.883297 -253.557652) (xy 384.853732 -253.596996) (xy 384.818239 -253.631088)
			(xy 384.777736 -253.659044) (xy 384.733274 -253.680142) (xy 384.686003 -253.693834) (xy 384.637148 -253.699766)
			(xy 384.587973 -253.697785) (xy 384.539754 -253.687941) (xy 384.493738 -253.670489) (xy 384.451117 -253.645882)
			(xy 384.412996 -253.614757) (xy 384.380361 -253.57792) (xy 384.354058 -253.536324) (xy 384.334767 -253.491048)
			(xy 384.32299 -253.443264) (xy 384.31903 -253.39421) (xy 384.000502 -253.39421) (xy 383.99999 -253.419656)
			(xy 383.991826 -253.46989) (xy 383.97571 -253.518164) (xy 383.952059 -253.563227) (xy 383.921486 -253.603913)
			(xy 383.884782 -253.639168) (xy 383.842898 -253.668078) (xy 383.796919 -253.689895) (xy 383.748035 -253.704055)
			(xy 383.697514 -253.710189) (xy 383.646662 -253.70814) (xy 383.596798 -253.69796) (xy 383.549212 -253.679913)
			(xy 383.505138 -253.654467) (xy 383.465716 -253.62228) (xy 383.431968 -253.584186) (xy 383.404767 -253.541172)
			(xy 383.384819 -253.494352) (xy 383.37264 -253.444938) (xy 383.368545 -253.39421) (xy 383.060448 -253.39421)
			(xy 383.059936 -253.419656) (xy 383.051772 -253.46989) (xy 383.035656 -253.518164) (xy 383.012005 -253.563227)
			(xy 382.981432 -253.603913) (xy 382.944728 -253.639168) (xy 382.902844 -253.668078) (xy 382.856865 -253.689895)
			(xy 382.807981 -253.704055) (xy 382.75746 -253.710189) (xy 382.706608 -253.70814) (xy 382.656744 -253.69796)
			(xy 382.609158 -253.679913) (xy 382.565084 -253.654467) (xy 382.525662 -253.62228) (xy 382.491914 -253.584186)
			(xy 382.464713 -253.541172) (xy 382.444765 -253.494352) (xy 382.432586 -253.444938) (xy 382.428491 -253.39421)
			(xy 382.110234 -253.39421) (xy 382.109739 -253.418817) (xy 382.101844 -253.467394) (xy 382.08626 -253.514075)
			(xy 382.063389 -253.557652) (xy 382.033824 -253.596996) (xy 381.998331 -253.631088) (xy 381.957828 -253.659044)
			(xy 381.913366 -253.680142) (xy 381.866095 -253.693834) (xy 381.81724 -253.699766) (xy 381.768065 -253.697785)
			(xy 381.719846 -253.687941) (xy 381.67383 -253.670489) (xy 381.631209 -253.645882) (xy 381.593088 -253.614757)
			(xy 381.560453 -253.57792) (xy 381.53415 -253.536324) (xy 381.514859 -253.491048) (xy 381.503082 -253.443264)
			(xy 381.499122 -253.39421) (xy 381.180594 -253.39421) (xy 381.180082 -253.419656) (xy 381.171918 -253.46989)
			(xy 381.155802 -253.518164) (xy 381.132151 -253.563227) (xy 381.101578 -253.603913) (xy 381.064874 -253.639168)
			(xy 381.02299 -253.668078) (xy 380.977011 -253.689895) (xy 380.928127 -253.704055) (xy 380.877606 -253.710189)
			(xy 380.826754 -253.70814) (xy 380.77689 -253.69796) (xy 380.729304 -253.679913) (xy 380.68523 -253.654467)
			(xy 380.645808 -253.62228) (xy 380.61206 -253.584186) (xy 380.584859 -253.541172) (xy 380.564911 -253.494352)
			(xy 380.552732 -253.444938) (xy 380.548637 -253.39421) (xy 380.230126 -253.39421) (xy 380.229631 -253.418817)
			(xy 380.221736 -253.467394) (xy 380.206152 -253.514075) (xy 380.183281 -253.557652) (xy 380.153716 -253.596996)
			(xy 380.118223 -253.631088) (xy 380.07772 -253.659044) (xy 380.033258 -253.680142) (xy 379.985987 -253.693834)
			(xy 379.937132 -253.699766) (xy 379.887957 -253.697785) (xy 379.839738 -253.687941) (xy 379.793722 -253.670489)
			(xy 379.751101 -253.645882) (xy 379.71298 -253.614757) (xy 379.680345 -253.57792) (xy 379.654042 -253.536324)
			(xy 379.634751 -253.491048) (xy 379.622974 -253.443264) (xy 379.619014 -253.39421) (xy 379.300486 -253.39421)
			(xy 379.299974 -253.419656) (xy 379.29181 -253.46989) (xy 379.275694 -253.518164) (xy 379.252043 -253.563227)
			(xy 379.22147 -253.603913) (xy 379.184766 -253.639168) (xy 379.142882 -253.668078) (xy 379.096903 -253.689895)
			(xy 379.048019 -253.704055) (xy 378.997498 -253.710189) (xy 378.946646 -253.70814) (xy 378.896782 -253.69796)
			(xy 378.849196 -253.679913) (xy 378.805122 -253.654467) (xy 378.7657 -253.62228) (xy 378.731952 -253.584186)
			(xy 378.704751 -253.541172) (xy 378.684803 -253.494352) (xy 378.672624 -253.444938) (xy 378.668529 -253.39421)
			(xy 378.350018 -253.39421) (xy 378.349523 -253.418817) (xy 378.341628 -253.467394) (xy 378.326044 -253.514075)
			(xy 378.303173 -253.557652) (xy 378.273608 -253.596996) (xy 378.238115 -253.631088) (xy 378.197612 -253.659044)
			(xy 378.15315 -253.680142) (xy 378.105879 -253.693834) (xy 378.057024 -253.699766) (xy 378.007849 -253.697785)
			(xy 377.95963 -253.687941) (xy 377.913614 -253.670489) (xy 377.870993 -253.645882) (xy 377.832872 -253.614757)
			(xy 377.800237 -253.57792) (xy 377.773934 -253.536324) (xy 377.754643 -253.491048) (xy 377.742866 -253.443264)
			(xy 377.738906 -253.39421) (xy 377.420632 -253.39421) (xy 377.42012 -253.419656) (xy 377.411956 -253.46989)
			(xy 377.39584 -253.518164) (xy 377.372189 -253.563227) (xy 377.341616 -253.603913) (xy 377.304912 -253.639168)
			(xy 377.263028 -253.668078) (xy 377.217049 -253.689895) (xy 377.168165 -253.704055) (xy 377.117644 -253.710189)
			(xy 377.066792 -253.70814) (xy 377.016928 -253.69796) (xy 376.969342 -253.679913) (xy 376.925268 -253.654467)
			(xy 376.885846 -253.62228) (xy 376.852098 -253.584186) (xy 376.824897 -253.541172) (xy 376.804949 -253.494352)
			(xy 376.79277 -253.444938) (xy 376.788675 -253.39421) (xy 376.480578 -253.39421) (xy 376.480066 -253.419656)
			(xy 376.471902 -253.46989) (xy 376.455786 -253.518164) (xy 376.432135 -253.563227) (xy 376.401562 -253.603913)
			(xy 376.364858 -253.639168) (xy 376.322974 -253.668078) (xy 376.276995 -253.689895) (xy 376.228111 -253.704055)
			(xy 376.17759 -253.710189) (xy 376.126738 -253.70814) (xy 376.076874 -253.69796) (xy 376.029288 -253.679913)
			(xy 375.985214 -253.654467) (xy 375.945792 -253.62228) (xy 375.912044 -253.584186) (xy 375.884843 -253.541172)
			(xy 375.864895 -253.494352) (xy 375.852716 -253.444938) (xy 375.848621 -253.39421) (xy 374.590056 -253.39421)
			(xy 374.589561 -253.418817) (xy 374.581666 -253.467394) (xy 374.566082 -253.514075) (xy 374.543211 -253.557652)
			(xy 374.513646 -253.596996) (xy 374.478153 -253.631088) (xy 374.43765 -253.659044) (xy 374.393188 -253.680142)
			(xy 374.345917 -253.693834) (xy 374.297062 -253.699766) (xy 374.247887 -253.697785) (xy 374.199668 -253.687941)
			(xy 374.153652 -253.670489) (xy 374.111031 -253.645882) (xy 374.07291 -253.614757) (xy 374.040275 -253.57792)
			(xy 374.013972 -253.536324) (xy 373.994681 -253.491048) (xy 373.982904 -253.443264) (xy 373.978944 -253.39421)
			(xy 372.710202 -253.39421) (xy 372.709707 -253.418817) (xy 372.701812 -253.467394) (xy 372.686228 -253.514075)
			(xy 372.663357 -253.557652) (xy 372.633792 -253.596996) (xy 372.598299 -253.631088) (xy 372.557796 -253.659044)
			(xy 372.513334 -253.680142) (xy 372.466063 -253.693834) (xy 372.417208 -253.699766) (xy 372.368033 -253.697785)
			(xy 372.319814 -253.687941) (xy 372.273798 -253.670489) (xy 372.231177 -253.645882) (xy 372.193056 -253.614757)
			(xy 372.160421 -253.57792) (xy 372.134118 -253.536324) (xy 372.114827 -253.491048) (xy 372.10305 -253.443264)
			(xy 372.09909 -253.39421) (xy 370.830094 -253.39421) (xy 370.829599 -253.418817) (xy 370.821704 -253.467394)
			(xy 370.80612 -253.514075) (xy 370.783249 -253.557652) (xy 370.753684 -253.596996) (xy 370.718191 -253.631088)
			(xy 370.677688 -253.659044) (xy 370.633226 -253.680142) (xy 370.585955 -253.693834) (xy 370.5371 -253.699766)
			(xy 370.487925 -253.697785) (xy 370.439706 -253.687941) (xy 370.39369 -253.670489) (xy 370.351069 -253.645882)
			(xy 370.312948 -253.614757) (xy 370.280313 -253.57792) (xy 370.25401 -253.536324) (xy 370.234719 -253.491048)
			(xy 370.222942 -253.443264) (xy 370.218982 -253.39421) (xy 367.073139 -253.39421) (xy 367.072685 -253.416785)
			(xy 367.06479 -253.465362) (xy 367.049206 -253.512043) (xy 367.026335 -253.55562) (xy 366.99677 -253.594964)
			(xy 366.961277 -253.629056) (xy 366.920774 -253.657012) (xy 366.876312 -253.67811) (xy 366.829041 -253.691802)
			(xy 366.780186 -253.697734) (xy 366.731011 -253.695753) (xy 366.682792 -253.685909) (xy 366.636776 -253.668457)
			(xy 366.594155 -253.64385) (xy 366.556034 -253.612725) (xy 366.523399 -253.575888) (xy 366.497096 -253.534292)
			(xy 366.477805 -253.489016) (xy 366.466028 -253.441232) (xy 366.462068 -253.392178) (xy 365.193326 -253.392178)
			(xy 365.192831 -253.416785) (xy 365.184936 -253.465362) (xy 365.169352 -253.512043) (xy 365.146481 -253.55562)
			(xy 365.116916 -253.594964) (xy 365.081423 -253.629056) (xy 365.04092 -253.657012) (xy 364.996458 -253.67811)
			(xy 364.949187 -253.691802) (xy 364.900332 -253.697734) (xy 364.851157 -253.695753) (xy 364.802938 -253.685909)
			(xy 364.756922 -253.668457) (xy 364.714301 -253.64385) (xy 364.67618 -253.612725) (xy 364.643545 -253.575888)
			(xy 364.617242 -253.534292) (xy 364.597951 -253.489016) (xy 364.586174 -253.441232) (xy 364.582214 -253.392178)
			(xy 363.313218 -253.392178) (xy 363.312723 -253.416785) (xy 363.304828 -253.465362) (xy 363.289244 -253.512043)
			(xy 363.266373 -253.55562) (xy 363.236808 -253.594964) (xy 363.201315 -253.629056) (xy 363.160812 -253.657012)
			(xy 363.11635 -253.67811) (xy 363.069079 -253.691802) (xy 363.020224 -253.697734) (xy 362.971049 -253.695753)
			(xy 362.92283 -253.685909) (xy 362.876814 -253.668457) (xy 362.834193 -253.64385) (xy 362.796072 -253.612725)
			(xy 362.763437 -253.575888) (xy 362.737134 -253.534292) (xy 362.717843 -253.489016) (xy 362.706066 -253.441232)
			(xy 362.702106 -253.392178) (xy 361.433364 -253.392178) (xy 361.432869 -253.416785) (xy 361.424974 -253.465362)
			(xy 361.40939 -253.512043) (xy 361.386519 -253.55562) (xy 361.356954 -253.594964) (xy 361.321461 -253.629056)
			(xy 361.280958 -253.657012) (xy 361.236496 -253.67811) (xy 361.189225 -253.691802) (xy 361.14037 -253.697734)
			(xy 361.091195 -253.695753) (xy 361.042976 -253.685909) (xy 360.99696 -253.668457) (xy 360.954339 -253.64385)
			(xy 360.916218 -253.612725) (xy 360.883583 -253.575888) (xy 360.85728 -253.534292) (xy 360.837989 -253.489016)
			(xy 360.826212 -253.441232) (xy 360.822252 -253.392178) (xy 360.538426 -253.392178) (xy 360.540558 -253.405984)
			(xy 360.541062 -253.43231) (xy 360.540558 -253.458636) (xy 360.532521 -253.510672) (xy 360.516635 -253.560871)
			(xy 360.493272 -253.608056) (xy 360.46298 -253.651122) (xy 360.426468 -253.68906) (xy 360.384594 -253.720979)
			(xy 360.338338 -253.746132) (xy 360.288785 -253.76393) (xy 360.237095 -253.773954) (xy 360.184481 -253.775971)
			(xy 360.132176 -253.769933) (xy 360.081405 -253.755981) (xy 360.03336 -253.734442) (xy 359.989165 -253.705822)
			(xy 359.949857 -253.670791) (xy 359.916357 -253.63017) (xy 359.889451 -253.584911) (xy 359.869768 -253.536076)
			(xy 359.857771 -253.484808) (xy 359.853741 -253.43231) (xy 357.670384 -253.43231) (xy 357.665012 -253.465362)
			(xy 357.649428 -253.512043) (xy 357.626557 -253.55562) (xy 357.596992 -253.594964) (xy 357.561499 -253.629056)
			(xy 357.520996 -253.657012) (xy 357.476534 -253.67811) (xy 357.429263 -253.691802) (xy 357.380408 -253.697734)
			(xy 357.331233 -253.695753) (xy 357.283014 -253.685909) (xy 357.236998 -253.668457) (xy 357.194377 -253.64385)
			(xy 357.156256 -253.612725) (xy 357.123621 -253.575888) (xy 357.097318 -253.534292) (xy 357.078027 -253.489016)
			(xy 357.06625 -253.441232) (xy 357.06229 -253.392178) (xy 355.793294 -253.392178) (xy 355.792799 -253.416785)
			(xy 355.784904 -253.465362) (xy 355.76932 -253.512043) (xy 355.746449 -253.55562) (xy 355.716884 -253.594964)
			(xy 355.681391 -253.629056) (xy 355.640888 -253.657012) (xy 355.596426 -253.67811) (xy 355.549155 -253.691802)
			(xy 355.5003 -253.697734) (xy 355.451125 -253.695753) (xy 355.402906 -253.685909) (xy 355.35689 -253.668457)
			(xy 355.314269 -253.64385) (xy 355.276148 -253.612725) (xy 355.243513 -253.575888) (xy 355.21721 -253.534292)
			(xy 355.197919 -253.489016) (xy 355.186142 -253.441232) (xy 355.182182 -253.392178) (xy 353.913186 -253.392178)
			(xy 353.912691 -253.416785) (xy 353.904796 -253.465362) (xy 353.889212 -253.512043) (xy 353.866341 -253.55562)
			(xy 353.836776 -253.594964) (xy 353.801283 -253.629056) (xy 353.76078 -253.657012) (xy 353.716318 -253.67811)
			(xy 353.669047 -253.691802) (xy 353.620192 -253.697734) (xy 353.571017 -253.695753) (xy 353.522798 -253.685909)
			(xy 353.476782 -253.668457) (xy 353.434161 -253.64385) (xy 353.39604 -253.612725) (xy 353.363405 -253.575888)
			(xy 353.337102 -253.534292) (xy 353.317811 -253.489016) (xy 353.306034 -253.441232) (xy 353.302074 -253.392178)
			(xy 352.033332 -253.392178) (xy 352.032837 -253.416785) (xy 352.024942 -253.465362) (xy 352.009358 -253.512043)
			(xy 351.986487 -253.55562) (xy 351.956922 -253.594964) (xy 351.921429 -253.629056) (xy 351.880926 -253.657012)
			(xy 351.836464 -253.67811) (xy 351.789193 -253.691802) (xy 351.740338 -253.697734) (xy 351.691163 -253.695753)
			(xy 351.642944 -253.685909) (xy 351.596928 -253.668457) (xy 351.554307 -253.64385) (xy 351.516186 -253.612725)
			(xy 351.483551 -253.575888) (xy 351.457248 -253.534292) (xy 351.437957 -253.489016) (xy 351.42618 -253.441232)
			(xy 351.42222 -253.392178) (xy 350.156485 -253.392178) (xy 350.156526 -253.39421) (xy 350.156031 -253.418817)
			(xy 350.148136 -253.467394) (xy 350.132552 -253.514075) (xy 350.109681 -253.557652) (xy 350.080116 -253.596996)
			(xy 350.044623 -253.631088) (xy 350.00412 -253.659044) (xy 349.959658 -253.680142) (xy 349.912387 -253.693834)
			(xy 349.863532 -253.699766) (xy 349.814357 -253.697785) (xy 349.766138 -253.687941) (xy 349.720122 -253.670489)
			(xy 349.677501 -253.645882) (xy 349.63938 -253.614757) (xy 349.606745 -253.57792) (xy 349.580442 -253.536324)
			(xy 349.561151 -253.491048) (xy 349.549374 -253.443264) (xy 349.545414 -253.39421) (xy 348.28734 -253.39421)
			(xy 348.28734 -253.800864) (xy 348.287842 -253.811702) (xy 348.296794 -253.831441) (xy 348.304612 -253.838964)
			(xy 348.361508 -253.888748) (xy 348.368668 -253.894515) (xy 348.385852 -253.90101) (xy 348.395036 -253.901448)
			(xy 348.40164 -253.901448) (xy 348.404688 -253.901194) (xy 348.413732 -253.900146) (xy 348.431906 -253.899003)
			(xy 348.44101 -253.898908) (xy 348.466263 -253.89943) (xy 348.516081 -253.907745) (xy 348.563851 -253.924146)
			(xy 348.60827 -253.948185) (xy 348.648127 -253.979208) (xy 348.682334 -254.016368) (xy 348.709958 -254.058651)
			(xy 348.730246 -254.104904) (xy 348.742644 -254.153866) (xy 348.746815 -254.2042) (xy 348.746814 -254.204216)
			(xy 349.07526 -254.204216) (xy 349.07922 -254.155162) (xy 349.090997 -254.107378) (xy 349.110288 -254.062102)
			(xy 349.136591 -254.020506) (xy 349.169226 -253.983669) (xy 349.207347 -253.952544) (xy 349.249968 -253.927937)
			(xy 349.295984 -253.910485) (xy 349.344203 -253.900641) (xy 349.393378 -253.89866) (xy 349.442233 -253.904592)
			(xy 349.489504 -253.918284) (xy 349.533966 -253.939382) (xy 349.574469 -253.967338) (xy 349.609962 -254.00143)
			(xy 349.639527 -254.040774) (xy 349.662398 -254.084351) (xy 349.677982 -254.131032) (xy 349.685877 -254.179609)
			(xy 349.686372 -254.204216) (xy 349.685877 -254.228823) (xy 349.677982 -254.2774) (xy 349.662398 -254.324081)
			(xy 349.639527 -254.367658) (xy 349.609962 -254.407002) (xy 349.574469 -254.441094) (xy 349.564014 -254.44831)
			(xy 359.853741 -254.44831) (xy 359.857771 -254.395812) (xy 359.869768 -254.344544) (xy 359.889451 -254.295709)
			(xy 359.916357 -254.25045) (xy 359.949857 -254.209829) (xy 359.989165 -254.174798) (xy 360.03336 -254.146178)
			(xy 360.081405 -254.124639) (xy 360.132176 -254.110687) (xy 360.184481 -254.104649) (xy 360.237095 -254.106666)
			(xy 360.288785 -254.11669) (xy 360.338338 -254.134488) (xy 360.384594 -254.159641) (xy 360.426468 -254.19156)
			(xy 360.438648 -254.204216) (xy 368.809028 -254.204216) (xy 368.812988 -254.155162) (xy 368.824765 -254.107378)
			(xy 368.844056 -254.062102) (xy 368.870359 -254.020506) (xy 368.902994 -253.983669) (xy 368.941115 -253.952544)
			(xy 368.983736 -253.927937) (xy 369.029752 -253.910485) (xy 369.077971 -253.900641) (xy 369.127146 -253.89866)
			(xy 369.176001 -253.904592) (xy 369.223272 -253.918284) (xy 369.267734 -253.939382) (xy 369.308237 -253.967338)
			(xy 369.34373 -254.00143) (xy 369.373295 -254.040774) (xy 369.396166 -254.084351) (xy 369.41175 -254.131032)
			(xy 369.419645 -254.179609) (xy 369.42014 -254.204216) (xy 370.688882 -254.204216) (xy 370.692842 -254.155162)
			(xy 370.704619 -254.107378) (xy 370.72391 -254.062102) (xy 370.750213 -254.020506) (xy 370.782848 -253.983669)
			(xy 370.820969 -253.952544) (xy 370.86359 -253.927937) (xy 370.909606 -253.910485) (xy 370.957825 -253.900641)
			(xy 371.007 -253.89866) (xy 371.055855 -253.904592) (xy 371.103126 -253.918284) (xy 371.147588 -253.939382)
			(xy 371.188091 -253.967338) (xy 371.223584 -254.00143) (xy 371.253149 -254.040774) (xy 371.27602 -254.084351)
			(xy 371.291604 -254.131032) (xy 371.299499 -254.179609) (xy 371.299994 -254.204216) (xy 372.56899 -254.204216)
			(xy 372.57295 -254.155162) (xy 372.584727 -254.107378) (xy 372.604018 -254.062102) (xy 372.630321 -254.020506)
			(xy 372.662956 -253.983669) (xy 372.701077 -253.952544) (xy 372.743698 -253.927937) (xy 372.789714 -253.910485)
			(xy 372.837933 -253.900641) (xy 372.887108 -253.89866) (xy 372.935963 -253.904592) (xy 372.983234 -253.918284)
			(xy 373.027696 -253.939382) (xy 373.068199 -253.967338) (xy 373.103692 -254.00143) (xy 373.133257 -254.040774)
			(xy 373.156128 -254.084351) (xy 373.171712 -254.131032) (xy 373.179607 -254.179609) (xy 373.180102 -254.204216)
			(xy 374.449098 -254.204216) (xy 374.453058 -254.155162) (xy 374.464835 -254.107378) (xy 374.484126 -254.062102)
			(xy 374.510429 -254.020506) (xy 374.543064 -253.983669) (xy 374.581185 -253.952544) (xy 374.623806 -253.927937)
			(xy 374.669822 -253.910485) (xy 374.718041 -253.900641) (xy 374.767216 -253.89866) (xy 374.816071 -253.904592)
			(xy 374.863342 -253.918284) (xy 374.907804 -253.939382) (xy 374.948307 -253.967338) (xy 374.9838 -254.00143)
			(xy 375.013365 -254.040774) (xy 375.036236 -254.084351) (xy 375.05182 -254.131032) (xy 375.059715 -254.179609)
			(xy 375.06021 -254.204216) (xy 375.378467 -254.204216) (xy 375.382562 -254.153488) (xy 375.394741 -254.104074)
			(xy 375.414689 -254.057254) (xy 375.44189 -254.01424) (xy 375.475638 -253.976146) (xy 375.51506 -253.943959)
			(xy 375.559134 -253.918513) (xy 375.60672 -253.900466) (xy 375.656584 -253.890286) (xy 375.707436 -253.888237)
			(xy 375.757957 -253.894371) (xy 375.806841 -253.908531) (xy 375.85282 -253.930348) (xy 375.894704 -253.959258)
			(xy 375.931408 -253.994513) (xy 375.961981 -254.035199) (xy 375.985632 -254.080262) (xy 376.001748 -254.128536)
			(xy 376.009912 -254.17877) (xy 376.010424 -254.204216) (xy 376.328952 -254.204216) (xy 376.332912 -254.155162)
			(xy 376.344689 -254.107378) (xy 376.36398 -254.062102) (xy 376.390283 -254.020506) (xy 376.422918 -253.983669)
			(xy 376.461039 -253.952544) (xy 376.50366 -253.927937) (xy 376.549676 -253.910485) (xy 376.597895 -253.900641)
			(xy 376.64707 -253.89866) (xy 376.695925 -253.904592) (xy 376.743196 -253.918284) (xy 376.787658 -253.939382)
			(xy 376.828161 -253.967338) (xy 376.863654 -254.00143) (xy 376.893219 -254.040774) (xy 376.91609 -254.084351)
			(xy 376.931674 -254.131032) (xy 376.939569 -254.179609) (xy 376.940064 -254.204216) (xy 377.258575 -254.204216)
			(xy 377.26267 -254.153488) (xy 377.274849 -254.104074) (xy 377.294797 -254.057254) (xy 377.321998 -254.01424)
			(xy 377.355746 -253.976146) (xy 377.395168 -253.943959) (xy 377.439242 -253.918513) (xy 377.486828 -253.900466)
			(xy 377.536692 -253.890286) (xy 377.587544 -253.888237) (xy 377.638065 -253.894371) (xy 377.686949 -253.908531)
			(xy 377.732928 -253.930348) (xy 377.774812 -253.959258) (xy 377.811516 -253.994513) (xy 377.842089 -254.035199)
			(xy 377.86574 -254.080262) (xy 377.881856 -254.128536) (xy 377.89002 -254.17877) (xy 377.890532 -254.204216)
			(xy 379.138683 -254.204216) (xy 379.142778 -254.153488) (xy 379.154957 -254.104074) (xy 379.174905 -254.057254)
			(xy 379.202106 -254.01424) (xy 379.235854 -253.976146) (xy 379.275276 -253.943959) (xy 379.31935 -253.918513)
			(xy 379.366936 -253.900466) (xy 379.4168 -253.890286) (xy 379.467652 -253.888237) (xy 379.518173 -253.894371)
			(xy 379.567057 -253.908531) (xy 379.613036 -253.930348) (xy 379.65492 -253.959258) (xy 379.691624 -253.994513)
			(xy 379.722197 -254.035199) (xy 379.745848 -254.080262) (xy 379.761964 -254.128536) (xy 379.770128 -254.17877)
			(xy 379.77064 -254.204216) (xy 380.078483 -254.204216) (xy 380.082578 -254.153488) (xy 380.094757 -254.104074)
			(xy 380.114705 -254.057254) (xy 380.141906 -254.01424) (xy 380.175654 -253.976146) (xy 380.215076 -253.943959)
			(xy 380.25915 -253.918513) (xy 380.306736 -253.900466) (xy 380.3566 -253.890286) (xy 380.407452 -253.888237)
			(xy 380.457973 -253.894371) (xy 380.506857 -253.908531) (xy 380.552836 -253.930348) (xy 380.59472 -253.959258)
			(xy 380.631424 -253.994513) (xy 380.661997 -254.035199) (xy 380.685648 -254.080262) (xy 380.701764 -254.128536)
			(xy 380.709928 -254.17877) (xy 380.71044 -254.204216) (xy 381.028968 -254.204216) (xy 381.032928 -254.155162)
			(xy 381.044705 -254.107378) (xy 381.063996 -254.062102) (xy 381.090299 -254.020506) (xy 381.122934 -253.983669)
			(xy 381.161055 -253.952544) (xy 381.203676 -253.927937) (xy 381.249692 -253.910485) (xy 381.297911 -253.900641)
			(xy 381.347086 -253.89866) (xy 381.395941 -253.904592) (xy 381.443212 -253.918284) (xy 381.487674 -253.939382)
			(xy 381.528177 -253.967338) (xy 381.56367 -254.00143) (xy 381.593235 -254.040774) (xy 381.616106 -254.084351)
			(xy 381.63169 -254.131032) (xy 381.639585 -254.179609) (xy 381.64008 -254.204216) (xy 381.958591 -254.204216)
			(xy 381.962686 -254.153488) (xy 381.974865 -254.104074) (xy 381.994813 -254.057254) (xy 382.022014 -254.01424)
			(xy 382.055762 -253.976146) (xy 382.095184 -253.943959) (xy 382.139258 -253.918513) (xy 382.186844 -253.900466)
			(xy 382.236708 -253.890286) (xy 382.28756 -253.888237) (xy 382.338081 -253.894371) (xy 382.386965 -253.908531)
			(xy 382.432944 -253.930348) (xy 382.474828 -253.959258) (xy 382.511532 -253.994513) (xy 382.542105 -254.035199)
			(xy 382.565756 -254.080262) (xy 382.581872 -254.128536) (xy 382.590036 -254.17877) (xy 382.590548 -254.204216)
			(xy 382.909076 -254.204216) (xy 382.913036 -254.155162) (xy 382.924813 -254.107378) (xy 382.944104 -254.062102)
			(xy 382.970407 -254.020506) (xy 383.003042 -253.983669) (xy 383.041163 -253.952544) (xy 383.083784 -253.927937)
			(xy 383.1298 -253.910485) (xy 383.178019 -253.900641) (xy 383.227194 -253.89866) (xy 383.276049 -253.904592)
			(xy 383.32332 -253.918284) (xy 383.367782 -253.939382) (xy 383.408285 -253.967338) (xy 383.443778 -254.00143)
			(xy 383.473343 -254.040774) (xy 383.496214 -254.084351) (xy 383.511798 -254.131032) (xy 383.519693 -254.179609)
			(xy 383.520188 -254.204216) (xy 383.838699 -254.204216) (xy 383.842794 -254.153488) (xy 383.854973 -254.104074)
			(xy 383.874921 -254.057254) (xy 383.902122 -254.01424) (xy 383.93587 -253.976146) (xy 383.975292 -253.943959)
			(xy 384.019366 -253.918513) (xy 384.066952 -253.900466) (xy 384.116816 -253.890286) (xy 384.167668 -253.888237)
			(xy 384.218189 -253.894371) (xy 384.267073 -253.908531) (xy 384.313052 -253.930348) (xy 384.354936 -253.959258)
			(xy 384.39164 -253.994513) (xy 384.422213 -254.035199) (xy 384.445864 -254.080262) (xy 384.46198 -254.128536)
			(xy 384.470144 -254.17877) (xy 384.470656 -254.204216) (xy 385.718553 -254.204216) (xy 385.722648 -254.153488)
			(xy 385.734827 -254.104074) (xy 385.754775 -254.057254) (xy 385.781976 -254.01424) (xy 385.815724 -253.976146)
			(xy 385.855146 -253.943959) (xy 385.89922 -253.918513) (xy 385.946806 -253.900466) (xy 385.99667 -253.890286)
			(xy 386.047522 -253.888237) (xy 386.098043 -253.894371) (xy 386.146927 -253.908531) (xy 386.192906 -253.930348)
			(xy 386.23479 -253.959258) (xy 386.271494 -253.994513) (xy 386.302067 -254.035199) (xy 386.325718 -254.080262)
			(xy 386.341834 -254.128536) (xy 386.349998 -254.17877) (xy 386.35051 -254.204216) (xy 386.658607 -254.204216)
			(xy 386.662702 -254.153488) (xy 386.674881 -254.104074) (xy 386.694829 -254.057254) (xy 386.72203 -254.01424)
			(xy 386.755778 -253.976146) (xy 386.7952 -253.943959) (xy 386.839274 -253.918513) (xy 386.88686 -253.900466)
			(xy 386.936724 -253.890286) (xy 386.987576 -253.888237) (xy 387.038097 -253.894371) (xy 387.086981 -253.908531)
			(xy 387.13296 -253.930348) (xy 387.174844 -253.959258) (xy 387.211548 -253.994513) (xy 387.242121 -254.035199)
			(xy 387.265772 -254.080262) (xy 387.281888 -254.128536) (xy 387.290052 -254.17877) (xy 387.290564 -254.204216)
			(xy 387.609092 -254.204216) (xy 387.613052 -254.155162) (xy 387.624829 -254.107378) (xy 387.64412 -254.062102)
			(xy 387.670423 -254.020506) (xy 387.703058 -253.983669) (xy 387.741179 -253.952544) (xy 387.7838 -253.927937)
			(xy 387.829816 -253.910485) (xy 387.878035 -253.900641) (xy 387.92721 -253.89866) (xy 387.976065 -253.904592)
			(xy 388.023336 -253.918284) (xy 388.067798 -253.939382) (xy 388.108301 -253.967338) (xy 388.143794 -254.00143)
			(xy 388.173359 -254.040774) (xy 388.19623 -254.084351) (xy 388.211814 -254.131032) (xy 388.219709 -254.179609)
			(xy 388.220204 -254.204216) (xy 388.538715 -254.204216) (xy 388.54281 -254.153488) (xy 388.554989 -254.104074)
			(xy 388.574937 -254.057254) (xy 388.602138 -254.01424) (xy 388.635886 -253.976146) (xy 388.675308 -253.943959)
			(xy 388.719382 -253.918513) (xy 388.766968 -253.900466) (xy 388.816832 -253.890286) (xy 388.867684 -253.888237)
			(xy 388.918205 -253.894371) (xy 388.967089 -253.908531) (xy 389.013068 -253.930348) (xy 389.054952 -253.959258)
			(xy 389.091656 -253.994513) (xy 389.122229 -254.035199) (xy 389.14588 -254.080262) (xy 389.161996 -254.128536)
			(xy 389.17016 -254.17877) (xy 389.170672 -254.204216) (xy 389.488946 -254.204216) (xy 389.492906 -254.155162)
			(xy 389.504683 -254.107378) (xy 389.523974 -254.062102) (xy 389.550277 -254.020506) (xy 389.582912 -253.983669)
			(xy 389.621033 -253.952544) (xy 389.663654 -253.927937) (xy 389.70967 -253.910485) (xy 389.757889 -253.900641)
			(xy 389.807064 -253.89866) (xy 389.855919 -253.904592) (xy 389.90319 -253.918284) (xy 389.947652 -253.939382)
			(xy 389.988155 -253.967338) (xy 390.023648 -254.00143) (xy 390.053213 -254.040774) (xy 390.076084 -254.084351)
			(xy 390.091668 -254.131032) (xy 390.099563 -254.179609) (xy 390.100058 -254.204216) (xy 390.418569 -254.204216)
			(xy 390.422664 -254.153488) (xy 390.434843 -254.104074) (xy 390.454791 -254.057254) (xy 390.481992 -254.01424)
			(xy 390.51574 -253.976146) (xy 390.555162 -253.943959) (xy 390.599236 -253.918513) (xy 390.646822 -253.900466)
			(xy 390.696686 -253.890286) (xy 390.747538 -253.888237) (xy 390.798059 -253.894371) (xy 390.846943 -253.908531)
			(xy 390.892922 -253.930348) (xy 390.934806 -253.959258) (xy 390.97151 -253.994513) (xy 391.002083 -254.035199)
			(xy 391.025734 -254.080262) (xy 391.04185 -254.128536) (xy 391.050014 -254.17877) (xy 391.050526 -254.204216)
			(xy 391.050014 -254.229662) (xy 391.04185 -254.279896) (xy 391.025734 -254.32817) (xy 391.002083 -254.373233)
			(xy 390.97151 -254.413919) (xy 390.934806 -254.449174) (xy 390.904411 -254.470154) (xy 394.377176 -254.470154)
			(xy 394.381136 -254.4211) (xy 394.392913 -254.373316) (xy 394.412204 -254.32804) (xy 394.438507 -254.286444)
			(xy 394.471142 -254.249607) (xy 394.509263 -254.218482) (xy 394.551884 -254.193875) (xy 394.5979 -254.176423)
			(xy 394.646119 -254.166579) (xy 394.695294 -254.164598) (xy 394.744149 -254.17053) (xy 394.79142 -254.184222)
			(xy 394.835882 -254.20532) (xy 394.876385 -254.233276) (xy 394.911878 -254.267368) (xy 394.941443 -254.306712)
			(xy 394.964314 -254.350289) (xy 394.979898 -254.39697) (xy 394.987793 -254.445547) (xy 394.988288 -254.470154)
			(xy 394.987793 -254.494761) (xy 394.979898 -254.543338) (xy 394.964314 -254.590019) (xy 394.941443 -254.633596)
			(xy 394.911878 -254.67294) (xy 394.876385 -254.707032) (xy 394.835882 -254.734988) (xy 394.79142 -254.756086)
			(xy 394.744149 -254.769778) (xy 394.695294 -254.77571) (xy 394.646119 -254.773729) (xy 394.5979 -254.763885)
			(xy 394.551884 -254.746433) (xy 394.509263 -254.721826) (xy 394.471142 -254.690701) (xy 394.438507 -254.653864)
			(xy 394.412204 -254.612268) (xy 394.392913 -254.566992) (xy 394.381136 -254.519208) (xy 394.377176 -254.470154)
			(xy 390.904411 -254.470154) (xy 390.892922 -254.478084) (xy 390.846943 -254.499901) (xy 390.798059 -254.514061)
			(xy 390.747538 -254.520195) (xy 390.696686 -254.518146) (xy 390.646822 -254.507966) (xy 390.599236 -254.489919)
			(xy 390.555162 -254.464473) (xy 390.51574 -254.432286) (xy 390.481992 -254.394192) (xy 390.454791 -254.351178)
			(xy 390.434843 -254.304358) (xy 390.422664 -254.254944) (xy 390.418569 -254.204216) (xy 390.100058 -254.204216)
			(xy 390.099563 -254.228823) (xy 390.091668 -254.2774) (xy 390.076084 -254.324081) (xy 390.053213 -254.367658)
			(xy 390.023648 -254.407002) (xy 389.988155 -254.441094) (xy 389.947652 -254.46905) (xy 389.90319 -254.490148)
			(xy 389.855919 -254.50384) (xy 389.807064 -254.509772) (xy 389.757889 -254.507791) (xy 389.70967 -254.497947)
			(xy 389.663654 -254.480495) (xy 389.621033 -254.455888) (xy 389.582912 -254.424763) (xy 389.550277 -254.387926)
			(xy 389.523974 -254.34633) (xy 389.504683 -254.301054) (xy 389.492906 -254.25327) (xy 389.488946 -254.204216)
			(xy 389.170672 -254.204216) (xy 389.17016 -254.229662) (xy 389.161996 -254.279896) (xy 389.14588 -254.32817)
			(xy 389.122229 -254.373233) (xy 389.091656 -254.413919) (xy 389.054952 -254.449174) (xy 389.013068 -254.478084)
			(xy 388.967089 -254.499901) (xy 388.918205 -254.514061) (xy 388.867684 -254.520195) (xy 388.816832 -254.518146)
			(xy 388.766968 -254.507966) (xy 388.719382 -254.489919) (xy 388.675308 -254.464473) (xy 388.635886 -254.432286)
			(xy 388.602138 -254.394192) (xy 388.574937 -254.351178) (xy 388.554989 -254.304358) (xy 388.54281 -254.254944)
			(xy 388.538715 -254.204216) (xy 388.220204 -254.204216) (xy 388.219709 -254.228823) (xy 388.211814 -254.2774)
			(xy 388.19623 -254.324081) (xy 388.173359 -254.367658) (xy 388.143794 -254.407002) (xy 388.108301 -254.441094)
			(xy 388.067798 -254.46905) (xy 388.023336 -254.490148) (xy 387.976065 -254.50384) (xy 387.92721 -254.509772)
			(xy 387.878035 -254.507791) (xy 387.829816 -254.497947) (xy 387.7838 -254.480495) (xy 387.741179 -254.455888)
			(xy 387.703058 -254.424763) (xy 387.670423 -254.387926) (xy 387.64412 -254.34633) (xy 387.624829 -254.301054)
			(xy 387.613052 -254.25327) (xy 387.609092 -254.204216) (xy 387.290564 -254.204216) (xy 387.290052 -254.229662)
			(xy 387.281888 -254.279896) (xy 387.265772 -254.32817) (xy 387.242121 -254.373233) (xy 387.211548 -254.413919)
			(xy 387.174844 -254.449174) (xy 387.13296 -254.478084) (xy 387.086981 -254.499901) (xy 387.038097 -254.514061)
			(xy 386.987576 -254.520195) (xy 386.936724 -254.518146) (xy 386.88686 -254.507966) (xy 386.839274 -254.489919)
			(xy 386.7952 -254.464473) (xy 386.755778 -254.432286) (xy 386.72203 -254.394192) (xy 386.694829 -254.351178)
			(xy 386.674881 -254.304358) (xy 386.662702 -254.254944) (xy 386.658607 -254.204216) (xy 386.35051 -254.204216)
			(xy 386.349998 -254.229662) (xy 386.341834 -254.279896) (xy 386.325718 -254.32817) (xy 386.302067 -254.373233)
			(xy 386.271494 -254.413919) (xy 386.23479 -254.449174) (xy 386.192906 -254.478084) (xy 386.146927 -254.499901)
			(xy 386.098043 -254.514061) (xy 386.047522 -254.520195) (xy 385.99667 -254.518146) (xy 385.946806 -254.507966)
			(xy 385.89922 -254.489919) (xy 385.855146 -254.464473) (xy 385.815724 -254.432286) (xy 385.781976 -254.394192)
			(xy 385.754775 -254.351178) (xy 385.734827 -254.304358) (xy 385.722648 -254.254944) (xy 385.718553 -254.204216)
			(xy 384.470656 -254.204216) (xy 384.470144 -254.229662) (xy 384.46198 -254.279896) (xy 384.445864 -254.32817)
			(xy 384.422213 -254.373233) (xy 384.39164 -254.413919) (xy 384.354936 -254.449174) (xy 384.313052 -254.478084)
			(xy 384.267073 -254.499901) (xy 384.218189 -254.514061) (xy 384.167668 -254.520195) (xy 384.116816 -254.518146)
			(xy 384.066952 -254.507966) (xy 384.019366 -254.489919) (xy 383.975292 -254.464473) (xy 383.93587 -254.432286)
			(xy 383.902122 -254.394192) (xy 383.874921 -254.351178) (xy 383.854973 -254.304358) (xy 383.842794 -254.254944)
			(xy 383.838699 -254.204216) (xy 383.520188 -254.204216) (xy 383.519693 -254.228823) (xy 383.511798 -254.2774)
			(xy 383.496214 -254.324081) (xy 383.473343 -254.367658) (xy 383.443778 -254.407002) (xy 383.408285 -254.441094)
			(xy 383.367782 -254.46905) (xy 383.32332 -254.490148) (xy 383.276049 -254.50384) (xy 383.227194 -254.509772)
			(xy 383.178019 -254.507791) (xy 383.1298 -254.497947) (xy 383.083784 -254.480495) (xy 383.041163 -254.455888)
			(xy 383.003042 -254.424763) (xy 382.970407 -254.387926) (xy 382.944104 -254.34633) (xy 382.924813 -254.301054)
			(xy 382.913036 -254.25327) (xy 382.909076 -254.204216) (xy 382.590548 -254.204216) (xy 382.590036 -254.229662)
			(xy 382.581872 -254.279896) (xy 382.565756 -254.32817) (xy 382.542105 -254.373233) (xy 382.511532 -254.413919)
			(xy 382.474828 -254.449174) (xy 382.432944 -254.478084) (xy 382.386965 -254.499901) (xy 382.338081 -254.514061)
			(xy 382.28756 -254.520195) (xy 382.236708 -254.518146) (xy 382.186844 -254.507966) (xy 382.139258 -254.489919)
			(xy 382.095184 -254.464473) (xy 382.055762 -254.432286) (xy 382.022014 -254.394192) (xy 381.994813 -254.351178)
			(xy 381.974865 -254.304358) (xy 381.962686 -254.254944) (xy 381.958591 -254.204216) (xy 381.64008 -254.204216)
			(xy 381.639585 -254.228823) (xy 381.63169 -254.2774) (xy 381.616106 -254.324081) (xy 381.593235 -254.367658)
			(xy 381.56367 -254.407002) (xy 381.528177 -254.441094) (xy 381.487674 -254.46905) (xy 381.443212 -254.490148)
			(xy 381.395941 -254.50384) (xy 381.347086 -254.509772) (xy 381.297911 -254.507791) (xy 381.249692 -254.497947)
			(xy 381.203676 -254.480495) (xy 381.161055 -254.455888) (xy 381.122934 -254.424763) (xy 381.090299 -254.387926)
			(xy 381.063996 -254.34633) (xy 381.044705 -254.301054) (xy 381.032928 -254.25327) (xy 381.028968 -254.204216)
			(xy 380.71044 -254.204216) (xy 380.709928 -254.229662) (xy 380.701764 -254.279896) (xy 380.685648 -254.32817)
			(xy 380.661997 -254.373233) (xy 380.631424 -254.413919) (xy 380.59472 -254.449174) (xy 380.552836 -254.478084)
			(xy 380.506857 -254.499901) (xy 380.457973 -254.514061) (xy 380.407452 -254.520195) (xy 380.3566 -254.518146)
			(xy 380.306736 -254.507966) (xy 380.25915 -254.489919) (xy 380.215076 -254.464473) (xy 380.175654 -254.432286)
			(xy 380.141906 -254.394192) (xy 380.114705 -254.351178) (xy 380.094757 -254.304358) (xy 380.082578 -254.254944)
			(xy 380.078483 -254.204216) (xy 379.77064 -254.204216) (xy 379.770128 -254.229662) (xy 379.761964 -254.279896)
			(xy 379.745848 -254.32817) (xy 379.722197 -254.373233) (xy 379.691624 -254.413919) (xy 379.65492 -254.449174)
			(xy 379.613036 -254.478084) (xy 379.567057 -254.499901) (xy 379.518173 -254.514061) (xy 379.467652 -254.520195)
			(xy 379.4168 -254.518146) (xy 379.366936 -254.507966) (xy 379.31935 -254.489919) (xy 379.275276 -254.464473)
			(xy 379.235854 -254.432286) (xy 379.202106 -254.394192) (xy 379.174905 -254.351178) (xy 379.154957 -254.304358)
			(xy 379.142778 -254.254944) (xy 379.138683 -254.204216) (xy 377.890532 -254.204216) (xy 377.89002 -254.229662)
			(xy 377.881856 -254.279896) (xy 377.86574 -254.32817) (xy 377.842089 -254.373233) (xy 377.811516 -254.413919)
			(xy 377.774812 -254.449174) (xy 377.732928 -254.478084) (xy 377.686949 -254.499901) (xy 377.638065 -254.514061)
			(xy 377.587544 -254.520195) (xy 377.536692 -254.518146) (xy 377.486828 -254.507966) (xy 377.439242 -254.489919)
			(xy 377.395168 -254.464473) (xy 377.355746 -254.432286) (xy 377.321998 -254.394192) (xy 377.294797 -254.351178)
			(xy 377.274849 -254.304358) (xy 377.26267 -254.254944) (xy 377.258575 -254.204216) (xy 376.940064 -254.204216)
			(xy 376.939569 -254.228823) (xy 376.931674 -254.2774) (xy 376.91609 -254.324081) (xy 376.893219 -254.367658)
			(xy 376.863654 -254.407002) (xy 376.828161 -254.441094) (xy 376.787658 -254.46905) (xy 376.743196 -254.490148)
			(xy 376.695925 -254.50384) (xy 376.64707 -254.509772) (xy 376.597895 -254.507791) (xy 376.549676 -254.497947)
			(xy 376.50366 -254.480495) (xy 376.461039 -254.455888) (xy 376.422918 -254.424763) (xy 376.390283 -254.387926)
			(xy 376.36398 -254.34633) (xy 376.344689 -254.301054) (xy 376.332912 -254.25327) (xy 376.328952 -254.204216)
			(xy 376.010424 -254.204216) (xy 376.009912 -254.229662) (xy 376.001748 -254.279896) (xy 375.985632 -254.32817)
			(xy 375.961981 -254.373233) (xy 375.931408 -254.413919) (xy 375.894704 -254.449174) (xy 375.85282 -254.478084)
			(xy 375.806841 -254.499901) (xy 375.757957 -254.514061) (xy 375.707436 -254.520195) (xy 375.656584 -254.518146)
			(xy 375.60672 -254.507966) (xy 375.559134 -254.489919) (xy 375.51506 -254.464473) (xy 375.475638 -254.432286)
			(xy 375.44189 -254.394192) (xy 375.414689 -254.351178) (xy 375.394741 -254.304358) (xy 375.382562 -254.254944)
			(xy 375.378467 -254.204216) (xy 375.06021 -254.204216) (xy 375.059715 -254.228823) (xy 375.05182 -254.2774)
			(xy 375.036236 -254.324081) (xy 375.013365 -254.367658) (xy 374.9838 -254.407002) (xy 374.948307 -254.441094)
			(xy 374.907804 -254.46905) (xy 374.863342 -254.490148) (xy 374.816071 -254.50384) (xy 374.767216 -254.509772)
			(xy 374.718041 -254.507791) (xy 374.669822 -254.497947) (xy 374.623806 -254.480495) (xy 374.581185 -254.455888)
			(xy 374.543064 -254.424763) (xy 374.510429 -254.387926) (xy 374.484126 -254.34633) (xy 374.464835 -254.301054)
			(xy 374.453058 -254.25327) (xy 374.449098 -254.204216) (xy 373.180102 -254.204216) (xy 373.179607 -254.228823)
			(xy 373.171712 -254.2774) (xy 373.156128 -254.324081) (xy 373.133257 -254.367658) (xy 373.103692 -254.407002)
			(xy 373.068199 -254.441094) (xy 373.027696 -254.46905) (xy 372.983234 -254.490148) (xy 372.935963 -254.50384)
			(xy 372.887108 -254.509772) (xy 372.837933 -254.507791) (xy 372.789714 -254.497947) (xy 372.743698 -254.480495)
			(xy 372.701077 -254.455888) (xy 372.662956 -254.424763) (xy 372.630321 -254.387926) (xy 372.604018 -254.34633)
			(xy 372.584727 -254.301054) (xy 372.57295 -254.25327) (xy 372.56899 -254.204216) (xy 371.299994 -254.204216)
			(xy 371.299499 -254.228823) (xy 371.291604 -254.2774) (xy 371.27602 -254.324081) (xy 371.253149 -254.367658)
			(xy 371.223584 -254.407002) (xy 371.188091 -254.441094) (xy 371.147588 -254.46905) (xy 371.103126 -254.490148)
			(xy 371.055855 -254.50384) (xy 371.007 -254.509772) (xy 370.957825 -254.507791) (xy 370.909606 -254.497947)
			(xy 370.86359 -254.480495) (xy 370.820969 -254.455888) (xy 370.782848 -254.424763) (xy 370.750213 -254.387926)
			(xy 370.72391 -254.34633) (xy 370.704619 -254.301054) (xy 370.692842 -254.25327) (xy 370.688882 -254.204216)
			(xy 369.42014 -254.204216) (xy 369.419645 -254.228823) (xy 369.41175 -254.2774) (xy 369.396166 -254.324081)
			(xy 369.373295 -254.367658) (xy 369.34373 -254.407002) (xy 369.308237 -254.441094) (xy 369.267734 -254.46905)
			(xy 369.223272 -254.490148) (xy 369.176001 -254.50384) (xy 369.127146 -254.509772) (xy 369.077971 -254.507791)
			(xy 369.029752 -254.497947) (xy 368.983736 -254.480495) (xy 368.941115 -254.455888) (xy 368.902994 -254.424763)
			(xy 368.870359 -254.387926) (xy 368.844056 -254.34633) (xy 368.824765 -254.301054) (xy 368.812988 -254.25327)
			(xy 368.809028 -254.204216) (xy 360.438648 -254.204216) (xy 360.46298 -254.229498) (xy 360.493272 -254.272564)
			(xy 360.516635 -254.319749) (xy 360.532521 -254.369948) (xy 360.540558 -254.421984) (xy 360.541062 -254.44831)
			(xy 360.540558 -254.474636) (xy 360.532521 -254.526672) (xy 360.516635 -254.576871) (xy 360.493272 -254.624056)
			(xy 360.46298 -254.667122) (xy 360.426468 -254.70506) (xy 360.384594 -254.736979) (xy 360.338338 -254.762132)
			(xy 360.288785 -254.77993) (xy 360.237095 -254.789954) (xy 360.184481 -254.791971) (xy 360.132176 -254.785933)
			(xy 360.081405 -254.771981) (xy 360.03336 -254.750442) (xy 359.989165 -254.721822) (xy 359.949857 -254.686791)
			(xy 359.916357 -254.64617) (xy 359.889451 -254.600911) (xy 359.869768 -254.552076) (xy 359.857771 -254.500808)
			(xy 359.853741 -254.44831) (xy 349.564014 -254.44831) (xy 349.533966 -254.46905) (xy 349.489504 -254.490148)
			(xy 349.442233 -254.50384) (xy 349.393378 -254.509772) (xy 349.344203 -254.507791) (xy 349.295984 -254.497947)
			(xy 349.249968 -254.480495) (xy 349.207347 -254.455888) (xy 349.169226 -254.424763) (xy 349.136591 -254.387926)
			(xy 349.110288 -254.34633) (xy 349.090997 -254.301054) (xy 349.07922 -254.25327) (xy 349.07526 -254.204216)
			(xy 348.746814 -254.204216) (xy 348.742644 -254.254534) (xy 348.730246 -254.303496) (xy 348.709958 -254.349749)
			(xy 348.682334 -254.392032) (xy 348.648127 -254.429192) (xy 348.60827 -254.460215) (xy 348.563851 -254.484254)
			(xy 348.516081 -254.500655) (xy 348.466263 -254.50897) (xy 348.44101 -254.509524) (xy 348.431203 -254.509437)
			(xy 348.41163 -254.508169) (xy 348.401894 -254.506984) (xy 348.390972 -254.505714) (xy 348.370144 -254.512064)
			(xy 348.304612 -254.569468) (xy 348.296785 -254.577059) (xy 348.287856 -254.596929) (xy 348.28734 -254.607822)
			(xy 348.28734 -255.014222) (xy 349.545414 -255.014222) (xy 349.549374 -254.965168) (xy 349.561151 -254.917384)
			(xy 349.580442 -254.872108) (xy 349.606745 -254.830512) (xy 349.63938 -254.793675) (xy 349.677501 -254.76255)
			(xy 349.720122 -254.737943) (xy 349.766138 -254.720491) (xy 349.814357 -254.710647) (xy 349.863532 -254.708666)
			(xy 349.912387 -254.714598) (xy 349.959658 -254.72829) (xy 350.00412 -254.749388) (xy 350.044623 -254.777344)
			(xy 350.080116 -254.811436) (xy 350.109681 -254.85078) (xy 350.132552 -254.894357) (xy 350.148136 -254.941038)
			(xy 350.156031 -254.989615) (xy 350.156526 -255.014222) (xy 370.218982 -255.014222) (xy 370.222942 -254.965168)
			(xy 370.234719 -254.917384) (xy 370.25401 -254.872108) (xy 370.280313 -254.830512) (xy 370.312948 -254.793675)
			(xy 370.351069 -254.76255) (xy 370.39369 -254.737943) (xy 370.439706 -254.720491) (xy 370.487925 -254.710647)
			(xy 370.5371 -254.708666) (xy 370.585955 -254.714598) (xy 370.633226 -254.72829) (xy 370.677688 -254.749388)
			(xy 370.718191 -254.777344) (xy 370.753684 -254.811436) (xy 370.783249 -254.85078) (xy 370.80612 -254.894357)
			(xy 370.821704 -254.941038) (xy 370.829599 -254.989615) (xy 370.830094 -255.014222) (xy 372.09909 -255.014222)
			(xy 372.10305 -254.965168) (xy 372.114827 -254.917384) (xy 372.134118 -254.872108) (xy 372.160421 -254.830512)
			(xy 372.193056 -254.793675) (xy 372.231177 -254.76255) (xy 372.273798 -254.737943) (xy 372.319814 -254.720491)
			(xy 372.368033 -254.710647) (xy 372.417208 -254.708666) (xy 372.466063 -254.714598) (xy 372.513334 -254.72829)
			(xy 372.557796 -254.749388) (xy 372.598299 -254.777344) (xy 372.633792 -254.811436) (xy 372.663357 -254.85078)
			(xy 372.686228 -254.894357) (xy 372.701812 -254.941038) (xy 372.709707 -254.989615) (xy 372.710202 -255.014222)
			(xy 373.978944 -255.014222) (xy 373.982904 -254.965168) (xy 373.994681 -254.917384) (xy 374.013972 -254.872108)
			(xy 374.040275 -254.830512) (xy 374.07291 -254.793675) (xy 374.111031 -254.76255) (xy 374.153652 -254.737943)
			(xy 374.199668 -254.720491) (xy 374.247887 -254.710647) (xy 374.297062 -254.708666) (xy 374.345917 -254.714598)
			(xy 374.393188 -254.72829) (xy 374.43765 -254.749388) (xy 374.478153 -254.777344) (xy 374.513646 -254.811436)
			(xy 374.543211 -254.85078) (xy 374.566082 -254.894357) (xy 374.581666 -254.941038) (xy 374.589561 -254.989615)
			(xy 374.590056 -255.014222) (xy 375.848621 -255.014222) (xy 375.852716 -254.963494) (xy 375.864895 -254.91408)
			(xy 375.884843 -254.86726) (xy 375.912044 -254.824246) (xy 375.945792 -254.786152) (xy 375.985214 -254.753965)
			(xy 376.029288 -254.728519) (xy 376.076874 -254.710472) (xy 376.126738 -254.700292) (xy 376.17759 -254.698243)
			(xy 376.228111 -254.704377) (xy 376.276995 -254.718537) (xy 376.322974 -254.740354) (xy 376.364858 -254.769264)
			(xy 376.401562 -254.804519) (xy 376.432135 -254.845205) (xy 376.455786 -254.890268) (xy 376.471902 -254.938542)
			(xy 376.480066 -254.988776) (xy 376.480578 -255.014222) (xy 376.788675 -255.014222) (xy 376.79277 -254.963494)
			(xy 376.804949 -254.91408) (xy 376.824897 -254.86726) (xy 376.852098 -254.824246) (xy 376.885846 -254.786152)
			(xy 376.925268 -254.753965) (xy 376.969342 -254.728519) (xy 377.016928 -254.710472) (xy 377.066792 -254.700292)
			(xy 377.117644 -254.698243) (xy 377.168165 -254.704377) (xy 377.217049 -254.718537) (xy 377.263028 -254.740354)
			(xy 377.304912 -254.769264) (xy 377.341616 -254.804519) (xy 377.372189 -254.845205) (xy 377.39584 -254.890268)
			(xy 377.411956 -254.938542) (xy 377.42012 -254.988776) (xy 377.420632 -255.014222) (xy 377.738906 -255.014222)
			(xy 377.742866 -254.965168) (xy 377.754643 -254.917384) (xy 377.773934 -254.872108) (xy 377.800237 -254.830512)
			(xy 377.832872 -254.793675) (xy 377.870993 -254.76255) (xy 377.913614 -254.737943) (xy 377.95963 -254.720491)
			(xy 378.007849 -254.710647) (xy 378.057024 -254.708666) (xy 378.105879 -254.714598) (xy 378.15315 -254.72829)
			(xy 378.197612 -254.749388) (xy 378.238115 -254.777344) (xy 378.273608 -254.811436) (xy 378.303173 -254.85078)
			(xy 378.326044 -254.894357) (xy 378.341628 -254.941038) (xy 378.349523 -254.989615) (xy 378.350018 -255.014222)
			(xy 378.668529 -255.014222) (xy 378.672624 -254.963494) (xy 378.684803 -254.91408) (xy 378.704751 -254.86726)
			(xy 378.731952 -254.824246) (xy 378.7657 -254.786152) (xy 378.805122 -254.753965) (xy 378.849196 -254.728519)
			(xy 378.896782 -254.710472) (xy 378.946646 -254.700292) (xy 378.997498 -254.698243) (xy 379.048019 -254.704377)
			(xy 379.096903 -254.718537) (xy 379.142882 -254.740354) (xy 379.184766 -254.769264) (xy 379.22147 -254.804519)
			(xy 379.252043 -254.845205) (xy 379.275694 -254.890268) (xy 379.29181 -254.938542) (xy 379.299974 -254.988776)
			(xy 379.300486 -255.014222) (xy 379.619014 -255.014222) (xy 379.622974 -254.965168) (xy 379.634751 -254.917384)
			(xy 379.654042 -254.872108) (xy 379.680345 -254.830512) (xy 379.71298 -254.793675) (xy 379.751101 -254.76255)
			(xy 379.793722 -254.737943) (xy 379.839738 -254.720491) (xy 379.887957 -254.710647) (xy 379.937132 -254.708666)
			(xy 379.985987 -254.714598) (xy 380.033258 -254.72829) (xy 380.07772 -254.749388) (xy 380.118223 -254.777344)
			(xy 380.153716 -254.811436) (xy 380.183281 -254.85078) (xy 380.206152 -254.894357) (xy 380.221736 -254.941038)
			(xy 380.229631 -254.989615) (xy 380.230126 -255.014222) (xy 380.548637 -255.014222) (xy 380.552732 -254.963494)
			(xy 380.564911 -254.91408) (xy 380.584859 -254.86726) (xy 380.61206 -254.824246) (xy 380.645808 -254.786152)
			(xy 380.68523 -254.753965) (xy 380.729304 -254.728519) (xy 380.77689 -254.710472) (xy 380.826754 -254.700292)
			(xy 380.877606 -254.698243) (xy 380.928127 -254.704377) (xy 380.977011 -254.718537) (xy 381.02299 -254.740354)
			(xy 381.064874 -254.769264) (xy 381.101578 -254.804519) (xy 381.132151 -254.845205) (xy 381.155802 -254.890268)
			(xy 381.171918 -254.938542) (xy 381.180082 -254.988776) (xy 381.180594 -255.014222) (xy 381.499122 -255.014222)
			(xy 381.503082 -254.965168) (xy 381.514859 -254.917384) (xy 381.53415 -254.872108) (xy 381.560453 -254.830512)
			(xy 381.593088 -254.793675) (xy 381.631209 -254.76255) (xy 381.67383 -254.737943) (xy 381.719846 -254.720491)
			(xy 381.768065 -254.710647) (xy 381.81724 -254.708666) (xy 381.866095 -254.714598) (xy 381.913366 -254.72829)
			(xy 381.957828 -254.749388) (xy 381.998331 -254.777344) (xy 382.033824 -254.811436) (xy 382.063389 -254.85078)
			(xy 382.08626 -254.894357) (xy 382.101844 -254.941038) (xy 382.109739 -254.989615) (xy 382.110234 -255.014222)
			(xy 382.428491 -255.014222) (xy 382.432586 -254.963494) (xy 382.444765 -254.91408) (xy 382.464713 -254.86726)
			(xy 382.491914 -254.824246) (xy 382.525662 -254.786152) (xy 382.565084 -254.753965) (xy 382.609158 -254.728519)
			(xy 382.656744 -254.710472) (xy 382.706608 -254.700292) (xy 382.75746 -254.698243) (xy 382.807981 -254.704377)
			(xy 382.856865 -254.718537) (xy 382.902844 -254.740354) (xy 382.944728 -254.769264) (xy 382.981432 -254.804519)
			(xy 383.012005 -254.845205) (xy 383.035656 -254.890268) (xy 383.051772 -254.938542) (xy 383.059936 -254.988776)
			(xy 383.060448 -255.014222) (xy 383.368545 -255.014222) (xy 383.37264 -254.963494) (xy 383.384819 -254.91408)
			(xy 383.404767 -254.86726) (xy 383.431968 -254.824246) (xy 383.465716 -254.786152) (xy 383.505138 -254.753965)
			(xy 383.549212 -254.728519) (xy 383.596798 -254.710472) (xy 383.646662 -254.700292) (xy 383.697514 -254.698243)
			(xy 383.748035 -254.704377) (xy 383.796919 -254.718537) (xy 383.842898 -254.740354) (xy 383.884782 -254.769264)
			(xy 383.921486 -254.804519) (xy 383.952059 -254.845205) (xy 383.97571 -254.890268) (xy 383.991826 -254.938542)
			(xy 383.99999 -254.988776) (xy 384.000502 -255.014222) (xy 384.31903 -255.014222) (xy 384.32299 -254.965168)
			(xy 384.334767 -254.917384) (xy 384.354058 -254.872108) (xy 384.380361 -254.830512) (xy 384.412996 -254.793675)
			(xy 384.451117 -254.76255) (xy 384.493738 -254.737943) (xy 384.539754 -254.720491) (xy 384.587973 -254.710647)
			(xy 384.637148 -254.708666) (xy 384.686003 -254.714598) (xy 384.733274 -254.72829) (xy 384.777736 -254.749388)
			(xy 384.818239 -254.777344) (xy 384.853732 -254.811436) (xy 384.883297 -254.85078) (xy 384.906168 -254.894357)
			(xy 384.921752 -254.941038) (xy 384.929647 -254.989615) (xy 384.930142 -255.014222) (xy 385.248653 -255.014222)
			(xy 385.252748 -254.963494) (xy 385.264927 -254.91408) (xy 385.284875 -254.86726) (xy 385.312076 -254.824246)
			(xy 385.345824 -254.786152) (xy 385.385246 -254.753965) (xy 385.42932 -254.728519) (xy 385.476906 -254.710472)
			(xy 385.52677 -254.700292) (xy 385.577622 -254.698243) (xy 385.628143 -254.704377) (xy 385.677027 -254.718537)
			(xy 385.723006 -254.740354) (xy 385.76489 -254.769264) (xy 385.801594 -254.804519) (xy 385.832167 -254.845205)
			(xy 385.855818 -254.890268) (xy 385.871934 -254.938542) (xy 385.880098 -254.988776) (xy 385.88061 -255.014222)
			(xy 386.199138 -255.014222) (xy 386.203098 -254.965168) (xy 386.214875 -254.917384) (xy 386.234166 -254.872108)
			(xy 386.260469 -254.830512) (xy 386.293104 -254.793675) (xy 386.331225 -254.76255) (xy 386.373846 -254.737943)
			(xy 386.419862 -254.720491) (xy 386.468081 -254.710647) (xy 386.517256 -254.708666) (xy 386.566111 -254.714598)
			(xy 386.613382 -254.72829) (xy 386.657844 -254.749388) (xy 386.698347 -254.777344) (xy 386.73384 -254.811436)
			(xy 386.763405 -254.85078) (xy 386.786276 -254.894357) (xy 386.80186 -254.941038) (xy 386.809755 -254.989615)
			(xy 386.81025 -255.014222) (xy 387.128507 -255.014222) (xy 387.132602 -254.963494) (xy 387.144781 -254.91408)
			(xy 387.164729 -254.86726) (xy 387.19193 -254.824246) (xy 387.225678 -254.786152) (xy 387.2651 -254.753965)
			(xy 387.309174 -254.728519) (xy 387.35676 -254.710472) (xy 387.406624 -254.700292) (xy 387.457476 -254.698243)
			(xy 387.507997 -254.704377) (xy 387.556881 -254.718537) (xy 387.60286 -254.740354) (xy 387.644744 -254.769264)
			(xy 387.681448 -254.804519) (xy 387.712021 -254.845205) (xy 387.735672 -254.890268) (xy 387.751788 -254.938542)
			(xy 387.759952 -254.988776) (xy 387.760464 -255.014222) (xy 388.078992 -255.014222) (xy 388.082952 -254.965168)
			(xy 388.094729 -254.917384) (xy 388.11402 -254.872108) (xy 388.140323 -254.830512) (xy 388.172958 -254.793675)
			(xy 388.211079 -254.76255) (xy 388.2537 -254.737943) (xy 388.299716 -254.720491) (xy 388.347935 -254.710647)
			(xy 388.39711 -254.708666) (xy 388.445965 -254.714598) (xy 388.493236 -254.72829) (xy 388.537698 -254.749388)
			(xy 388.578201 -254.777344) (xy 388.613694 -254.811436) (xy 388.643259 -254.85078) (xy 388.66613 -254.894357)
			(xy 388.681714 -254.941038) (xy 388.689609 -254.989615) (xy 388.690104 -255.014222) (xy 389.008615 -255.014222)
			(xy 389.01271 -254.963494) (xy 389.024889 -254.91408) (xy 389.044837 -254.86726) (xy 389.072038 -254.824246)
			(xy 389.105786 -254.786152) (xy 389.145208 -254.753965) (xy 389.189282 -254.728519) (xy 389.236868 -254.710472)
			(xy 389.286732 -254.700292) (xy 389.337584 -254.698243) (xy 389.388105 -254.704377) (xy 389.436989 -254.718537)
			(xy 389.482968 -254.740354) (xy 389.524852 -254.769264) (xy 389.561556 -254.804519) (xy 389.592129 -254.845205)
			(xy 389.61578 -254.890268) (xy 389.631896 -254.938542) (xy 389.64006 -254.988776) (xy 389.640572 -255.014222)
			(xy 389.948669 -255.014222) (xy 389.952764 -254.963494) (xy 389.964943 -254.91408) (xy 389.984891 -254.86726)
			(xy 390.012092 -254.824246) (xy 390.04584 -254.786152) (xy 390.085262 -254.753965) (xy 390.129336 -254.728519)
			(xy 390.176922 -254.710472) (xy 390.226786 -254.700292) (xy 390.277638 -254.698243) (xy 390.328159 -254.704377)
			(xy 390.377043 -254.718537) (xy 390.423022 -254.740354) (xy 390.464906 -254.769264) (xy 390.50161 -254.804519)
			(xy 390.532183 -254.845205) (xy 390.555834 -254.890268) (xy 390.57195 -254.938542) (xy 390.580114 -254.988776)
			(xy 390.580626 -255.014222) (xy 390.8989 -255.014222) (xy 390.90286 -254.965168) (xy 390.914637 -254.917384)
			(xy 390.933928 -254.872108) (xy 390.960231 -254.830512) (xy 390.992866 -254.793675) (xy 391.030987 -254.76255)
			(xy 391.073608 -254.737943) (xy 391.119624 -254.720491) (xy 391.167843 -254.710647) (xy 391.217018 -254.708666)
			(xy 391.265873 -254.714598) (xy 391.313144 -254.72829) (xy 391.357606 -254.749388) (xy 391.398109 -254.777344)
			(xy 391.433602 -254.811436) (xy 391.463167 -254.85078) (xy 391.486038 -254.894357) (xy 391.501622 -254.941038)
			(xy 391.509517 -254.989615) (xy 391.510012 -255.014222) (xy 392.779008 -255.014222) (xy 392.782968 -254.965168)
			(xy 392.794745 -254.917384) (xy 392.814036 -254.872108) (xy 392.840339 -254.830512) (xy 392.872974 -254.793675)
			(xy 392.911095 -254.76255) (xy 392.953716 -254.737943) (xy 392.999732 -254.720491) (xy 393.047951 -254.710647)
			(xy 393.097126 -254.708666) (xy 393.145981 -254.714598) (xy 393.193252 -254.72829) (xy 393.237714 -254.749388)
			(xy 393.278217 -254.777344) (xy 393.31371 -254.811436) (xy 393.343275 -254.85078) (xy 393.366146 -254.894357)
			(xy 393.38173 -254.941038) (xy 393.389625 -254.989615) (xy 393.39012 -255.014222) (xy 393.389625 -255.038829)
			(xy 393.38173 -255.087406) (xy 393.366146 -255.134087) (xy 393.343275 -255.177664) (xy 393.31371 -255.217008)
			(xy 393.278217 -255.2511) (xy 393.237714 -255.279056) (xy 393.193252 -255.300154) (xy 393.145981 -255.313846)
			(xy 393.097126 -255.319778) (xy 393.047951 -255.317797) (xy 392.999732 -255.307953) (xy 392.953716 -255.290501)
			(xy 392.911095 -255.265894) (xy 392.872974 -255.234769) (xy 392.840339 -255.197932) (xy 392.814036 -255.156336)
			(xy 392.794745 -255.11106) (xy 392.782968 -255.063276) (xy 392.779008 -255.014222) (xy 391.510012 -255.014222)
			(xy 391.509517 -255.038829) (xy 391.501622 -255.087406) (xy 391.486038 -255.134087) (xy 391.463167 -255.177664)
			(xy 391.433602 -255.217008) (xy 391.398109 -255.2511) (xy 391.357606 -255.279056) (xy 391.313144 -255.300154)
			(xy 391.265873 -255.313846) (xy 391.217018 -255.319778) (xy 391.167843 -255.317797) (xy 391.119624 -255.307953)
			(xy 391.073608 -255.290501) (xy 391.030987 -255.265894) (xy 390.992866 -255.234769) (xy 390.960231 -255.197932)
			(xy 390.933928 -255.156336) (xy 390.914637 -255.11106) (xy 390.90286 -255.063276) (xy 390.8989 -255.014222)
			(xy 390.580626 -255.014222) (xy 390.580114 -255.039668) (xy 390.57195 -255.089902) (xy 390.555834 -255.138176)
			(xy 390.532183 -255.183239) (xy 390.50161 -255.223925) (xy 390.464906 -255.25918) (xy 390.423022 -255.28809)
			(xy 390.377043 -255.309907) (xy 390.328159 -255.324067) (xy 390.277638 -255.330201) (xy 390.226786 -255.328152)
			(xy 390.176922 -255.317972) (xy 390.129336 -255.299925) (xy 390.085262 -255.274479) (xy 390.04584 -255.242292)
			(xy 390.012092 -255.204198) (xy 389.984891 -255.161184) (xy 389.964943 -255.114364) (xy 389.952764 -255.06495)
			(xy 389.948669 -255.014222) (xy 389.640572 -255.014222) (xy 389.64006 -255.039668) (xy 389.631896 -255.089902)
			(xy 389.61578 -255.138176) (xy 389.592129 -255.183239) (xy 389.561556 -255.223925) (xy 389.524852 -255.25918)
			(xy 389.482968 -255.28809) (xy 389.436989 -255.309907) (xy 389.388105 -255.324067) (xy 389.337584 -255.330201)
			(xy 389.286732 -255.328152) (xy 389.236868 -255.317972) (xy 389.189282 -255.299925) (xy 389.145208 -255.274479)
			(xy 389.105786 -255.242292) (xy 389.072038 -255.204198) (xy 389.044837 -255.161184) (xy 389.024889 -255.114364)
			(xy 389.01271 -255.06495) (xy 389.008615 -255.014222) (xy 388.690104 -255.014222) (xy 388.689609 -255.038829)
			(xy 388.681714 -255.087406) (xy 388.66613 -255.134087) (xy 388.643259 -255.177664) (xy 388.613694 -255.217008)
			(xy 388.578201 -255.2511) (xy 388.537698 -255.279056) (xy 388.493236 -255.300154) (xy 388.445965 -255.313846)
			(xy 388.39711 -255.319778) (xy 388.347935 -255.317797) (xy 388.299716 -255.307953) (xy 388.2537 -255.290501)
			(xy 388.211079 -255.265894) (xy 388.172958 -255.234769) (xy 388.140323 -255.197932) (xy 388.11402 -255.156336)
			(xy 388.094729 -255.11106) (xy 388.082952 -255.063276) (xy 388.078992 -255.014222) (xy 387.760464 -255.014222)
			(xy 387.759952 -255.039668) (xy 387.751788 -255.089902) (xy 387.735672 -255.138176) (xy 387.712021 -255.183239)
			(xy 387.681448 -255.223925) (xy 387.644744 -255.25918) (xy 387.60286 -255.28809) (xy 387.556881 -255.309907)
			(xy 387.507997 -255.324067) (xy 387.457476 -255.330201) (xy 387.406624 -255.328152) (xy 387.35676 -255.317972)
			(xy 387.309174 -255.299925) (xy 387.2651 -255.274479) (xy 387.225678 -255.242292) (xy 387.19193 -255.204198)
			(xy 387.164729 -255.161184) (xy 387.144781 -255.114364) (xy 387.132602 -255.06495) (xy 387.128507 -255.014222)
			(xy 386.81025 -255.014222) (xy 386.809755 -255.038829) (xy 386.80186 -255.087406) (xy 386.786276 -255.134087)
			(xy 386.763405 -255.177664) (xy 386.73384 -255.217008) (xy 386.698347 -255.2511) (xy 386.657844 -255.279056)
			(xy 386.613382 -255.300154) (xy 386.566111 -255.313846) (xy 386.517256 -255.319778) (xy 386.468081 -255.317797)
			(xy 386.419862 -255.307953) (xy 386.373846 -255.290501) (xy 386.331225 -255.265894) (xy 386.293104 -255.234769)
			(xy 386.260469 -255.197932) (xy 386.234166 -255.156336) (xy 386.214875 -255.11106) (xy 386.203098 -255.063276)
			(xy 386.199138 -255.014222) (xy 385.88061 -255.014222) (xy 385.880098 -255.039668) (xy 385.871934 -255.089902)
			(xy 385.855818 -255.138176) (xy 385.832167 -255.183239) (xy 385.801594 -255.223925) (xy 385.76489 -255.25918)
			(xy 385.723006 -255.28809) (xy 385.677027 -255.309907) (xy 385.628143 -255.324067) (xy 385.577622 -255.330201)
			(xy 385.52677 -255.328152) (xy 385.476906 -255.317972) (xy 385.42932 -255.299925) (xy 385.385246 -255.274479)
			(xy 385.345824 -255.242292) (xy 385.312076 -255.204198) (xy 385.284875 -255.161184) (xy 385.264927 -255.114364)
			(xy 385.252748 -255.06495) (xy 385.248653 -255.014222) (xy 384.930142 -255.014222) (xy 384.929647 -255.038829)
			(xy 384.921752 -255.087406) (xy 384.906168 -255.134087) (xy 384.883297 -255.177664) (xy 384.853732 -255.217008)
			(xy 384.818239 -255.2511) (xy 384.777736 -255.279056) (xy 384.733274 -255.300154) (xy 384.686003 -255.313846)
			(xy 384.637148 -255.319778) (xy 384.587973 -255.317797) (xy 384.539754 -255.307953) (xy 384.493738 -255.290501)
			(xy 384.451117 -255.265894) (xy 384.412996 -255.234769) (xy 384.380361 -255.197932) (xy 384.354058 -255.156336)
			(xy 384.334767 -255.11106) (xy 384.32299 -255.063276) (xy 384.31903 -255.014222) (xy 384.000502 -255.014222)
			(xy 383.99999 -255.039668) (xy 383.991826 -255.089902) (xy 383.97571 -255.138176) (xy 383.952059 -255.183239)
			(xy 383.921486 -255.223925) (xy 383.884782 -255.25918) (xy 383.842898 -255.28809) (xy 383.796919 -255.309907)
			(xy 383.748035 -255.324067) (xy 383.697514 -255.330201) (xy 383.646662 -255.328152) (xy 383.596798 -255.317972)
			(xy 383.549212 -255.299925) (xy 383.505138 -255.274479) (xy 383.465716 -255.242292) (xy 383.431968 -255.204198)
			(xy 383.404767 -255.161184) (xy 383.384819 -255.114364) (xy 383.37264 -255.06495) (xy 383.368545 -255.014222)
			(xy 383.060448 -255.014222) (xy 383.059936 -255.039668) (xy 383.051772 -255.089902) (xy 383.035656 -255.138176)
			(xy 383.012005 -255.183239) (xy 382.981432 -255.223925) (xy 382.944728 -255.25918) (xy 382.902844 -255.28809)
			(xy 382.856865 -255.309907) (xy 382.807981 -255.324067) (xy 382.75746 -255.330201) (xy 382.706608 -255.328152)
			(xy 382.656744 -255.317972) (xy 382.609158 -255.299925) (xy 382.565084 -255.274479) (xy 382.525662 -255.242292)
			(xy 382.491914 -255.204198) (xy 382.464713 -255.161184) (xy 382.444765 -255.114364) (xy 382.432586 -255.06495)
			(xy 382.428491 -255.014222) (xy 382.110234 -255.014222) (xy 382.109739 -255.038829) (xy 382.101844 -255.087406)
			(xy 382.08626 -255.134087) (xy 382.063389 -255.177664) (xy 382.033824 -255.217008) (xy 381.998331 -255.2511)
			(xy 381.957828 -255.279056) (xy 381.913366 -255.300154) (xy 381.866095 -255.313846) (xy 381.81724 -255.319778)
			(xy 381.768065 -255.317797) (xy 381.719846 -255.307953) (xy 381.67383 -255.290501) (xy 381.631209 -255.265894)
			(xy 381.593088 -255.234769) (xy 381.560453 -255.197932) (xy 381.53415 -255.156336) (xy 381.514859 -255.11106)
			(xy 381.503082 -255.063276) (xy 381.499122 -255.014222) (xy 381.180594 -255.014222) (xy 381.180082 -255.039668)
			(xy 381.171918 -255.089902) (xy 381.155802 -255.138176) (xy 381.132151 -255.183239) (xy 381.101578 -255.223925)
			(xy 381.064874 -255.25918) (xy 381.02299 -255.28809) (xy 380.977011 -255.309907) (xy 380.928127 -255.324067)
			(xy 380.877606 -255.330201) (xy 380.826754 -255.328152) (xy 380.77689 -255.317972) (xy 380.729304 -255.299925)
			(xy 380.68523 -255.274479) (xy 380.645808 -255.242292) (xy 380.61206 -255.204198) (xy 380.584859 -255.161184)
			(xy 380.564911 -255.114364) (xy 380.552732 -255.06495) (xy 380.548637 -255.014222) (xy 380.230126 -255.014222)
			(xy 380.229631 -255.038829) (xy 380.221736 -255.087406) (xy 380.206152 -255.134087) (xy 380.183281 -255.177664)
			(xy 380.153716 -255.217008) (xy 380.118223 -255.2511) (xy 380.07772 -255.279056) (xy 380.033258 -255.300154)
			(xy 379.985987 -255.313846) (xy 379.937132 -255.319778) (xy 379.887957 -255.317797) (xy 379.839738 -255.307953)
			(xy 379.793722 -255.290501) (xy 379.751101 -255.265894) (xy 379.71298 -255.234769) (xy 379.680345 -255.197932)
			(xy 379.654042 -255.156336) (xy 379.634751 -255.11106) (xy 379.622974 -255.063276) (xy 379.619014 -255.014222)
			(xy 379.300486 -255.014222) (xy 379.299974 -255.039668) (xy 379.29181 -255.089902) (xy 379.275694 -255.138176)
			(xy 379.252043 -255.183239) (xy 379.22147 -255.223925) (xy 379.184766 -255.25918) (xy 379.142882 -255.28809)
			(xy 379.096903 -255.309907) (xy 379.048019 -255.324067) (xy 378.997498 -255.330201) (xy 378.946646 -255.328152)
			(xy 378.896782 -255.317972) (xy 378.849196 -255.299925) (xy 378.805122 -255.274479) (xy 378.7657 -255.242292)
			(xy 378.731952 -255.204198) (xy 378.704751 -255.161184) (xy 378.684803 -255.114364) (xy 378.672624 -255.06495)
			(xy 378.668529 -255.014222) (xy 378.350018 -255.014222) (xy 378.349523 -255.038829) (xy 378.341628 -255.087406)
			(xy 378.326044 -255.134087) (xy 378.303173 -255.177664) (xy 378.273608 -255.217008) (xy 378.238115 -255.2511)
			(xy 378.197612 -255.279056) (xy 378.15315 -255.300154) (xy 378.105879 -255.313846) (xy 378.057024 -255.319778)
			(xy 378.007849 -255.317797) (xy 377.95963 -255.307953) (xy 377.913614 -255.290501) (xy 377.870993 -255.265894)
			(xy 377.832872 -255.234769) (xy 377.800237 -255.197932) (xy 377.773934 -255.156336) (xy 377.754643 -255.11106)
			(xy 377.742866 -255.063276) (xy 377.738906 -255.014222) (xy 377.420632 -255.014222) (xy 377.42012 -255.039668)
			(xy 377.411956 -255.089902) (xy 377.39584 -255.138176) (xy 377.372189 -255.183239) (xy 377.341616 -255.223925)
			(xy 377.304912 -255.25918) (xy 377.263028 -255.28809) (xy 377.217049 -255.309907) (xy 377.168165 -255.324067)
			(xy 377.117644 -255.330201) (xy 377.066792 -255.328152) (xy 377.016928 -255.317972) (xy 376.969342 -255.299925)
			(xy 376.925268 -255.274479) (xy 376.885846 -255.242292) (xy 376.852098 -255.204198) (xy 376.824897 -255.161184)
			(xy 376.804949 -255.114364) (xy 376.79277 -255.06495) (xy 376.788675 -255.014222) (xy 376.480578 -255.014222)
			(xy 376.480066 -255.039668) (xy 376.471902 -255.089902) (xy 376.455786 -255.138176) (xy 376.432135 -255.183239)
			(xy 376.401562 -255.223925) (xy 376.364858 -255.25918) (xy 376.322974 -255.28809) (xy 376.276995 -255.309907)
			(xy 376.228111 -255.324067) (xy 376.17759 -255.330201) (xy 376.126738 -255.328152) (xy 376.076874 -255.317972)
			(xy 376.029288 -255.299925) (xy 375.985214 -255.274479) (xy 375.945792 -255.242292) (xy 375.912044 -255.204198)
			(xy 375.884843 -255.161184) (xy 375.864895 -255.114364) (xy 375.852716 -255.06495) (xy 375.848621 -255.014222)
			(xy 374.590056 -255.014222) (xy 374.589561 -255.038829) (xy 374.581666 -255.087406) (xy 374.566082 -255.134087)
			(xy 374.543211 -255.177664) (xy 374.513646 -255.217008) (xy 374.478153 -255.2511) (xy 374.43765 -255.279056)
			(xy 374.393188 -255.300154) (xy 374.345917 -255.313846) (xy 374.297062 -255.319778) (xy 374.247887 -255.317797)
			(xy 374.199668 -255.307953) (xy 374.153652 -255.290501) (xy 374.111031 -255.265894) (xy 374.07291 -255.234769)
			(xy 374.040275 -255.197932) (xy 374.013972 -255.156336) (xy 373.994681 -255.11106) (xy 373.982904 -255.063276)
			(xy 373.978944 -255.014222) (xy 372.710202 -255.014222) (xy 372.709707 -255.038829) (xy 372.701812 -255.087406)
			(xy 372.686228 -255.134087) (xy 372.663357 -255.177664) (xy 372.633792 -255.217008) (xy 372.598299 -255.2511)
			(xy 372.557796 -255.279056) (xy 372.513334 -255.300154) (xy 372.466063 -255.313846) (xy 372.417208 -255.319778)
			(xy 372.368033 -255.317797) (xy 372.319814 -255.307953) (xy 372.273798 -255.290501) (xy 372.231177 -255.265894)
			(xy 372.193056 -255.234769) (xy 372.160421 -255.197932) (xy 372.134118 -255.156336) (xy 372.114827 -255.11106)
			(xy 372.10305 -255.063276) (xy 372.09909 -255.014222) (xy 370.830094 -255.014222) (xy 370.829599 -255.038829)
			(xy 370.821704 -255.087406) (xy 370.80612 -255.134087) (xy 370.783249 -255.177664) (xy 370.753684 -255.217008)
			(xy 370.718191 -255.2511) (xy 370.677688 -255.279056) (xy 370.633226 -255.300154) (xy 370.585955 -255.313846)
			(xy 370.5371 -255.319778) (xy 370.487925 -255.317797) (xy 370.439706 -255.307953) (xy 370.39369 -255.290501)
			(xy 370.351069 -255.265894) (xy 370.312948 -255.234769) (xy 370.280313 -255.197932) (xy 370.25401 -255.156336)
			(xy 370.234719 -255.11106) (xy 370.222942 -255.063276) (xy 370.218982 -255.014222) (xy 350.156526 -255.014222)
			(xy 350.156031 -255.038829) (xy 350.148136 -255.087406) (xy 350.132552 -255.134087) (xy 350.109681 -255.177664)
			(xy 350.080116 -255.217008) (xy 350.044623 -255.2511) (xy 350.00412 -255.279056) (xy 349.959658 -255.300154)
			(xy 349.912387 -255.313846) (xy 349.863532 -255.319778) (xy 349.814357 -255.317797) (xy 349.766138 -255.307953)
			(xy 349.720122 -255.290501) (xy 349.677501 -255.265894) (xy 349.63938 -255.234769) (xy 349.606745 -255.197932)
			(xy 349.580442 -255.156336) (xy 349.561151 -255.11106) (xy 349.549374 -255.063276) (xy 349.545414 -255.014222)
			(xy 348.28734 -255.014222) (xy 348.28734 -255.420876) (xy 348.287844 -255.431713) (xy 348.296799 -255.451448)
			(xy 348.304612 -255.458976) (xy 348.361508 -255.50876) (xy 348.368668 -255.514525) (xy 348.385852 -255.521019)
			(xy 348.395036 -255.52146) (xy 348.40164 -255.52146) (xy 348.404688 -255.521206) (xy 348.413732 -255.520158)
			(xy 348.431906 -255.519015) (xy 348.44101 -255.51892) (xy 348.464787 -255.519374) (xy 348.511766 -255.526747)
			(xy 348.557035 -255.541314) (xy 348.599498 -255.562721) (xy 348.63813 -255.590452) (xy 348.671997 -255.623836)
			(xy 348.700279 -255.662066) (xy 348.722293 -255.704218) (xy 348.737507 -255.749273) (xy 348.745553 -255.796141)
			(xy 348.746318 -255.81991) (xy 348.746318 -255.824228) (xy 349.07526 -255.824228) (xy 349.07922 -255.775174)
			(xy 349.090997 -255.72739) (xy 349.110288 -255.682114) (xy 349.136591 -255.640518) (xy 349.169226 -255.603681)
			(xy 349.207347 -255.572556) (xy 349.249968 -255.547949) (xy 349.295984 -255.530497) (xy 349.344203 -255.520653)
			(xy 349.393378 -255.518672) (xy 349.442233 -255.524604) (xy 349.489504 -255.538296) (xy 349.533966 -255.559394)
			(xy 349.574469 -255.58735) (xy 349.609962 -255.621442) (xy 349.639527 -255.660786) (xy 349.662398 -255.704363)
			(xy 349.677982 -255.751044) (xy 349.685877 -255.799621) (xy 349.686331 -255.822196) (xy 351.89212 -255.822196)
			(xy 351.89608 -255.773142) (xy 351.907857 -255.725358) (xy 351.927148 -255.680082) (xy 351.953451 -255.638486)
			(xy 351.986086 -255.601649) (xy 352.024207 -255.570524) (xy 352.066828 -255.545917) (xy 352.112844 -255.528465)
			(xy 352.161063 -255.518621) (xy 352.210238 -255.51664) (xy 352.259093 -255.522572) (xy 352.285069 -255.530096)
			(xy 353.086927 -255.530096) (xy 353.090957 -255.477598) (xy 353.102954 -255.42633) (xy 353.122637 -255.377495)
			(xy 353.149543 -255.332236) (xy 353.183043 -255.291615) (xy 353.222351 -255.256584) (xy 353.266546 -255.227964)
			(xy 353.314591 -255.206425) (xy 353.365362 -255.192473) (xy 353.417667 -255.186435) (xy 353.470281 -255.188452)
			(xy 353.521971 -255.198476) (xy 353.571524 -255.216274) (xy 353.61778 -255.241427) (xy 353.659654 -255.273346)
			(xy 353.696166 -255.311284) (xy 353.726458 -255.35435) (xy 353.749821 -255.401535) (xy 353.765707 -255.451734)
			(xy 353.773744 -255.50377) (xy 353.774248 -255.530096) (xy 354.001327 -255.530096) (xy 354.005357 -255.477598)
			(xy 354.017354 -255.42633) (xy 354.037037 -255.377495) (xy 354.063943 -255.332236) (xy 354.097443 -255.291615)
			(xy 354.136751 -255.256584) (xy 354.180946 -255.227964) (xy 354.228991 -255.206425) (xy 354.279762 -255.192473)
			(xy 354.332067 -255.186435) (xy 354.384681 -255.188452) (xy 354.436371 -255.198476) (xy 354.485924 -255.216274)
			(xy 354.53218 -255.241427) (xy 354.574054 -255.273346) (xy 354.610566 -255.311284) (xy 354.640858 -255.35435)
			(xy 354.664221 -255.401535) (xy 354.680107 -255.451734) (xy 354.688144 -255.50377) (xy 354.688648 -255.530096)
			(xy 365.036865 -255.530096) (xy 365.040895 -255.477598) (xy 365.052892 -255.42633) (xy 365.072575 -255.377495)
			(xy 365.099481 -255.332236) (xy 365.132981 -255.291615) (xy 365.172289 -255.256584) (xy 365.216484 -255.227964)
			(xy 365.264529 -255.206425) (xy 365.3153 -255.192473) (xy 365.367605 -255.186435) (xy 365.420219 -255.188452)
			(xy 365.471909 -255.198476) (xy 365.521462 -255.216274) (xy 365.567718 -255.241427) (xy 365.609592 -255.273346)
			(xy 365.646104 -255.311284) (xy 365.676396 -255.35435) (xy 365.699759 -255.401535) (xy 365.715645 -255.451734)
			(xy 365.723682 -255.50377) (xy 365.724186 -255.530096) (xy 365.723682 -255.556422) (xy 365.715645 -255.608458)
			(xy 365.699759 -255.658657) (xy 365.676396 -255.705842) (xy 365.646104 -255.748908) (xy 365.609592 -255.786846)
			(xy 365.567718 -255.818765) (xy 365.557672 -255.824228) (xy 368.809028 -255.824228) (xy 368.812988 -255.775174)
			(xy 368.824765 -255.72739) (xy 368.844056 -255.682114) (xy 368.870359 -255.640518) (xy 368.902994 -255.603681)
			(xy 368.941115 -255.572556) (xy 368.983736 -255.547949) (xy 369.029752 -255.530497) (xy 369.077971 -255.520653)
			(xy 369.127146 -255.518672) (xy 369.176001 -255.524604) (xy 369.223272 -255.538296) (xy 369.267734 -255.559394)
			(xy 369.308237 -255.58735) (xy 369.34373 -255.621442) (xy 369.373295 -255.660786) (xy 369.396166 -255.704363)
			(xy 369.41175 -255.751044) (xy 369.419645 -255.799621) (xy 369.42014 -255.824228) (xy 370.688882 -255.824228)
			(xy 370.692842 -255.775174) (xy 370.704619 -255.72739) (xy 370.72391 -255.682114) (xy 370.750213 -255.640518)
			(xy 370.782848 -255.603681) (xy 370.820969 -255.572556) (xy 370.86359 -255.547949) (xy 370.909606 -255.530497)
			(xy 370.957825 -255.520653) (xy 371.007 -255.518672) (xy 371.055855 -255.524604) (xy 371.103126 -255.538296)
			(xy 371.147588 -255.559394) (xy 371.188091 -255.58735) (xy 371.223584 -255.621442) (xy 371.253149 -255.660786)
			(xy 371.27602 -255.704363) (xy 371.291604 -255.751044) (xy 371.299499 -255.799621) (xy 371.299994 -255.824228)
			(xy 372.56899 -255.824228) (xy 372.57295 -255.775174) (xy 372.584727 -255.72739) (xy 372.604018 -255.682114)
			(xy 372.630321 -255.640518) (xy 372.662956 -255.603681) (xy 372.701077 -255.572556) (xy 372.743698 -255.547949)
			(xy 372.789714 -255.530497) (xy 372.837933 -255.520653) (xy 372.887108 -255.518672) (xy 372.935963 -255.524604)
			(xy 372.983234 -255.538296) (xy 373.027696 -255.559394) (xy 373.068199 -255.58735) (xy 373.103692 -255.621442)
			(xy 373.133257 -255.660786) (xy 373.156128 -255.704363) (xy 373.171712 -255.751044) (xy 373.179607 -255.799621)
			(xy 373.180102 -255.824228) (xy 374.449098 -255.824228) (xy 374.453058 -255.775174) (xy 374.464835 -255.72739)
			(xy 374.484126 -255.682114) (xy 374.510429 -255.640518) (xy 374.543064 -255.603681) (xy 374.581185 -255.572556)
			(xy 374.623806 -255.547949) (xy 374.669822 -255.530497) (xy 374.718041 -255.520653) (xy 374.767216 -255.518672)
			(xy 374.816071 -255.524604) (xy 374.863342 -255.538296) (xy 374.907804 -255.559394) (xy 374.948307 -255.58735)
			(xy 374.9838 -255.621442) (xy 375.013365 -255.660786) (xy 375.036236 -255.704363) (xy 375.05182 -255.751044)
			(xy 375.059715 -255.799621) (xy 375.06021 -255.824228) (xy 375.378467 -255.824228) (xy 375.382562 -255.7735)
			(xy 375.394741 -255.724086) (xy 375.414689 -255.677266) (xy 375.44189 -255.634252) (xy 375.475638 -255.596158)
			(xy 375.51506 -255.563971) (xy 375.559134 -255.538525) (xy 375.60672 -255.520478) (xy 375.656584 -255.510298)
			(xy 375.707436 -255.508249) (xy 375.757957 -255.514383) (xy 375.806841 -255.528543) (xy 375.85282 -255.55036)
			(xy 375.894704 -255.57927) (xy 375.931408 -255.614525) (xy 375.961981 -255.655211) (xy 375.985632 -255.700274)
			(xy 376.001748 -255.748548) (xy 376.009912 -255.798782) (xy 376.010424 -255.824228) (xy 376.328952 -255.824228)
			(xy 376.332912 -255.775174) (xy 376.344689 -255.72739) (xy 376.36398 -255.682114) (xy 376.390283 -255.640518)
			(xy 376.422918 -255.603681) (xy 376.461039 -255.572556) (xy 376.50366 -255.547949) (xy 376.549676 -255.530497)
			(xy 376.597895 -255.520653) (xy 376.64707 -255.518672) (xy 376.695925 -255.524604) (xy 376.743196 -255.538296)
			(xy 376.787658 -255.559394) (xy 376.828161 -255.58735) (xy 376.863654 -255.621442) (xy 376.893219 -255.660786)
			(xy 376.91609 -255.704363) (xy 376.931674 -255.751044) (xy 376.939569 -255.799621) (xy 376.940064 -255.824228)
			(xy 377.258575 -255.824228) (xy 377.26267 -255.7735) (xy 377.274849 -255.724086) (xy 377.294797 -255.677266)
			(xy 377.321998 -255.634252) (xy 377.355746 -255.596158) (xy 377.395168 -255.563971) (xy 377.439242 -255.538525)
			(xy 377.486828 -255.520478) (xy 377.536692 -255.510298) (xy 377.587544 -255.508249) (xy 377.638065 -255.514383)
			(xy 377.686949 -255.528543) (xy 377.732928 -255.55036) (xy 377.774812 -255.57927) (xy 377.811516 -255.614525)
			(xy 377.842089 -255.655211) (xy 377.86574 -255.700274) (xy 377.881856 -255.748548) (xy 377.89002 -255.798782)
			(xy 377.890532 -255.824228) (xy 378.20906 -255.824228) (xy 378.21302 -255.775174) (xy 378.224797 -255.72739)
			(xy 378.244088 -255.682114) (xy 378.270391 -255.640518) (xy 378.303026 -255.603681) (xy 378.341147 -255.572556)
			(xy 378.383768 -255.547949) (xy 378.429784 -255.530497) (xy 378.478003 -255.520653) (xy 378.527178 -255.518672)
			(xy 378.576033 -255.524604) (xy 378.623304 -255.538296) (xy 378.667766 -255.559394) (xy 378.708269 -255.58735)
			(xy 378.743762 -255.621442) (xy 378.773327 -255.660786) (xy 378.796198 -255.704363) (xy 378.811782 -255.751044)
			(xy 378.819677 -255.799621) (xy 378.820172 -255.824228) (xy 379.138683 -255.824228) (xy 379.142778 -255.7735)
			(xy 379.154957 -255.724086) (xy 379.174905 -255.677266) (xy 379.202106 -255.634252) (xy 379.235854 -255.596158)
			(xy 379.275276 -255.563971) (xy 379.31935 -255.538525) (xy 379.366936 -255.520478) (xy 379.4168 -255.510298)
			(xy 379.467652 -255.508249) (xy 379.518173 -255.514383) (xy 379.567057 -255.528543) (xy 379.613036 -255.55036)
			(xy 379.65492 -255.57927) (xy 379.691624 -255.614525) (xy 379.722197 -255.655211) (xy 379.745848 -255.700274)
			(xy 379.761964 -255.748548) (xy 379.770128 -255.798782) (xy 379.77064 -255.824228) (xy 380.078483 -255.824228)
			(xy 380.082578 -255.7735) (xy 380.094757 -255.724086) (xy 380.114705 -255.677266) (xy 380.141906 -255.634252)
			(xy 380.175654 -255.596158) (xy 380.215076 -255.563971) (xy 380.25915 -255.538525) (xy 380.306736 -255.520478)
			(xy 380.3566 -255.510298) (xy 380.407452 -255.508249) (xy 380.457973 -255.514383) (xy 380.506857 -255.528543)
			(xy 380.552836 -255.55036) (xy 380.59472 -255.57927) (xy 380.631424 -255.614525) (xy 380.661997 -255.655211)
			(xy 380.685648 -255.700274) (xy 380.701764 -255.748548) (xy 380.709928 -255.798782) (xy 380.71044 -255.824228)
			(xy 381.028968 -255.824228) (xy 381.032928 -255.775174) (xy 381.044705 -255.72739) (xy 381.063996 -255.682114)
			(xy 381.090299 -255.640518) (xy 381.122934 -255.603681) (xy 381.161055 -255.572556) (xy 381.203676 -255.547949)
			(xy 381.249692 -255.530497) (xy 381.297911 -255.520653) (xy 381.347086 -255.518672) (xy 381.395941 -255.524604)
			(xy 381.443212 -255.538296) (xy 381.487674 -255.559394) (xy 381.528177 -255.58735) (xy 381.56367 -255.621442)
			(xy 381.593235 -255.660786) (xy 381.616106 -255.704363) (xy 381.63169 -255.751044) (xy 381.639585 -255.799621)
			(xy 381.64008 -255.824228) (xy 381.958591 -255.824228) (xy 381.962686 -255.7735) (xy 381.974865 -255.724086)
			(xy 381.994813 -255.677266) (xy 382.022014 -255.634252) (xy 382.055762 -255.596158) (xy 382.095184 -255.563971)
			(xy 382.139258 -255.538525) (xy 382.186844 -255.520478) (xy 382.236708 -255.510298) (xy 382.28756 -255.508249)
			(xy 382.338081 -255.514383) (xy 382.386965 -255.528543) (xy 382.432944 -255.55036) (xy 382.474828 -255.57927)
			(xy 382.511532 -255.614525) (xy 382.542105 -255.655211) (xy 382.565756 -255.700274) (xy 382.581872 -255.748548)
			(xy 382.590036 -255.798782) (xy 382.590548 -255.824228) (xy 382.909076 -255.824228) (xy 382.913036 -255.775174)
			(xy 382.924813 -255.72739) (xy 382.944104 -255.682114) (xy 382.970407 -255.640518) (xy 383.003042 -255.603681)
			(xy 383.041163 -255.572556) (xy 383.083784 -255.547949) (xy 383.1298 -255.530497) (xy 383.178019 -255.520653)
			(xy 383.227194 -255.518672) (xy 383.276049 -255.524604) (xy 383.32332 -255.538296) (xy 383.367782 -255.559394)
			(xy 383.408285 -255.58735) (xy 383.443778 -255.621442) (xy 383.473343 -255.660786) (xy 383.496214 -255.704363)
			(xy 383.511798 -255.751044) (xy 383.519693 -255.799621) (xy 383.520188 -255.824228) (xy 383.838699 -255.824228)
			(xy 383.842794 -255.7735) (xy 383.854973 -255.724086) (xy 383.874921 -255.677266) (xy 383.902122 -255.634252)
			(xy 383.93587 -255.596158) (xy 383.975292 -255.563971) (xy 384.019366 -255.538525) (xy 384.066952 -255.520478)
			(xy 384.116816 -255.510298) (xy 384.167668 -255.508249) (xy 384.218189 -255.514383) (xy 384.267073 -255.528543)
			(xy 384.313052 -255.55036) (xy 384.354936 -255.57927) (xy 384.39164 -255.614525) (xy 384.422213 -255.655211)
			(xy 384.445864 -255.700274) (xy 384.46198 -255.748548) (xy 384.470144 -255.798782) (xy 384.470656 -255.824228)
			(xy 384.78893 -255.824228) (xy 384.79289 -255.775174) (xy 384.804667 -255.72739) (xy 384.823958 -255.682114)
			(xy 384.850261 -255.640518) (xy 384.882896 -255.603681) (xy 384.921017 -255.572556) (xy 384.963638 -255.547949)
			(xy 385.009654 -255.530497) (xy 385.057873 -255.520653) (xy 385.107048 -255.518672) (xy 385.155903 -255.524604)
			(xy 385.203174 -255.538296) (xy 385.247636 -255.559394) (xy 385.288139 -255.58735) (xy 385.323632 -255.621442)
			(xy 385.353197 -255.660786) (xy 385.376068 -255.704363) (xy 385.391652 -255.751044) (xy 385.399547 -255.799621)
			(xy 385.400042 -255.824228) (xy 385.718553 -255.824228) (xy 385.722648 -255.7735) (xy 385.734827 -255.724086)
			(xy 385.754775 -255.677266) (xy 385.781976 -255.634252) (xy 385.815724 -255.596158) (xy 385.855146 -255.563971)
			(xy 385.89922 -255.538525) (xy 385.946806 -255.520478) (xy 385.99667 -255.510298) (xy 386.047522 -255.508249)
			(xy 386.098043 -255.514383) (xy 386.146927 -255.528543) (xy 386.192906 -255.55036) (xy 386.23479 -255.57927)
			(xy 386.271494 -255.614525) (xy 386.302067 -255.655211) (xy 386.325718 -255.700274) (xy 386.341834 -255.748548)
			(xy 386.349998 -255.798782) (xy 386.35051 -255.824228) (xy 386.658607 -255.824228) (xy 386.662702 -255.7735)
			(xy 386.674881 -255.724086) (xy 386.694829 -255.677266) (xy 386.72203 -255.634252) (xy 386.755778 -255.596158)
			(xy 386.7952 -255.563971) (xy 386.839274 -255.538525) (xy 386.88686 -255.520478) (xy 386.936724 -255.510298)
			(xy 386.987576 -255.508249) (xy 387.038097 -255.514383) (xy 387.086981 -255.528543) (xy 387.13296 -255.55036)
			(xy 387.174844 -255.57927) (xy 387.211548 -255.614525) (xy 387.242121 -255.655211) (xy 387.265772 -255.700274)
			(xy 387.281888 -255.748548) (xy 387.290052 -255.798782) (xy 387.290564 -255.824228) (xy 387.609092 -255.824228)
			(xy 387.613052 -255.775174) (xy 387.624829 -255.72739) (xy 387.64412 -255.682114) (xy 387.670423 -255.640518)
			(xy 387.703058 -255.603681) (xy 387.741179 -255.572556) (xy 387.7838 -255.547949) (xy 387.829816 -255.530497)
			(xy 387.878035 -255.520653) (xy 387.92721 -255.518672) (xy 387.976065 -255.524604) (xy 388.023336 -255.538296)
			(xy 388.067798 -255.559394) (xy 388.108301 -255.58735) (xy 388.143794 -255.621442) (xy 388.173359 -255.660786)
			(xy 388.19623 -255.704363) (xy 388.211814 -255.751044) (xy 388.219709 -255.799621) (xy 388.220204 -255.824228)
			(xy 388.538715 -255.824228) (xy 388.54281 -255.7735) (xy 388.554989 -255.724086) (xy 388.574937 -255.677266)
			(xy 388.602138 -255.634252) (xy 388.635886 -255.596158) (xy 388.675308 -255.563971) (xy 388.719382 -255.538525)
			(xy 388.766968 -255.520478) (xy 388.816832 -255.510298) (xy 388.867684 -255.508249) (xy 388.918205 -255.514383)
			(xy 388.967089 -255.528543) (xy 389.013068 -255.55036) (xy 389.054952 -255.57927) (xy 389.091656 -255.614525)
			(xy 389.122229 -255.655211) (xy 389.14588 -255.700274) (xy 389.161996 -255.748548) (xy 389.17016 -255.798782)
			(xy 389.170672 -255.824228) (xy 389.488946 -255.824228) (xy 389.492906 -255.775174) (xy 389.504683 -255.72739)
			(xy 389.523974 -255.682114) (xy 389.550277 -255.640518) (xy 389.582912 -255.603681) (xy 389.621033 -255.572556)
			(xy 389.663654 -255.547949) (xy 389.70967 -255.530497) (xy 389.757889 -255.520653) (xy 389.807064 -255.518672)
			(xy 389.855919 -255.524604) (xy 389.90319 -255.538296) (xy 389.947652 -255.559394) (xy 389.988155 -255.58735)
			(xy 390.023648 -255.621442) (xy 390.053213 -255.660786) (xy 390.076084 -255.704363) (xy 390.091668 -255.751044)
			(xy 390.099563 -255.799621) (xy 390.100058 -255.824228) (xy 390.418569 -255.824228) (xy 390.422664 -255.7735)
			(xy 390.434843 -255.724086) (xy 390.454791 -255.677266) (xy 390.481992 -255.634252) (xy 390.51574 -255.596158)
			(xy 390.555162 -255.563971) (xy 390.599236 -255.538525) (xy 390.646822 -255.520478) (xy 390.696686 -255.510298)
			(xy 390.747538 -255.508249) (xy 390.798059 -255.514383) (xy 390.846943 -255.528543) (xy 390.892922 -255.55036)
			(xy 390.934806 -255.57927) (xy 390.97151 -255.614525) (xy 391.002083 -255.655211) (xy 391.025734 -255.700274)
			(xy 391.04185 -255.748548) (xy 391.050014 -255.798782) (xy 391.050526 -255.824228) (xy 391.369054 -255.824228)
			(xy 391.373014 -255.775174) (xy 391.384791 -255.72739) (xy 391.404082 -255.682114) (xy 391.430385 -255.640518)
			(xy 391.46302 -255.603681) (xy 391.501141 -255.572556) (xy 391.543762 -255.547949) (xy 391.589778 -255.530497)
			(xy 391.637997 -255.520653) (xy 391.687172 -255.518672) (xy 391.736027 -255.524604) (xy 391.783298 -255.538296)
			(xy 391.82776 -255.559394) (xy 391.868263 -255.58735) (xy 391.903756 -255.621442) (xy 391.933321 -255.660786)
			(xy 391.956192 -255.704363) (xy 391.971776 -255.751044) (xy 391.979671 -255.799621) (xy 391.980166 -255.824228)
			(xy 391.979671 -255.848835) (xy 391.971776 -255.897412) (xy 391.956192 -255.944093) (xy 391.933321 -255.98767)
			(xy 391.903756 -256.027014) (xy 391.868263 -256.061106) (xy 391.82776 -256.089062) (xy 391.825433 -256.090166)
			(xy 394.377176 -256.090166) (xy 394.381136 -256.041112) (xy 394.392913 -255.993328) (xy 394.412204 -255.948052)
			(xy 394.438507 -255.906456) (xy 394.471142 -255.869619) (xy 394.509263 -255.838494) (xy 394.551884 -255.813887)
			(xy 394.5979 -255.796435) (xy 394.646119 -255.786591) (xy 394.695294 -255.78461) (xy 394.744149 -255.790542)
			(xy 394.79142 -255.804234) (xy 394.835882 -255.825332) (xy 394.876385 -255.853288) (xy 394.911878 -255.88738)
			(xy 394.941443 -255.926724) (xy 394.964314 -255.970301) (xy 394.979898 -256.016982) (xy 394.987793 -256.065559)
			(xy 394.988288 -256.090166) (xy 394.987793 -256.114773) (xy 394.979898 -256.16335) (xy 394.964314 -256.210031)
			(xy 394.941443 -256.253608) (xy 394.911878 -256.292952) (xy 394.876385 -256.327044) (xy 394.835882 -256.355)
			(xy 394.79142 -256.376098) (xy 394.744149 -256.38979) (xy 394.695294 -256.395722) (xy 394.646119 -256.393741)
			(xy 394.5979 -256.383897) (xy 394.551884 -256.366445) (xy 394.509263 -256.341838) (xy 394.471142 -256.310713)
			(xy 394.438507 -256.273876) (xy 394.412204 -256.23228) (xy 394.392913 -256.187004) (xy 394.381136 -256.13922)
			(xy 394.377176 -256.090166) (xy 391.825433 -256.090166) (xy 391.783298 -256.11016) (xy 391.736027 -256.123852)
			(xy 391.687172 -256.129784) (xy 391.637997 -256.127803) (xy 391.589778 -256.117959) (xy 391.543762 -256.100507)
			(xy 391.501141 -256.0759) (xy 391.46302 -256.044775) (xy 391.430385 -256.007938) (xy 391.404082 -255.966342)
			(xy 391.384791 -255.921066) (xy 391.373014 -255.873282) (xy 391.369054 -255.824228) (xy 391.050526 -255.824228)
			(xy 391.050014 -255.849674) (xy 391.04185 -255.899908) (xy 391.025734 -255.948182) (xy 391.002083 -255.993245)
			(xy 390.97151 -256.033931) (xy 390.934806 -256.069186) (xy 390.892922 -256.098096) (xy 390.846943 -256.119913)
			(xy 390.798059 -256.134073) (xy 390.747538 -256.140207) (xy 390.696686 -256.138158) (xy 390.646822 -256.127978)
			(xy 390.599236 -256.109931) (xy 390.555162 -256.084485) (xy 390.51574 -256.052298) (xy 390.481992 -256.014204)
			(xy 390.454791 -255.97119) (xy 390.434843 -255.92437) (xy 390.422664 -255.874956) (xy 390.418569 -255.824228)
			(xy 390.100058 -255.824228) (xy 390.099563 -255.848835) (xy 390.091668 -255.897412) (xy 390.076084 -255.944093)
			(xy 390.053213 -255.98767) (xy 390.023648 -256.027014) (xy 389.988155 -256.061106) (xy 389.947652 -256.089062)
			(xy 389.90319 -256.11016) (xy 389.855919 -256.123852) (xy 389.807064 -256.129784) (xy 389.757889 -256.127803)
			(xy 389.70967 -256.117959) (xy 389.663654 -256.100507) (xy 389.621033 -256.0759) (xy 389.582912 -256.044775)
			(xy 389.550277 -256.007938) (xy 389.523974 -255.966342) (xy 389.504683 -255.921066) (xy 389.492906 -255.873282)
			(xy 389.488946 -255.824228) (xy 389.170672 -255.824228) (xy 389.17016 -255.849674) (xy 389.161996 -255.899908)
			(xy 389.14588 -255.948182) (xy 389.122229 -255.993245) (xy 389.091656 -256.033931) (xy 389.054952 -256.069186)
			(xy 389.013068 -256.098096) (xy 388.967089 -256.119913) (xy 388.918205 -256.134073) (xy 388.867684 -256.140207)
			(xy 388.816832 -256.138158) (xy 388.766968 -256.127978) (xy 388.719382 -256.109931) (xy 388.675308 -256.084485)
			(xy 388.635886 -256.052298) (xy 388.602138 -256.014204) (xy 388.574937 -255.97119) (xy 388.554989 -255.92437)
			(xy 388.54281 -255.874956) (xy 388.538715 -255.824228) (xy 388.220204 -255.824228) (xy 388.219709 -255.848835)
			(xy 388.211814 -255.897412) (xy 388.19623 -255.944093) (xy 388.173359 -255.98767) (xy 388.143794 -256.027014)
			(xy 388.108301 -256.061106) (xy 388.067798 -256.089062) (xy 388.023336 -256.11016) (xy 387.976065 -256.123852)
			(xy 387.92721 -256.129784) (xy 387.878035 -256.127803) (xy 387.829816 -256.117959) (xy 387.7838 -256.100507)
			(xy 387.741179 -256.0759) (xy 387.703058 -256.044775) (xy 387.670423 -256.007938) (xy 387.64412 -255.966342)
			(xy 387.624829 -255.921066) (xy 387.613052 -255.873282) (xy 387.609092 -255.824228) (xy 387.290564 -255.824228)
			(xy 387.290052 -255.849674) (xy 387.281888 -255.899908) (xy 387.265772 -255.948182) (xy 387.242121 -255.993245)
			(xy 387.211548 -256.033931) (xy 387.174844 -256.069186) (xy 387.13296 -256.098096) (xy 387.086981 -256.119913)
			(xy 387.038097 -256.134073) (xy 386.987576 -256.140207) (xy 386.936724 -256.138158) (xy 386.88686 -256.127978)
			(xy 386.839274 -256.109931) (xy 386.7952 -256.084485) (xy 386.755778 -256.052298) (xy 386.72203 -256.014204)
			(xy 386.694829 -255.97119) (xy 386.674881 -255.92437) (xy 386.662702 -255.874956) (xy 386.658607 -255.824228)
			(xy 386.35051 -255.824228) (xy 386.349998 -255.849674) (xy 386.341834 -255.899908) (xy 386.325718 -255.948182)
			(xy 386.302067 -255.993245) (xy 386.271494 -256.033931) (xy 386.23479 -256.069186) (xy 386.192906 -256.098096)
			(xy 386.146927 -256.119913) (xy 386.098043 -256.134073) (xy 386.047522 -256.140207) (xy 385.99667 -256.138158)
			(xy 385.946806 -256.127978) (xy 385.89922 -256.109931) (xy 385.855146 -256.084485) (xy 385.815724 -256.052298)
			(xy 385.781976 -256.014204) (xy 385.754775 -255.97119) (xy 385.734827 -255.92437) (xy 385.722648 -255.874956)
			(xy 385.718553 -255.824228) (xy 385.400042 -255.824228) (xy 385.399547 -255.848835) (xy 385.391652 -255.897412)
			(xy 385.376068 -255.944093) (xy 385.353197 -255.98767) (xy 385.323632 -256.027014) (xy 385.288139 -256.061106)
			(xy 385.247636 -256.089062) (xy 385.203174 -256.11016) (xy 385.155903 -256.123852) (xy 385.107048 -256.129784)
			(xy 385.057873 -256.127803) (xy 385.009654 -256.117959) (xy 384.963638 -256.100507) (xy 384.921017 -256.0759)
			(xy 384.882896 -256.044775) (xy 384.850261 -256.007938) (xy 384.823958 -255.966342) (xy 384.804667 -255.921066)
			(xy 384.79289 -255.873282) (xy 384.78893 -255.824228) (xy 384.470656 -255.824228) (xy 384.470144 -255.849674)
			(xy 384.46198 -255.899908) (xy 384.445864 -255.948182) (xy 384.422213 -255.993245) (xy 384.39164 -256.033931)
			(xy 384.354936 -256.069186) (xy 384.313052 -256.098096) (xy 384.267073 -256.119913) (xy 384.218189 -256.134073)
			(xy 384.167668 -256.140207) (xy 384.116816 -256.138158) (xy 384.066952 -256.127978) (xy 384.019366 -256.109931)
			(xy 383.975292 -256.084485) (xy 383.93587 -256.052298) (xy 383.902122 -256.014204) (xy 383.874921 -255.97119)
			(xy 383.854973 -255.92437) (xy 383.842794 -255.874956) (xy 383.838699 -255.824228) (xy 383.520188 -255.824228)
			(xy 383.519693 -255.848835) (xy 383.511798 -255.897412) (xy 383.496214 -255.944093) (xy 383.473343 -255.98767)
			(xy 383.443778 -256.027014) (xy 383.408285 -256.061106) (xy 383.367782 -256.089062) (xy 383.32332 -256.11016)
			(xy 383.276049 -256.123852) (xy 383.227194 -256.129784) (xy 383.178019 -256.127803) (xy 383.1298 -256.117959)
			(xy 383.083784 -256.100507) (xy 383.041163 -256.0759) (xy 383.003042 -256.044775) (xy 382.970407 -256.007938)
			(xy 382.944104 -255.966342) (xy 382.924813 -255.921066) (xy 382.913036 -255.873282) (xy 382.909076 -255.824228)
			(xy 382.590548 -255.824228) (xy 382.590036 -255.849674) (xy 382.581872 -255.899908) (xy 382.565756 -255.948182)
			(xy 382.542105 -255.993245) (xy 382.511532 -256.033931) (xy 382.474828 -256.069186) (xy 382.432944 -256.098096)
			(xy 382.386965 -256.119913) (xy 382.338081 -256.134073) (xy 382.28756 -256.140207) (xy 382.236708 -256.138158)
			(xy 382.186844 -256.127978) (xy 382.139258 -256.109931) (xy 382.095184 -256.084485) (xy 382.055762 -256.052298)
			(xy 382.022014 -256.014204) (xy 381.994813 -255.97119) (xy 381.974865 -255.92437) (xy 381.962686 -255.874956)
			(xy 381.958591 -255.824228) (xy 381.64008 -255.824228) (xy 381.639585 -255.848835) (xy 381.63169 -255.897412)
			(xy 381.616106 -255.944093) (xy 381.593235 -255.98767) (xy 381.56367 -256.027014) (xy 381.528177 -256.061106)
			(xy 381.487674 -256.089062) (xy 381.443212 -256.11016) (xy 381.395941 -256.123852) (xy 381.347086 -256.129784)
			(xy 381.297911 -256.127803) (xy 381.249692 -256.117959) (xy 381.203676 -256.100507) (xy 381.161055 -256.0759)
			(xy 381.122934 -256.044775) (xy 381.090299 -256.007938) (xy 381.063996 -255.966342) (xy 381.044705 -255.921066)
			(xy 381.032928 -255.873282) (xy 381.028968 -255.824228) (xy 380.71044 -255.824228) (xy 380.709928 -255.849674)
			(xy 380.701764 -255.899908) (xy 380.685648 -255.948182) (xy 380.661997 -255.993245) (xy 380.631424 -256.033931)
			(xy 380.59472 -256.069186) (xy 380.552836 -256.098096) (xy 380.506857 -256.119913) (xy 380.457973 -256.134073)
			(xy 380.407452 -256.140207) (xy 380.3566 -256.138158) (xy 380.306736 -256.127978) (xy 380.25915 -256.109931)
			(xy 380.215076 -256.084485) (xy 380.175654 -256.052298) (xy 380.141906 -256.014204) (xy 380.114705 -255.97119)
			(xy 380.094757 -255.92437) (xy 380.082578 -255.874956) (xy 380.078483 -255.824228) (xy 379.77064 -255.824228)
			(xy 379.770128 -255.849674) (xy 379.761964 -255.899908) (xy 379.745848 -255.948182) (xy 379.722197 -255.993245)
			(xy 379.691624 -256.033931) (xy 379.65492 -256.069186) (xy 379.613036 -256.098096) (xy 379.567057 -256.119913)
			(xy 379.518173 -256.134073) (xy 379.467652 -256.140207) (xy 379.4168 -256.138158) (xy 379.366936 -256.127978)
			(xy 379.31935 -256.109931) (xy 379.275276 -256.084485) (xy 379.235854 -256.052298) (xy 379.202106 -256.014204)
			(xy 379.174905 -255.97119) (xy 379.154957 -255.92437) (xy 379.142778 -255.874956) (xy 379.138683 -255.824228)
			(xy 378.820172 -255.824228) (xy 378.819677 -255.848835) (xy 378.811782 -255.897412) (xy 378.796198 -255.944093)
			(xy 378.773327 -255.98767) (xy 378.743762 -256.027014) (xy 378.708269 -256.061106) (xy 378.667766 -256.089062)
			(xy 378.623304 -256.11016) (xy 378.576033 -256.123852) (xy 378.527178 -256.129784) (xy 378.478003 -256.127803)
			(xy 378.429784 -256.117959) (xy 378.383768 -256.100507) (xy 378.341147 -256.0759) (xy 378.303026 -256.044775)
			(xy 378.270391 -256.007938) (xy 378.244088 -255.966342) (xy 378.224797 -255.921066) (xy 378.21302 -255.873282)
			(xy 378.20906 -255.824228) (xy 377.890532 -255.824228) (xy 377.89002 -255.849674) (xy 377.881856 -255.899908)
			(xy 377.86574 -255.948182) (xy 377.842089 -255.993245) (xy 377.811516 -256.033931) (xy 377.774812 -256.069186)
			(xy 377.732928 -256.098096) (xy 377.686949 -256.119913) (xy 377.638065 -256.134073) (xy 377.587544 -256.140207)
			(xy 377.536692 -256.138158) (xy 377.486828 -256.127978) (xy 377.439242 -256.109931) (xy 377.395168 -256.084485)
			(xy 377.355746 -256.052298) (xy 377.321998 -256.014204) (xy 377.294797 -255.97119) (xy 377.274849 -255.92437)
			(xy 377.26267 -255.874956) (xy 377.258575 -255.824228) (xy 376.940064 -255.824228) (xy 376.939569 -255.848835)
			(xy 376.931674 -255.897412) (xy 376.91609 -255.944093) (xy 376.893219 -255.98767) (xy 376.863654 -256.027014)
			(xy 376.828161 -256.061106) (xy 376.787658 -256.089062) (xy 376.743196 -256.11016) (xy 376.695925 -256.123852)
			(xy 376.64707 -256.129784) (xy 376.597895 -256.127803) (xy 376.549676 -256.117959) (xy 376.50366 -256.100507)
			(xy 376.461039 -256.0759) (xy 376.422918 -256.044775) (xy 376.390283 -256.007938) (xy 376.36398 -255.966342)
			(xy 376.344689 -255.921066) (xy 376.332912 -255.873282) (xy 376.328952 -255.824228) (xy 376.010424 -255.824228)
			(xy 376.009912 -255.849674) (xy 376.001748 -255.899908) (xy 375.985632 -255.948182) (xy 375.961981 -255.993245)
			(xy 375.931408 -256.033931) (xy 375.894704 -256.069186) (xy 375.85282 -256.098096) (xy 375.806841 -256.119913)
			(xy 375.757957 -256.134073) (xy 375.707436 -256.140207) (xy 375.656584 -256.138158) (xy 375.60672 -256.127978)
			(xy 375.559134 -256.109931) (xy 375.51506 -256.084485) (xy 375.475638 -256.052298) (xy 375.44189 -256.014204)
			(xy 375.414689 -255.97119) (xy 375.394741 -255.92437) (xy 375.382562 -255.874956) (xy 375.378467 -255.824228)
			(xy 375.06021 -255.824228) (xy 375.059715 -255.848835) (xy 375.05182 -255.897412) (xy 375.036236 -255.944093)
			(xy 375.013365 -255.98767) (xy 374.9838 -256.027014) (xy 374.948307 -256.061106) (xy 374.907804 -256.089062)
			(xy 374.863342 -256.11016) (xy 374.816071 -256.123852) (xy 374.767216 -256.129784) (xy 374.718041 -256.127803)
			(xy 374.669822 -256.117959) (xy 374.623806 -256.100507) (xy 374.581185 -256.0759) (xy 374.543064 -256.044775)
			(xy 374.510429 -256.007938) (xy 374.484126 -255.966342) (xy 374.464835 -255.921066) (xy 374.453058 -255.873282)
			(xy 374.449098 -255.824228) (xy 373.180102 -255.824228) (xy 373.179607 -255.848835) (xy 373.171712 -255.897412)
			(xy 373.156128 -255.944093) (xy 373.133257 -255.98767) (xy 373.103692 -256.027014) (xy 373.068199 -256.061106)
			(xy 373.027696 -256.089062) (xy 372.983234 -256.11016) (xy 372.935963 -256.123852) (xy 372.887108 -256.129784)
			(xy 372.837933 -256.127803) (xy 372.789714 -256.117959) (xy 372.743698 -256.100507) (xy 372.701077 -256.0759)
			(xy 372.662956 -256.044775) (xy 372.630321 -256.007938) (xy 372.604018 -255.966342) (xy 372.584727 -255.921066)
			(xy 372.57295 -255.873282) (xy 372.56899 -255.824228) (xy 371.299994 -255.824228) (xy 371.299499 -255.848835)
			(xy 371.291604 -255.897412) (xy 371.27602 -255.944093) (xy 371.253149 -255.98767) (xy 371.223584 -256.027014)
			(xy 371.188091 -256.061106) (xy 371.147588 -256.089062) (xy 371.103126 -256.11016) (xy 371.055855 -256.123852)
			(xy 371.007 -256.129784) (xy 370.957825 -256.127803) (xy 370.909606 -256.117959) (xy 370.86359 -256.100507)
			(xy 370.820969 -256.0759) (xy 370.782848 -256.044775) (xy 370.750213 -256.007938) (xy 370.72391 -255.966342)
			(xy 370.704619 -255.921066) (xy 370.692842 -255.873282) (xy 370.688882 -255.824228) (xy 369.42014 -255.824228)
			(xy 369.419645 -255.848835) (xy 369.41175 -255.897412) (xy 369.396166 -255.944093) (xy 369.373295 -255.98767)
			(xy 369.34373 -256.027014) (xy 369.308237 -256.061106) (xy 369.267734 -256.089062) (xy 369.223272 -256.11016)
			(xy 369.176001 -256.123852) (xy 369.127146 -256.129784) (xy 369.077971 -256.127803) (xy 369.029752 -256.117959)
			(xy 368.983736 -256.100507) (xy 368.941115 -256.0759) (xy 368.902994 -256.044775) (xy 368.870359 -256.007938)
			(xy 368.844056 -255.966342) (xy 368.824765 -255.921066) (xy 368.812988 -255.873282) (xy 368.809028 -255.824228)
			(xy 365.557672 -255.824228) (xy 365.521462 -255.843918) (xy 365.471909 -255.861716) (xy 365.420219 -255.87174)
			(xy 365.367605 -255.873757) (xy 365.3153 -255.867719) (xy 365.264529 -255.853767) (xy 365.216484 -255.832228)
			(xy 365.172289 -255.803608) (xy 365.132981 -255.768577) (xy 365.099481 -255.727956) (xy 365.072575 -255.682697)
			(xy 365.052892 -255.633862) (xy 365.040895 -255.582594) (xy 365.036865 -255.530096) (xy 354.688648 -255.530096)
			(xy 354.688144 -255.556422) (xy 354.680107 -255.608458) (xy 354.664221 -255.658657) (xy 354.640858 -255.705842)
			(xy 354.610566 -255.748908) (xy 354.574054 -255.786846) (xy 354.53218 -255.818765) (xy 354.485924 -255.843918)
			(xy 354.436371 -255.861716) (xy 354.384681 -255.87174) (xy 354.332067 -255.873757) (xy 354.279762 -255.867719)
			(xy 354.228991 -255.853767) (xy 354.180946 -255.832228) (xy 354.136751 -255.803608) (xy 354.097443 -255.768577)
			(xy 354.063943 -255.727956) (xy 354.037037 -255.682697) (xy 354.017354 -255.633862) (xy 354.005357 -255.582594)
			(xy 354.001327 -255.530096) (xy 353.774248 -255.530096) (xy 353.773744 -255.556422) (xy 353.765707 -255.608458)
			(xy 353.749821 -255.658657) (xy 353.726458 -255.705842) (xy 353.696166 -255.748908) (xy 353.659654 -255.786846)
			(xy 353.61778 -255.818765) (xy 353.571524 -255.843918) (xy 353.521971 -255.861716) (xy 353.470281 -255.87174)
			(xy 353.417667 -255.873757) (xy 353.365362 -255.867719) (xy 353.314591 -255.853767) (xy 353.266546 -255.832228)
			(xy 353.222351 -255.803608) (xy 353.183043 -255.768577) (xy 353.149543 -255.727956) (xy 353.122637 -255.682697)
			(xy 353.102954 -255.633862) (xy 353.090957 -255.582594) (xy 353.086927 -255.530096) (xy 352.285069 -255.530096)
			(xy 352.306364 -255.536264) (xy 352.350826 -255.557362) (xy 352.391329 -255.585318) (xy 352.426822 -255.61941)
			(xy 352.456387 -255.658754) (xy 352.479258 -255.702331) (xy 352.494842 -255.749012) (xy 352.502737 -255.797589)
			(xy 352.503232 -255.822196) (xy 352.502737 -255.846803) (xy 352.494842 -255.89538) (xy 352.479258 -255.942061)
			(xy 352.456387 -255.985638) (xy 352.426822 -256.024982) (xy 352.391329 -256.059074) (xy 352.350826 -256.08703)
			(xy 352.306364 -256.108128) (xy 352.259093 -256.12182) (xy 352.210238 -256.127752) (xy 352.161063 -256.125771)
			(xy 352.112844 -256.115927) (xy 352.066828 -256.098475) (xy 352.024207 -256.073868) (xy 351.986086 -256.042743)
			(xy 351.953451 -256.005906) (xy 351.927148 -255.96431) (xy 351.907857 -255.919034) (xy 351.89608 -255.87125)
			(xy 351.89212 -255.822196) (xy 349.686331 -255.822196) (xy 349.686372 -255.824228) (xy 349.685877 -255.848835)
			(xy 349.677982 -255.897412) (xy 349.662398 -255.944093) (xy 349.639527 -255.98767) (xy 349.609962 -256.027014)
			(xy 349.574469 -256.061106) (xy 349.533966 -256.089062) (xy 349.489504 -256.11016) (xy 349.442233 -256.123852)
			(xy 349.393378 -256.129784) (xy 349.344203 -256.127803) (xy 349.295984 -256.117959) (xy 349.249968 -256.100507)
			(xy 349.207347 -256.0759) (xy 349.169226 -256.044775) (xy 349.136591 -256.007938) (xy 349.110288 -255.966342)
			(xy 349.090997 -255.921066) (xy 349.07922 -255.873282) (xy 349.07526 -255.824228) (xy 348.746318 -255.824228)
			(xy 348.745898 -255.847189) (xy 348.739024 -255.892595) (xy 348.725448 -255.936466) (xy 348.715838 -255.957324)
			(xy 348.711666 -255.967011) (xy 348.710758 -255.98806) (xy 348.718383 -256.0077) (xy 348.72549 -256.01549)
			(xy 349.532194 -256.822194) (xy 349.532702 -256.822702) (xy 349.540083 -256.829282) (xy 349.558383 -256.836723)
			(xy 349.568262 -256.83718) (xy 350.39681 -256.83718) (xy 350.408475 -256.836607) (xy 350.429395 -256.826281)
			(xy 350.436942 -256.817368) (xy 350.486218 -256.753868) (xy 350.492861 -256.744253) (xy 350.497483 -256.72137)
			(xy 350.495108 -256.709926) (xy 350.49053 -256.691272) (xy 350.485561 -256.653184) (xy 350.485202 -256.63398)
			(xy 350.485202 -256.63144) (xy 350.485823 -256.606254) (xy 350.4943 -256.556594) (xy 350.510814 -256.509)
			(xy 350.534917 -256.464763) (xy 350.565955 -256.425082) (xy 350.603086 -256.391036) (xy 350.645303 -256.363546)
			(xy 350.691459 -256.34336) (xy 350.740304 -256.331026) (xy 350.79051 -256.326876) (xy 350.840716 -256.331026)
			(xy 350.889561 -256.34336) (xy 350.935717 -256.363546) (xy 350.977934 -256.391036) (xy 351.015065 -256.425082)
			(xy 351.046103 -256.464763) (xy 351.070206 -256.509) (xy 351.08672 -256.556594) (xy 351.095197 -256.606254)
			(xy 351.095818 -256.63144) (xy 351.095818 -256.632964) (xy 351.095493 -256.652422) (xy 351.090519 -256.691019)
			(xy 351.085912 -256.709926) (xy 351.083489 -256.72137) (xy 351.088109 -256.744276) (xy 351.094802 -256.753868)
			(xy 351.144078 -256.817368) (xy 351.151663 -256.826231) (xy 351.172562 -256.83654) (xy 351.18421 -256.83718)
			(xy 353.06635 -256.83718) (xy 353.075625 -256.836819) (xy 353.092989 -256.8303) (xy 353.106892 -256.818024)
			(xy 353.111562 -256.810002) (xy 353.14382 -256.747772) (xy 353.146487 -256.742299) (xy 353.149429 -256.730488)
			(xy 353.149662 -256.724404) (xy 353.149662 -256.685034) (xy 353.145598 -256.671572) (xy 353.141534 -256.665222)
			(xy 353.128733 -256.644384) (xy 353.108508 -256.599859) (xy 353.094791 -256.552918) (xy 353.087859 -256.504508)
			(xy 353.087432 -256.480056) (xy 353.087912 -256.454357) (xy 353.095573 -256.403533) (xy 353.110722 -256.354419)
			(xy 353.133023 -256.308111) (xy 353.161976 -256.265644) (xy 353.196936 -256.227967) (xy 353.23712 -256.195921)
			(xy 353.281632 -256.170222) (xy 353.329477 -256.151445) (xy 353.379586 -256.140007) (xy 353.43084 -256.136167)
			(xy 353.482094 -256.140007) (xy 353.532203 -256.151445) (xy 353.580048 -256.170222) (xy 353.62456 -256.195921)
			(xy 353.664744 -256.227967) (xy 353.699704 -256.265644) (xy 353.728657 -256.308111) (xy 353.750958 -256.354419)
			(xy 353.766107 -256.403533) (xy 353.773768 -256.454357) (xy 353.774248 -256.480056) (xy 353.773772 -256.506347)
			(xy 353.765803 -256.55832) (xy 353.749998 -256.608468) (xy 353.726728 -256.655619) (xy 353.712018 -256.677414)
			(xy 353.703636 -256.689098) (xy 353.701858 -256.717292) (xy 353.750118 -256.810002) (xy 353.754796 -256.818014)
			(xy 353.768703 -256.83027) (xy 353.786059 -256.836782) (xy 353.79533 -256.83718) (xy 353.98075 -256.83718)
			(xy 353.990025 -256.836819) (xy 354.007389 -256.8303) (xy 354.021292 -256.818024) (xy 354.025962 -256.810002)
			(xy 354.05822 -256.747772) (xy 354.060887 -256.742299) (xy 354.063829 -256.730488) (xy 354.064062 -256.724404)
			(xy 354.064062 -256.685034) (xy 354.059998 -256.671572) (xy 354.055934 -256.665222) (xy 354.043133 -256.644384)
			(xy 354.022908 -256.599859) (xy 354.009191 -256.552918) (xy 354.002259 -256.504508) (xy 354.001832 -256.480056)
			(xy 354.002312 -256.454357) (xy 354.009973 -256.403533) (xy 354.025122 -256.354419) (xy 354.047423 -256.308111)
			(xy 354.076376 -256.265644) (xy 354.111336 -256.227967) (xy 354.15152 -256.195921) (xy 354.196032 -256.170222)
			(xy 354.243877 -256.151445) (xy 354.293986 -256.140007) (xy 354.34524 -256.136167) (xy 354.396494 -256.140007)
			(xy 354.446603 -256.151445) (xy 354.494448 -256.170222) (xy 354.53896 -256.195921) (xy 354.579144 -256.227967)
			(xy 354.614104 -256.265644) (xy 354.643057 -256.308111) (xy 354.665358 -256.354419) (xy 354.675514 -256.387346)
			(xy 355.244149 -256.387346) (xy 355.248179 -256.334848) (xy 355.260176 -256.28358) (xy 355.279859 -256.234745)
			(xy 355.306765 -256.189486) (xy 355.340265 -256.148865) (xy 355.379573 -256.113834) (xy 355.423768 -256.085214)
			(xy 355.471813 -256.063675) (xy 355.522584 -256.049723) (xy 355.574889 -256.043685) (xy 355.627503 -256.045702)
			(xy 355.679193 -256.055726) (xy 355.728746 -256.073524) (xy 355.775002 -256.098677) (xy 355.816876 -256.130596)
			(xy 355.853388 -256.168534) (xy 355.88368 -256.2116) (xy 355.907043 -256.258785) (xy 355.922929 -256.308984)
			(xy 355.930966 -256.36102) (xy 355.93147 -256.387346) (xy 356.194109 -256.387346) (xy 356.198139 -256.334848)
			(xy 356.210136 -256.28358) (xy 356.229819 -256.234745) (xy 356.256725 -256.189486) (xy 356.290225 -256.148865)
			(xy 356.329533 -256.113834) (xy 356.373728 -256.085214) (xy 356.421773 -256.063675) (xy 356.472544 -256.049723)
			(xy 356.524849 -256.043685) (xy 356.577463 -256.045702) (xy 356.629153 -256.055726) (xy 356.678706 -256.073524)
			(xy 356.724962 -256.098677) (xy 356.766836 -256.130596) (xy 356.803348 -256.168534) (xy 356.83364 -256.2116)
			(xy 356.857003 -256.258785) (xy 356.872889 -256.308984) (xy 356.880926 -256.36102) (xy 356.88143 -256.387346)
			(xy 357.144069 -256.387346) (xy 357.148099 -256.334848) (xy 357.160096 -256.28358) (xy 357.179779 -256.234745)
			(xy 357.206685 -256.189486) (xy 357.240185 -256.148865) (xy 357.279493 -256.113834) (xy 357.323688 -256.085214)
			(xy 357.371733 -256.063675) (xy 357.422504 -256.049723) (xy 357.474809 -256.043685) (xy 357.527423 -256.045702)
			(xy 357.579113 -256.055726) (xy 357.628666 -256.073524) (xy 357.674922 -256.098677) (xy 357.716796 -256.130596)
			(xy 357.753308 -256.168534) (xy 357.7836 -256.2116) (xy 357.806963 -256.258785) (xy 357.822849 -256.308984)
			(xy 357.830886 -256.36102) (xy 357.83139 -256.387346) (xy 358.094029 -256.387346) (xy 358.098059 -256.334848)
			(xy 358.110056 -256.28358) (xy 358.129739 -256.234745) (xy 358.156645 -256.189486) (xy 358.190145 -256.148865)
			(xy 358.229453 -256.113834) (xy 358.273648 -256.085214) (xy 358.321693 -256.063675) (xy 358.372464 -256.049723)
			(xy 358.424769 -256.043685) (xy 358.477383 -256.045702) (xy 358.529073 -256.055726) (xy 358.578626 -256.073524)
			(xy 358.624882 -256.098677) (xy 358.666756 -256.130596) (xy 358.703268 -256.168534) (xy 358.73356 -256.2116)
			(xy 358.756923 -256.258785) (xy 358.772809 -256.308984) (xy 358.780846 -256.36102) (xy 358.78135 -256.387346)
			(xy 359.043989 -256.387346) (xy 359.048019 -256.334848) (xy 359.060016 -256.28358) (xy 359.079699 -256.234745)
			(xy 359.106605 -256.189486) (xy 359.140105 -256.148865) (xy 359.179413 -256.113834) (xy 359.223608 -256.085214)
			(xy 359.271653 -256.063675) (xy 359.322424 -256.049723) (xy 359.374729 -256.043685) (xy 359.427343 -256.045702)
			(xy 359.479033 -256.055726) (xy 359.528586 -256.073524) (xy 359.574842 -256.098677) (xy 359.616716 -256.130596)
			(xy 359.653228 -256.168534) (xy 359.68352 -256.2116) (xy 359.706883 -256.258785) (xy 359.722769 -256.308984)
			(xy 359.730806 -256.36102) (xy 359.73131 -256.387346) (xy 359.993949 -256.387346) (xy 359.997979 -256.334848)
			(xy 360.009976 -256.28358) (xy 360.029659 -256.234745) (xy 360.056565 -256.189486) (xy 360.090065 -256.148865)
			(xy 360.129373 -256.113834) (xy 360.173568 -256.085214) (xy 360.221613 -256.063675) (xy 360.272384 -256.049723)
			(xy 360.324689 -256.043685) (xy 360.377303 -256.045702) (xy 360.428993 -256.055726) (xy 360.478546 -256.073524)
			(xy 360.524802 -256.098677) (xy 360.566676 -256.130596) (xy 360.603188 -256.168534) (xy 360.63348 -256.2116)
			(xy 360.656843 -256.258785) (xy 360.672729 -256.308984) (xy 360.680766 -256.36102) (xy 360.68127 -256.387346)
			(xy 360.944163 -256.387346) (xy 360.948193 -256.334848) (xy 360.96019 -256.28358) (xy 360.979873 -256.234745)
			(xy 361.006779 -256.189486) (xy 361.040279 -256.148865) (xy 361.079587 -256.113834) (xy 361.123782 -256.085214)
			(xy 361.171827 -256.063675) (xy 361.222598 -256.049723) (xy 361.274903 -256.043685) (xy 361.327517 -256.045702)
			(xy 361.379207 -256.055726) (xy 361.42876 -256.073524) (xy 361.475016 -256.098677) (xy 361.51689 -256.130596)
			(xy 361.553402 -256.168534) (xy 361.583694 -256.2116) (xy 361.607057 -256.258785) (xy 361.622943 -256.308984)
			(xy 361.63098 -256.36102) (xy 361.631484 -256.387346) (xy 361.894123 -256.387346) (xy 361.898153 -256.334848)
			(xy 361.91015 -256.28358) (xy 361.929833 -256.234745) (xy 361.956739 -256.189486) (xy 361.990239 -256.148865)
			(xy 362.029547 -256.113834) (xy 362.073742 -256.085214) (xy 362.121787 -256.063675) (xy 362.172558 -256.049723)
			(xy 362.224863 -256.043685) (xy 362.277477 -256.045702) (xy 362.329167 -256.055726) (xy 362.37872 -256.073524)
			(xy 362.424976 -256.098677) (xy 362.46685 -256.130596) (xy 362.503362 -256.168534) (xy 362.533654 -256.2116)
			(xy 362.557017 -256.258785) (xy 362.572903 -256.308984) (xy 362.58094 -256.36102) (xy 362.581444 -256.387346)
			(xy 362.844083 -256.387346) (xy 362.848113 -256.334848) (xy 362.86011 -256.28358) (xy 362.879793 -256.234745)
			(xy 362.906699 -256.189486) (xy 362.940199 -256.148865) (xy 362.979507 -256.113834) (xy 363.023702 -256.085214)
			(xy 363.071747 -256.063675) (xy 363.122518 -256.049723) (xy 363.174823 -256.043685) (xy 363.227437 -256.045702)
			(xy 363.279127 -256.055726) (xy 363.32868 -256.073524) (xy 363.374936 -256.098677) (xy 363.41681 -256.130596)
			(xy 363.453322 -256.168534) (xy 363.483614 -256.2116) (xy 363.506977 -256.258785) (xy 363.522863 -256.308984)
			(xy 363.5309 -256.36102) (xy 363.531404 -256.387346) (xy 363.794043 -256.387346) (xy 363.798073 -256.334848)
			(xy 363.81007 -256.28358) (xy 363.829753 -256.234745) (xy 363.856659 -256.189486) (xy 363.890159 -256.148865)
			(xy 363.929467 -256.113834) (xy 363.973662 -256.085214) (xy 364.021707 -256.063675) (xy 364.072478 -256.049723)
			(xy 364.124783 -256.043685) (xy 364.177397 -256.045702) (xy 364.229087 -256.055726) (xy 364.27864 -256.073524)
			(xy 364.324896 -256.098677) (xy 364.36677 -256.130596) (xy 364.403282 -256.168534) (xy 364.433574 -256.2116)
			(xy 364.456937 -256.258785) (xy 364.472823 -256.308984) (xy 364.48086 -256.36102) (xy 364.481364 -256.387346)
			(xy 364.48086 -256.413672) (xy 364.472823 -256.465708) (xy 364.468282 -256.480056) (xy 365.036865 -256.480056)
			(xy 365.040895 -256.427558) (xy 365.052892 -256.37629) (xy 365.072575 -256.327455) (xy 365.099481 -256.282196)
			(xy 365.132981 -256.241575) (xy 365.172289 -256.206544) (xy 365.216484 -256.177924) (xy 365.264529 -256.156385)
			(xy 365.3153 -256.142433) (xy 365.367605 -256.136395) (xy 365.420219 -256.138412) (xy 365.471909 -256.148436)
			(xy 365.521462 -256.166234) (xy 365.567718 -256.191387) (xy 365.609592 -256.223306) (xy 365.646104 -256.261244)
			(xy 365.676396 -256.30431) (xy 365.699759 -256.351495) (xy 365.715645 -256.401694) (xy 365.723682 -256.45373)
			(xy 365.724186 -256.480056) (xy 365.723682 -256.506382) (xy 365.715645 -256.558418) (xy 365.699759 -256.608617)
			(xy 365.687075 -256.634234) (xy 370.218982 -256.634234) (xy 370.222942 -256.58518) (xy 370.234719 -256.537396)
			(xy 370.25401 -256.49212) (xy 370.280313 -256.450524) (xy 370.312948 -256.413687) (xy 370.351069 -256.382562)
			(xy 370.39369 -256.357955) (xy 370.439706 -256.340503) (xy 370.487925 -256.330659) (xy 370.5371 -256.328678)
			(xy 370.585955 -256.33461) (xy 370.633226 -256.348302) (xy 370.677688 -256.3694) (xy 370.718191 -256.397356)
			(xy 370.753684 -256.431448) (xy 370.783249 -256.470792) (xy 370.80612 -256.514369) (xy 370.821704 -256.56105)
			(xy 370.829599 -256.609627) (xy 370.830094 -256.634234) (xy 372.09909 -256.634234) (xy 372.10305 -256.58518)
			(xy 372.114827 -256.537396) (xy 372.134118 -256.49212) (xy 372.160421 -256.450524) (xy 372.193056 -256.413687)
			(xy 372.231177 -256.382562) (xy 372.273798 -256.357955) (xy 372.319814 -256.340503) (xy 372.368033 -256.330659)
			(xy 372.417208 -256.328678) (xy 372.466063 -256.33461) (xy 372.513334 -256.348302) (xy 372.557796 -256.3694)
			(xy 372.598299 -256.397356) (xy 372.633792 -256.431448) (xy 372.663357 -256.470792) (xy 372.686228 -256.514369)
			(xy 372.701812 -256.56105) (xy 372.709707 -256.609627) (xy 372.710202 -256.634234) (xy 373.978944 -256.634234)
			(xy 373.982904 -256.58518) (xy 373.994681 -256.537396) (xy 374.013972 -256.49212) (xy 374.040275 -256.450524)
			(xy 374.07291 -256.413687) (xy 374.111031 -256.382562) (xy 374.153652 -256.357955) (xy 374.199668 -256.340503)
			(xy 374.247887 -256.330659) (xy 374.297062 -256.328678) (xy 374.345917 -256.33461) (xy 374.393188 -256.348302)
			(xy 374.43765 -256.3694) (xy 374.478153 -256.397356) (xy 374.513646 -256.431448) (xy 374.543211 -256.470792)
			(xy 374.566082 -256.514369) (xy 374.581666 -256.56105) (xy 374.589561 -256.609627) (xy 374.590056 -256.634234)
			(xy 375.859052 -256.634234) (xy 375.863012 -256.58518) (xy 375.874789 -256.537396) (xy 375.89408 -256.49212)
			(xy 375.920383 -256.450524) (xy 375.953018 -256.413687) (xy 375.991139 -256.382562) (xy 376.03376 -256.357955)
			(xy 376.079776 -256.340503) (xy 376.127995 -256.330659) (xy 376.17717 -256.328678) (xy 376.226025 -256.33461)
			(xy 376.273296 -256.348302) (xy 376.317758 -256.3694) (xy 376.358261 -256.397356) (xy 376.393754 -256.431448)
			(xy 376.423319 -256.470792) (xy 376.44619 -256.514369) (xy 376.461774 -256.56105) (xy 376.469669 -256.609627)
			(xy 376.470164 -256.634234) (xy 376.788675 -256.634234) (xy 376.79277 -256.583506) (xy 376.804949 -256.534092)
			(xy 376.824897 -256.487272) (xy 376.852098 -256.444258) (xy 376.885846 -256.406164) (xy 376.925268 -256.373977)
			(xy 376.969342 -256.348531) (xy 377.016928 -256.330484) (xy 377.066792 -256.320304) (xy 377.117644 -256.318255)
			(xy 377.168165 -256.324389) (xy 377.217049 -256.338549) (xy 377.263028 -256.360366) (xy 377.304912 -256.389276)
			(xy 377.341616 -256.424531) (xy 377.372189 -256.465217) (xy 377.39584 -256.51028) (xy 377.411956 -256.558554)
			(xy 377.42012 -256.608788) (xy 377.420632 -256.634234) (xy 378.67896 -256.634234) (xy 378.68292 -256.58518)
			(xy 378.694697 -256.537396) (xy 378.713988 -256.49212) (xy 378.740291 -256.450524) (xy 378.772926 -256.413687)
			(xy 378.811047 -256.382562) (xy 378.853668 -256.357955) (xy 378.899684 -256.340503) (xy 378.947903 -256.330659)
			(xy 378.997078 -256.328678) (xy 379.045933 -256.33461) (xy 379.093204 -256.348302) (xy 379.137666 -256.3694)
			(xy 379.178169 -256.397356) (xy 379.213662 -256.431448) (xy 379.243227 -256.470792) (xy 379.266098 -256.514369)
			(xy 379.281682 -256.56105) (xy 379.289577 -256.609627) (xy 379.290072 -256.634234) (xy 379.619014 -256.634234)
			(xy 379.622974 -256.58518) (xy 379.634751 -256.537396) (xy 379.654042 -256.49212) (xy 379.680345 -256.450524)
			(xy 379.71298 -256.413687) (xy 379.751101 -256.382562) (xy 379.793722 -256.357955) (xy 379.839738 -256.340503)
			(xy 379.887957 -256.330659) (xy 379.937132 -256.328678) (xy 379.985987 -256.33461) (xy 380.033258 -256.348302)
			(xy 380.07772 -256.3694) (xy 380.118223 -256.397356) (xy 380.153716 -256.431448) (xy 380.183281 -256.470792)
			(xy 380.206152 -256.514369) (xy 380.221736 -256.56105) (xy 380.229631 -256.609627) (xy 380.230126 -256.634234)
			(xy 380.548637 -256.634234) (xy 380.552732 -256.583506) (xy 380.564911 -256.534092) (xy 380.584859 -256.487272)
			(xy 380.61206 -256.444258) (xy 380.645808 -256.406164) (xy 380.68523 -256.373977) (xy 380.729304 -256.348531)
			(xy 380.77689 -256.330484) (xy 380.826754 -256.320304) (xy 380.877606 -256.318255) (xy 380.928127 -256.324389)
			(xy 380.977011 -256.338549) (xy 381.02299 -256.360366) (xy 381.064874 -256.389276) (xy 381.101578 -256.424531)
			(xy 381.132151 -256.465217) (xy 381.155802 -256.51028) (xy 381.171918 -256.558554) (xy 381.180082 -256.608788)
			(xy 381.180594 -256.634234) (xy 381.499122 -256.634234) (xy 381.503082 -256.58518) (xy 381.514859 -256.537396)
			(xy 381.53415 -256.49212) (xy 381.560453 -256.450524) (xy 381.593088 -256.413687) (xy 381.631209 -256.382562)
			(xy 381.67383 -256.357955) (xy 381.719846 -256.340503) (xy 381.768065 -256.330659) (xy 381.81724 -256.328678)
			(xy 381.866095 -256.33461) (xy 381.913366 -256.348302) (xy 381.957828 -256.3694) (xy 381.998331 -256.397356)
			(xy 382.033824 -256.431448) (xy 382.063389 -256.470792) (xy 382.08626 -256.514369) (xy 382.101844 -256.56105)
			(xy 382.109739 -256.609627) (xy 382.110234 -256.634234) (xy 382.438922 -256.634234) (xy 382.442882 -256.58518)
			(xy 382.454659 -256.537396) (xy 382.47395 -256.49212) (xy 382.500253 -256.450524) (xy 382.532888 -256.413687)
			(xy 382.571009 -256.382562) (xy 382.61363 -256.357955) (xy 382.659646 -256.340503) (xy 382.707865 -256.330659)
			(xy 382.75704 -256.328678) (xy 382.805895 -256.33461) (xy 382.853166 -256.348302) (xy 382.897628 -256.3694)
			(xy 382.938131 -256.397356) (xy 382.973624 -256.431448) (xy 383.003189 -256.470792) (xy 383.02606 -256.514369)
			(xy 383.041644 -256.56105) (xy 383.049539 -256.609627) (xy 383.050034 -256.634234) (xy 383.368545 -256.634234)
			(xy 383.37264 -256.583506) (xy 383.384819 -256.534092) (xy 383.404767 -256.487272) (xy 383.431968 -256.444258)
			(xy 383.465716 -256.406164) (xy 383.505138 -256.373977) (xy 383.549212 -256.348531) (xy 383.596798 -256.330484)
			(xy 383.646662 -256.320304) (xy 383.697514 -256.318255) (xy 383.748035 -256.324389) (xy 383.796919 -256.338549)
			(xy 383.842898 -256.360366) (xy 383.884782 -256.389276) (xy 383.921486 -256.424531) (xy 383.952059 -256.465217)
			(xy 383.97571 -256.51028) (xy 383.991826 -256.558554) (xy 383.99999 -256.608788) (xy 384.000502 -256.634234)
			(xy 385.259084 -256.634234) (xy 385.263044 -256.58518) (xy 385.274821 -256.537396) (xy 385.294112 -256.49212)
			(xy 385.320415 -256.450524) (xy 385.35305 -256.413687) (xy 385.391171 -256.382562) (xy 385.433792 -256.357955)
			(xy 385.479808 -256.340503) (xy 385.528027 -256.330659) (xy 385.577202 -256.328678) (xy 385.626057 -256.33461)
			(xy 385.673328 -256.348302) (xy 385.71779 -256.3694) (xy 385.758293 -256.397356) (xy 385.793786 -256.431448)
			(xy 385.823351 -256.470792) (xy 385.846222 -256.514369) (xy 385.861806 -256.56105) (xy 385.869701 -256.609627)
			(xy 385.870196 -256.634234) (xy 386.199138 -256.634234) (xy 386.203098 -256.58518) (xy 386.214875 -256.537396)
			(xy 386.234166 -256.49212) (xy 386.260469 -256.450524) (xy 386.293104 -256.413687) (xy 386.331225 -256.382562)
			(xy 386.373846 -256.357955) (xy 386.419862 -256.340503) (xy 386.468081 -256.330659) (xy 386.517256 -256.328678)
			(xy 386.566111 -256.33461) (xy 386.613382 -256.348302) (xy 386.657844 -256.3694) (xy 386.698347 -256.397356)
			(xy 386.73384 -256.431448) (xy 386.763405 -256.470792) (xy 386.786276 -256.514369) (xy 386.80186 -256.56105)
			(xy 386.809755 -256.609627) (xy 386.81025 -256.634234) (xy 387.128507 -256.634234) (xy 387.132602 -256.583506)
			(xy 387.144781 -256.534092) (xy 387.164729 -256.487272) (xy 387.19193 -256.444258) (xy 387.225678 -256.406164)
			(xy 387.2651 -256.373977) (xy 387.309174 -256.348531) (xy 387.35676 -256.330484) (xy 387.406624 -256.320304)
			(xy 387.457476 -256.318255) (xy 387.507997 -256.324389) (xy 387.556881 -256.338549) (xy 387.60286 -256.360366)
			(xy 387.644744 -256.389276) (xy 387.681448 -256.424531) (xy 387.712021 -256.465217) (xy 387.735672 -256.51028)
			(xy 387.751788 -256.558554) (xy 387.759952 -256.608788) (xy 387.760464 -256.634234) (xy 388.078992 -256.634234)
			(xy 388.082952 -256.58518) (xy 388.094729 -256.537396) (xy 388.11402 -256.49212) (xy 388.140323 -256.450524)
			(xy 388.172958 -256.413687) (xy 388.211079 -256.382562) (xy 388.2537 -256.357955) (xy 388.299716 -256.340503)
			(xy 388.347935 -256.330659) (xy 388.39711 -256.328678) (xy 388.445965 -256.33461) (xy 388.493236 -256.348302)
			(xy 388.537698 -256.3694) (xy 388.578201 -256.397356) (xy 388.613694 -256.431448) (xy 388.643259 -256.470792)
			(xy 388.66613 -256.514369) (xy 388.681714 -256.56105) (xy 388.689609 -256.609627) (xy 388.690104 -256.634234)
			(xy 389.019046 -256.634234) (xy 389.023006 -256.58518) (xy 389.034783 -256.537396) (xy 389.054074 -256.49212)
			(xy 389.080377 -256.450524) (xy 389.113012 -256.413687) (xy 389.151133 -256.382562) (xy 389.193754 -256.357955)
			(xy 389.23977 -256.340503) (xy 389.287989 -256.330659) (xy 389.337164 -256.328678) (xy 389.386019 -256.33461)
			(xy 389.43329 -256.348302) (xy 389.477752 -256.3694) (xy 389.518255 -256.397356) (xy 389.553748 -256.431448)
			(xy 389.583313 -256.470792) (xy 389.606184 -256.514369) (xy 389.621768 -256.56105) (xy 389.629663 -256.609627)
			(xy 389.630158 -256.634234) (xy 389.948669 -256.634234) (xy 389.952764 -256.583506) (xy 389.964943 -256.534092)
			(xy 389.984891 -256.487272) (xy 390.012092 -256.444258) (xy 390.04584 -256.406164) (xy 390.085262 -256.373977)
			(xy 390.129336 -256.348531) (xy 390.176922 -256.330484) (xy 390.226786 -256.320304) (xy 390.277638 -256.318255)
			(xy 390.328159 -256.324389) (xy 390.377043 -256.338549) (xy 390.423022 -256.360366) (xy 390.464906 -256.389276)
			(xy 390.50161 -256.424531) (xy 390.532183 -256.465217) (xy 390.555834 -256.51028) (xy 390.57195 -256.558554)
			(xy 390.580114 -256.608788) (xy 390.580626 -256.634234) (xy 391.838954 -256.634234) (xy 391.842914 -256.58518)
			(xy 391.854691 -256.537396) (xy 391.873982 -256.49212) (xy 391.900285 -256.450524) (xy 391.93292 -256.413687)
			(xy 391.971041 -256.382562) (xy 392.013662 -256.357955) (xy 392.059678 -256.340503) (xy 392.107897 -256.330659)
			(xy 392.157072 -256.328678) (xy 392.205927 -256.33461) (xy 392.253198 -256.348302) (xy 392.29766 -256.3694)
			(xy 392.338163 -256.397356) (xy 392.373656 -256.431448) (xy 392.403221 -256.470792) (xy 392.426092 -256.514369)
			(xy 392.441676 -256.56105) (xy 392.449571 -256.609627) (xy 392.450066 -256.634234) (xy 392.779008 -256.634234)
			(xy 392.782968 -256.58518) (xy 392.794745 -256.537396) (xy 392.814036 -256.49212) (xy 392.840339 -256.450524)
			(xy 392.872974 -256.413687) (xy 392.911095 -256.382562) (xy 392.953716 -256.357955) (xy 392.999732 -256.340503)
			(xy 393.047951 -256.330659) (xy 393.097126 -256.328678) (xy 393.145981 -256.33461) (xy 393.193252 -256.348302)
			(xy 393.237714 -256.3694) (xy 393.278217 -256.397356) (xy 393.31371 -256.431448) (xy 393.343275 -256.470792)
			(xy 393.366146 -256.514369) (xy 393.38173 -256.56105) (xy 393.389625 -256.609627) (xy 393.39012 -256.634234)
			(xy 393.389625 -256.658841) (xy 393.38173 -256.707418) (xy 393.366146 -256.754099) (xy 393.343275 -256.797676)
			(xy 393.31371 -256.83702) (xy 393.278217 -256.871112) (xy 393.237714 -256.899068) (xy 393.193252 -256.920166)
			(xy 393.145981 -256.933858) (xy 393.097126 -256.93979) (xy 393.047951 -256.937809) (xy 392.999732 -256.927965)
			(xy 392.953716 -256.910513) (xy 392.911095 -256.885906) (xy 392.872974 -256.854781) (xy 392.840339 -256.817944)
			(xy 392.814036 -256.776348) (xy 392.794745 -256.731072) (xy 392.782968 -256.683288) (xy 392.779008 -256.634234)
			(xy 392.450066 -256.634234) (xy 392.449571 -256.658841) (xy 392.441676 -256.707418) (xy 392.426092 -256.754099)
			(xy 392.403221 -256.797676) (xy 392.373656 -256.83702) (xy 392.338163 -256.871112) (xy 392.29766 -256.899068)
			(xy 392.253198 -256.920166) (xy 392.205927 -256.933858) (xy 392.157072 -256.93979) (xy 392.107897 -256.937809)
			(xy 392.059678 -256.927965) (xy 392.013662 -256.910513) (xy 391.971041 -256.885906) (xy 391.93292 -256.854781)
			(xy 391.900285 -256.817944) (xy 391.873982 -256.776348) (xy 391.854691 -256.731072) (xy 391.842914 -256.683288)
			(xy 391.838954 -256.634234) (xy 390.580626 -256.634234) (xy 390.580114 -256.65968) (xy 390.57195 -256.709914)
			(xy 390.555834 -256.758188) (xy 390.532183 -256.803251) (xy 390.50161 -256.843937) (xy 390.464906 -256.879192)
			(xy 390.423022 -256.908102) (xy 390.377043 -256.929919) (xy 390.328159 -256.944079) (xy 390.277638 -256.950213)
			(xy 390.226786 -256.948164) (xy 390.176922 -256.937984) (xy 390.129336 -256.919937) (xy 390.085262 -256.894491)
			(xy 390.04584 -256.862304) (xy 390.012092 -256.82421) (xy 389.984891 -256.781196) (xy 389.964943 -256.734376)
			(xy 389.952764 -256.684962) (xy 389.948669 -256.634234) (xy 389.630158 -256.634234) (xy 389.629663 -256.658841)
			(xy 389.621768 -256.707418) (xy 389.606184 -256.754099) (xy 389.583313 -256.797676) (xy 389.553748 -256.83702)
			(xy 389.518255 -256.871112) (xy 389.477752 -256.899068) (xy 389.43329 -256.920166) (xy 389.386019 -256.933858)
			(xy 389.337164 -256.93979) (xy 389.287989 -256.937809) (xy 389.23977 -256.927965) (xy 389.193754 -256.910513)
			(xy 389.151133 -256.885906) (xy 389.113012 -256.854781) (xy 389.080377 -256.817944) (xy 389.054074 -256.776348)
			(xy 389.034783 -256.731072) (xy 389.023006 -256.683288) (xy 389.019046 -256.634234) (xy 388.690104 -256.634234)
			(xy 388.689609 -256.658841) (xy 388.681714 -256.707418) (xy 388.66613 -256.754099) (xy 388.643259 -256.797676)
			(xy 388.613694 -256.83702) (xy 388.578201 -256.871112) (xy 388.537698 -256.899068) (xy 388.493236 -256.920166)
			(xy 388.445965 -256.933858) (xy 388.39711 -256.93979) (xy 388.347935 -256.937809) (xy 388.299716 -256.927965)
			(xy 388.2537 -256.910513) (xy 388.211079 -256.885906) (xy 388.172958 -256.854781) (xy 388.140323 -256.817944)
			(xy 388.11402 -256.776348) (xy 388.094729 -256.731072) (xy 388.082952 -256.683288) (xy 388.078992 -256.634234)
			(xy 387.760464 -256.634234) (xy 387.759952 -256.65968) (xy 387.751788 -256.709914) (xy 387.735672 -256.758188)
			(xy 387.712021 -256.803251) (xy 387.681448 -256.843937) (xy 387.644744 -256.879192) (xy 387.60286 -256.908102)
			(xy 387.556881 -256.929919) (xy 387.507997 -256.944079) (xy 387.457476 -256.950213) (xy 387.406624 -256.948164)
			(xy 387.35676 -256.937984) (xy 387.309174 -256.919937) (xy 387.2651 -256.894491) (xy 387.225678 -256.862304)
			(xy 387.19193 -256.82421) (xy 387.164729 -256.781196) (xy 387.144781 -256.734376) (xy 387.132602 -256.684962)
			(xy 387.128507 -256.634234) (xy 386.81025 -256.634234) (xy 386.809755 -256.658841) (xy 386.80186 -256.707418)
			(xy 386.786276 -256.754099) (xy 386.763405 -256.797676) (xy 386.73384 -256.83702) (xy 386.698347 -256.871112)
			(xy 386.657844 -256.899068) (xy 386.613382 -256.920166) (xy 386.566111 -256.933858) (xy 386.517256 -256.93979)
			(xy 386.468081 -256.937809) (xy 386.419862 -256.927965) (xy 386.373846 -256.910513) (xy 386.331225 -256.885906)
			(xy 386.293104 -256.854781) (xy 386.260469 -256.817944) (xy 386.234166 -256.776348) (xy 386.214875 -256.731072)
			(xy 386.203098 -256.683288) (xy 386.199138 -256.634234) (xy 385.870196 -256.634234) (xy 385.869701 -256.658841)
			(xy 385.861806 -256.707418) (xy 385.846222 -256.754099) (xy 385.823351 -256.797676) (xy 385.793786 -256.83702)
			(xy 385.758293 -256.871112) (xy 385.71779 -256.899068) (xy 385.673328 -256.920166) (xy 385.626057 -256.933858)
			(xy 385.577202 -256.93979) (xy 385.528027 -256.937809) (xy 385.479808 -256.927965) (xy 385.433792 -256.910513)
			(xy 385.391171 -256.885906) (xy 385.35305 -256.854781) (xy 385.320415 -256.817944) (xy 385.294112 -256.776348)
			(xy 385.274821 -256.731072) (xy 385.263044 -256.683288) (xy 385.259084 -256.634234) (xy 384.000502 -256.634234)
			(xy 383.99999 -256.65968) (xy 383.991826 -256.709914) (xy 383.97571 -256.758188) (xy 383.952059 -256.803251)
			(xy 383.921486 -256.843937) (xy 383.884782 -256.879192) (xy 383.842898 -256.908102) (xy 383.796919 -256.929919)
			(xy 383.748035 -256.944079) (xy 383.697514 -256.950213) (xy 383.646662 -256.948164) (xy 383.596798 -256.937984)
			(xy 383.549212 -256.919937) (xy 383.505138 -256.894491) (xy 383.465716 -256.862304) (xy 383.431968 -256.82421)
			(xy 383.404767 -256.781196) (xy 383.384819 -256.734376) (xy 383.37264 -256.684962) (xy 383.368545 -256.634234)
			(xy 383.050034 -256.634234) (xy 383.049539 -256.658841) (xy 383.041644 -256.707418) (xy 383.02606 -256.754099)
			(xy 383.003189 -256.797676) (xy 382.973624 -256.83702) (xy 382.938131 -256.871112) (xy 382.897628 -256.899068)
			(xy 382.853166 -256.920166) (xy 382.805895 -256.933858) (xy 382.75704 -256.93979) (xy 382.707865 -256.937809)
			(xy 382.659646 -256.927965) (xy 382.61363 -256.910513) (xy 382.571009 -256.885906) (xy 382.532888 -256.854781)
			(xy 382.500253 -256.817944) (xy 382.47395 -256.776348) (xy 382.454659 -256.731072) (xy 382.442882 -256.683288)
			(xy 382.438922 -256.634234) (xy 382.110234 -256.634234) (xy 382.109739 -256.658841) (xy 382.101844 -256.707418)
			(xy 382.08626 -256.754099) (xy 382.063389 -256.797676) (xy 382.033824 -256.83702) (xy 381.998331 -256.871112)
			(xy 381.957828 -256.899068) (xy 381.913366 -256.920166) (xy 381.866095 -256.933858) (xy 381.81724 -256.93979)
			(xy 381.768065 -256.937809) (xy 381.719846 -256.927965) (xy 381.67383 -256.910513) (xy 381.631209 -256.885906)
			(xy 381.593088 -256.854781) (xy 381.560453 -256.817944) (xy 381.53415 -256.776348) (xy 381.514859 -256.731072)
			(xy 381.503082 -256.683288) (xy 381.499122 -256.634234) (xy 381.180594 -256.634234) (xy 381.180082 -256.65968)
			(xy 381.171918 -256.709914) (xy 381.155802 -256.758188) (xy 381.132151 -256.803251) (xy 381.101578 -256.843937)
			(xy 381.064874 -256.879192) (xy 381.02299 -256.908102) (xy 380.977011 -256.929919) (xy 380.928127 -256.944079)
			(xy 380.877606 -256.950213) (xy 380.826754 -256.948164) (xy 380.77689 -256.937984) (xy 380.729304 -256.919937)
			(xy 380.68523 -256.894491) (xy 380.645808 -256.862304) (xy 380.61206 -256.82421) (xy 380.584859 -256.781196)
			(xy 380.564911 -256.734376) (xy 380.552732 -256.684962) (xy 380.548637 -256.634234) (xy 380.230126 -256.634234)
			(xy 380.229631 -256.658841) (xy 380.221736 -256.707418) (xy 380.206152 -256.754099) (xy 380.183281 -256.797676)
			(xy 380.153716 -256.83702) (xy 380.118223 -256.871112) (xy 380.07772 -256.899068) (xy 380.033258 -256.920166)
			(xy 379.985987 -256.933858) (xy 379.937132 -256.93979) (xy 379.887957 -256.937809) (xy 379.839738 -256.927965)
			(xy 379.793722 -256.910513) (xy 379.751101 -256.885906) (xy 379.71298 -256.854781) (xy 379.680345 -256.817944)
			(xy 379.654042 -256.776348) (xy 379.634751 -256.731072) (xy 379.622974 -256.683288) (xy 379.619014 -256.634234)
			(xy 379.290072 -256.634234) (xy 379.289577 -256.658841) (xy 379.281682 -256.707418) (xy 379.266098 -256.754099)
			(xy 379.243227 -256.797676) (xy 379.213662 -256.83702) (xy 379.178169 -256.871112) (xy 379.137666 -256.899068)
			(xy 379.093204 -256.920166) (xy 379.045933 -256.933858) (xy 378.997078 -256.93979) (xy 378.947903 -256.937809)
			(xy 378.899684 -256.927965) (xy 378.853668 -256.910513) (xy 378.811047 -256.885906) (xy 378.772926 -256.854781)
			(xy 378.740291 -256.817944) (xy 378.713988 -256.776348) (xy 378.694697 -256.731072) (xy 378.68292 -256.683288)
			(xy 378.67896 -256.634234) (xy 377.420632 -256.634234) (xy 377.42012 -256.65968) (xy 377.411956 -256.709914)
			(xy 377.39584 -256.758188) (xy 377.372189 -256.803251) (xy 377.341616 -256.843937) (xy 377.304912 -256.879192)
			(xy 377.263028 -256.908102) (xy 377.217049 -256.929919) (xy 377.168165 -256.944079) (xy 377.117644 -256.950213)
			(xy 377.066792 -256.948164) (xy 377.016928 -256.937984) (xy 376.969342 -256.919937) (xy 376.925268 -256.894491)
			(xy 376.885846 -256.862304) (xy 376.852098 -256.82421) (xy 376.824897 -256.781196) (xy 376.804949 -256.734376)
			(xy 376.79277 -256.684962) (xy 376.788675 -256.634234) (xy 376.470164 -256.634234) (xy 376.469669 -256.658841)
			(xy 376.461774 -256.707418) (xy 376.44619 -256.754099) (xy 376.423319 -256.797676) (xy 376.393754 -256.83702)
			(xy 376.358261 -256.871112) (xy 376.317758 -256.899068) (xy 376.273296 -256.920166) (xy 376.226025 -256.933858)
			(xy 376.17717 -256.93979) (xy 376.127995 -256.937809) (xy 376.079776 -256.927965) (xy 376.03376 -256.910513)
			(xy 375.991139 -256.885906) (xy 375.953018 -256.854781) (xy 375.920383 -256.817944) (xy 375.89408 -256.776348)
			(xy 375.874789 -256.731072) (xy 375.863012 -256.683288) (xy 375.859052 -256.634234) (xy 374.590056 -256.634234)
			(xy 374.589561 -256.658841) (xy 374.581666 -256.707418) (xy 374.566082 -256.754099) (xy 374.543211 -256.797676)
			(xy 374.513646 -256.83702) (xy 374.478153 -256.871112) (xy 374.43765 -256.899068) (xy 374.393188 -256.920166)
			(xy 374.345917 -256.933858) (xy 374.297062 -256.93979) (xy 374.247887 -256.937809) (xy 374.199668 -256.927965)
			(xy 374.153652 -256.910513) (xy 374.111031 -256.885906) (xy 374.07291 -256.854781) (xy 374.040275 -256.817944)
			(xy 374.013972 -256.776348) (xy 373.994681 -256.731072) (xy 373.982904 -256.683288) (xy 373.978944 -256.634234)
			(xy 372.710202 -256.634234) (xy 372.709707 -256.658841) (xy 372.701812 -256.707418) (xy 372.686228 -256.754099)
			(xy 372.663357 -256.797676) (xy 372.633792 -256.83702) (xy 372.598299 -256.871112) (xy 372.557796 -256.899068)
			(xy 372.513334 -256.920166) (xy 372.466063 -256.933858) (xy 372.417208 -256.93979) (xy 372.368033 -256.937809)
			(xy 372.319814 -256.927965) (xy 372.273798 -256.910513) (xy 372.231177 -256.885906) (xy 372.193056 -256.854781)
			(xy 372.160421 -256.817944) (xy 372.134118 -256.776348) (xy 372.114827 -256.731072) (xy 372.10305 -256.683288)
			(xy 372.09909 -256.634234) (xy 370.830094 -256.634234) (xy 370.829599 -256.658841) (xy 370.821704 -256.707418)
			(xy 370.80612 -256.754099) (xy 370.783249 -256.797676) (xy 370.753684 -256.83702) (xy 370.718191 -256.871112)
			(xy 370.677688 -256.899068) (xy 370.633226 -256.920166) (xy 370.585955 -256.933858) (xy 370.5371 -256.93979)
			(xy 370.487925 -256.937809) (xy 370.439706 -256.927965) (xy 370.39369 -256.910513) (xy 370.351069 -256.885906)
			(xy 370.312948 -256.854781) (xy 370.280313 -256.817944) (xy 370.25401 -256.776348) (xy 370.234719 -256.731072)
			(xy 370.222942 -256.683288) (xy 370.218982 -256.634234) (xy 365.687075 -256.634234) (xy 365.676396 -256.655802)
			(xy 365.646104 -256.698868) (xy 365.609592 -256.736806) (xy 365.567718 -256.768725) (xy 365.521462 -256.793878)
			(xy 365.471909 -256.811676) (xy 365.420219 -256.8217) (xy 365.367605 -256.823717) (xy 365.3153 -256.817679)
			(xy 365.264529 -256.803727) (xy 365.216484 -256.782188) (xy 365.172289 -256.753568) (xy 365.132981 -256.718537)
			(xy 365.099481 -256.677916) (xy 365.072575 -256.632657) (xy 365.052892 -256.583822) (xy 365.040895 -256.532554)
			(xy 365.036865 -256.480056) (xy 364.468282 -256.480056) (xy 364.456937 -256.515907) (xy 364.433574 -256.563092)
			(xy 364.403282 -256.606158) (xy 364.36677 -256.644096) (xy 364.324896 -256.676015) (xy 364.27864 -256.701168)
			(xy 364.229087 -256.718966) (xy 364.177397 -256.72899) (xy 364.124783 -256.731007) (xy 364.072478 -256.724969)
			(xy 364.021707 -256.711017) (xy 363.973662 -256.689478) (xy 363.929467 -256.660858) (xy 363.890159 -256.625827)
			(xy 363.856659 -256.585206) (xy 363.829753 -256.539947) (xy 363.81007 -256.491112) (xy 363.798073 -256.439844)
			(xy 363.794043 -256.387346) (xy 363.531404 -256.387346) (xy 363.5309 -256.413672) (xy 363.522863 -256.465708)
			(xy 363.506977 -256.515907) (xy 363.483614 -256.563092) (xy 363.453322 -256.606158) (xy 363.41681 -256.644096)
			(xy 363.374936 -256.676015) (xy 363.32868 -256.701168) (xy 363.279127 -256.718966) (xy 363.227437 -256.72899)
			(xy 363.174823 -256.731007) (xy 363.122518 -256.724969) (xy 363.071747 -256.711017) (xy 363.023702 -256.689478)
			(xy 362.979507 -256.660858) (xy 362.940199 -256.625827) (xy 362.906699 -256.585206) (xy 362.879793 -256.539947)
			(xy 362.86011 -256.491112) (xy 362.848113 -256.439844) (xy 362.844083 -256.387346) (xy 362.581444 -256.387346)
			(xy 362.58094 -256.413672) (xy 362.572903 -256.465708) (xy 362.557017 -256.515907) (xy 362.533654 -256.563092)
			(xy 362.503362 -256.606158) (xy 362.46685 -256.644096) (xy 362.424976 -256.676015) (xy 362.37872 -256.701168)
			(xy 362.329167 -256.718966) (xy 362.277477 -256.72899) (xy 362.224863 -256.731007) (xy 362.172558 -256.724969)
			(xy 362.121787 -256.711017) (xy 362.073742 -256.689478) (xy 362.029547 -256.660858) (xy 361.990239 -256.625827)
			(xy 361.956739 -256.585206) (xy 361.929833 -256.539947) (xy 361.91015 -256.491112) (xy 361.898153 -256.439844)
			(xy 361.894123 -256.387346) (xy 361.631484 -256.387346) (xy 361.63098 -256.413672) (xy 361.622943 -256.465708)
			(xy 361.607057 -256.515907) (xy 361.583694 -256.563092) (xy 361.553402 -256.606158) (xy 361.51689 -256.644096)
			(xy 361.475016 -256.676015) (xy 361.42876 -256.701168) (xy 361.379207 -256.718966) (xy 361.327517 -256.72899)
			(xy 361.274903 -256.731007) (xy 361.222598 -256.724969) (xy 361.171827 -256.711017) (xy 361.123782 -256.689478)
			(xy 361.079587 -256.660858) (xy 361.040279 -256.625827) (xy 361.006779 -256.585206) (xy 360.979873 -256.539947)
			(xy 360.96019 -256.491112) (xy 360.948193 -256.439844) (xy 360.944163 -256.387346) (xy 360.68127 -256.387346)
			(xy 360.680766 -256.413672) (xy 360.672729 -256.465708) (xy 360.656843 -256.515907) (xy 360.63348 -256.563092)
			(xy 360.603188 -256.606158) (xy 360.566676 -256.644096) (xy 360.524802 -256.676015) (xy 360.478546 -256.701168)
			(xy 360.428993 -256.718966) (xy 360.377303 -256.72899) (xy 360.324689 -256.731007) (xy 360.272384 -256.724969)
			(xy 360.221613 -256.711017) (xy 360.173568 -256.689478) (xy 360.129373 -256.660858) (xy 360.090065 -256.625827)
			(xy 360.056565 -256.585206) (xy 360.029659 -256.539947) (xy 360.009976 -256.491112) (xy 359.997979 -256.439844)
			(xy 359.993949 -256.387346) (xy 359.73131 -256.387346) (xy 359.730806 -256.413672) (xy 359.722769 -256.465708)
			(xy 359.706883 -256.515907) (xy 359.68352 -256.563092) (xy 359.653228 -256.606158) (xy 359.616716 -256.644096)
			(xy 359.574842 -256.676015) (xy 359.528586 -256.701168) (xy 359.479033 -256.718966) (xy 359.427343 -256.72899)
			(xy 359.374729 -256.731007) (xy 359.322424 -256.724969) (xy 359.271653 -256.711017) (xy 359.223608 -256.689478)
			(xy 359.179413 -256.660858) (xy 359.140105 -256.625827) (xy 359.106605 -256.585206) (xy 359.079699 -256.539947)
			(xy 359.060016 -256.491112) (xy 359.048019 -256.439844) (xy 359.043989 -256.387346) (xy 358.78135 -256.387346)
			(xy 358.780846 -256.413672) (xy 358.772809 -256.465708) (xy 358.756923 -256.515907) (xy 358.73356 -256.563092)
			(xy 358.703268 -256.606158) (xy 358.666756 -256.644096) (xy 358.624882 -256.676015) (xy 358.578626 -256.701168)
			(xy 358.529073 -256.718966) (xy 358.477383 -256.72899) (xy 358.424769 -256.731007) (xy 358.372464 -256.724969)
			(xy 358.321693 -256.711017) (xy 358.273648 -256.689478) (xy 358.229453 -256.660858) (xy 358.190145 -256.625827)
			(xy 358.156645 -256.585206) (xy 358.129739 -256.539947) (xy 358.110056 -256.491112) (xy 358.098059 -256.439844)
			(xy 358.094029 -256.387346) (xy 357.83139 -256.387346) (xy 357.830886 -256.413672) (xy 357.822849 -256.465708)
			(xy 357.806963 -256.515907) (xy 357.7836 -256.563092) (xy 357.753308 -256.606158) (xy 357.716796 -256.644096)
			(xy 357.674922 -256.676015) (xy 357.628666 -256.701168) (xy 357.579113 -256.718966) (xy 357.527423 -256.72899)
			(xy 357.474809 -256.731007) (xy 357.422504 -256.724969) (xy 357.371733 -256.711017) (xy 357.323688 -256.689478)
			(xy 357.279493 -256.660858) (xy 357.240185 -256.625827) (xy 357.206685 -256.585206) (xy 357.179779 -256.539947)
			(xy 357.160096 -256.491112) (xy 357.148099 -256.439844) (xy 357.144069 -256.387346) (xy 356.88143 -256.387346)
			(xy 356.880926 -256.413672) (xy 356.872889 -256.465708) (xy 356.857003 -256.515907) (xy 356.83364 -256.563092)
			(xy 356.803348 -256.606158) (xy 356.766836 -256.644096) (xy 356.724962 -256.676015) (xy 356.678706 -256.701168)
			(xy 356.629153 -256.718966) (xy 356.577463 -256.72899) (xy 356.524849 -256.731007) (xy 356.472544 -256.724969)
			(xy 356.421773 -256.711017) (xy 356.373728 -256.689478) (xy 356.329533 -256.660858) (xy 356.290225 -256.625827)
			(xy 356.256725 -256.585206) (xy 356.229819 -256.539947) (xy 356.210136 -256.491112) (xy 356.198139 -256.439844)
			(xy 356.194109 -256.387346) (xy 355.93147 -256.387346) (xy 355.930966 -256.413672) (xy 355.922929 -256.465708)
			(xy 355.907043 -256.515907) (xy 355.88368 -256.563092) (xy 355.853388 -256.606158) (xy 355.816876 -256.644096)
			(xy 355.775002 -256.676015) (xy 355.728746 -256.701168) (xy 355.679193 -256.718966) (xy 355.627503 -256.72899)
			(xy 355.574889 -256.731007) (xy 355.522584 -256.724969) (xy 355.471813 -256.711017) (xy 355.423768 -256.689478)
			(xy 355.379573 -256.660858) (xy 355.340265 -256.625827) (xy 355.306765 -256.585206) (xy 355.279859 -256.539947)
			(xy 355.260176 -256.491112) (xy 355.248179 -256.439844) (xy 355.244149 -256.387346) (xy 354.675514 -256.387346)
			(xy 354.680507 -256.403533) (xy 354.688168 -256.454357) (xy 354.688648 -256.480056) (xy 354.688172 -256.506347)
			(xy 354.680203 -256.55832) (xy 354.664398 -256.608468) (xy 354.641128 -256.655619) (xy 354.626418 -256.677414)
			(xy 354.618036 -256.689098) (xy 354.616258 -256.717292) (xy 354.664518 -256.810002) (xy 354.669196 -256.818014)
			(xy 354.683103 -256.83027) (xy 354.700459 -256.836782) (xy 354.70973 -256.83718) (xy 355.746558 -256.83718)
			(xy 355.756624 -256.837613) (xy 355.775215 -256.84534) (xy 355.782626 -256.852166) (xy 356.410006 -257.479546)
			(xy 356.410768 -257.480308) (xy 356.411022 -257.480562) (xy 356.418002 -257.486646) (xy 356.435064 -257.493801)
			(xy 356.444296 -257.494532) (xy 356.504494 -257.496818) (xy 356.509555 -257.496875) (xy 356.519535 -257.495207)
			(xy 356.524306 -257.493516) (xy 356.547928 -257.484626) (xy 356.554532 -257.479292) (xy 356.577735 -257.461085)
			(xy 356.629075 -257.432066) (xy 356.684614 -257.412233) (xy 356.742723 -257.402171) (xy 356.77221 -257.401568)
			(xy 356.799195 -257.402098) (xy 356.852501 -257.410542) (xy 356.90383 -257.42722) (xy 356.951919 -257.451722)
			(xy 356.995582 -257.483445) (xy 357.033746 -257.521607) (xy 357.06547 -257.565269) (xy 357.089974 -257.613357)
			(xy 357.106655 -257.664685) (xy 357.115101 -257.717991) (xy 357.115618 -257.744976) (xy 357.115232 -257.768314)
			(xy 357.108912 -257.814559) (xy 357.096373 -257.859518) (xy 357.077846 -257.902359) (xy 357.066088 -257.922522)
			(xy 357.058976 -257.93446) (xy 357.058468 -257.961638) (xy 357.109014 -258.051046) (xy 357.113744 -258.058661)
			(xy 357.127423 -258.07023) (xy 357.144252 -258.076372) (xy 357.15321 -258.0767) (xy 358.891332 -258.0767)
			(xy 358.900316 -258.076351) (xy 358.917173 -258.070136) (xy 358.930824 -258.058455) (xy 358.935528 -258.050792)
			(xy 358.977946 -257.976116) (xy 358.982487 -257.967171) (xy 358.984849 -257.947265) (xy 358.982518 -257.937508)
			(xy 358.978454 -257.92303) (xy 358.975406 -257.917442) (xy 358.960802 -257.89107) (xy 358.940072 -257.834468)
			(xy 358.929548 -257.775115) (xy 358.928924 -257.744976) (xy 358.929404 -257.719277) (xy 358.937065 -257.668453)
			(xy 358.952214 -257.619339) (xy 358.974515 -257.573031) (xy 359.003468 -257.530564) (xy 359.038428 -257.492887)
			(xy 359.078612 -257.460841) (xy 359.123124 -257.435142) (xy 359.170969 -257.416365) (xy 359.221078 -257.404927)
			(xy 359.272332 -257.401087) (xy 359.323586 -257.404927) (xy 359.373695 -257.416365) (xy 359.42154 -257.435142)
			(xy 359.466052 -257.460841) (xy 359.506236 -257.492887) (xy 359.541196 -257.530564) (xy 359.570149 -257.573031)
			(xy 359.59245 -257.619339) (xy 359.607599 -257.668453) (xy 359.61526 -257.719277) (xy 359.61574 -257.744976)
			(xy 361.178351 -257.744976) (xy 361.182381 -257.692478) (xy 361.194378 -257.64121) (xy 361.214061 -257.592375)
			(xy 361.240967 -257.547116) (xy 361.274467 -257.506495) (xy 361.313775 -257.471464) (xy 361.35797 -257.442844)
			(xy 361.406015 -257.421305) (xy 361.456786 -257.407353) (xy 361.509091 -257.401315) (xy 361.561705 -257.403332)
			(xy 361.613395 -257.413356) (xy 361.662948 -257.431154) (xy 361.709204 -257.456307) (xy 361.751078 -257.488226)
			(xy 361.78759 -257.526164) (xy 361.817882 -257.56923) (xy 361.841245 -257.616415) (xy 361.857131 -257.666614)
			(xy 361.865168 -257.71865) (xy 361.865672 -257.744976) (xy 363.778295 -257.744976) (xy 363.782325 -257.692478)
			(xy 363.794322 -257.64121) (xy 363.814005 -257.592375) (xy 363.840911 -257.547116) (xy 363.874411 -257.506495)
			(xy 363.913719 -257.471464) (xy 363.957914 -257.442844) (xy 364.005959 -257.421305) (xy 364.05673 -257.407353)
			(xy 364.109035 -257.401315) (xy 364.161649 -257.403332) (xy 364.213339 -257.413356) (xy 364.259724 -257.430016)
			(xy 365.036865 -257.430016) (xy 365.040895 -257.377518) (xy 365.052892 -257.32625) (xy 365.072575 -257.277415)
			(xy 365.099481 -257.232156) (xy 365.132981 -257.191535) (xy 365.172289 -257.156504) (xy 365.216484 -257.127884)
			(xy 365.264529 -257.106345) (xy 365.3153 -257.092393) (xy 365.367605 -257.086355) (xy 365.420219 -257.088372)
			(xy 365.471909 -257.098396) (xy 365.521462 -257.116194) (xy 365.567718 -257.141347) (xy 365.609592 -257.173266)
			(xy 365.646104 -257.211204) (xy 365.676396 -257.25427) (xy 365.699759 -257.301455) (xy 365.715645 -257.351654)
			(xy 365.723682 -257.40369) (xy 365.724186 -257.430016) (xy 365.723682 -257.456342) (xy 365.715645 -257.508378)
			(xy 365.699759 -257.558577) (xy 365.676396 -257.605762) (xy 365.646104 -257.648828) (xy 365.609592 -257.686766)
			(xy 365.567718 -257.718685) (xy 365.521462 -257.743838) (xy 365.471909 -257.761636) (xy 365.420219 -257.77166)
			(xy 365.367605 -257.773677) (xy 365.3153 -257.767639) (xy 365.264529 -257.753687) (xy 365.216484 -257.732148)
			(xy 365.172289 -257.703528) (xy 365.132981 -257.668497) (xy 365.099481 -257.627876) (xy 365.072575 -257.582617)
			(xy 365.052892 -257.533782) (xy 365.040895 -257.482514) (xy 365.036865 -257.430016) (xy 364.259724 -257.430016)
			(xy 364.262892 -257.431154) (xy 364.309148 -257.456307) (xy 364.351022 -257.488226) (xy 364.387534 -257.526164)
			(xy 364.417826 -257.56923) (xy 364.441189 -257.616415) (xy 364.457075 -257.666614) (xy 364.465112 -257.71865)
			(xy 364.465616 -257.744976) (xy 364.465112 -257.771302) (xy 364.457075 -257.823338) (xy 364.441189 -257.873537)
			(xy 364.417826 -257.920722) (xy 364.4112 -257.930142) (xy 368.805717 -257.930142) (xy 368.809747 -257.877644)
			(xy 368.821744 -257.826376) (xy 368.841427 -257.777541) (xy 368.868333 -257.732282) (xy 368.901833 -257.691661)
			(xy 368.941141 -257.65663) (xy 368.985336 -257.62801) (xy 369.033381 -257.606471) (xy 369.084152 -257.592519)
			(xy 369.136457 -257.586481) (xy 369.189071 -257.588498) (xy 369.240761 -257.598522) (xy 369.290314 -257.61632)
			(xy 369.33657 -257.641473) (xy 369.378444 -257.673392) (xy 369.414956 -257.71133) (xy 369.445248 -257.754396)
			(xy 369.468611 -257.801581) (xy 369.484497 -257.85178) (xy 369.492534 -257.903816) (xy 369.493038 -257.930142)
			(xy 370.731291 -257.930142) (xy 370.735321 -257.877644) (xy 370.747318 -257.826376) (xy 370.767001 -257.777541)
			(xy 370.793907 -257.732282) (xy 370.827407 -257.691661) (xy 370.866715 -257.65663) (xy 370.91091 -257.62801)
			(xy 370.958955 -257.606471) (xy 371.009726 -257.592519) (xy 371.062031 -257.586481) (xy 371.114645 -257.588498)
			(xy 371.166335 -257.598522) (xy 371.215888 -257.61632) (xy 371.262144 -257.641473) (xy 371.304018 -257.673392)
			(xy 371.34053 -257.71133) (xy 371.370822 -257.754396) (xy 371.394185 -257.801581) (xy 371.410071 -257.85178)
			(xy 371.418108 -257.903816) (xy 371.418612 -257.930142) (xy 372.509291 -257.930142) (xy 372.513321 -257.877644)
			(xy 372.525318 -257.826376) (xy 372.545001 -257.777541) (xy 372.571907 -257.732282) (xy 372.605407 -257.691661)
			(xy 372.644715 -257.65663) (xy 372.68891 -257.62801) (xy 372.736955 -257.606471) (xy 372.787726 -257.592519)
			(xy 372.840031 -257.586481) (xy 372.892645 -257.588498) (xy 372.944335 -257.598522) (xy 372.993888 -257.61632)
			(xy 373.040144 -257.641473) (xy 373.082018 -257.673392) (xy 373.11853 -257.71133) (xy 373.148822 -257.754396)
			(xy 373.172185 -257.801581) (xy 373.188071 -257.85178) (xy 373.196108 -257.903816) (xy 373.196612 -257.930142)
			(xy 373.196108 -257.956468) (xy 373.188071 -258.008504) (xy 373.172185 -258.058703) (xy 373.148822 -258.105888)
			(xy 373.11853 -258.148954) (xy 373.082018 -258.186892) (xy 373.040144 -258.218811) (xy 372.993888 -258.243964)
			(xy 372.944335 -258.261762) (xy 372.892645 -258.271786) (xy 372.840031 -258.273803) (xy 372.787726 -258.267765)
			(xy 372.736955 -258.253813) (xy 372.68891 -258.232274) (xy 372.644715 -258.203654) (xy 372.605407 -258.168623)
			(xy 372.571907 -258.128002) (xy 372.545001 -258.082743) (xy 372.525318 -258.033908) (xy 372.513321 -257.98264)
			(xy 372.509291 -257.930142) (xy 371.418612 -257.930142) (xy 371.418108 -257.956468) (xy 371.410071 -258.008504)
			(xy 371.394185 -258.058703) (xy 371.370822 -258.105888) (xy 371.34053 -258.148954) (xy 371.304018 -258.186892)
			(xy 371.262144 -258.218811) (xy 371.215888 -258.243964) (xy 371.166335 -258.261762) (xy 371.114645 -258.271786)
			(xy 371.062031 -258.273803) (xy 371.009726 -258.267765) (xy 370.958955 -258.253813) (xy 370.91091 -258.232274)
			(xy 370.866715 -258.203654) (xy 370.827407 -258.168623) (xy 370.793907 -258.128002) (xy 370.767001 -258.082743)
			(xy 370.747318 -258.033908) (xy 370.735321 -257.98264) (xy 370.731291 -257.930142) (xy 369.493038 -257.930142)
			(xy 369.492534 -257.956468) (xy 369.484497 -258.008504) (xy 369.468611 -258.058703) (xy 369.445248 -258.105888)
			(xy 369.414956 -258.148954) (xy 369.378444 -258.186892) (xy 369.33657 -258.218811) (xy 369.290314 -258.243964)
			(xy 369.240761 -258.261762) (xy 369.189071 -258.271786) (xy 369.136457 -258.273803) (xy 369.084152 -258.267765)
			(xy 369.033381 -258.253813) (xy 368.985336 -258.232274) (xy 368.941141 -258.203654) (xy 368.901833 -258.168623)
			(xy 368.868333 -258.128002) (xy 368.841427 -258.082743) (xy 368.821744 -258.033908) (xy 368.809747 -257.98264)
			(xy 368.805717 -257.930142) (xy 364.4112 -257.930142) (xy 364.387534 -257.963788) (xy 364.351022 -258.001726)
			(xy 364.309148 -258.033645) (xy 364.262892 -258.058798) (xy 364.213339 -258.076596) (xy 364.161649 -258.08662)
			(xy 364.109035 -258.088637) (xy 364.05673 -258.082599) (xy 364.005959 -258.068647) (xy 363.957914 -258.047108)
			(xy 363.913719 -258.018488) (xy 363.874411 -257.983457) (xy 363.840911 -257.942836) (xy 363.814005 -257.897577)
			(xy 363.794322 -257.848742) (xy 363.782325 -257.797474) (xy 363.778295 -257.744976) (xy 361.865672 -257.744976)
			(xy 361.865168 -257.771302) (xy 361.857131 -257.823338) (xy 361.841245 -257.873537) (xy 361.817882 -257.920722)
			(xy 361.78759 -257.963788) (xy 361.751078 -258.001726) (xy 361.709204 -258.033645) (xy 361.662948 -258.058798)
			(xy 361.613395 -258.076596) (xy 361.561705 -258.08662) (xy 361.509091 -258.088637) (xy 361.456786 -258.082599)
			(xy 361.406015 -258.068647) (xy 361.35797 -258.047108) (xy 361.313775 -258.018488) (xy 361.274467 -257.983457)
			(xy 361.240967 -257.942836) (xy 361.214061 -257.897577) (xy 361.194378 -257.848742) (xy 361.182381 -257.797474)
			(xy 361.178351 -257.744976) (xy 359.61574 -257.744976) (xy 359.615338 -257.769027) (xy 359.608627 -257.816659)
			(xy 359.595333 -257.862888) (xy 359.575717 -257.906809) (xy 359.550163 -257.947562) (xy 359.534968 -257.96621)
			(xy 359.528872 -257.973322) (xy 359.522776 -257.991356) (xy 359.526078 -258.069588) (xy 359.526834 -258.079034)
			(xy 359.534395 -258.096396) (xy 359.54081 -258.10337) (xy 359.817416 -258.379976) (xy 365.036865 -258.379976)
			(xy 365.040895 -258.327478) (xy 365.052892 -258.27621) (xy 365.072575 -258.227375) (xy 365.099481 -258.182116)
			(xy 365.132981 -258.141495) (xy 365.172289 -258.106464) (xy 365.216484 -258.077844) (xy 365.264529 -258.056305)
			(xy 365.3153 -258.042353) (xy 365.367605 -258.036315) (xy 365.420219 -258.038332) (xy 365.471909 -258.048356)
			(xy 365.521462 -258.066154) (xy 365.567718 -258.091307) (xy 365.609592 -258.123226) (xy 365.646104 -258.161164)
			(xy 365.676396 -258.20423) (xy 365.699759 -258.251415) (xy 365.715645 -258.301614) (xy 365.723682 -258.35365)
			(xy 365.724186 -258.379976) (xy 365.723682 -258.406302) (xy 365.715645 -258.458338) (xy 365.699759 -258.508537)
			(xy 365.676396 -258.555722) (xy 365.646104 -258.598788) (xy 365.609592 -258.636726) (xy 365.567718 -258.668645)
			(xy 365.521462 -258.693798) (xy 365.471909 -258.711596) (xy 365.420219 -258.72162) (xy 365.367605 -258.723637)
			(xy 365.3153 -258.717599) (xy 365.264529 -258.703647) (xy 365.216484 -258.682108) (xy 365.172289 -258.653488)
			(xy 365.132981 -258.618457) (xy 365.099481 -258.577836) (xy 365.072575 -258.532577) (xy 365.052892 -258.483742)
			(xy 365.040895 -258.432474) (xy 365.036865 -258.379976) (xy 359.817416 -258.379976) (xy 360.479594 -259.042154)
			(xy 360.480102 -259.042662) (xy 360.487486 -259.049236) (xy 360.505785 -259.056667) (xy 360.515662 -259.05714)
			(xy 361.107228 -259.05714) (xy 361.10799 -259.05714) (xy 361.119634 -259.056382) (xy 361.140393 -259.045783)
			(xy 361.147868 -259.03682) (xy 361.149138 -259.035042) (xy 361.203748 -258.955286) (xy 361.206542 -258.930648)
			(xy 361.20197 -258.91871) (xy 361.191285 -258.889166) (xy 361.179653 -258.827435) (xy 361.178856 -258.796028)
			(xy 361.178856 -258.792726) (xy 361.179555 -258.765858) (xy 361.18828 -258.712828) (xy 361.20516 -258.661805)
			(xy 361.229782 -258.614033) (xy 361.261545 -258.570681) (xy 361.299673 -258.532805) (xy 361.343236 -258.501331)
			(xy 361.39117 -258.477028) (xy 361.442305 -258.460489) (xy 361.495392 -258.452117) (xy 361.549136 -258.452117)
			(xy 361.602223 -258.460489) (xy 361.653358 -258.477028) (xy 361.701292 -258.501331) (xy 361.744855 -258.532805)
			(xy 361.782983 -258.570681) (xy 361.814746 -258.614033) (xy 361.839368 -258.661805) (xy 361.856248 -258.712828)
			(xy 361.864973 -258.765858) (xy 361.865672 -258.792726) (xy 361.865672 -258.795266) (xy 361.864908 -258.826863)
			(xy 361.853282 -258.88898) (xy 361.842558 -258.91871) (xy 361.837986 -258.930648) (xy 361.84078 -258.955286)
			(xy 361.89539 -259.035042) (xy 361.89666 -259.03682) (xy 361.904118 -259.045796) (xy 361.924893 -259.05637)
			(xy 361.936538 -259.05714) (xy 363.707172 -259.05714) (xy 363.707934 -259.05714) (xy 363.719584 -259.056394)
			(xy 363.740363 -259.045808) (xy 363.747812 -259.03682) (xy 363.749082 -259.035042) (xy 363.803692 -258.955286)
			(xy 363.806486 -258.930648) (xy 363.801914 -258.91871) (xy 363.791228 -258.889166) (xy 363.779595 -258.827435)
			(xy 363.7788 -258.796028) (xy 363.7788 -258.792726) (xy 363.779499 -258.765858) (xy 363.788224 -258.712828)
			(xy 363.805104 -258.661805) (xy 363.829726 -258.614033) (xy 363.861489 -258.570681) (xy 363.899617 -258.532805)
			(xy 363.94318 -258.501331) (xy 363.991114 -258.477028) (xy 364.042249 -258.460489) (xy 364.095336 -258.452117)
			(xy 364.14908 -258.452117) (xy 364.202167 -258.460489) (xy 364.253302 -258.477028) (xy 364.301236 -258.501331)
			(xy 364.344799 -258.532805) (xy 364.382927 -258.570681) (xy 364.41469 -258.614033) (xy 364.439312 -258.661805)
			(xy 364.456192 -258.712828) (xy 364.464917 -258.765858) (xy 364.465616 -258.792726) (xy 364.465616 -258.795266)
			(xy 364.464853 -258.826863) (xy 364.464254 -258.830064) (xy 368.805717 -258.830064) (xy 368.809747 -258.777566)
			(xy 368.821744 -258.726298) (xy 368.841427 -258.677463) (xy 368.868333 -258.632204) (xy 368.901833 -258.591583)
			(xy 368.941141 -258.556552) (xy 368.985336 -258.527932) (xy 369.033381 -258.506393) (xy 369.084152 -258.492441)
			(xy 369.136457 -258.486403) (xy 369.189071 -258.48842) (xy 369.240761 -258.498444) (xy 369.290314 -258.516242)
			(xy 369.33657 -258.541395) (xy 369.378444 -258.573314) (xy 369.414956 -258.611252) (xy 369.445248 -258.654318)
			(xy 369.468611 -258.701503) (xy 369.484497 -258.751702) (xy 369.492534 -258.803738) (xy 369.493038 -258.830064)
			(xy 370.731291 -258.830064) (xy 370.735321 -258.777566) (xy 370.747318 -258.726298) (xy 370.767001 -258.677463)
			(xy 370.793907 -258.632204) (xy 370.827407 -258.591583) (xy 370.866715 -258.556552) (xy 370.91091 -258.527932)
			(xy 370.958955 -258.506393) (xy 371.009726 -258.492441) (xy 371.062031 -258.486403) (xy 371.114645 -258.48842)
			(xy 371.166335 -258.498444) (xy 371.215888 -258.516242) (xy 371.262144 -258.541395) (xy 371.304018 -258.573314)
			(xy 371.34053 -258.611252) (xy 371.370822 -258.654318) (xy 371.394185 -258.701503) (xy 371.410071 -258.751702)
			(xy 371.418108 -258.803738) (xy 371.418612 -258.830064) (xy 372.509291 -258.830064) (xy 372.513321 -258.777566)
			(xy 372.525318 -258.726298) (xy 372.545001 -258.677463) (xy 372.571907 -258.632204) (xy 372.605407 -258.591583)
			(xy 372.644715 -258.556552) (xy 372.68891 -258.527932) (xy 372.736955 -258.506393) (xy 372.787726 -258.492441)
			(xy 372.840031 -258.486403) (xy 372.892645 -258.48842) (xy 372.944335 -258.498444) (xy 372.993888 -258.516242)
			(xy 373.040144 -258.541395) (xy 373.082018 -258.573314) (xy 373.11853 -258.611252) (xy 373.148822 -258.654318)
			(xy 373.172185 -258.701503) (xy 373.188071 -258.751702) (xy 373.196108 -258.803738) (xy 373.196612 -258.830064)
			(xy 373.196108 -258.85639) (xy 373.188071 -258.908426) (xy 373.172185 -258.958625) (xy 373.148822 -259.00581)
			(xy 373.11853 -259.048876) (xy 373.082018 -259.086814) (xy 373.040144 -259.118733) (xy 372.993888 -259.143886)
			(xy 372.944335 -259.161684) (xy 372.892645 -259.171708) (xy 372.840031 -259.173725) (xy 372.787726 -259.167687)
			(xy 372.736955 -259.153735) (xy 372.68891 -259.132196) (xy 372.644715 -259.103576) (xy 372.605407 -259.068545)
			(xy 372.571907 -259.027924) (xy 372.545001 -258.982665) (xy 372.525318 -258.93383) (xy 372.513321 -258.882562)
			(xy 372.509291 -258.830064) (xy 371.418612 -258.830064) (xy 371.418108 -258.85639) (xy 371.410071 -258.908426)
			(xy 371.394185 -258.958625) (xy 371.370822 -259.00581) (xy 371.34053 -259.048876) (xy 371.304018 -259.086814)
			(xy 371.262144 -259.118733) (xy 371.215888 -259.143886) (xy 371.166335 -259.161684) (xy 371.114645 -259.171708)
			(xy 371.062031 -259.173725) (xy 371.009726 -259.167687) (xy 370.958955 -259.153735) (xy 370.91091 -259.132196)
			(xy 370.866715 -259.103576) (xy 370.827407 -259.068545) (xy 370.793907 -259.027924) (xy 370.767001 -258.982665)
			(xy 370.747318 -258.93383) (xy 370.735321 -258.882562) (xy 370.731291 -258.830064) (xy 369.493038 -258.830064)
			(xy 369.492534 -258.85639) (xy 369.484497 -258.908426) (xy 369.468611 -258.958625) (xy 369.445248 -259.00581)
			(xy 369.414956 -259.048876) (xy 369.378444 -259.086814) (xy 369.33657 -259.118733) (xy 369.290314 -259.143886)
			(xy 369.240761 -259.161684) (xy 369.189071 -259.171708) (xy 369.136457 -259.173725) (xy 369.084152 -259.167687)
			(xy 369.033381 -259.153735) (xy 368.985336 -259.132196) (xy 368.941141 -259.103576) (xy 368.901833 -259.068545)
			(xy 368.868333 -259.027924) (xy 368.841427 -258.982665) (xy 368.821744 -258.93383) (xy 368.809747 -258.882562)
			(xy 368.805717 -258.830064) (xy 364.464254 -258.830064) (xy 364.453228 -258.88898) (xy 364.442502 -258.91871)
			(xy 364.43793 -258.930648) (xy 364.440724 -258.955286) (xy 364.495334 -259.035042) (xy 364.496604 -259.03682)
			(xy 364.504058 -259.045805) (xy 364.524832 -259.056402) (xy 364.536482 -259.05714) (xy 365.148114 -259.05714)
			(xy 365.151984 -259.057089) (xy 365.159637 -259.055934) (xy 365.163354 -259.054854) (xy 365.18469 -259.047996)
			(xy 365.190532 -259.044186) (xy 365.21178 -259.030607) (xy 365.257408 -259.009144) (xy 365.305682 -258.994573)
			(xy 365.355566 -258.987207) (xy 365.380778 -258.986782) (xy 365.385604 -258.986782) (xy 365.410812 -258.987585)
			(xy 365.460594 -258.995667) (xy 365.50866 -259.010939) (xy 365.553977 -259.033072) (xy 365.595573 -259.061591)
			(xy 365.632555 -259.095883) (xy 365.664127 -259.135212) (xy 365.689611 -259.178733) (xy 365.708461 -259.225512)
			(xy 365.714788 -259.249926) (xy 365.714788 -259.25018) (xy 365.715042 -259.250688) (xy 365.716916 -259.257287)
			(xy 365.723617 -259.26925) (xy 365.72825 -259.27431) (xy 366.034574 -259.580634) (xy 366.041418 -259.588033)
			(xy 366.049144 -259.606631) (xy 366.04956 -259.616702) (xy 366.04956 -259.729986) (xy 368.805717 -259.729986)
			(xy 368.809747 -259.677488) (xy 368.821744 -259.62622) (xy 368.841427 -259.577385) (xy 368.868333 -259.532126)
			(xy 368.901833 -259.491505) (xy 368.941141 -259.456474) (xy 368.985336 -259.427854) (xy 369.033381 -259.406315)
			(xy 369.084152 -259.392363) (xy 369.136457 -259.386325) (xy 369.189071 -259.388342) (xy 369.240761 -259.398366)
			(xy 369.290314 -259.416164) (xy 369.33657 -259.441317) (xy 369.378444 -259.473236) (xy 369.414956 -259.511174)
			(xy 369.445248 -259.55424) (xy 369.468611 -259.601425) (xy 369.484497 -259.651624) (xy 369.492534 -259.70366)
			(xy 369.493038 -259.729986) (xy 370.731291 -259.729986) (xy 370.735321 -259.677488) (xy 370.747318 -259.62622)
			(xy 370.767001 -259.577385) (xy 370.793907 -259.532126) (xy 370.827407 -259.491505) (xy 370.866715 -259.456474)
			(xy 370.91091 -259.427854) (xy 370.958955 -259.406315) (xy 371.009726 -259.392363) (xy 371.062031 -259.386325)
			(xy 371.114645 -259.388342) (xy 371.166335 -259.398366) (xy 371.215888 -259.416164) (xy 371.262144 -259.441317)
			(xy 371.304018 -259.473236) (xy 371.34053 -259.511174) (xy 371.370822 -259.55424) (xy 371.394185 -259.601425)
			(xy 371.410071 -259.651624) (xy 371.418108 -259.70366) (xy 371.418612 -259.729986) (xy 372.509291 -259.729986)
			(xy 372.513321 -259.677488) (xy 372.525318 -259.62622) (xy 372.545001 -259.577385) (xy 372.571907 -259.532126)
			(xy 372.605407 -259.491505) (xy 372.644715 -259.456474) (xy 372.68891 -259.427854) (xy 372.736955 -259.406315)
			(xy 372.787726 -259.392363) (xy 372.840031 -259.386325) (xy 372.892645 -259.388342) (xy 372.944335 -259.398366)
			(xy 372.993888 -259.416164) (xy 373.040144 -259.441317) (xy 373.082018 -259.473236) (xy 373.11853 -259.511174)
			(xy 373.148822 -259.55424) (xy 373.172185 -259.601425) (xy 373.188071 -259.651624) (xy 373.196108 -259.70366)
			(xy 373.196612 -259.729986) (xy 373.196108 -259.756312) (xy 373.188071 -259.808348) (xy 373.172185 -259.858547)
			(xy 373.148822 -259.905732) (xy 373.11853 -259.948798) (xy 373.082018 -259.986736) (xy 373.040144 -260.018655)
			(xy 372.993888 -260.043808) (xy 372.944335 -260.061606) (xy 372.892645 -260.07163) (xy 372.840031 -260.073647)
			(xy 372.787726 -260.067609) (xy 372.736955 -260.053657) (xy 372.68891 -260.032118) (xy 372.644715 -260.003498)
			(xy 372.605407 -259.968467) (xy 372.571907 -259.927846) (xy 372.545001 -259.882587) (xy 372.525318 -259.833752)
			(xy 372.513321 -259.782484) (xy 372.509291 -259.729986) (xy 371.418612 -259.729986) (xy 371.418108 -259.756312)
			(xy 371.410071 -259.808348) (xy 371.394185 -259.858547) (xy 371.370822 -259.905732) (xy 371.34053 -259.948798)
			(xy 371.304018 -259.986736) (xy 371.262144 -260.018655) (xy 371.215888 -260.043808) (xy 371.166335 -260.061606)
			(xy 371.114645 -260.07163) (xy 371.062031 -260.073647) (xy 371.009726 -260.067609) (xy 370.958955 -260.053657)
			(xy 370.91091 -260.032118) (xy 370.866715 -260.003498) (xy 370.827407 -259.968467) (xy 370.793907 -259.927846)
			(xy 370.767001 -259.882587) (xy 370.747318 -259.833752) (xy 370.735321 -259.782484) (xy 370.731291 -259.729986)
			(xy 369.493038 -259.729986) (xy 369.492534 -259.756312) (xy 369.484497 -259.808348) (xy 369.468611 -259.858547)
			(xy 369.445248 -259.905732) (xy 369.414956 -259.948798) (xy 369.378444 -259.986736) (xy 369.33657 -260.018655)
			(xy 369.290314 -260.043808) (xy 369.240761 -260.061606) (xy 369.189071 -260.07163) (xy 369.136457 -260.073647)
			(xy 369.084152 -260.067609) (xy 369.033381 -260.053657) (xy 368.985336 -260.032118) (xy 368.941141 -260.003498)
			(xy 368.901833 -259.968467) (xy 368.868333 -259.927846) (xy 368.841427 -259.882587) (xy 368.821744 -259.833752)
			(xy 368.809747 -259.782484) (xy 368.805717 -259.729986) (xy 366.04956 -259.729986) (xy 366.04956 -261.12597)
			(xy 369.578902 -261.12597) (xy 369.582862 -261.076916) (xy 369.594639 -261.029132) (xy 369.61393 -260.983856)
			(xy 369.640233 -260.94226) (xy 369.672868 -260.905423) (xy 369.710989 -260.874298) (xy 369.75361 -260.849691)
			(xy 369.799626 -260.832239) (xy 369.847845 -260.822395) (xy 369.89702 -260.820414) (xy 369.945875 -260.826346)
			(xy 369.993146 -260.840038) (xy 370.037608 -260.861136) (xy 370.078111 -260.889092) (xy 370.113604 -260.923184)
			(xy 370.143169 -260.962528) (xy 370.16604 -261.006105) (xy 370.181624 -261.052786) (xy 370.189519 -261.101363)
			(xy 370.190014 -261.12597) (xy 371.45901 -261.12597) (xy 371.46297 -261.076916) (xy 371.474747 -261.029132)
			(xy 371.494038 -260.983856) (xy 371.520341 -260.94226) (xy 371.552976 -260.905423) (xy 371.591097 -260.874298)
			(xy 371.633718 -260.849691) (xy 371.679734 -260.832239) (xy 371.727953 -260.822395) (xy 371.777128 -260.820414)
			(xy 371.825983 -260.826346) (xy 371.873254 -260.840038) (xy 371.917716 -260.861136) (xy 371.958219 -260.889092)
			(xy 371.993712 -260.923184) (xy 372.023277 -260.962528) (xy 372.046148 -261.006105) (xy 372.061732 -261.052786)
			(xy 372.069627 -261.101363) (xy 372.070122 -261.12597) (xy 373.339118 -261.12597) (xy 373.343078 -261.076916)
			(xy 373.354855 -261.029132) (xy 373.374146 -260.983856) (xy 373.400449 -260.94226) (xy 373.433084 -260.905423)
			(xy 373.471205 -260.874298) (xy 373.513826 -260.849691) (xy 373.559842 -260.832239) (xy 373.608061 -260.822395)
			(xy 373.657236 -260.820414) (xy 373.706091 -260.826346) (xy 373.753362 -260.840038) (xy 373.797824 -260.861136)
			(xy 373.838327 -260.889092) (xy 373.87382 -260.923184) (xy 373.903385 -260.962528) (xy 373.926256 -261.006105)
			(xy 373.94184 -261.052786) (xy 373.949735 -261.101363) (xy 373.95023 -261.12597) (xy 375.218972 -261.12597)
			(xy 375.222932 -261.076916) (xy 375.234709 -261.029132) (xy 375.254 -260.983856) (xy 375.280303 -260.94226)
			(xy 375.312938 -260.905423) (xy 375.351059 -260.874298) (xy 375.39368 -260.849691) (xy 375.439696 -260.832239)
			(xy 375.487915 -260.822395) (xy 375.53709 -260.820414) (xy 375.585945 -260.826346) (xy 375.633216 -260.840038)
			(xy 375.677678 -260.861136) (xy 375.718181 -260.889092) (xy 375.753674 -260.923184) (xy 375.783239 -260.962528)
			(xy 375.80611 -261.006105) (xy 375.821694 -261.052786) (xy 375.829589 -261.101363) (xy 375.830084 -261.12597)
			(xy 376.159026 -261.12597) (xy 376.162986 -261.076916) (xy 376.174763 -261.029132) (xy 376.194054 -260.983856)
			(xy 376.220357 -260.94226) (xy 376.252992 -260.905423) (xy 376.291113 -260.874298) (xy 376.333734 -260.849691)
			(xy 376.37975 -260.832239) (xy 376.427969 -260.822395) (xy 376.477144 -260.820414) (xy 376.525999 -260.826346)
			(xy 376.57327 -260.840038) (xy 376.617732 -260.861136) (xy 376.658235 -260.889092) (xy 376.693728 -260.923184)
			(xy 376.723293 -260.962528) (xy 376.746164 -261.006105) (xy 376.761748 -261.052786) (xy 376.769643 -261.101363)
			(xy 376.770138 -261.12597) (xy 377.09908 -261.12597) (xy 377.10304 -261.076916) (xy 377.114817 -261.029132)
			(xy 377.134108 -260.983856) (xy 377.160411 -260.94226) (xy 377.193046 -260.905423) (xy 377.231167 -260.874298)
			(xy 377.273788 -260.849691) (xy 377.319804 -260.832239) (xy 377.368023 -260.822395) (xy 377.417198 -260.820414)
			(xy 377.466053 -260.826346) (xy 377.513324 -260.840038) (xy 377.557786 -260.861136) (xy 377.598289 -260.889092)
			(xy 377.633782 -260.923184) (xy 377.663347 -260.962528) (xy 377.686218 -261.006105) (xy 377.701802 -261.052786)
			(xy 377.709697 -261.101363) (xy 377.710192 -261.12597) (xy 378.039134 -261.12597) (xy 378.043094 -261.076916)
			(xy 378.054871 -261.029132) (xy 378.074162 -260.983856) (xy 378.100465 -260.94226) (xy 378.1331 -260.905423)
			(xy 378.171221 -260.874298) (xy 378.213842 -260.849691) (xy 378.259858 -260.832239) (xy 378.308077 -260.822395)
			(xy 378.357252 -260.820414) (xy 378.406107 -260.826346) (xy 378.453378 -260.840038) (xy 378.49784 -260.861136)
			(xy 378.538343 -260.889092) (xy 378.573836 -260.923184) (xy 378.603401 -260.962528) (xy 378.626272 -261.006105)
			(xy 378.641856 -261.052786) (xy 378.649751 -261.101363) (xy 378.650246 -261.12597) (xy 378.978934 -261.12597)
			(xy 378.982894 -261.076916) (xy 378.994671 -261.029132) (xy 379.013962 -260.983856) (xy 379.040265 -260.94226)
			(xy 379.0729 -260.905423) (xy 379.111021 -260.874298) (xy 379.153642 -260.849691) (xy 379.199658 -260.832239)
			(xy 379.247877 -260.822395) (xy 379.297052 -260.820414) (xy 379.345907 -260.826346) (xy 379.393178 -260.840038)
			(xy 379.43764 -260.861136) (xy 379.478143 -260.889092) (xy 379.513636 -260.923184) (xy 379.543201 -260.962528)
			(xy 379.566072 -261.006105) (xy 379.581656 -261.052786) (xy 379.589551 -261.101363) (xy 379.590046 -261.12597)
			(xy 379.918988 -261.12597) (xy 379.922948 -261.076916) (xy 379.934725 -261.029132) (xy 379.954016 -260.983856)
			(xy 379.980319 -260.94226) (xy 380.012954 -260.905423) (xy 380.051075 -260.874298) (xy 380.093696 -260.849691)
			(xy 380.139712 -260.832239) (xy 380.187931 -260.822395) (xy 380.237106 -260.820414) (xy 380.285961 -260.826346)
			(xy 380.333232 -260.840038) (xy 380.377694 -260.861136) (xy 380.418197 -260.889092) (xy 380.45369 -260.923184)
			(xy 380.483255 -260.962528) (xy 380.506126 -261.006105) (xy 380.52171 -261.052786) (xy 380.529605 -261.101363)
			(xy 380.5301 -261.12597) (xy 380.859042 -261.12597) (xy 380.863002 -261.076916) (xy 380.874779 -261.029132)
			(xy 380.89407 -260.983856) (xy 380.920373 -260.94226) (xy 380.953008 -260.905423) (xy 380.991129 -260.874298)
			(xy 381.03375 -260.849691) (xy 381.079766 -260.832239) (xy 381.127985 -260.822395) (xy 381.17716 -260.820414)
			(xy 381.226015 -260.826346) (xy 381.273286 -260.840038) (xy 381.317748 -260.861136) (xy 381.358251 -260.889092)
			(xy 381.393744 -260.923184) (xy 381.423309 -260.962528) (xy 381.44618 -261.006105) (xy 381.461764 -261.052786)
			(xy 381.469659 -261.101363) (xy 381.470154 -261.12597) (xy 381.799096 -261.12597) (xy 381.803056 -261.076916)
			(xy 381.814833 -261.029132) (xy 381.834124 -260.983856) (xy 381.860427 -260.94226) (xy 381.893062 -260.905423)
			(xy 381.931183 -260.874298) (xy 381.973804 -260.849691) (xy 382.01982 -260.832239) (xy 382.068039 -260.822395)
			(xy 382.117214 -260.820414) (xy 382.166069 -260.826346) (xy 382.21334 -260.840038) (xy 382.257802 -260.861136)
			(xy 382.298305 -260.889092) (xy 382.333798 -260.923184) (xy 382.363363 -260.962528) (xy 382.386234 -261.006105)
			(xy 382.401818 -261.052786) (xy 382.409713 -261.101363) (xy 382.410208 -261.12597) (xy 382.738896 -261.12597)
			(xy 382.742856 -261.076916) (xy 382.754633 -261.029132) (xy 382.773924 -260.983856) (xy 382.800227 -260.94226)
			(xy 382.832862 -260.905423) (xy 382.870983 -260.874298) (xy 382.913604 -260.849691) (xy 382.95962 -260.832239)
			(xy 383.007839 -260.822395) (xy 383.057014 -260.820414) (xy 383.105869 -260.826346) (xy 383.15314 -260.840038)
			(xy 383.197602 -260.861136) (xy 383.238105 -260.889092) (xy 383.273598 -260.923184) (xy 383.303163 -260.962528)
			(xy 383.326034 -261.006105) (xy 383.341618 -261.052786) (xy 383.349513 -261.101363) (xy 383.350008 -261.12597)
			(xy 383.67895 -261.12597) (xy 383.68291 -261.076916) (xy 383.694687 -261.029132) (xy 383.713978 -260.983856)
			(xy 383.740281 -260.94226) (xy 383.772916 -260.905423) (xy 383.811037 -260.874298) (xy 383.853658 -260.849691)
			(xy 383.899674 -260.832239) (xy 383.947893 -260.822395) (xy 383.997068 -260.820414) (xy 384.045923 -260.826346)
			(xy 384.093194 -260.840038) (xy 384.137656 -260.861136) (xy 384.178159 -260.889092) (xy 384.213652 -260.923184)
			(xy 384.243217 -260.962528) (xy 384.266088 -261.006105) (xy 384.281672 -261.052786) (xy 384.289567 -261.101363)
			(xy 384.290062 -261.12597) (xy 384.619004 -261.12597) (xy 384.622964 -261.076916) (xy 384.634741 -261.029132)
			(xy 384.654032 -260.983856) (xy 384.680335 -260.94226) (xy 384.71297 -260.905423) (xy 384.751091 -260.874298)
			(xy 384.793712 -260.849691) (xy 384.839728 -260.832239) (xy 384.887947 -260.822395) (xy 384.937122 -260.820414)
			(xy 384.985977 -260.826346) (xy 385.033248 -260.840038) (xy 385.07771 -260.861136) (xy 385.118213 -260.889092)
			(xy 385.153706 -260.923184) (xy 385.183271 -260.962528) (xy 385.206142 -261.006105) (xy 385.221726 -261.052786)
			(xy 385.229621 -261.101363) (xy 385.230116 -261.12597) (xy 385.559058 -261.12597) (xy 385.563018 -261.076916)
			(xy 385.574795 -261.029132) (xy 385.594086 -260.983856) (xy 385.620389 -260.94226) (xy 385.653024 -260.905423)
			(xy 385.691145 -260.874298) (xy 385.733766 -260.849691) (xy 385.779782 -260.832239) (xy 385.828001 -260.822395)
			(xy 385.877176 -260.820414) (xy 385.926031 -260.826346) (xy 385.973302 -260.840038) (xy 386.017764 -260.861136)
			(xy 386.058267 -260.889092) (xy 386.09376 -260.923184) (xy 386.123325 -260.962528) (xy 386.146196 -261.006105)
			(xy 386.16178 -261.052786) (xy 386.169675 -261.101363) (xy 386.17017 -261.12597) (xy 386.499112 -261.12597)
			(xy 386.503072 -261.076916) (xy 386.514849 -261.029132) (xy 386.53414 -260.983856) (xy 386.560443 -260.94226)
			(xy 386.593078 -260.905423) (xy 386.631199 -260.874298) (xy 386.67382 -260.849691) (xy 386.719836 -260.832239)
			(xy 386.768055 -260.822395) (xy 386.81723 -260.820414) (xy 386.866085 -260.826346) (xy 386.913356 -260.840038)
			(xy 386.957818 -260.861136) (xy 386.998321 -260.889092) (xy 387.033814 -260.923184) (xy 387.063379 -260.962528)
			(xy 387.08625 -261.006105) (xy 387.101834 -261.052786) (xy 387.109729 -261.101363) (xy 387.110224 -261.12597)
			(xy 387.438912 -261.12597) (xy 387.442872 -261.076916) (xy 387.454649 -261.029132) (xy 387.47394 -260.983856)
			(xy 387.500243 -260.94226) (xy 387.532878 -260.905423) (xy 387.570999 -260.874298) (xy 387.61362 -260.849691)
			(xy 387.659636 -260.832239) (xy 387.707855 -260.822395) (xy 387.75703 -260.820414) (xy 387.805885 -260.826346)
			(xy 387.853156 -260.840038) (xy 387.897618 -260.861136) (xy 387.938121 -260.889092) (xy 387.973614 -260.923184)
			(xy 388.003179 -260.962528) (xy 388.02605 -261.006105) (xy 388.041634 -261.052786) (xy 388.049529 -261.101363)
			(xy 388.050024 -261.12597) (xy 388.378966 -261.12597) (xy 388.382926 -261.076916) (xy 388.394703 -261.029132)
			(xy 388.413994 -260.983856) (xy 388.440297 -260.94226) (xy 388.472932 -260.905423) (xy 388.511053 -260.874298)
			(xy 388.553674 -260.849691) (xy 388.59969 -260.832239) (xy 388.647909 -260.822395) (xy 388.697084 -260.820414)
			(xy 388.745939 -260.826346) (xy 388.79321 -260.840038) (xy 388.837672 -260.861136) (xy 388.878175 -260.889092)
			(xy 388.913668 -260.923184) (xy 388.943233 -260.962528) (xy 388.966104 -261.006105) (xy 388.981688 -261.052786)
			(xy 388.989583 -261.101363) (xy 388.990078 -261.12597) (xy 389.31902 -261.12597) (xy 389.32298 -261.076916)
			(xy 389.334757 -261.029132) (xy 389.354048 -260.983856) (xy 389.380351 -260.94226) (xy 389.412986 -260.905423)
			(xy 389.451107 -260.874298) (xy 389.493728 -260.849691) (xy 389.539744 -260.832239) (xy 389.587963 -260.822395)
			(xy 389.637138 -260.820414) (xy 389.685993 -260.826346) (xy 389.733264 -260.840038) (xy 389.777726 -260.861136)
			(xy 389.818229 -260.889092) (xy 389.853722 -260.923184) (xy 389.883287 -260.962528) (xy 389.906158 -261.006105)
			(xy 389.921742 -261.052786) (xy 389.929637 -261.101363) (xy 389.930132 -261.12597) (xy 390.259074 -261.12597)
			(xy 390.263034 -261.076916) (xy 390.274811 -261.029132) (xy 390.294102 -260.983856) (xy 390.320405 -260.94226)
			(xy 390.35304 -260.905423) (xy 390.391161 -260.874298) (xy 390.433782 -260.849691) (xy 390.479798 -260.832239)
			(xy 390.528017 -260.822395) (xy 390.577192 -260.820414) (xy 390.626047 -260.826346) (xy 390.673318 -260.840038)
			(xy 390.71778 -260.861136) (xy 390.758283 -260.889092) (xy 390.793776 -260.923184) (xy 390.823341 -260.962528)
			(xy 390.846212 -261.006105) (xy 390.861796 -261.052786) (xy 390.869691 -261.101363) (xy 390.870186 -261.12597)
			(xy 391.199128 -261.12597) (xy 391.203088 -261.076916) (xy 391.214865 -261.029132) (xy 391.234156 -260.983856)
			(xy 391.260459 -260.94226) (xy 391.293094 -260.905423) (xy 391.331215 -260.874298) (xy 391.373836 -260.849691)
			(xy 391.419852 -260.832239) (xy 391.468071 -260.822395) (xy 391.517246 -260.820414) (xy 391.566101 -260.826346)
			(xy 391.613372 -260.840038) (xy 391.657834 -260.861136) (xy 391.698337 -260.889092) (xy 391.73383 -260.923184)
			(xy 391.763395 -260.962528) (xy 391.786266 -261.006105) (xy 391.80185 -261.052786) (xy 391.809745 -261.101363)
			(xy 391.81024 -261.12597) (xy 392.138928 -261.12597) (xy 392.142888 -261.076916) (xy 392.154665 -261.029132)
			(xy 392.173956 -260.983856) (xy 392.200259 -260.94226) (xy 392.232894 -260.905423) (xy 392.271015 -260.874298)
			(xy 392.313636 -260.849691) (xy 392.359652 -260.832239) (xy 392.407871 -260.822395) (xy 392.457046 -260.820414)
			(xy 392.505901 -260.826346) (xy 392.553172 -260.840038) (xy 392.597634 -260.861136) (xy 392.638137 -260.889092)
			(xy 392.67363 -260.923184) (xy 392.703195 -260.962528) (xy 392.726066 -261.006105) (xy 392.74165 -261.052786)
			(xy 392.749545 -261.101363) (xy 392.75004 -261.12597) (xy 393.078982 -261.12597) (xy 393.082942 -261.076916)
			(xy 393.094719 -261.029132) (xy 393.11401 -260.983856) (xy 393.140313 -260.94226) (xy 393.172948 -260.905423)
			(xy 393.211069 -260.874298) (xy 393.25369 -260.849691) (xy 393.299706 -260.832239) (xy 393.347925 -260.822395)
			(xy 393.3971 -260.820414) (xy 393.445955 -260.826346) (xy 393.493226 -260.840038) (xy 393.537688 -260.861136)
			(xy 393.578191 -260.889092) (xy 393.613684 -260.923184) (xy 393.643249 -260.962528) (xy 393.66612 -261.006105)
			(xy 393.681704 -261.052786) (xy 393.689599 -261.101363) (xy 393.690094 -261.12597) (xy 393.689599 -261.150577)
			(xy 393.681704 -261.199154) (xy 393.66612 -261.245835) (xy 393.643249 -261.289412) (xy 393.613684 -261.328756)
			(xy 393.578191 -261.362848) (xy 393.537688 -261.390804) (xy 393.493226 -261.411902) (xy 393.445955 -261.425594)
			(xy 393.3971 -261.431526) (xy 393.347925 -261.429545) (xy 393.299706 -261.419701) (xy 393.25369 -261.402249)
			(xy 393.211069 -261.377642) (xy 393.172948 -261.346517) (xy 393.140313 -261.30968) (xy 393.11401 -261.268084)
			(xy 393.094719 -261.222808) (xy 393.082942 -261.175024) (xy 393.078982 -261.12597) (xy 392.75004 -261.12597)
			(xy 392.749545 -261.150577) (xy 392.74165 -261.199154) (xy 392.726066 -261.245835) (xy 392.703195 -261.289412)
			(xy 392.67363 -261.328756) (xy 392.638137 -261.362848) (xy 392.597634 -261.390804) (xy 392.553172 -261.411902)
			(xy 392.505901 -261.425594) (xy 392.457046 -261.431526) (xy 392.407871 -261.429545) (xy 392.359652 -261.419701)
			(xy 392.313636 -261.402249) (xy 392.271015 -261.377642) (xy 392.232894 -261.346517) (xy 392.200259 -261.30968)
			(xy 392.173956 -261.268084) (xy 392.154665 -261.222808) (xy 392.142888 -261.175024) (xy 392.138928 -261.12597)
			(xy 391.81024 -261.12597) (xy 391.809745 -261.150577) (xy 391.80185 -261.199154) (xy 391.786266 -261.245835)
			(xy 391.763395 -261.289412) (xy 391.73383 -261.328756) (xy 391.698337 -261.362848) (xy 391.657834 -261.390804)
			(xy 391.613372 -261.411902) (xy 391.566101 -261.425594) (xy 391.517246 -261.431526) (xy 391.468071 -261.429545)
			(xy 391.419852 -261.419701) (xy 391.373836 -261.402249) (xy 391.331215 -261.377642) (xy 391.293094 -261.346517)
			(xy 391.260459 -261.30968) (xy 391.234156 -261.268084) (xy 391.214865 -261.222808) (xy 391.203088 -261.175024)
			(xy 391.199128 -261.12597) (xy 390.870186 -261.12597) (xy 390.869691 -261.150577) (xy 390.861796 -261.199154)
			(xy 390.846212 -261.245835) (xy 390.823341 -261.289412) (xy 390.793776 -261.328756) (xy 390.758283 -261.362848)
			(xy 390.71778 -261.390804) (xy 390.673318 -261.411902) (xy 390.626047 -261.425594) (xy 390.577192 -261.431526)
			(xy 390.528017 -261.429545) (xy 390.479798 -261.419701) (xy 390.433782 -261.402249) (xy 390.391161 -261.377642)
			(xy 390.35304 -261.346517) (xy 390.320405 -261.30968) (xy 390.294102 -261.268084) (xy 390.274811 -261.222808)
			(xy 390.263034 -261.175024) (xy 390.259074 -261.12597) (xy 389.930132 -261.12597) (xy 389.929637 -261.150577)
			(xy 389.921742 -261.199154) (xy 389.906158 -261.245835) (xy 389.883287 -261.289412) (xy 389.853722 -261.328756)
			(xy 389.818229 -261.362848) (xy 389.777726 -261.390804) (xy 389.733264 -261.411902) (xy 389.685993 -261.425594)
			(xy 389.637138 -261.431526) (xy 389.587963 -261.429545) (xy 389.539744 -261.419701) (xy 389.493728 -261.402249)
			(xy 389.451107 -261.377642) (xy 389.412986 -261.346517) (xy 389.380351 -261.30968) (xy 389.354048 -261.268084)
			(xy 389.334757 -261.222808) (xy 389.32298 -261.175024) (xy 389.31902 -261.12597) (xy 388.990078 -261.12597)
			(xy 388.989583 -261.150577) (xy 388.981688 -261.199154) (xy 388.966104 -261.245835) (xy 388.943233 -261.289412)
			(xy 388.913668 -261.328756) (xy 388.878175 -261.362848) (xy 388.837672 -261.390804) (xy 388.79321 -261.411902)
			(xy 388.745939 -261.425594) (xy 388.697084 -261.431526) (xy 388.647909 -261.429545) (xy 388.59969 -261.419701)
			(xy 388.553674 -261.402249) (xy 388.511053 -261.377642) (xy 388.472932 -261.346517) (xy 388.440297 -261.30968)
			(xy 388.413994 -261.268084) (xy 388.394703 -261.222808) (xy 388.382926 -261.175024) (xy 388.378966 -261.12597)
			(xy 388.050024 -261.12597) (xy 388.049529 -261.150577) (xy 388.041634 -261.199154) (xy 388.02605 -261.245835)
			(xy 388.003179 -261.289412) (xy 387.973614 -261.328756) (xy 387.938121 -261.362848) (xy 387.897618 -261.390804)
			(xy 387.853156 -261.411902) (xy 387.805885 -261.425594) (xy 387.75703 -261.431526) (xy 387.707855 -261.429545)
			(xy 387.659636 -261.419701) (xy 387.61362 -261.402249) (xy 387.570999 -261.377642) (xy 387.532878 -261.346517)
			(xy 387.500243 -261.30968) (xy 387.47394 -261.268084) (xy 387.454649 -261.222808) (xy 387.442872 -261.175024)
			(xy 387.438912 -261.12597) (xy 387.110224 -261.12597) (xy 387.109729 -261.150577) (xy 387.101834 -261.199154)
			(xy 387.08625 -261.245835) (xy 387.063379 -261.289412) (xy 387.033814 -261.328756) (xy 386.998321 -261.362848)
			(xy 386.957818 -261.390804) (xy 386.913356 -261.411902) (xy 386.866085 -261.425594) (xy 386.81723 -261.431526)
			(xy 386.768055 -261.429545) (xy 386.719836 -261.419701) (xy 386.67382 -261.402249) (xy 386.631199 -261.377642)
			(xy 386.593078 -261.346517) (xy 386.560443 -261.30968) (xy 386.53414 -261.268084) (xy 386.514849 -261.222808)
			(xy 386.503072 -261.175024) (xy 386.499112 -261.12597) (xy 386.17017 -261.12597) (xy 386.169675 -261.150577)
			(xy 386.16178 -261.199154) (xy 386.146196 -261.245835) (xy 386.123325 -261.289412) (xy 386.09376 -261.328756)
			(xy 386.058267 -261.362848) (xy 386.017764 -261.390804) (xy 385.973302 -261.411902) (xy 385.926031 -261.425594)
			(xy 385.877176 -261.431526) (xy 385.828001 -261.429545) (xy 385.779782 -261.419701) (xy 385.733766 -261.402249)
			(xy 385.691145 -261.377642) (xy 385.653024 -261.346517) (xy 385.620389 -261.30968) (xy 385.594086 -261.268084)
			(xy 385.574795 -261.222808) (xy 385.563018 -261.175024) (xy 385.559058 -261.12597) (xy 385.230116 -261.12597)
			(xy 385.229621 -261.150577) (xy 385.221726 -261.199154) (xy 385.206142 -261.245835) (xy 385.183271 -261.289412)
			(xy 385.153706 -261.328756) (xy 385.118213 -261.362848) (xy 385.07771 -261.390804) (xy 385.033248 -261.411902)
			(xy 384.985977 -261.425594) (xy 384.937122 -261.431526) (xy 384.887947 -261.429545) (xy 384.839728 -261.419701)
			(xy 384.793712 -261.402249) (xy 384.751091 -261.377642) (xy 384.71297 -261.346517) (xy 384.680335 -261.30968)
			(xy 384.654032 -261.268084) (xy 384.634741 -261.222808) (xy 384.622964 -261.175024) (xy 384.619004 -261.12597)
			(xy 384.290062 -261.12597) (xy 384.289567 -261.150577) (xy 384.281672 -261.199154) (xy 384.266088 -261.245835)
			(xy 384.243217 -261.289412) (xy 384.213652 -261.328756) (xy 384.178159 -261.362848) (xy 384.137656 -261.390804)
			(xy 384.093194 -261.411902) (xy 384.045923 -261.425594) (xy 383.997068 -261.431526) (xy 383.947893 -261.429545)
			(xy 383.899674 -261.419701) (xy 383.853658 -261.402249) (xy 383.811037 -261.377642) (xy 383.772916 -261.346517)
			(xy 383.740281 -261.30968) (xy 383.713978 -261.268084) (xy 383.694687 -261.222808) (xy 383.68291 -261.175024)
			(xy 383.67895 -261.12597) (xy 383.350008 -261.12597) (xy 383.349513 -261.150577) (xy 383.341618 -261.199154)
			(xy 383.326034 -261.245835) (xy 383.303163 -261.289412) (xy 383.273598 -261.328756) (xy 383.238105 -261.362848)
			(xy 383.197602 -261.390804) (xy 383.15314 -261.411902) (xy 383.105869 -261.425594) (xy 383.057014 -261.431526)
			(xy 383.007839 -261.429545) (xy 382.95962 -261.419701) (xy 382.913604 -261.402249) (xy 382.870983 -261.377642)
			(xy 382.832862 -261.346517) (xy 382.800227 -261.30968) (xy 382.773924 -261.268084) (xy 382.754633 -261.222808)
			(xy 382.742856 -261.175024) (xy 382.738896 -261.12597) (xy 382.410208 -261.12597) (xy 382.409713 -261.150577)
			(xy 382.401818 -261.199154) (xy 382.386234 -261.245835) (xy 382.363363 -261.289412) (xy 382.333798 -261.328756)
			(xy 382.298305 -261.362848) (xy 382.257802 -261.390804) (xy 382.21334 -261.411902) (xy 382.166069 -261.425594)
			(xy 382.117214 -261.431526) (xy 382.068039 -261.429545) (xy 382.01982 -261.419701) (xy 381.973804 -261.402249)
			(xy 381.931183 -261.377642) (xy 381.893062 -261.346517) (xy 381.860427 -261.30968) (xy 381.834124 -261.268084)
			(xy 381.814833 -261.222808) (xy 381.803056 -261.175024) (xy 381.799096 -261.12597) (xy 381.470154 -261.12597)
			(xy 381.469659 -261.150577) (xy 381.461764 -261.199154) (xy 381.44618 -261.245835) (xy 381.423309 -261.289412)
			(xy 381.393744 -261.328756) (xy 381.358251 -261.362848) (xy 381.317748 -261.390804) (xy 381.273286 -261.411902)
			(xy 381.226015 -261.425594) (xy 381.17716 -261.431526) (xy 381.127985 -261.429545) (xy 381.079766 -261.419701)
			(xy 381.03375 -261.402249) (xy 380.991129 -261.377642) (xy 380.953008 -261.346517) (xy 380.920373 -261.30968)
			(xy 380.89407 -261.268084) (xy 380.874779 -261.222808) (xy 380.863002 -261.175024) (xy 380.859042 -261.12597)
			(xy 380.5301 -261.12597) (xy 380.529605 -261.150577) (xy 380.52171 -261.199154) (xy 380.506126 -261.245835)
			(xy 380.483255 -261.289412) (xy 380.45369 -261.328756) (xy 380.418197 -261.362848) (xy 380.377694 -261.390804)
			(xy 380.333232 -261.411902) (xy 380.285961 -261.425594) (xy 380.237106 -261.431526) (xy 380.187931 -261.429545)
			(xy 380.139712 -261.419701) (xy 380.093696 -261.402249) (xy 380.051075 -261.377642) (xy 380.012954 -261.346517)
			(xy 379.980319 -261.30968) (xy 379.954016 -261.268084) (xy 379.934725 -261.222808) (xy 379.922948 -261.175024)
			(xy 379.918988 -261.12597) (xy 379.590046 -261.12597) (xy 379.589551 -261.150577) (xy 379.581656 -261.199154)
			(xy 379.566072 -261.245835) (xy 379.543201 -261.289412) (xy 379.513636 -261.328756) (xy 379.478143 -261.362848)
			(xy 379.43764 -261.390804) (xy 379.393178 -261.411902) (xy 379.345907 -261.425594) (xy 379.297052 -261.431526)
			(xy 379.247877 -261.429545) (xy 379.199658 -261.419701) (xy 379.153642 -261.402249) (xy 379.111021 -261.377642)
			(xy 379.0729 -261.346517) (xy 379.040265 -261.30968) (xy 379.013962 -261.268084) (xy 378.994671 -261.222808)
			(xy 378.982894 -261.175024) (xy 378.978934 -261.12597) (xy 378.650246 -261.12597) (xy 378.649751 -261.150577)
			(xy 378.641856 -261.199154) (xy 378.626272 -261.245835) (xy 378.603401 -261.289412) (xy 378.573836 -261.328756)
			(xy 378.538343 -261.362848) (xy 378.49784 -261.390804) (xy 378.453378 -261.411902) (xy 378.406107 -261.425594)
			(xy 378.357252 -261.431526) (xy 378.308077 -261.429545) (xy 378.259858 -261.419701) (xy 378.213842 -261.402249)
			(xy 378.171221 -261.377642) (xy 378.1331 -261.346517) (xy 378.100465 -261.30968) (xy 378.074162 -261.268084)
			(xy 378.054871 -261.222808) (xy 378.043094 -261.175024) (xy 378.039134 -261.12597) (xy 377.710192 -261.12597)
			(xy 377.709697 -261.150577) (xy 377.701802 -261.199154) (xy 377.686218 -261.245835) (xy 377.663347 -261.289412)
			(xy 377.633782 -261.328756) (xy 377.598289 -261.362848) (xy 377.557786 -261.390804) (xy 377.513324 -261.411902)
			(xy 377.466053 -261.425594) (xy 377.417198 -261.431526) (xy 377.368023 -261.429545) (xy 377.319804 -261.419701)
			(xy 377.273788 -261.402249) (xy 377.231167 -261.377642) (xy 377.193046 -261.346517) (xy 377.160411 -261.30968)
			(xy 377.134108 -261.268084) (xy 377.114817 -261.222808) (xy 377.10304 -261.175024) (xy 377.09908 -261.12597)
			(xy 376.770138 -261.12597) (xy 376.769643 -261.150577) (xy 376.761748 -261.199154) (xy 376.746164 -261.245835)
			(xy 376.723293 -261.289412) (xy 376.693728 -261.328756) (xy 376.658235 -261.362848) (xy 376.617732 -261.390804)
			(xy 376.57327 -261.411902) (xy 376.525999 -261.425594) (xy 376.477144 -261.431526) (xy 376.427969 -261.429545)
			(xy 376.37975 -261.419701) (xy 376.333734 -261.402249) (xy 376.291113 -261.377642) (xy 376.252992 -261.346517)
			(xy 376.220357 -261.30968) (xy 376.194054 -261.268084) (xy 376.174763 -261.222808) (xy 376.162986 -261.175024)
			(xy 376.159026 -261.12597) (xy 375.830084 -261.12597) (xy 375.829589 -261.150577) (xy 375.821694 -261.199154)
			(xy 375.80611 -261.245835) (xy 375.783239 -261.289412) (xy 375.753674 -261.328756) (xy 375.718181 -261.362848)
			(xy 375.677678 -261.390804) (xy 375.633216 -261.411902) (xy 375.585945 -261.425594) (xy 375.53709 -261.431526)
			(xy 375.487915 -261.429545) (xy 375.439696 -261.419701) (xy 375.39368 -261.402249) (xy 375.351059 -261.377642)
			(xy 375.312938 -261.346517) (xy 375.280303 -261.30968) (xy 375.254 -261.268084) (xy 375.234709 -261.222808)
			(xy 375.222932 -261.175024) (xy 375.218972 -261.12597) (xy 373.95023 -261.12597) (xy 373.949735 -261.150577)
			(xy 373.94184 -261.199154) (xy 373.926256 -261.245835) (xy 373.903385 -261.289412) (xy 373.87382 -261.328756)
			(xy 373.838327 -261.362848) (xy 373.797824 -261.390804) (xy 373.753362 -261.411902) (xy 373.706091 -261.425594)
			(xy 373.657236 -261.431526) (xy 373.608061 -261.429545) (xy 373.559842 -261.419701) (xy 373.513826 -261.402249)
			(xy 373.471205 -261.377642) (xy 373.433084 -261.346517) (xy 373.400449 -261.30968) (xy 373.374146 -261.268084)
			(xy 373.354855 -261.222808) (xy 373.343078 -261.175024) (xy 373.339118 -261.12597) (xy 372.070122 -261.12597)
			(xy 372.069627 -261.150577) (xy 372.061732 -261.199154) (xy 372.046148 -261.245835) (xy 372.023277 -261.289412)
			(xy 371.993712 -261.328756) (xy 371.958219 -261.362848) (xy 371.917716 -261.390804) (xy 371.873254 -261.411902)
			(xy 371.825983 -261.425594) (xy 371.777128 -261.431526) (xy 371.727953 -261.429545) (xy 371.679734 -261.419701)
			(xy 371.633718 -261.402249) (xy 371.591097 -261.377642) (xy 371.552976 -261.346517) (xy 371.520341 -261.30968)
			(xy 371.494038 -261.268084) (xy 371.474747 -261.222808) (xy 371.46297 -261.175024) (xy 371.45901 -261.12597)
			(xy 370.190014 -261.12597) (xy 370.189519 -261.150577) (xy 370.181624 -261.199154) (xy 370.16604 -261.245835)
			(xy 370.143169 -261.289412) (xy 370.113604 -261.328756) (xy 370.078111 -261.362848) (xy 370.037608 -261.390804)
			(xy 369.993146 -261.411902) (xy 369.945875 -261.425594) (xy 369.89702 -261.431526) (xy 369.847845 -261.429545)
			(xy 369.799626 -261.419701) (xy 369.75361 -261.402249) (xy 369.710989 -261.377642) (xy 369.672868 -261.346517)
			(xy 369.640233 -261.30968) (xy 369.61393 -261.268084) (xy 369.594639 -261.222808) (xy 369.582862 -261.175024)
			(xy 369.578902 -261.12597) (xy 366.04956 -261.12597) (xy 366.04956 -261.263638) (xy 366.050023 -261.273514)
			(xy 366.057467 -261.291811) (xy 366.064038 -261.299198) (xy 366.064292 -261.299452) (xy 366.250474 -261.485634)
			(xy 366.250982 -261.486142) (xy 366.258364 -261.492721) (xy 366.276663 -261.500162) (xy 366.286542 -261.50062)
			(xy 368.482118 -261.50062) (xy 368.492186 -261.501047) (xy 368.510784 -261.508768) (xy 368.518186 -261.515606)
			(xy 368.938556 -261.935976) (xy 370.049056 -261.935976) (xy 370.053016 -261.886922) (xy 370.064793 -261.839138)
			(xy 370.084084 -261.793862) (xy 370.110387 -261.752266) (xy 370.143022 -261.715429) (xy 370.181143 -261.684304)
			(xy 370.223764 -261.659697) (xy 370.26978 -261.642245) (xy 370.317999 -261.632401) (xy 370.367174 -261.63042)
			(xy 370.416029 -261.636352) (xy 370.4633 -261.650044) (xy 370.507762 -261.671142) (xy 370.548265 -261.699098)
			(xy 370.583758 -261.73319) (xy 370.613323 -261.772534) (xy 370.636194 -261.816111) (xy 370.651778 -261.862792)
			(xy 370.659673 -261.911369) (xy 370.660168 -261.935976) (xy 371.92891 -261.935976) (xy 371.93287 -261.886922)
			(xy 371.944647 -261.839138) (xy 371.963938 -261.793862) (xy 371.990241 -261.752266) (xy 372.022876 -261.715429)
			(xy 372.060997 -261.684304) (xy 372.103618 -261.659697) (xy 372.149634 -261.642245) (xy 372.197853 -261.632401)
			(xy 372.247028 -261.63042) (xy 372.295883 -261.636352) (xy 372.343154 -261.650044) (xy 372.387616 -261.671142)
			(xy 372.428119 -261.699098) (xy 372.463612 -261.73319) (xy 372.493177 -261.772534) (xy 372.516048 -261.816111)
			(xy 372.531632 -261.862792) (xy 372.539527 -261.911369) (xy 372.540022 -261.935976) (xy 373.809018 -261.935976)
			(xy 373.812978 -261.886922) (xy 373.824755 -261.839138) (xy 373.844046 -261.793862) (xy 373.870349 -261.752266)
			(xy 373.902984 -261.715429) (xy 373.941105 -261.684304) (xy 373.983726 -261.659697) (xy 374.029742 -261.642245)
			(xy 374.077961 -261.632401) (xy 374.127136 -261.63042) (xy 374.175991 -261.636352) (xy 374.223262 -261.650044)
			(xy 374.267724 -261.671142) (xy 374.308227 -261.699098) (xy 374.34372 -261.73319) (xy 374.373285 -261.772534)
			(xy 374.396156 -261.816111) (xy 374.41174 -261.862792) (xy 374.419635 -261.911369) (xy 374.42013 -261.935976)
			(xy 375.678695 -261.935976) (xy 375.68279 -261.885248) (xy 375.694969 -261.835834) (xy 375.714917 -261.789014)
			(xy 375.742118 -261.746) (xy 375.775866 -261.707906) (xy 375.815288 -261.675719) (xy 375.859362 -261.650273)
			(xy 375.906948 -261.632226) (xy 375.956812 -261.622046) (xy 376.007664 -261.619997) (xy 376.058185 -261.626131)
			(xy 376.107069 -261.640291) (xy 376.153048 -261.662108) (xy 376.194932 -261.691018) (xy 376.231636 -261.726273)
			(xy 376.262209 -261.766959) (xy 376.28586 -261.812022) (xy 376.301976 -261.860296) (xy 376.31014 -261.91053)
			(xy 376.310652 -261.935976) (xy 376.628926 -261.935976) (xy 376.632886 -261.886922) (xy 376.644663 -261.839138)
			(xy 376.663954 -261.793862) (xy 376.690257 -261.752266) (xy 376.722892 -261.715429) (xy 376.761013 -261.684304)
			(xy 376.803634 -261.659697) (xy 376.84965 -261.642245) (xy 376.897869 -261.632401) (xy 376.947044 -261.63042)
			(xy 376.995899 -261.636352) (xy 377.04317 -261.650044) (xy 377.087632 -261.671142) (xy 377.128135 -261.699098)
			(xy 377.163628 -261.73319) (xy 377.193193 -261.772534) (xy 377.216064 -261.816111) (xy 377.231648 -261.862792)
			(xy 377.239543 -261.911369) (xy 377.240038 -261.935976) (xy 377.56898 -261.935976) (xy 377.57294 -261.886922)
			(xy 377.584717 -261.839138) (xy 377.604008 -261.793862) (xy 377.630311 -261.752266) (xy 377.662946 -261.715429)
			(xy 377.701067 -261.684304) (xy 377.743688 -261.659697) (xy 377.789704 -261.642245) (xy 377.837923 -261.632401)
			(xy 377.887098 -261.63042) (xy 377.935953 -261.636352) (xy 377.983224 -261.650044) (xy 378.027686 -261.671142)
			(xy 378.068189 -261.699098) (xy 378.103682 -261.73319) (xy 378.133247 -261.772534) (xy 378.156118 -261.816111)
			(xy 378.171702 -261.862792) (xy 378.179597 -261.911369) (xy 378.180092 -261.935976) (xy 378.509034 -261.935976)
			(xy 378.512994 -261.886922) (xy 378.524771 -261.839138) (xy 378.544062 -261.793862) (xy 378.570365 -261.752266)
			(xy 378.603 -261.715429) (xy 378.641121 -261.684304) (xy 378.683742 -261.659697) (xy 378.729758 -261.642245)
			(xy 378.777977 -261.632401) (xy 378.827152 -261.63042) (xy 378.876007 -261.636352) (xy 378.923278 -261.650044)
			(xy 378.96774 -261.671142) (xy 379.008243 -261.699098) (xy 379.043736 -261.73319) (xy 379.073301 -261.772534)
			(xy 379.096172 -261.816111) (xy 379.111756 -261.862792) (xy 379.119651 -261.911369) (xy 379.120146 -261.935976)
			(xy 379.438657 -261.935976) (xy 379.442752 -261.885248) (xy 379.454931 -261.835834) (xy 379.474879 -261.789014)
			(xy 379.50208 -261.746) (xy 379.535828 -261.707906) (xy 379.57525 -261.675719) (xy 379.619324 -261.650273)
			(xy 379.66691 -261.632226) (xy 379.716774 -261.622046) (xy 379.767626 -261.619997) (xy 379.818147 -261.626131)
			(xy 379.867031 -261.640291) (xy 379.91301 -261.662108) (xy 379.954894 -261.691018) (xy 379.991598 -261.726273)
			(xy 380.022171 -261.766959) (xy 380.045822 -261.812022) (xy 380.061938 -261.860296) (xy 380.070102 -261.91053)
			(xy 380.070614 -261.935976) (xy 380.388888 -261.935976) (xy 380.392848 -261.886922) (xy 380.404625 -261.839138)
			(xy 380.423916 -261.793862) (xy 380.450219 -261.752266) (xy 380.482854 -261.715429) (xy 380.520975 -261.684304)
			(xy 380.563596 -261.659697) (xy 380.609612 -261.642245) (xy 380.657831 -261.632401) (xy 380.707006 -261.63042)
			(xy 380.755861 -261.636352) (xy 380.803132 -261.650044) (xy 380.847594 -261.671142) (xy 380.888097 -261.699098)
			(xy 380.92359 -261.73319) (xy 380.953155 -261.772534) (xy 380.976026 -261.816111) (xy 380.99161 -261.862792)
			(xy 380.999505 -261.911369) (xy 381 -261.935976) (xy 381.328942 -261.935976) (xy 381.332902 -261.886922)
			(xy 381.344679 -261.839138) (xy 381.36397 -261.793862) (xy 381.390273 -261.752266) (xy 381.422908 -261.715429)
			(xy 381.461029 -261.684304) (xy 381.50365 -261.659697) (xy 381.549666 -261.642245) (xy 381.597885 -261.632401)
			(xy 381.64706 -261.63042) (xy 381.695915 -261.636352) (xy 381.743186 -261.650044) (xy 381.787648 -261.671142)
			(xy 381.828151 -261.699098) (xy 381.863644 -261.73319) (xy 381.893209 -261.772534) (xy 381.91608 -261.816111)
			(xy 381.931664 -261.862792) (xy 381.939559 -261.911369) (xy 381.940054 -261.935976) (xy 382.258565 -261.935976)
			(xy 382.26266 -261.885248) (xy 382.274839 -261.835834) (xy 382.294787 -261.789014) (xy 382.321988 -261.746)
			(xy 382.355736 -261.707906) (xy 382.395158 -261.675719) (xy 382.439232 -261.650273) (xy 382.486818 -261.632226)
			(xy 382.536682 -261.622046) (xy 382.587534 -261.619997) (xy 382.638055 -261.626131) (xy 382.686939 -261.640291)
			(xy 382.732918 -261.662108) (xy 382.774802 -261.691018) (xy 382.811506 -261.726273) (xy 382.842079 -261.766959)
			(xy 382.86573 -261.812022) (xy 382.881846 -261.860296) (xy 382.89001 -261.91053) (xy 382.890522 -261.935976)
			(xy 383.20905 -261.935976) (xy 383.21301 -261.886922) (xy 383.224787 -261.839138) (xy 383.244078 -261.793862)
			(xy 383.270381 -261.752266) (xy 383.303016 -261.715429) (xy 383.341137 -261.684304) (xy 383.383758 -261.659697)
			(xy 383.429774 -261.642245) (xy 383.477993 -261.632401) (xy 383.527168 -261.63042) (xy 383.576023 -261.636352)
			(xy 383.623294 -261.650044) (xy 383.667756 -261.671142) (xy 383.708259 -261.699098) (xy 383.743752 -261.73319)
			(xy 383.773317 -261.772534) (xy 383.796188 -261.816111) (xy 383.811772 -261.862792) (xy 383.819667 -261.911369)
			(xy 383.820162 -261.935976) (xy 384.149104 -261.935976) (xy 384.153064 -261.886922) (xy 384.164841 -261.839138)
			(xy 384.184132 -261.793862) (xy 384.210435 -261.752266) (xy 384.24307 -261.715429) (xy 384.281191 -261.684304)
			(xy 384.323812 -261.659697) (xy 384.369828 -261.642245) (xy 384.418047 -261.632401) (xy 384.467222 -261.63042)
			(xy 384.516077 -261.636352) (xy 384.563348 -261.650044) (xy 384.60781 -261.671142) (xy 384.648313 -261.699098)
			(xy 384.683806 -261.73319) (xy 384.713371 -261.772534) (xy 384.736242 -261.816111) (xy 384.751826 -261.862792)
			(xy 384.759721 -261.911369) (xy 384.760216 -261.935976) (xy 385.088904 -261.935976) (xy 385.092864 -261.886922)
			(xy 385.104641 -261.839138) (xy 385.123932 -261.793862) (xy 385.150235 -261.752266) (xy 385.18287 -261.715429)
			(xy 385.220991 -261.684304) (xy 385.263612 -261.659697) (xy 385.309628 -261.642245) (xy 385.357847 -261.632401)
			(xy 385.407022 -261.63042) (xy 385.455877 -261.636352) (xy 385.503148 -261.650044) (xy 385.54761 -261.671142)
			(xy 385.588113 -261.699098) (xy 385.623606 -261.73319) (xy 385.653171 -261.772534) (xy 385.676042 -261.816111)
			(xy 385.691626 -261.862792) (xy 385.699521 -261.911369) (xy 385.700016 -261.935976) (xy 386.018527 -261.935976)
			(xy 386.022622 -261.885248) (xy 386.034801 -261.835834) (xy 386.054749 -261.789014) (xy 386.08195 -261.746)
			(xy 386.115698 -261.707906) (xy 386.15512 -261.675719) (xy 386.199194 -261.650273) (xy 386.24678 -261.632226)
			(xy 386.296644 -261.622046) (xy 386.347496 -261.619997) (xy 386.398017 -261.626131) (xy 386.446901 -261.640291)
			(xy 386.49288 -261.662108) (xy 386.534764 -261.691018) (xy 386.571468 -261.726273) (xy 386.602041 -261.766959)
			(xy 386.625692 -261.812022) (xy 386.641808 -261.860296) (xy 386.649972 -261.91053) (xy 386.650484 -261.935976)
			(xy 386.969012 -261.935976) (xy 386.972972 -261.886922) (xy 386.984749 -261.839138) (xy 387.00404 -261.793862)
			(xy 387.030343 -261.752266) (xy 387.062978 -261.715429) (xy 387.101099 -261.684304) (xy 387.14372 -261.659697)
			(xy 387.189736 -261.642245) (xy 387.237955 -261.632401) (xy 387.28713 -261.63042) (xy 387.335985 -261.636352)
			(xy 387.383256 -261.650044) (xy 387.427718 -261.671142) (xy 387.468221 -261.699098) (xy 387.503714 -261.73319)
			(xy 387.533279 -261.772534) (xy 387.55615 -261.816111) (xy 387.571734 -261.862792) (xy 387.579629 -261.911369)
			(xy 387.580124 -261.935976) (xy 387.909066 -261.935976) (xy 387.913026 -261.886922) (xy 387.924803 -261.839138)
			(xy 387.944094 -261.793862) (xy 387.970397 -261.752266) (xy 388.003032 -261.715429) (xy 388.041153 -261.684304)
			(xy 388.083774 -261.659697) (xy 388.12979 -261.642245) (xy 388.178009 -261.632401) (xy 388.227184 -261.63042)
			(xy 388.276039 -261.636352) (xy 388.32331 -261.650044) (xy 388.367772 -261.671142) (xy 388.408275 -261.699098)
			(xy 388.443768 -261.73319) (xy 388.473333 -261.772534) (xy 388.496204 -261.816111) (xy 388.511788 -261.862792)
			(xy 388.519683 -261.911369) (xy 388.520178 -261.935976) (xy 388.838689 -261.935976) (xy 388.842784 -261.885248)
			(xy 388.854963 -261.835834) (xy 388.874911 -261.789014) (xy 388.902112 -261.746) (xy 388.93586 -261.707906)
			(xy 388.975282 -261.675719) (xy 389.019356 -261.650273) (xy 389.066942 -261.632226) (xy 389.116806 -261.622046)
			(xy 389.167658 -261.619997) (xy 389.218179 -261.626131) (xy 389.267063 -261.640291) (xy 389.313042 -261.662108)
			(xy 389.354926 -261.691018) (xy 389.39163 -261.726273) (xy 389.422203 -261.766959) (xy 389.445854 -261.812022)
			(xy 389.46197 -261.860296) (xy 389.470134 -261.91053) (xy 389.470646 -261.935976) (xy 389.78892 -261.935976)
			(xy 389.79288 -261.886922) (xy 389.804657 -261.839138) (xy 389.823948 -261.793862) (xy 389.850251 -261.752266)
			(xy 389.882886 -261.715429) (xy 389.921007 -261.684304) (xy 389.963628 -261.659697) (xy 390.009644 -261.642245)
			(xy 390.057863 -261.632401) (xy 390.107038 -261.63042) (xy 390.155893 -261.636352) (xy 390.203164 -261.650044)
			(xy 390.247626 -261.671142) (xy 390.288129 -261.699098) (xy 390.323622 -261.73319) (xy 390.353187 -261.772534)
			(xy 390.376058 -261.816111) (xy 390.391642 -261.862792) (xy 390.399537 -261.911369) (xy 390.400032 -261.935976)
			(xy 390.728974 -261.935976) (xy 390.732934 -261.886922) (xy 390.744711 -261.839138) (xy 390.764002 -261.793862)
			(xy 390.790305 -261.752266) (xy 390.82294 -261.715429) (xy 390.861061 -261.684304) (xy 390.903682 -261.659697)
			(xy 390.949698 -261.642245) (xy 390.997917 -261.632401) (xy 391.047092 -261.63042) (xy 391.095947 -261.636352)
			(xy 391.143218 -261.650044) (xy 391.18768 -261.671142) (xy 391.228183 -261.699098) (xy 391.263676 -261.73319)
			(xy 391.293241 -261.772534) (xy 391.316112 -261.816111) (xy 391.331696 -261.862792) (xy 391.339591 -261.911369)
			(xy 391.340086 -261.935976) (xy 391.669028 -261.935976) (xy 391.672988 -261.886922) (xy 391.684765 -261.839138)
			(xy 391.704056 -261.793862) (xy 391.730359 -261.752266) (xy 391.762994 -261.715429) (xy 391.801115 -261.684304)
			(xy 391.843736 -261.659697) (xy 391.889752 -261.642245) (xy 391.937971 -261.632401) (xy 391.987146 -261.63042)
			(xy 392.036001 -261.636352) (xy 392.083272 -261.650044) (xy 392.125407 -261.670038) (xy 394.67715 -261.670038)
			(xy 394.68111 -261.620984) (xy 394.692887 -261.5732) (xy 394.712178 -261.527924) (xy 394.738481 -261.486328)
			(xy 394.771116 -261.449491) (xy 394.809237 -261.418366) (xy 394.851858 -261.393759) (xy 394.897874 -261.376307)
			(xy 394.946093 -261.366463) (xy 394.995268 -261.364482) (xy 395.044123 -261.370414) (xy 395.091394 -261.384106)
			(xy 395.135856 -261.405204) (xy 395.176359 -261.43316) (xy 395.211852 -261.467252) (xy 395.241417 -261.506596)
			(xy 395.264288 -261.550173) (xy 395.279872 -261.596854) (xy 395.287767 -261.645431) (xy 395.288262 -261.670038)
			(xy 395.287767 -261.694645) (xy 395.279872 -261.743222) (xy 395.264288 -261.789903) (xy 395.241417 -261.83348)
			(xy 395.211852 -261.872824) (xy 395.176359 -261.906916) (xy 395.135856 -261.934872) (xy 395.091394 -261.95597)
			(xy 395.044123 -261.969662) (xy 394.995268 -261.975594) (xy 394.946093 -261.973613) (xy 394.897874 -261.963769)
			(xy 394.851858 -261.946317) (xy 394.809237 -261.92171) (xy 394.771116 -261.890585) (xy 394.738481 -261.853748)
			(xy 394.712178 -261.812152) (xy 394.692887 -261.766876) (xy 394.68111 -261.719092) (xy 394.67715 -261.670038)
			(xy 392.125407 -261.670038) (xy 392.127734 -261.671142) (xy 392.168237 -261.699098) (xy 392.20373 -261.73319)
			(xy 392.233295 -261.772534) (xy 392.256166 -261.816111) (xy 392.27175 -261.862792) (xy 392.279645 -261.911369)
			(xy 392.28014 -261.935976) (xy 392.279645 -261.960583) (xy 392.27175 -262.00916) (xy 392.256166 -262.055841)
			(xy 392.233295 -262.099418) (xy 392.20373 -262.138762) (xy 392.168237 -262.172854) (xy 392.127734 -262.20081)
			(xy 392.083272 -262.221908) (xy 392.036001 -262.2356) (xy 391.987146 -262.241532) (xy 391.937971 -262.239551)
			(xy 391.889752 -262.229707) (xy 391.843736 -262.212255) (xy 391.801115 -262.187648) (xy 391.762994 -262.156523)
			(xy 391.730359 -262.119686) (xy 391.704056 -262.07809) (xy 391.684765 -262.032814) (xy 391.672988 -261.98503)
			(xy 391.669028 -261.935976) (xy 391.340086 -261.935976) (xy 391.339591 -261.960583) (xy 391.331696 -262.00916)
			(xy 391.316112 -262.055841) (xy 391.293241 -262.099418) (xy 391.263676 -262.138762) (xy 391.228183 -262.172854)
			(xy 391.18768 -262.20081) (xy 391.143218 -262.221908) (xy 391.095947 -262.2356) (xy 391.047092 -262.241532)
			(xy 390.997917 -262.239551) (xy 390.949698 -262.229707) (xy 390.903682 -262.212255) (xy 390.861061 -262.187648)
			(xy 390.82294 -262.156523) (xy 390.790305 -262.119686) (xy 390.764002 -262.07809) (xy 390.744711 -262.032814)
			(xy 390.732934 -261.98503) (xy 390.728974 -261.935976) (xy 390.400032 -261.935976) (xy 390.399537 -261.960583)
			(xy 390.391642 -262.00916) (xy 390.376058 -262.055841) (xy 390.353187 -262.099418) (xy 390.323622 -262.138762)
			(xy 390.288129 -262.172854) (xy 390.247626 -262.20081) (xy 390.203164 -262.221908) (xy 390.155893 -262.2356)
			(xy 390.107038 -262.241532) (xy 390.057863 -262.239551) (xy 390.009644 -262.229707) (xy 389.963628 -262.212255)
			(xy 389.921007 -262.187648) (xy 389.882886 -262.156523) (xy 389.850251 -262.119686) (xy 389.823948 -262.07809)
			(xy 389.804657 -262.032814) (xy 389.79288 -261.98503) (xy 389.78892 -261.935976) (xy 389.470646 -261.935976)
			(xy 389.470134 -261.961422) (xy 389.46197 -262.011656) (xy 389.445854 -262.05993) (xy 389.422203 -262.104993)
			(xy 389.39163 -262.145679) (xy 389.354926 -262.180934) (xy 389.313042 -262.209844) (xy 389.267063 -262.231661)
			(xy 389.218179 -262.245821) (xy 389.167658 -262.251955) (xy 389.116806 -262.249906) (xy 389.066942 -262.239726)
			(xy 389.019356 -262.221679) (xy 388.975282 -262.196233) (xy 388.93586 -262.164046) (xy 388.902112 -262.125952)
			(xy 388.874911 -262.082938) (xy 388.854963 -262.036118) (xy 388.842784 -261.986704) (xy 388.838689 -261.935976)
			(xy 388.520178 -261.935976) (xy 388.519683 -261.960583) (xy 388.511788 -262.00916) (xy 388.496204 -262.055841)
			(xy 388.473333 -262.099418) (xy 388.443768 -262.138762) (xy 388.408275 -262.172854) (xy 388.367772 -262.20081)
			(xy 388.32331 -262.221908) (xy 388.276039 -262.2356) (xy 388.227184 -262.241532) (xy 388.178009 -262.239551)
			(xy 388.12979 -262.229707) (xy 388.083774 -262.212255) (xy 388.041153 -262.187648) (xy 388.003032 -262.156523)
			(xy 387.970397 -262.119686) (xy 387.944094 -262.07809) (xy 387.924803 -262.032814) (xy 387.913026 -261.98503)
			(xy 387.909066 -261.935976) (xy 387.580124 -261.935976) (xy 387.579629 -261.960583) (xy 387.571734 -262.00916)
			(xy 387.55615 -262.055841) (xy 387.533279 -262.099418) (xy 387.503714 -262.138762) (xy 387.468221 -262.172854)
			(xy 387.427718 -262.20081) (xy 387.383256 -262.221908) (xy 387.335985 -262.2356) (xy 387.28713 -262.241532)
			(xy 387.237955 -262.239551) (xy 387.189736 -262.229707) (xy 387.14372 -262.212255) (xy 387.101099 -262.187648)
			(xy 387.062978 -262.156523) (xy 387.030343 -262.119686) (xy 387.00404 -262.07809) (xy 386.984749 -262.032814)
			(xy 386.972972 -261.98503) (xy 386.969012 -261.935976) (xy 386.650484 -261.935976) (xy 386.649972 -261.961422)
			(xy 386.641808 -262.011656) (xy 386.625692 -262.05993) (xy 386.602041 -262.104993) (xy 386.571468 -262.145679)
			(xy 386.534764 -262.180934) (xy 386.49288 -262.209844) (xy 386.446901 -262.231661) (xy 386.398017 -262.245821)
			(xy 386.347496 -262.251955) (xy 386.296644 -262.249906) (xy 386.24678 -262.239726) (xy 386.199194 -262.221679)
			(xy 386.15512 -262.196233) (xy 386.115698 -262.164046) (xy 386.08195 -262.125952) (xy 386.054749 -262.082938)
			(xy 386.034801 -262.036118) (xy 386.022622 -261.986704) (xy 386.018527 -261.935976) (xy 385.700016 -261.935976)
			(xy 385.699521 -261.960583) (xy 385.691626 -262.00916) (xy 385.676042 -262.055841) (xy 385.653171 -262.099418)
			(xy 385.623606 -262.138762) (xy 385.588113 -262.172854) (xy 385.54761 -262.20081) (xy 385.503148 -262.221908)
			(xy 385.455877 -262.2356) (xy 385.407022 -262.241532) (xy 385.357847 -262.239551) (xy 385.309628 -262.229707)
			(xy 385.263612 -262.212255) (xy 385.220991 -262.187648) (xy 385.18287 -262.156523) (xy 385.150235 -262.119686)
			(xy 385.123932 -262.07809) (xy 385.104641 -262.032814) (xy 385.092864 -261.98503) (xy 385.088904 -261.935976)
			(xy 384.760216 -261.935976) (xy 384.759721 -261.960583) (xy 384.751826 -262.00916) (xy 384.736242 -262.055841)
			(xy 384.713371 -262.099418) (xy 384.683806 -262.138762) (xy 384.648313 -262.172854) (xy 384.60781 -262.20081)
			(xy 384.563348 -262.221908) (xy 384.516077 -262.2356) (xy 384.467222 -262.241532) (xy 384.418047 -262.239551)
			(xy 384.369828 -262.229707) (xy 384.323812 -262.212255) (xy 384.281191 -262.187648) (xy 384.24307 -262.156523)
			(xy 384.210435 -262.119686) (xy 384.184132 -262.07809) (xy 384.164841 -262.032814) (xy 384.153064 -261.98503)
			(xy 384.149104 -261.935976) (xy 383.820162 -261.935976) (xy 383.819667 -261.960583) (xy 383.811772 -262.00916)
			(xy 383.796188 -262.055841) (xy 383.773317 -262.099418) (xy 383.743752 -262.138762) (xy 383.708259 -262.172854)
			(xy 383.667756 -262.20081) (xy 383.623294 -262.221908) (xy 383.576023 -262.2356) (xy 383.527168 -262.241532)
			(xy 383.477993 -262.239551) (xy 383.429774 -262.229707) (xy 383.383758 -262.212255) (xy 383.341137 -262.187648)
			(xy 383.303016 -262.156523) (xy 383.270381 -262.119686) (xy 383.244078 -262.07809) (xy 383.224787 -262.032814)
			(xy 383.21301 -261.98503) (xy 383.20905 -261.935976) (xy 382.890522 -261.935976) (xy 382.89001 -261.961422)
			(xy 382.881846 -262.011656) (xy 382.86573 -262.05993) (xy 382.842079 -262.104993) (xy 382.811506 -262.145679)
			(xy 382.774802 -262.180934) (xy 382.732918 -262.209844) (xy 382.686939 -262.231661) (xy 382.638055 -262.245821)
			(xy 382.587534 -262.251955) (xy 382.536682 -262.249906) (xy 382.486818 -262.239726) (xy 382.439232 -262.221679)
			(xy 382.395158 -262.196233) (xy 382.355736 -262.164046) (xy 382.321988 -262.125952) (xy 382.294787 -262.082938)
			(xy 382.274839 -262.036118) (xy 382.26266 -261.986704) (xy 382.258565 -261.935976) (xy 381.940054 -261.935976)
			(xy 381.939559 -261.960583) (xy 381.931664 -262.00916) (xy 381.91608 -262.055841) (xy 381.893209 -262.099418)
			(xy 381.863644 -262.138762) (xy 381.828151 -262.172854) (xy 381.787648 -262.20081) (xy 381.743186 -262.221908)
			(xy 381.695915 -262.2356) (xy 381.64706 -262.241532) (xy 381.597885 -262.239551) (xy 381.549666 -262.229707)
			(xy 381.50365 -262.212255) (xy 381.461029 -262.187648) (xy 381.422908 -262.156523) (xy 381.390273 -262.119686)
			(xy 381.36397 -262.07809) (xy 381.344679 -262.032814) (xy 381.332902 -261.98503) (xy 381.328942 -261.935976)
			(xy 381 -261.935976) (xy 380.999505 -261.960583) (xy 380.99161 -262.00916) (xy 380.976026 -262.055841)
			(xy 380.953155 -262.099418) (xy 380.92359 -262.138762) (xy 380.888097 -262.172854) (xy 380.847594 -262.20081)
			(xy 380.803132 -262.221908) (xy 380.755861 -262.2356) (xy 380.707006 -262.241532) (xy 380.657831 -262.239551)
			(xy 380.609612 -262.229707) (xy 380.563596 -262.212255) (xy 380.520975 -262.187648) (xy 380.482854 -262.156523)
			(xy 380.450219 -262.119686) (xy 380.423916 -262.07809) (xy 380.404625 -262.032814) (xy 380.392848 -261.98503)
			(xy 380.388888 -261.935976) (xy 380.070614 -261.935976) (xy 380.070102 -261.961422) (xy 380.061938 -262.011656)
			(xy 380.045822 -262.05993) (xy 380.022171 -262.104993) (xy 379.991598 -262.145679) (xy 379.954894 -262.180934)
			(xy 379.91301 -262.209844) (xy 379.867031 -262.231661) (xy 379.818147 -262.245821) (xy 379.767626 -262.251955)
			(xy 379.716774 -262.249906) (xy 379.66691 -262.239726) (xy 379.619324 -262.221679) (xy 379.57525 -262.196233)
			(xy 379.535828 -262.164046) (xy 379.50208 -262.125952) (xy 379.474879 -262.082938) (xy 379.454931 -262.036118)
			(xy 379.442752 -261.986704) (xy 379.438657 -261.935976) (xy 379.120146 -261.935976) (xy 379.119651 -261.960583)
			(xy 379.111756 -262.00916) (xy 379.096172 -262.055841) (xy 379.073301 -262.099418) (xy 379.043736 -262.138762)
			(xy 379.008243 -262.172854) (xy 378.96774 -262.20081) (xy 378.923278 -262.221908) (xy 378.876007 -262.2356)
			(xy 378.827152 -262.241532) (xy 378.777977 -262.239551) (xy 378.729758 -262.229707) (xy 378.683742 -262.212255)
			(xy 378.641121 -262.187648) (xy 378.603 -262.156523) (xy 378.570365 -262.119686) (xy 378.544062 -262.07809)
			(xy 378.524771 -262.032814) (xy 378.512994 -261.98503) (xy 378.509034 -261.935976) (xy 378.180092 -261.935976)
			(xy 378.179597 -261.960583) (xy 378.171702 -262.00916) (xy 378.156118 -262.055841) (xy 378.133247 -262.099418)
			(xy 378.103682 -262.138762) (xy 378.068189 -262.172854) (xy 378.027686 -262.20081) (xy 377.983224 -262.221908)
			(xy 377.935953 -262.2356) (xy 377.887098 -262.241532) (xy 377.837923 -262.239551) (xy 377.789704 -262.229707)
			(xy 377.743688 -262.212255) (xy 377.701067 -262.187648) (xy 377.662946 -262.156523) (xy 377.630311 -262.119686)
			(xy 377.604008 -262.07809) (xy 377.584717 -262.032814) (xy 377.57294 -261.98503) (xy 377.56898 -261.935976)
			(xy 377.240038 -261.935976) (xy 377.239543 -261.960583) (xy 377.231648 -262.00916) (xy 377.216064 -262.055841)
			(xy 377.193193 -262.099418) (xy 377.163628 -262.138762) (xy 377.128135 -262.172854) (xy 377.087632 -262.20081)
			(xy 377.04317 -262.221908) (xy 376.995899 -262.2356) (xy 376.947044 -262.241532) (xy 376.897869 -262.239551)
			(xy 376.84965 -262.229707) (xy 376.803634 -262.212255) (xy 376.761013 -262.187648) (xy 376.722892 -262.156523)
			(xy 376.690257 -262.119686) (xy 376.663954 -262.07809) (xy 376.644663 -262.032814) (xy 376.632886 -261.98503)
			(xy 376.628926 -261.935976) (xy 376.310652 -261.935976) (xy 376.31014 -261.961422) (xy 376.301976 -262.011656)
			(xy 376.28586 -262.05993) (xy 376.262209 -262.104993) (xy 376.231636 -262.145679) (xy 376.194932 -262.180934)
			(xy 376.153048 -262.209844) (xy 376.107069 -262.231661) (xy 376.058185 -262.245821) (xy 376.007664 -262.251955)
			(xy 375.956812 -262.249906) (xy 375.906948 -262.239726) (xy 375.859362 -262.221679) (xy 375.815288 -262.196233)
			(xy 375.775866 -262.164046) (xy 375.742118 -262.125952) (xy 375.714917 -262.082938) (xy 375.694969 -262.036118)
			(xy 375.68279 -261.986704) (xy 375.678695 -261.935976) (xy 374.42013 -261.935976) (xy 374.419635 -261.960583)
			(xy 374.41174 -262.00916) (xy 374.396156 -262.055841) (xy 374.373285 -262.099418) (xy 374.34372 -262.138762)
			(xy 374.308227 -262.172854) (xy 374.267724 -262.20081) (xy 374.223262 -262.221908) (xy 374.175991 -262.2356)
			(xy 374.127136 -262.241532) (xy 374.077961 -262.239551) (xy 374.029742 -262.229707) (xy 373.983726 -262.212255)
			(xy 373.941105 -262.187648) (xy 373.902984 -262.156523) (xy 373.870349 -262.119686) (xy 373.844046 -262.07809)
			(xy 373.824755 -262.032814) (xy 373.812978 -261.98503) (xy 373.809018 -261.935976) (xy 372.540022 -261.935976)
			(xy 372.539527 -261.960583) (xy 372.531632 -262.00916) (xy 372.516048 -262.055841) (xy 372.493177 -262.099418)
			(xy 372.463612 -262.138762) (xy 372.428119 -262.172854) (xy 372.387616 -262.20081) (xy 372.343154 -262.221908)
			(xy 372.295883 -262.2356) (xy 372.247028 -262.241532) (xy 372.197853 -262.239551) (xy 372.149634 -262.229707)
			(xy 372.103618 -262.212255) (xy 372.060997 -262.187648) (xy 372.022876 -262.156523) (xy 371.990241 -262.119686)
			(xy 371.963938 -262.07809) (xy 371.944647 -262.032814) (xy 371.93287 -261.98503) (xy 371.92891 -261.935976)
			(xy 370.660168 -261.935976) (xy 370.659673 -261.960583) (xy 370.651778 -262.00916) (xy 370.636194 -262.055841)
			(xy 370.613323 -262.099418) (xy 370.583758 -262.138762) (xy 370.548265 -262.172854) (xy 370.507762 -262.20081)
			(xy 370.4633 -262.221908) (xy 370.416029 -262.2356) (xy 370.367174 -262.241532) (xy 370.317999 -262.239551)
			(xy 370.26978 -262.229707) (xy 370.223764 -262.212255) (xy 370.181143 -262.187648) (xy 370.143022 -262.156523)
			(xy 370.110387 -262.119686) (xy 370.084084 -262.07809) (xy 370.064793 -262.032814) (xy 370.053016 -261.98503)
			(xy 370.049056 -261.935976) (xy 368.938556 -261.935976) (xy 369.528852 -262.526272) (xy 369.531392 -262.528812)
			(xy 369.531646 -262.528812) (xy 369.538714 -262.534457) (xy 369.55563 -262.540827) (xy 369.564666 -262.541258)
			(xy 369.626388 -262.541512) (xy 369.631343 -262.541395) (xy 369.641065 -262.539478) (xy 369.645692 -262.537702)
			(xy 369.671346 -262.527542) (xy 369.67795 -262.521192) (xy 369.69497 -262.506142) (xy 369.732622 -262.48072)
			(xy 369.77362 -262.461144) (xy 369.817061 -262.447844) (xy 369.86199 -262.441113) (xy 369.884706 -262.440674)
			(xy 369.908697 -262.441145) (xy 369.956089 -262.448652) (xy 370.001724 -262.463479) (xy 370.044477 -262.485263)
			(xy 370.083296 -262.513466) (xy 370.117226 -262.547395) (xy 370.145431 -262.586213) (xy 370.167216 -262.628965)
			(xy 370.182045 -262.674599) (xy 370.189554 -262.721991) (xy 370.190014 -262.745982) (xy 370.189654 -262.76689)
			(xy 370.18392 -262.808313) (xy 370.178584 -262.828532) (xy 370.177822 -262.831834) (xy 370.176806 -262.838692)
			(xy 370.175888 -262.848651) (xy 370.180852 -262.868002) (xy 370.186458 -262.876284) (xy 370.234718 -262.9408)
			(xy 370.24232 -262.94991) (xy 370.26351 -262.960518) (xy 370.275358 -262.96112) (xy 370.434108 -262.96112)
			(xy 370.445954 -262.9605) (xy 370.467145 -262.949905) (xy 370.474748 -262.9408) (xy 370.530882 -262.866378)
			(xy 370.534946 -262.84301) (xy 370.531644 -262.831326) (xy 370.525962 -262.810449) (xy 370.519848 -262.767615)
			(xy 370.519452 -262.745982) (xy 370.519974 -262.720727) (xy 370.528287 -262.670905) (xy 370.544688 -262.623131)
			(xy 370.568729 -262.578708) (xy 370.599753 -262.538848) (xy 370.636915 -262.504638) (xy 370.679201 -262.477012)
			(xy 370.725457 -262.456722) (xy 370.774422 -262.444322) (xy 370.82476 -262.440151) (xy 370.875098 -262.444322)
			(xy 370.924063 -262.456722) (xy 370.970319 -262.477012) (xy 371.012605 -262.504638) (xy 371.049767 -262.538848)
			(xy 371.080791 -262.578708) (xy 371.104832 -262.623131) (xy 371.121233 -262.670905) (xy 371.129546 -262.720727)
			(xy 371.130068 -262.745982) (xy 371.129708 -262.76689) (xy 371.123975 -262.808313) (xy 371.118638 -262.828532)
			(xy 371.117876 -262.831834) (xy 371.11686 -262.838692) (xy 371.115942 -262.84865) (xy 371.120911 -262.868)
			(xy 371.126512 -262.876284) (xy 371.174772 -262.9408) (xy 371.182377 -262.9499) (xy 371.203568 -262.960487)
			(xy 371.215412 -262.96112) (xy 371.374162 -262.96112) (xy 371.386013 -262.96051) (xy 371.40722 -262.949926)
			(xy 371.414802 -262.9408) (xy 371.463062 -262.876284) (xy 371.468676 -262.868004) (xy 371.473658 -262.84865)
			(xy 371.472714 -262.838692) (xy 371.471698 -262.831834) (xy 371.470936 -262.828532) (xy 371.465598 -262.808313)
			(xy 371.459868 -262.766891) (xy 371.459506 -262.745982) (xy 371.460028 -262.720727) (xy 371.468341 -262.670905)
			(xy 371.484742 -262.623131) (xy 371.508783 -262.578708) (xy 371.539807 -262.538848) (xy 371.576969 -262.504638)
			(xy 371.619255 -262.477012) (xy 371.665511 -262.456722) (xy 371.714476 -262.444322) (xy 371.764814 -262.440151)
			(xy 371.815152 -262.444322) (xy 371.864117 -262.456722) (xy 371.910373 -262.477012) (xy 371.952659 -262.504638)
			(xy 371.989821 -262.538848) (xy 372.020845 -262.578708) (xy 372.044886 -262.623131) (xy 372.061287 -262.670905)
			(xy 372.0696 -262.720727) (xy 372.070122 -262.745982) (xy 372.069762 -262.76689) (xy 372.064028 -262.808313)
			(xy 372.058692 -262.828532) (xy 372.05793 -262.831834) (xy 372.056914 -262.838692) (xy 372.055996 -262.848651)
			(xy 372.060961 -262.868002) (xy 372.066566 -262.876284) (xy 372.114826 -262.9408) (xy 372.122428 -262.949908)
			(xy 372.143618 -262.960514) (xy 372.155466 -262.96112) (xy 373.25427 -262.96112) (xy 373.26612 -262.960508)
			(xy 373.287324 -262.949922) (xy 373.29491 -262.9408) (xy 373.34317 -262.876284) (xy 373.348783 -262.868003)
			(xy 373.353764 -262.84865) (xy 373.352822 -262.838692) (xy 373.351806 -262.831834) (xy 373.351044 -262.828532)
			(xy 373.345706 -262.808313) (xy 373.339976 -262.766891) (xy 373.339614 -262.745982) (xy 373.340136 -262.720727)
			(xy 373.348449 -262.670905) (xy 373.36485 -262.623131) (xy 373.388891 -262.578708) (xy 373.419915 -262.538848)
			(xy 373.457077 -262.504638) (xy 373.499363 -262.477012) (xy 373.545619 -262.456722) (xy 373.594584 -262.444322)
			(xy 373.644922 -262.440151) (xy 373.69526 -262.444322) (xy 373.744225 -262.456722) (xy 373.790481 -262.477012)
			(xy 373.832767 -262.504638) (xy 373.869929 -262.538848) (xy 373.900953 -262.578708) (xy 373.924994 -262.623131)
			(xy 373.941395 -262.670905) (xy 373.949708 -262.720727) (xy 373.95023 -262.745982) (xy 373.94987 -262.76689)
			(xy 373.944136 -262.808313) (xy 373.9388 -262.828532) (xy 373.938038 -262.831834) (xy 373.937022 -262.838692)
			(xy 373.936104 -262.84865) (xy 373.941069 -262.868002) (xy 373.946674 -262.876284) (xy 373.994934 -262.9408)
			(xy 374.002537 -262.949907) (xy 374.023727 -262.960509) (xy 374.035574 -262.96112) (xy 375.134124 -262.96112)
			(xy 375.145968 -262.960497) (xy 375.167154 -262.949898) (xy 375.174764 -262.9408) (xy 375.223024 -262.876284)
			(xy 375.228632 -262.868002) (xy 375.233608 -262.84865) (xy 375.232676 -262.838692) (xy 375.23166 -262.831834)
			(xy 375.230898 -262.828532) (xy 375.225559 -262.808313) (xy 375.219828 -262.766891) (xy 375.219468 -262.745982)
			(xy 375.21999 -262.720727) (xy 375.228303 -262.670905) (xy 375.244704 -262.623131) (xy 375.268745 -262.578708)
			(xy 375.299769 -262.538848) (xy 375.336931 -262.504638) (xy 375.379217 -262.477012) (xy 375.425473 -262.456722)
			(xy 375.474438 -262.444322) (xy 375.524776 -262.440151) (xy 375.575114 -262.444322) (xy 375.624079 -262.456722)
			(xy 375.670335 -262.477012) (xy 375.712621 -262.504638) (xy 375.749783 -262.538848) (xy 375.780807 -262.578708)
			(xy 375.804848 -262.623131) (xy 375.821249 -262.670905) (xy 375.829562 -262.720727) (xy 375.830084 -262.745982)
			(xy 375.829724 -262.76689) (xy 375.823991 -262.808313) (xy 375.818654 -262.828532) (xy 375.817892 -262.831834)
			(xy 375.816876 -262.838692) (xy 375.815958 -262.84865) (xy 375.820928 -262.867999) (xy 375.826528 -262.876284)
			(xy 375.874788 -262.9408) (xy 375.882394 -262.949898) (xy 375.903585 -262.960477) (xy 375.915428 -262.96112)
			(xy 376.06986 -262.96112) (xy 376.081711 -262.96051) (xy 376.102919 -262.949927) (xy 376.1105 -262.9408)
			(xy 376.162062 -262.872474) (xy 376.166126 -262.848852) (xy 376.16257 -262.837168) (xy 376.156269 -262.8149)
			(xy 376.149507 -262.76912) (xy 376.149108 -262.745982) (xy 376.149595 -262.721172) (xy 376.157357 -262.672164)
			(xy 376.17269 -262.624974) (xy 376.195217 -262.580763) (xy 376.224382 -262.54062) (xy 376.259468 -262.505534)
			(xy 376.299611 -262.476369) (xy 376.343822 -262.453842) (xy 376.391012 -262.438509) (xy 376.44002 -262.430747)
			(xy 376.48964 -262.430747) (xy 376.538648 -262.438509) (xy 376.585838 -262.453842) (xy 376.630049 -262.476369)
			(xy 376.670192 -262.505534) (xy 376.705278 -262.54062) (xy 376.734443 -262.580763) (xy 376.75697 -262.624974)
			(xy 376.772303 -262.672164) (xy 376.780065 -262.721172) (xy 376.780552 -262.745982) (xy 376.780148 -262.76912)
			(xy 376.773394 -262.814901) (xy 376.76709 -262.837168) (xy 376.763534 -262.848852) (xy 376.767598 -262.872474)
			(xy 376.81916 -262.9408) (xy 376.826764 -262.949903) (xy 376.847955 -262.960494) (xy 376.8598 -262.96112)
			(xy 377.009914 -262.96112) (xy 377.021759 -262.960499) (xy 377.042948 -262.949902) (xy 377.050554 -262.9408)
			(xy 377.102116 -262.872474) (xy 377.10618 -262.848852) (xy 377.102624 -262.837168) (xy 377.096382 -262.814893)
			(xy 377.089749 -262.769113) (xy 377.089416 -262.745982) (xy 377.089902 -262.721192) (xy 377.097658 -262.672224)
			(xy 377.112979 -262.625071) (xy 377.135488 -262.580896) (xy 377.16463 -262.540785) (xy 377.199687 -262.505728)
			(xy 377.239798 -262.476586) (xy 377.283973 -262.454077) (xy 377.331126 -262.438756) (xy 377.380094 -262.431)
			(xy 377.429674 -262.431) (xy 377.478642 -262.438756) (xy 377.525795 -262.454077) (xy 377.56997 -262.476586)
			(xy 377.610081 -262.505728) (xy 377.645138 -262.540785) (xy 377.67428 -262.580896) (xy 377.696789 -262.625071)
			(xy 377.71211 -262.672224) (xy 377.719866 -262.721192) (xy 377.720352 -262.745982) (xy 377.719983 -262.76911)
			(xy 377.713358 -262.814887) (xy 377.707144 -262.837168) (xy 377.703588 -262.848852) (xy 377.707652 -262.872474)
			(xy 377.759214 -262.9408) (xy 377.766815 -262.94991) (xy 377.788006 -262.96052) (xy 377.799854 -262.96112)
			(xy 377.954286 -262.96112) (xy 377.966134 -262.960505) (xy 377.987333 -262.949915) (xy 377.994926 -262.9408)
			(xy 378.043186 -262.876284) (xy 378.048798 -262.868003) (xy 378.053777 -262.84865) (xy 378.052838 -262.838692)
			(xy 378.051822 -262.831834) (xy 378.05106 -262.828532) (xy 378.045722 -262.808313) (xy 378.039991 -262.766891)
			(xy 378.03963 -262.745982) (xy 378.040152 -262.720727) (xy 378.048465 -262.670905) (xy 378.064866 -262.623131)
			(xy 378.088907 -262.578708) (xy 378.119931 -262.538848) (xy 378.157093 -262.504638) (xy 378.199379 -262.477012)
			(xy 378.245635 -262.456722) (xy 378.2946 -262.444322) (xy 378.344938 -262.440151) (xy 378.395276 -262.444322)
			(xy 378.444241 -262.456722) (xy 378.490497 -262.477012) (xy 378.532783 -262.504638) (xy 378.569945 -262.538848)
			(xy 378.600969 -262.578708) (xy 378.62501 -262.623131) (xy 378.641411 -262.670905) (xy 378.649724 -262.720727)
			(xy 378.650246 -262.745982) (xy 378.649886 -262.76689) (xy 378.644152 -262.808313) (xy 378.638816 -262.828532)
			(xy 378.638054 -262.831834) (xy 378.637038 -262.838692) (xy 378.63612 -262.84865) (xy 378.641087 -262.868001)
			(xy 378.64669 -262.876284) (xy 378.69495 -262.9408) (xy 378.702554 -262.949904) (xy 378.723744 -262.9605)
			(xy 378.73559 -262.96112) (xy 378.889768 -262.96112) (xy 378.901618 -262.960508) (xy 378.922823 -262.949923)
			(xy 378.930408 -262.9408) (xy 378.98197 -262.872474) (xy 378.986034 -262.848852) (xy 378.982478 -262.837168)
			(xy 378.976177 -262.8149) (xy 378.969415 -262.76912) (xy 378.969016 -262.745982) (xy 378.969503 -262.721172)
			(xy 378.977265 -262.672164) (xy 378.992598 -262.624974) (xy 379.015125 -262.580763) (xy 379.04429 -262.54062)
			(xy 379.079376 -262.505534) (xy 379.119519 -262.476369) (xy 379.16373 -262.453842) (xy 379.21092 -262.438509)
			(xy 379.259928 -262.430747) (xy 379.309548 -262.430747) (xy 379.358556 -262.438509) (xy 379.405746 -262.453842)
			(xy 379.449957 -262.476369) (xy 379.4901 -262.505534) (xy 379.525186 -262.54062) (xy 379.554351 -262.580763)
			(xy 379.576878 -262.624974) (xy 379.592211 -262.672164) (xy 379.599973 -262.721172) (xy 379.60046 -262.745982)
			(xy 379.600056 -262.76912) (xy 379.593302 -262.814901) (xy 379.586998 -262.837168) (xy 379.583442 -262.848852)
			(xy 379.587506 -262.872474) (xy 379.639068 -262.9408) (xy 379.646673 -262.949901) (xy 379.667864 -262.960489)
			(xy 379.679708 -262.96112) (xy 379.83414 -262.96112) (xy 379.845982 -262.960493) (xy 379.867163 -262.949891)
			(xy 379.87478 -262.9408) (xy 379.92304 -262.876284) (xy 379.928647 -262.868001) (xy 379.933621 -262.84865)
			(xy 379.932692 -262.838692) (xy 379.931676 -262.831834) (xy 379.930914 -262.828532) (xy 379.925575 -262.808314)
			(xy 379.919843 -262.766891) (xy 379.919484 -262.745982) (xy 379.920006 -262.720727) (xy 379.928319 -262.670905)
			(xy 379.94472 -262.623131) (xy 379.968761 -262.578708) (xy 379.999785 -262.538848) (xy 380.036947 -262.504638)
			(xy 380.079233 -262.477012) (xy 380.125489 -262.456722) (xy 380.174454 -262.444322) (xy 380.224792 -262.440151)
			(xy 380.27513 -262.444322) (xy 380.324095 -262.456722) (xy 380.370351 -262.477012) (xy 380.412637 -262.504638)
			(xy 380.449799 -262.538848) (xy 380.480823 -262.578708) (xy 380.504864 -262.623131) (xy 380.521265 -262.670905)
			(xy 380.529578 -262.720727) (xy 380.5301 -262.745982) (xy 380.52974 -262.76689) (xy 380.524005 -262.808313)
			(xy 380.51867 -262.828532) (xy 380.517908 -262.831834) (xy 380.516892 -262.838692) (xy 380.515974 -262.84865)
			(xy 380.520945 -262.867998) (xy 380.526544 -262.876284) (xy 380.574804 -262.9408) (xy 380.582411 -262.949895)
			(xy 380.603602 -262.960468) (xy 380.615444 -262.96112) (xy 380.769876 -262.96112) (xy 380.781725 -262.960507)
			(xy 380.802928 -262.94992) (xy 380.810516 -262.9408) (xy 380.862078 -262.872474) (xy 380.866142 -262.848852)
			(xy 380.862586 -262.837168) (xy 380.856285 -262.8149) (xy 380.849523 -262.76912) (xy 380.849124 -262.745982)
			(xy 380.849611 -262.721172) (xy 380.857373 -262.672164) (xy 380.872706 -262.624974) (xy 380.895233 -262.580763)
			(xy 380.924398 -262.54062) (xy 380.959484 -262.505534) (xy 380.999627 -262.476369) (xy 381.043838 -262.453842)
			(xy 381.091028 -262.438509) (xy 381.140036 -262.430747) (xy 381.189656 -262.430747) (xy 381.238664 -262.438509)
			(xy 381.285854 -262.453842) (xy 381.330065 -262.476369) (xy 381.370208 -262.505534) (xy 381.405294 -262.54062)
			(xy 381.434459 -262.580763) (xy 381.456986 -262.624974) (xy 381.472319 -262.672164) (xy 381.480081 -262.721172)
			(xy 381.480568 -262.745982) (xy 381.480164 -262.76912) (xy 381.47341 -262.814901) (xy 381.467106 -262.837168)
			(xy 381.46355 -262.848852) (xy 381.467614 -262.872474) (xy 381.519176 -262.9408) (xy 381.526782 -262.9499)
			(xy 381.547972 -262.960484) (xy 381.559816 -262.96112) (xy 381.714248 -262.96112) (xy 381.726089 -262.960492)
			(xy 381.747267 -262.949887) (xy 381.754888 -262.9408) (xy 381.803148 -262.876284) (xy 381.808763 -262.868004)
			(xy 381.813746 -262.84865) (xy 381.8128 -262.838692) (xy 381.811784 -262.831834) (xy 381.811022 -262.828532)
			(xy 381.805684 -262.808313) (xy 381.799954 -262.766891) (xy 381.799592 -262.745982) (xy 381.800114 -262.720727)
			(xy 381.808427 -262.670905) (xy 381.824828 -262.623131) (xy 381.848869 -262.578708) (xy 381.879893 -262.538848)
			(xy 381.917055 -262.504638) (xy 381.959341 -262.477012) (xy 382.005597 -262.456722) (xy 382.054562 -262.444322)
			(xy 382.1049 -262.440151) (xy 382.155238 -262.444322) (xy 382.204203 -262.456722) (xy 382.250459 -262.477012)
			(xy 382.292745 -262.504638) (xy 382.329907 -262.538848) (xy 382.360931 -262.578708) (xy 382.384972 -262.623131)
			(xy 382.401373 -262.670905) (xy 382.409686 -262.720727) (xy 382.410208 -262.745982) (xy 382.409848 -262.76689)
			(xy 382.404113 -262.808313) (xy 382.398778 -262.828532) (xy 382.398016 -262.831834) (xy 382.397 -262.838692)
			(xy 382.396082 -262.84865) (xy 382.401054 -262.867997) (xy 382.406652 -262.876284) (xy 382.454912 -262.9408)
			(xy 382.462513 -262.949911) (xy 382.483703 -262.960522) (xy 382.495552 -262.96112) (xy 382.64973 -262.96112)
			(xy 382.661573 -262.960495) (xy 382.682757 -262.949895) (xy 382.69037 -262.9408) (xy 382.741932 -262.872474)
			(xy 382.745996 -262.848852) (xy 382.74244 -262.837168) (xy 382.736197 -262.814893) (xy 382.729565 -262.769113)
			(xy 382.729232 -262.745982) (xy 382.729718 -262.721192) (xy 382.737474 -262.672224) (xy 382.752795 -262.625071)
			(xy 382.775304 -262.580896) (xy 382.804446 -262.540785) (xy 382.839503 -262.505728) (xy 382.879614 -262.476586)
			(xy 382.923789 -262.454077) (xy 382.970942 -262.438756) (xy 383.01991 -262.431) (xy 383.06949 -262.431)
			(xy 383.118458 -262.438756) (xy 383.165611 -262.454077) (xy 383.209786 -262.476586) (xy 383.249897 -262.505728)
			(xy 383.284954 -262.540785) (xy 383.314096 -262.580896) (xy 383.336605 -262.625071) (xy 383.351926 -262.672224)
			(xy 383.359682 -262.721192) (xy 383.360168 -262.745982) (xy 383.359799 -262.76911) (xy 383.353174 -262.814887)
			(xy 383.34696 -262.837168) (xy 383.343404 -262.848852) (xy 383.347468 -262.872474) (xy 383.39903 -262.9408)
			(xy 383.406633 -262.949907) (xy 383.427823 -262.960511) (xy 383.43967 -262.96112) (xy 383.589784 -262.96112)
			(xy 383.601633 -262.960505) (xy 383.622832 -262.949916) (xy 383.630424 -262.9408) (xy 383.681986 -262.872474)
			(xy 383.68605 -262.848852) (xy 383.682494 -262.837168) (xy 383.676195 -262.8149) (xy 383.669434 -262.76912)
			(xy 383.669032 -262.745982) (xy 383.669519 -262.721172) (xy 383.677281 -262.672164) (xy 383.692614 -262.624974)
			(xy 383.715141 -262.580763) (xy 383.744306 -262.54062) (xy 383.779392 -262.505534) (xy 383.819535 -262.476369)
			(xy 383.863746 -262.453842) (xy 383.910936 -262.438509) (xy 383.959944 -262.430747) (xy 384.009564 -262.430747)
			(xy 384.058572 -262.438509) (xy 384.105762 -262.453842) (xy 384.149973 -262.476369) (xy 384.190116 -262.505534)
			(xy 384.225202 -262.54062) (xy 384.254367 -262.580763) (xy 384.276894 -262.624974) (xy 384.292227 -262.672164)
			(xy 384.299989 -262.721172) (xy 384.300476 -262.745982) (xy 384.619004 -262.745982) (xy 384.622964 -262.696928)
			(xy 384.634741 -262.649144) (xy 384.654032 -262.603868) (xy 384.680335 -262.562272) (xy 384.71297 -262.525435)
			(xy 384.751091 -262.49431) (xy 384.793712 -262.469703) (xy 384.839728 -262.452251) (xy 384.887947 -262.442407)
			(xy 384.937122 -262.440426) (xy 384.985977 -262.446358) (xy 385.033248 -262.46005) (xy 385.07771 -262.481148)
			(xy 385.118213 -262.509104) (xy 385.153706 -262.543196) (xy 385.183271 -262.58254) (xy 385.206142 -262.626117)
			(xy 385.221726 -262.672798) (xy 385.229621 -262.721375) (xy 385.230116 -262.745982) (xy 385.548627 -262.745982)
			(xy 385.552722 -262.695254) (xy 385.564901 -262.64584) (xy 385.584849 -262.59902) (xy 385.61205 -262.556006)
			(xy 385.645798 -262.517912) (xy 385.68522 -262.485725) (xy 385.729294 -262.460279) (xy 385.77688 -262.442232)
			(xy 385.826744 -262.432052) (xy 385.877596 -262.430003) (xy 385.928117 -262.436137) (xy 385.977001 -262.450297)
			(xy 386.02298 -262.472114) (xy 386.064864 -262.501024) (xy 386.101568 -262.536279) (xy 386.132141 -262.576965)
			(xy 386.155792 -262.622028) (xy 386.171908 -262.670302) (xy 386.180072 -262.720536) (xy 386.180584 -262.745982)
			(xy 386.499112 -262.745982) (xy 386.503072 -262.696928) (xy 386.514849 -262.649144) (xy 386.53414 -262.603868)
			(xy 386.560443 -262.562272) (xy 386.593078 -262.525435) (xy 386.631199 -262.49431) (xy 386.67382 -262.469703)
			(xy 386.719836 -262.452251) (xy 386.768055 -262.442407) (xy 386.81723 -262.440426) (xy 386.866085 -262.446358)
			(xy 386.913356 -262.46005) (xy 386.957818 -262.481148) (xy 386.998321 -262.509104) (xy 387.033814 -262.543196)
			(xy 387.063379 -262.58254) (xy 387.08625 -262.626117) (xy 387.101834 -262.672798) (xy 387.109729 -262.721375)
			(xy 387.110224 -262.745982) (xy 387.428481 -262.745982) (xy 387.432576 -262.695254) (xy 387.444755 -262.64584)
			(xy 387.464703 -262.59902) (xy 387.491904 -262.556006) (xy 387.525652 -262.517912) (xy 387.565074 -262.485725)
			(xy 387.609148 -262.460279) (xy 387.656734 -262.442232) (xy 387.706598 -262.432052) (xy 387.75745 -262.430003)
			(xy 387.807971 -262.436137) (xy 387.856855 -262.450297) (xy 387.902834 -262.472114) (xy 387.944718 -262.501024)
			(xy 387.981422 -262.536279) (xy 388.011995 -262.576965) (xy 388.035646 -262.622028) (xy 388.051762 -262.670302)
			(xy 388.059926 -262.720536) (xy 388.060438 -262.745982) (xy 388.378966 -262.745982) (xy 388.382926 -262.696928)
			(xy 388.394703 -262.649144) (xy 388.413994 -262.603868) (xy 388.440297 -262.562272) (xy 388.472932 -262.525435)
			(xy 388.511053 -262.49431) (xy 388.553674 -262.469703) (xy 388.59969 -262.452251) (xy 388.647909 -262.442407)
			(xy 388.697084 -262.440426) (xy 388.745939 -262.446358) (xy 388.79321 -262.46005) (xy 388.837672 -262.481148)
			(xy 388.878175 -262.509104) (xy 388.913668 -262.543196) (xy 388.943233 -262.58254) (xy 388.966104 -262.626117)
			(xy 388.981688 -262.672798) (xy 388.989583 -262.721375) (xy 388.990078 -262.745982) (xy 389.308589 -262.745982)
			(xy 389.312684 -262.695254) (xy 389.324863 -262.64584) (xy 389.344811 -262.59902) (xy 389.372012 -262.556006)
			(xy 389.40576 -262.517912) (xy 389.445182 -262.485725) (xy 389.489256 -262.460279) (xy 389.536842 -262.442232)
			(xy 389.586706 -262.432052) (xy 389.637558 -262.430003) (xy 389.688079 -262.436137) (xy 389.736963 -262.450297)
			(xy 389.782942 -262.472114) (xy 389.824826 -262.501024) (xy 389.86153 -262.536279) (xy 389.892103 -262.576965)
			(xy 389.915754 -262.622028) (xy 389.93187 -262.670302) (xy 389.940034 -262.720536) (xy 389.940546 -262.745982)
			(xy 390.248643 -262.745982) (xy 390.252738 -262.695254) (xy 390.264917 -262.64584) (xy 390.284865 -262.59902)
			(xy 390.312066 -262.556006) (xy 390.345814 -262.517912) (xy 390.385236 -262.485725) (xy 390.42931 -262.460279)
			(xy 390.476896 -262.442232) (xy 390.52676 -262.432052) (xy 390.577612 -262.430003) (xy 390.628133 -262.436137)
			(xy 390.677017 -262.450297) (xy 390.722996 -262.472114) (xy 390.76488 -262.501024) (xy 390.801584 -262.536279)
			(xy 390.832157 -262.576965) (xy 390.855808 -262.622028) (xy 390.871924 -262.670302) (xy 390.880088 -262.720536)
			(xy 390.8806 -262.745982) (xy 391.198874 -262.745982) (xy 391.202834 -262.696928) (xy 391.214611 -262.649144)
			(xy 391.233902 -262.603868) (xy 391.260205 -262.562272) (xy 391.29284 -262.525435) (xy 391.330961 -262.49431)
			(xy 391.373582 -262.469703) (xy 391.419598 -262.452251) (xy 391.467817 -262.442407) (xy 391.516992 -262.440426)
			(xy 391.565847 -262.446358) (xy 391.613118 -262.46005) (xy 391.65758 -262.481148) (xy 391.698083 -262.509104)
			(xy 391.733576 -262.543196) (xy 391.763141 -262.58254) (xy 391.786012 -262.626117) (xy 391.801596 -262.672798)
			(xy 391.809491 -262.721375) (xy 391.809986 -262.745982) (xy 393.078982 -262.745982) (xy 393.082942 -262.696928)
			(xy 393.094719 -262.649144) (xy 393.11401 -262.603868) (xy 393.140313 -262.562272) (xy 393.172948 -262.525435)
			(xy 393.211069 -262.49431) (xy 393.25369 -262.469703) (xy 393.299706 -262.452251) (xy 393.347925 -262.442407)
			(xy 393.3971 -262.440426) (xy 393.445955 -262.446358) (xy 393.493226 -262.46005) (xy 393.537688 -262.481148)
			(xy 393.578191 -262.509104) (xy 393.613684 -262.543196) (xy 393.643249 -262.58254) (xy 393.66612 -262.626117)
			(xy 393.681704 -262.672798) (xy 393.689599 -262.721375) (xy 393.690094 -262.745982) (xy 393.689599 -262.770589)
			(xy 393.681704 -262.819166) (xy 393.66612 -262.865847) (xy 393.643249 -262.909424) (xy 393.613684 -262.948768)
			(xy 393.578191 -262.98286) (xy 393.537688 -263.010816) (xy 393.493226 -263.031914) (xy 393.445955 -263.045606)
			(xy 393.3971 -263.051538) (xy 393.347925 -263.049557) (xy 393.299706 -263.039713) (xy 393.25369 -263.022261)
			(xy 393.211069 -262.997654) (xy 393.172948 -262.966529) (xy 393.140313 -262.929692) (xy 393.11401 -262.888096)
			(xy 393.094719 -262.84282) (xy 393.082942 -262.795036) (xy 393.078982 -262.745982) (xy 391.809986 -262.745982)
			(xy 391.809491 -262.770589) (xy 391.801596 -262.819166) (xy 391.786012 -262.865847) (xy 391.763141 -262.909424)
			(xy 391.733576 -262.948768) (xy 391.698083 -262.98286) (xy 391.65758 -263.010816) (xy 391.613118 -263.031914)
			(xy 391.565847 -263.045606) (xy 391.516992 -263.051538) (xy 391.467817 -263.049557) (xy 391.419598 -263.039713)
			(xy 391.373582 -263.022261) (xy 391.330961 -262.997654) (xy 391.29284 -262.966529) (xy 391.260205 -262.929692)
			(xy 391.233902 -262.888096) (xy 391.214611 -262.84282) (xy 391.202834 -262.795036) (xy 391.198874 -262.745982)
			(xy 390.8806 -262.745982) (xy 390.880088 -262.771428) (xy 390.871924 -262.821662) (xy 390.855808 -262.869936)
			(xy 390.832157 -262.914999) (xy 390.801584 -262.955685) (xy 390.76488 -262.99094) (xy 390.722996 -263.01985)
			(xy 390.677017 -263.041667) (xy 390.628133 -263.055827) (xy 390.577612 -263.061961) (xy 390.52676 -263.059912)
			(xy 390.476896 -263.049732) (xy 390.42931 -263.031685) (xy 390.385236 -263.006239) (xy 390.345814 -262.974052)
			(xy 390.312066 -262.935958) (xy 390.284865 -262.892944) (xy 390.264917 -262.846124) (xy 390.252738 -262.79671)
			(xy 390.248643 -262.745982) (xy 389.940546 -262.745982) (xy 389.940034 -262.771428) (xy 389.93187 -262.821662)
			(xy 389.915754 -262.869936) (xy 389.892103 -262.914999) (xy 389.86153 -262.955685) (xy 389.824826 -262.99094)
			(xy 389.782942 -263.01985) (xy 389.736963 -263.041667) (xy 389.688079 -263.055827) (xy 389.637558 -263.061961)
			(xy 389.586706 -263.059912) (xy 389.536842 -263.049732) (xy 389.489256 -263.031685) (xy 389.445182 -263.006239)
			(xy 389.40576 -262.974052) (xy 389.372012 -262.935958) (xy 389.344811 -262.892944) (xy 389.324863 -262.846124)
			(xy 389.312684 -262.79671) (xy 389.308589 -262.745982) (xy 388.990078 -262.745982) (xy 388.989583 -262.770589)
			(xy 388.981688 -262.819166) (xy 388.966104 -262.865847) (xy 388.943233 -262.909424) (xy 388.913668 -262.948768)
			(xy 388.878175 -262.98286) (xy 388.837672 -263.010816) (xy 388.79321 -263.031914) (xy 388.745939 -263.045606)
			(xy 388.697084 -263.051538) (xy 388.647909 -263.049557) (xy 388.59969 -263.039713) (xy 388.553674 -263.022261)
			(xy 388.511053 -262.997654) (xy 388.472932 -262.966529) (xy 388.440297 -262.929692) (xy 388.413994 -262.888096)
			(xy 388.394703 -262.84282) (xy 388.382926 -262.795036) (xy 388.378966 -262.745982) (xy 388.060438 -262.745982)
			(xy 388.059926 -262.771428) (xy 388.051762 -262.821662) (xy 388.035646 -262.869936) (xy 388.011995 -262.914999)
			(xy 387.981422 -262.955685) (xy 387.944718 -262.99094) (xy 387.902834 -263.01985) (xy 387.856855 -263.041667)
			(xy 387.807971 -263.055827) (xy 387.75745 -263.061961) (xy 387.706598 -263.059912) (xy 387.656734 -263.049732)
			(xy 387.609148 -263.031685) (xy 387.565074 -263.006239) (xy 387.525652 -262.974052) (xy 387.491904 -262.935958)
			(xy 387.464703 -262.892944) (xy 387.444755 -262.846124) (xy 387.432576 -262.79671) (xy 387.428481 -262.745982)
			(xy 387.110224 -262.745982) (xy 387.109729 -262.770589) (xy 387.101834 -262.819166) (xy 387.08625 -262.865847)
			(xy 387.063379 -262.909424) (xy 387.033814 -262.948768) (xy 386.998321 -262.98286) (xy 386.957818 -263.010816)
			(xy 386.913356 -263.031914) (xy 386.866085 -263.045606) (xy 386.81723 -263.051538) (xy 386.768055 -263.049557)
			(xy 386.719836 -263.039713) (xy 386.67382 -263.022261) (xy 386.631199 -262.997654) (xy 386.593078 -262.966529)
			(xy 386.560443 -262.929692) (xy 386.53414 -262.888096) (xy 386.514849 -262.84282) (xy 386.503072 -262.795036)
			(xy 386.499112 -262.745982) (xy 386.180584 -262.745982) (xy 386.180072 -262.771428) (xy 386.171908 -262.821662)
			(xy 386.155792 -262.869936) (xy 386.132141 -262.914999) (xy 386.101568 -262.955685) (xy 386.064864 -262.99094)
			(xy 386.02298 -263.01985) (xy 385.977001 -263.041667) (xy 385.928117 -263.055827) (xy 385.877596 -263.061961)
			(xy 385.826744 -263.059912) (xy 385.77688 -263.049732) (xy 385.729294 -263.031685) (xy 385.68522 -263.006239)
			(xy 385.645798 -262.974052) (xy 385.61205 -262.935958) (xy 385.584849 -262.892944) (xy 385.564901 -262.846124)
			(xy 385.552722 -262.79671) (xy 385.548627 -262.745982) (xy 385.230116 -262.745982) (xy 385.229621 -262.770589)
			(xy 385.221726 -262.819166) (xy 385.206142 -262.865847) (xy 385.183271 -262.909424) (xy 385.153706 -262.948768)
			(xy 385.118213 -262.98286) (xy 385.07771 -263.010816) (xy 385.033248 -263.031914) (xy 384.985977 -263.045606)
			(xy 384.937122 -263.051538) (xy 384.887947 -263.049557) (xy 384.839728 -263.039713) (xy 384.793712 -263.022261)
			(xy 384.751091 -262.997654) (xy 384.71297 -262.966529) (xy 384.680335 -262.929692) (xy 384.654032 -262.888096)
			(xy 384.634741 -262.84282) (xy 384.622964 -262.795036) (xy 384.619004 -262.745982) (xy 384.300476 -262.745982)
			(xy 384.299975 -262.770457) (xy 384.29233 -262.818809) (xy 384.277299 -262.865396) (xy 384.266694 -262.88746)
			(xy 384.264154 -262.892794) (xy 384.26136 -262.904478) (xy 384.26136 -262.91032) (xy 384.261851 -262.920328)
			(xy 384.269513 -262.93882) (xy 384.283663 -262.952976) (xy 384.302152 -262.960645) (xy 384.31216 -262.96112)
			(xy 384.324098 -262.96112) (xy 384.334168 -262.961543) (xy 384.352771 -262.969259) (xy 384.360166 -262.976106)
			(xy 384.940048 -263.555988) (xy 386.018527 -263.555988) (xy 386.022622 -263.50526) (xy 386.034801 -263.455846)
			(xy 386.054749 -263.409026) (xy 386.08195 -263.366012) (xy 386.115698 -263.327918) (xy 386.15512 -263.295731)
			(xy 386.199194 -263.270285) (xy 386.24678 -263.252238) (xy 386.296644 -263.242058) (xy 386.347496 -263.240009)
			(xy 386.398017 -263.246143) (xy 386.446901 -263.260303) (xy 386.49288 -263.28212) (xy 386.534764 -263.31103)
			(xy 386.571468 -263.346285) (xy 386.602041 -263.386971) (xy 386.625692 -263.432034) (xy 386.641808 -263.480308)
			(xy 386.649972 -263.530542) (xy 386.650484 -263.555988) (xy 386.958581 -263.555988) (xy 386.962676 -263.50526)
			(xy 386.974855 -263.455846) (xy 386.994803 -263.409026) (xy 387.022004 -263.366012) (xy 387.055752 -263.327918)
			(xy 387.095174 -263.295731) (xy 387.139248 -263.270285) (xy 387.186834 -263.252238) (xy 387.236698 -263.242058)
			(xy 387.28755 -263.240009) (xy 387.338071 -263.246143) (xy 387.386955 -263.260303) (xy 387.432934 -263.28212)
			(xy 387.474818 -263.31103) (xy 387.511522 -263.346285) (xy 387.542095 -263.386971) (xy 387.565746 -263.432034)
			(xy 387.581862 -263.480308) (xy 387.590026 -263.530542) (xy 387.590538 -263.555988) (xy 387.909066 -263.555988)
			(xy 387.913026 -263.506934) (xy 387.924803 -263.45915) (xy 387.944094 -263.413874) (xy 387.970397 -263.372278)
			(xy 388.003032 -263.335441) (xy 388.041153 -263.304316) (xy 388.083774 -263.279709) (xy 388.12979 -263.262257)
			(xy 388.178009 -263.252413) (xy 388.227184 -263.250432) (xy 388.276039 -263.256364) (xy 388.32331 -263.270056)
			(xy 388.367772 -263.291154) (xy 388.408275 -263.31911) (xy 388.443768 -263.353202) (xy 388.473333 -263.392546)
			(xy 388.496204 -263.436123) (xy 388.511788 -263.482804) (xy 388.519683 -263.531381) (xy 388.520178 -263.555988)
			(xy 388.838689 -263.555988) (xy 388.842784 -263.50526) (xy 388.854963 -263.455846) (xy 388.874911 -263.409026)
			(xy 388.902112 -263.366012) (xy 388.93586 -263.327918) (xy 388.975282 -263.295731) (xy 389.019356 -263.270285)
			(xy 389.066942 -263.252238) (xy 389.116806 -263.242058) (xy 389.167658 -263.240009) (xy 389.218179 -263.246143)
			(xy 389.267063 -263.260303) (xy 389.313042 -263.28212) (xy 389.354926 -263.31103) (xy 389.39163 -263.346285)
			(xy 389.422203 -263.386971) (xy 389.445854 -263.432034) (xy 389.46197 -263.480308) (xy 389.470134 -263.530542)
			(xy 389.470646 -263.555988) (xy 389.78892 -263.555988) (xy 389.79288 -263.506934) (xy 389.804657 -263.45915)
			(xy 389.823948 -263.413874) (xy 389.850251 -263.372278) (xy 389.882886 -263.335441) (xy 389.921007 -263.304316)
			(xy 389.963628 -263.279709) (xy 390.009644 -263.262257) (xy 390.057863 -263.252413) (xy 390.107038 -263.250432)
			(xy 390.155893 -263.256364) (xy 390.203164 -263.270056) (xy 390.247626 -263.291154) (xy 390.288129 -263.31911)
			(xy 390.323622 -263.353202) (xy 390.353187 -263.392546) (xy 390.376058 -263.436123) (xy 390.391642 -263.482804)
			(xy 390.399537 -263.531381) (xy 390.400032 -263.555988) (xy 390.718543 -263.555988) (xy 390.722638 -263.50526)
			(xy 390.734817 -263.455846) (xy 390.754765 -263.409026) (xy 390.781966 -263.366012) (xy 390.815714 -263.327918)
			(xy 390.855136 -263.295731) (xy 390.89921 -263.270285) (xy 390.946796 -263.252238) (xy 390.99666 -263.242058)
			(xy 391.047512 -263.240009) (xy 391.098033 -263.246143) (xy 391.146917 -263.260303) (xy 391.192896 -263.28212)
			(xy 391.204385 -263.29005) (xy 394.67715 -263.29005) (xy 394.68111 -263.240996) (xy 394.692887 -263.193212)
			(xy 394.712178 -263.147936) (xy 394.738481 -263.10634) (xy 394.771116 -263.069503) (xy 394.809237 -263.038378)
			(xy 394.851858 -263.013771) (xy 394.897874 -262.996319) (xy 394.946093 -262.986475) (xy 394.995268 -262.984494)
			(xy 395.044123 -262.990426) (xy 395.091394 -263.004118) (xy 395.135856 -263.025216) (xy 395.176359 -263.053172)
			(xy 395.211852 -263.087264) (xy 395.241417 -263.126608) (xy 395.264288 -263.170185) (xy 395.279872 -263.216866)
			(xy 395.287767 -263.265443) (xy 395.288262 -263.29005) (xy 395.287767 -263.314657) (xy 395.279872 -263.363234)
			(xy 395.264288 -263.409915) (xy 395.241417 -263.453492) (xy 395.211852 -263.492836) (xy 395.176359 -263.526928)
			(xy 395.135856 -263.554884) (xy 395.091394 -263.575982) (xy 395.044123 -263.589674) (xy 394.995268 -263.595606)
			(xy 394.946093 -263.593625) (xy 394.897874 -263.583781) (xy 394.851858 -263.566329) (xy 394.809237 -263.541722)
			(xy 394.771116 -263.510597) (xy 394.738481 -263.47376) (xy 394.712178 -263.432164) (xy 394.692887 -263.386888)
			(xy 394.68111 -263.339104) (xy 394.67715 -263.29005) (xy 391.204385 -263.29005) (xy 391.23478 -263.31103)
			(xy 391.271484 -263.346285) (xy 391.302057 -263.386971) (xy 391.325708 -263.432034) (xy 391.341824 -263.480308)
			(xy 391.349988 -263.530542) (xy 391.3505 -263.555988) (xy 391.349988 -263.581434) (xy 391.341824 -263.631668)
			(xy 391.325708 -263.679942) (xy 391.302057 -263.725005) (xy 391.271484 -263.765691) (xy 391.23478 -263.800946)
			(xy 391.192896 -263.829856) (xy 391.146917 -263.851673) (xy 391.098033 -263.865833) (xy 391.047512 -263.871967)
			(xy 390.99666 -263.869918) (xy 390.946796 -263.859738) (xy 390.89921 -263.841691) (xy 390.855136 -263.816245)
			(xy 390.815714 -263.784058) (xy 390.781966 -263.745964) (xy 390.754765 -263.70295) (xy 390.734817 -263.65613)
			(xy 390.722638 -263.606716) (xy 390.718543 -263.555988) (xy 390.400032 -263.555988) (xy 390.399537 -263.580595)
			(xy 390.391642 -263.629172) (xy 390.376058 -263.675853) (xy 390.353187 -263.71943) (xy 390.323622 -263.758774)
			(xy 390.288129 -263.792866) (xy 390.247626 -263.820822) (xy 390.203164 -263.84192) (xy 390.155893 -263.855612)
			(xy 390.107038 -263.861544) (xy 390.057863 -263.859563) (xy 390.009644 -263.849719) (xy 389.963628 -263.832267)
			(xy 389.921007 -263.80766) (xy 389.882886 -263.776535) (xy 389.850251 -263.739698) (xy 389.823948 -263.698102)
			(xy 389.804657 -263.652826) (xy 389.79288 -263.605042) (xy 389.78892 -263.555988) (xy 389.470646 -263.555988)
			(xy 389.470134 -263.581434) (xy 389.46197 -263.631668) (xy 389.445854 -263.679942) (xy 389.422203 -263.725005)
			(xy 389.39163 -263.765691) (xy 389.354926 -263.800946) (xy 389.313042 -263.829856) (xy 389.267063 -263.851673)
			(xy 389.218179 -263.865833) (xy 389.167658 -263.871967) (xy 389.116806 -263.869918) (xy 389.066942 -263.859738)
			(xy 389.019356 -263.841691) (xy 388.975282 -263.816245) (xy 388.93586 -263.784058) (xy 388.902112 -263.745964)
			(xy 388.874911 -263.70295) (xy 388.854963 -263.65613) (xy 388.842784 -263.606716) (xy 388.838689 -263.555988)
			(xy 388.520178 -263.555988) (xy 388.519683 -263.580595) (xy 388.511788 -263.629172) (xy 388.496204 -263.675853)
			(xy 388.473333 -263.71943) (xy 388.443768 -263.758774) (xy 388.408275 -263.792866) (xy 388.367772 -263.820822)
			(xy 388.32331 -263.84192) (xy 388.276039 -263.855612) (xy 388.227184 -263.861544) (xy 388.178009 -263.859563)
			(xy 388.12979 -263.849719) (xy 388.083774 -263.832267) (xy 388.041153 -263.80766) (xy 388.003032 -263.776535)
			(xy 387.970397 -263.739698) (xy 387.944094 -263.698102) (xy 387.924803 -263.652826) (xy 387.913026 -263.605042)
			(xy 387.909066 -263.555988) (xy 387.590538 -263.555988) (xy 387.590026 -263.581434) (xy 387.581862 -263.631668)
			(xy 387.565746 -263.679942) (xy 387.542095 -263.725005) (xy 387.511522 -263.765691) (xy 387.474818 -263.800946)
			(xy 387.432934 -263.829856) (xy 387.386955 -263.851673) (xy 387.338071 -263.865833) (xy 387.28755 -263.871967)
			(xy 387.236698 -263.869918) (xy 387.186834 -263.859738) (xy 387.139248 -263.841691) (xy 387.095174 -263.816245)
			(xy 387.055752 -263.784058) (xy 387.022004 -263.745964) (xy 386.994803 -263.70295) (xy 386.974855 -263.65613)
			(xy 386.962676 -263.606716) (xy 386.958581 -263.555988) (xy 386.650484 -263.555988) (xy 386.649972 -263.581434)
			(xy 386.641808 -263.631668) (xy 386.625692 -263.679942) (xy 386.602041 -263.725005) (xy 386.571468 -263.765691)
			(xy 386.534764 -263.800946) (xy 386.49288 -263.829856) (xy 386.446901 -263.851673) (xy 386.398017 -263.865833)
			(xy 386.347496 -263.871967) (xy 386.296644 -263.869918) (xy 386.24678 -263.859738) (xy 386.199194 -263.841691)
			(xy 386.15512 -263.816245) (xy 386.115698 -263.784058) (xy 386.08195 -263.745964) (xy 386.054749 -263.70295)
			(xy 386.034801 -263.65613) (xy 386.022622 -263.606716) (xy 386.018527 -263.555988) (xy 384.940048 -263.555988)
			(xy 385.517136 -264.133076) (xy 385.524308 -264.139686) (xy 385.542203 -264.147404) (xy 385.551934 -264.148062)
			(xy 385.631944 -264.150094) (xy 385.636262 -264.14857) (xy 385.654253 -264.130363) (xy 385.695034 -264.099435)
			(xy 385.740267 -264.075484) (xy 385.788769 -264.059135) (xy 385.839271 -264.050817) (xy 385.864862 -264.050272)
			(xy 385.889676 -264.050731) (xy 385.938693 -264.058489) (xy 385.985893 -264.073819) (xy 386.030113 -264.096346)
			(xy 386.070264 -264.125513) (xy 386.105359 -264.160602) (xy 386.134531 -264.20075) (xy 386.157064 -264.244967)
			(xy 386.172401 -264.292164) (xy 386.180166 -264.34118) (xy 386.180584 -264.365994) (xy 386.499112 -264.365994)
			(xy 386.503072 -264.31694) (xy 386.514849 -264.269156) (xy 386.53414 -264.22388) (xy 386.560443 -264.182284)
			(xy 386.593078 -264.145447) (xy 386.631199 -264.114322) (xy 386.67382 -264.089715) (xy 386.719836 -264.072263)
			(xy 386.768055 -264.062419) (xy 386.81723 -264.060438) (xy 386.866085 -264.06637) (xy 386.913356 -264.080062)
			(xy 386.957818 -264.10116) (xy 386.998321 -264.129116) (xy 387.033814 -264.163208) (xy 387.063379 -264.202552)
			(xy 387.08625 -264.246129) (xy 387.101834 -264.29281) (xy 387.109729 -264.341387) (xy 387.110224 -264.365994)
			(xy 387.428481 -264.365994) (xy 387.432576 -264.315266) (xy 387.444755 -264.265852) (xy 387.464703 -264.219032)
			(xy 387.491904 -264.176018) (xy 387.525652 -264.137924) (xy 387.565074 -264.105737) (xy 387.609148 -264.080291)
			(xy 387.656734 -264.062244) (xy 387.706598 -264.052064) (xy 387.75745 -264.050015) (xy 387.807971 -264.056149)
			(xy 387.856855 -264.070309) (xy 387.902834 -264.092126) (xy 387.944718 -264.121036) (xy 387.981422 -264.156291)
			(xy 388.011995 -264.196977) (xy 388.035646 -264.24204) (xy 388.051762 -264.290314) (xy 388.059926 -264.340548)
			(xy 388.060438 -264.365994) (xy 388.378966 -264.365994) (xy 388.382926 -264.31694) (xy 388.394703 -264.269156)
			(xy 388.413994 -264.22388) (xy 388.440297 -264.182284) (xy 388.472932 -264.145447) (xy 388.511053 -264.114322)
			(xy 388.553674 -264.089715) (xy 388.59969 -264.072263) (xy 388.647909 -264.062419) (xy 388.697084 -264.060438)
			(xy 388.745939 -264.06637) (xy 388.79321 -264.080062) (xy 388.837672 -264.10116) (xy 388.878175 -264.129116)
			(xy 388.913668 -264.163208) (xy 388.943233 -264.202552) (xy 388.966104 -264.246129) (xy 388.981688 -264.29281)
			(xy 388.989583 -264.341387) (xy 388.990078 -264.365994) (xy 389.308589 -264.365994) (xy 389.312684 -264.315266)
			(xy 389.324863 -264.265852) (xy 389.344811 -264.219032) (xy 389.372012 -264.176018) (xy 389.40576 -264.137924)
			(xy 389.445182 -264.105737) (xy 389.489256 -264.080291) (xy 389.536842 -264.062244) (xy 389.586706 -264.052064)
			(xy 389.637558 -264.050015) (xy 389.688079 -264.056149) (xy 389.736963 -264.070309) (xy 389.782942 -264.092126)
			(xy 389.824826 -264.121036) (xy 389.86153 -264.156291) (xy 389.892103 -264.196977) (xy 389.915754 -264.24204)
			(xy 389.93187 -264.290314) (xy 389.940034 -264.340548) (xy 389.940546 -264.365994) (xy 390.248643 -264.365994)
			(xy 390.252738 -264.315266) (xy 390.264917 -264.265852) (xy 390.284865 -264.219032) (xy 390.312066 -264.176018)
			(xy 390.345814 -264.137924) (xy 390.385236 -264.105737) (xy 390.42931 -264.080291) (xy 390.476896 -264.062244)
			(xy 390.52676 -264.052064) (xy 390.577612 -264.050015) (xy 390.628133 -264.056149) (xy 390.677017 -264.070309)
			(xy 390.722996 -264.092126) (xy 390.76488 -264.121036) (xy 390.801584 -264.156291) (xy 390.832157 -264.196977)
			(xy 390.855808 -264.24204) (xy 390.871924 -264.290314) (xy 390.880088 -264.340548) (xy 390.8806 -264.365994)
			(xy 391.198874 -264.365994) (xy 391.202834 -264.31694) (xy 391.214611 -264.269156) (xy 391.233902 -264.22388)
			(xy 391.260205 -264.182284) (xy 391.29284 -264.145447) (xy 391.330961 -264.114322) (xy 391.373582 -264.089715)
			(xy 391.419598 -264.072263) (xy 391.467817 -264.062419) (xy 391.516992 -264.060438) (xy 391.565847 -264.06637)
			(xy 391.613118 -264.080062) (xy 391.65758 -264.10116) (xy 391.698083 -264.129116) (xy 391.733576 -264.163208)
			(xy 391.763141 -264.202552) (xy 391.786012 -264.246129) (xy 391.801596 -264.29281) (xy 391.809491 -264.341387)
			(xy 391.809986 -264.365994) (xy 393.078982 -264.365994) (xy 393.082942 -264.31694) (xy 393.094719 -264.269156)
			(xy 393.11401 -264.22388) (xy 393.140313 -264.182284) (xy 393.172948 -264.145447) (xy 393.211069 -264.114322)
			(xy 393.25369 -264.089715) (xy 393.299706 -264.072263) (xy 393.347925 -264.062419) (xy 393.3971 -264.060438)
			(xy 393.445955 -264.06637) (xy 393.493226 -264.080062) (xy 393.537688 -264.10116) (xy 393.578191 -264.129116)
			(xy 393.613684 -264.163208) (xy 393.643249 -264.202552) (xy 393.66612 -264.246129) (xy 393.681704 -264.29281)
			(xy 393.689599 -264.341387) (xy 393.690094 -264.365994) (xy 393.689599 -264.390601) (xy 393.681704 -264.439178)
			(xy 393.66612 -264.485859) (xy 393.643249 -264.529436) (xy 393.613684 -264.56878) (xy 393.578191 -264.602872)
			(xy 393.537688 -264.630828) (xy 393.493226 -264.651926) (xy 393.445955 -264.665618) (xy 393.3971 -264.67155)
			(xy 393.347925 -264.669569) (xy 393.299706 -264.659725) (xy 393.25369 -264.642273) (xy 393.211069 -264.617666)
			(xy 393.172948 -264.586541) (xy 393.140313 -264.549704) (xy 393.11401 -264.508108) (xy 393.094719 -264.462832)
			(xy 393.082942 -264.415048) (xy 393.078982 -264.365994) (xy 391.809986 -264.365994) (xy 391.809491 -264.390601)
			(xy 391.801596 -264.439178) (xy 391.786012 -264.485859) (xy 391.763141 -264.529436) (xy 391.733576 -264.56878)
			(xy 391.698083 -264.602872) (xy 391.65758 -264.630828) (xy 391.613118 -264.651926) (xy 391.565847 -264.665618)
			(xy 391.516992 -264.67155) (xy 391.467817 -264.669569) (xy 391.419598 -264.659725) (xy 391.373582 -264.642273)
			(xy 391.330961 -264.617666) (xy 391.29284 -264.586541) (xy 391.260205 -264.549704) (xy 391.233902 -264.508108)
			(xy 391.214611 -264.462832) (xy 391.202834 -264.415048) (xy 391.198874 -264.365994) (xy 390.8806 -264.365994)
			(xy 390.880088 -264.39144) (xy 390.871924 -264.441674) (xy 390.855808 -264.489948) (xy 390.832157 -264.535011)
			(xy 390.801584 -264.575697) (xy 390.76488 -264.610952) (xy 390.722996 -264.639862) (xy 390.677017 -264.661679)
			(xy 390.628133 -264.675839) (xy 390.577612 -264.681973) (xy 390.52676 -264.679924) (xy 390.476896 -264.669744)
			(xy 390.42931 -264.651697) (xy 390.385236 -264.626251) (xy 390.345814 -264.594064) (xy 390.312066 -264.55597)
			(xy 390.284865 -264.512956) (xy 390.264917 -264.466136) (xy 390.252738 -264.416722) (xy 390.248643 -264.365994)
			(xy 389.940546 -264.365994) (xy 389.940034 -264.39144) (xy 389.93187 -264.441674) (xy 389.915754 -264.489948)
			(xy 389.892103 -264.535011) (xy 389.86153 -264.575697) (xy 389.824826 -264.610952) (xy 389.782942 -264.639862)
			(xy 389.736963 -264.661679) (xy 389.688079 -264.675839) (xy 389.637558 -264.681973) (xy 389.586706 -264.679924)
			(xy 389.536842 -264.669744) (xy 389.489256 -264.651697) (xy 389.445182 -264.626251) (xy 389.40576 -264.594064)
			(xy 389.372012 -264.55597) (xy 389.344811 -264.512956) (xy 389.324863 -264.466136) (xy 389.312684 -264.416722)
			(xy 389.308589 -264.365994) (xy 388.990078 -264.365994) (xy 388.989583 -264.390601) (xy 388.981688 -264.439178)
			(xy 388.966104 -264.485859) (xy 388.943233 -264.529436) (xy 388.913668 -264.56878) (xy 388.878175 -264.602872)
			(xy 388.837672 -264.630828) (xy 388.79321 -264.651926) (xy 388.745939 -264.665618) (xy 388.697084 -264.67155)
			(xy 388.647909 -264.669569) (xy 388.59969 -264.659725) (xy 388.553674 -264.642273) (xy 388.511053 -264.617666)
			(xy 388.472932 -264.586541) (xy 388.440297 -264.549704) (xy 388.413994 -264.508108) (xy 388.394703 -264.462832)
			(xy 388.382926 -264.415048) (xy 388.378966 -264.365994) (xy 388.060438 -264.365994) (xy 388.059926 -264.39144)
			(xy 388.051762 -264.441674) (xy 388.035646 -264.489948) (xy 388.011995 -264.535011) (xy 387.981422 -264.575697)
			(xy 387.944718 -264.610952) (xy 387.902834 -264.639862) (xy 387.856855 -264.661679) (xy 387.807971 -264.675839)
			(xy 387.75745 -264.681973) (xy 387.706598 -264.679924) (xy 387.656734 -264.669744) (xy 387.609148 -264.651697)
			(xy 387.565074 -264.626251) (xy 387.525652 -264.594064) (xy 387.491904 -264.55597) (xy 387.464703 -264.512956)
			(xy 387.444755 -264.466136) (xy 387.432576 -264.416722) (xy 387.428481 -264.365994) (xy 387.110224 -264.365994)
			(xy 387.109729 -264.390601) (xy 387.101834 -264.439178) (xy 387.08625 -264.485859) (xy 387.063379 -264.529436)
			(xy 387.033814 -264.56878) (xy 386.998321 -264.602872) (xy 386.957818 -264.630828) (xy 386.913356 -264.651926)
			(xy 386.866085 -264.665618) (xy 386.81723 -264.67155) (xy 386.768055 -264.669569) (xy 386.719836 -264.659725)
			(xy 386.67382 -264.642273) (xy 386.631199 -264.617666) (xy 386.593078 -264.586541) (xy 386.560443 -264.549704)
			(xy 386.53414 -264.508108) (xy 386.514849 -264.462832) (xy 386.503072 -264.415048) (xy 386.499112 -264.365994)
			(xy 386.180584 -264.365994) (xy 386.18013 -264.389788) (xy 386.172943 -264.436831) (xy 386.158776 -264.482263)
			(xy 386.137951 -264.525053) (xy 386.110938 -264.564233) (xy 386.094986 -264.581894) (xy 386.088128 -264.589514)
			(xy 386.081016 -264.607802) (xy 386.082794 -264.678922) (xy 386.083478 -264.688647) (xy 386.091191 -264.706534)
			(xy 386.09778 -264.71372) (xy 386.2451 -264.86104) (xy 386.25526 -264.867136) (xy 386.261102 -264.869168)
			(xy 386.279245 -264.865107) (xy 386.316172 -264.860781) (xy 386.334762 -264.860532) (xy 386.359562 -264.861015)
			(xy 386.408553 -264.868764) (xy 386.45573 -264.884078) (xy 386.499933 -264.90658) (xy 386.540073 -264.935716)
			(xy 386.575164 -264.970769) (xy 386.604343 -265.010879) (xy 386.626892 -265.055057) (xy 386.642257 -265.102218)
			(xy 386.650058 -265.1512) (xy 386.650484 -265.176) (xy 386.969012 -265.176) (xy 386.972972 -265.126946)
			(xy 386.984749 -265.079162) (xy 387.00404 -265.033886) (xy 387.030343 -264.99229) (xy 387.062978 -264.955453)
			(xy 387.101099 -264.924328) (xy 387.14372 -264.899721) (xy 387.189736 -264.882269) (xy 387.237955 -264.872425)
			(xy 387.28713 -264.870444) (xy 387.335985 -264.876376) (xy 387.383256 -264.890068) (xy 387.427718 -264.911166)
			(xy 387.468221 -264.939122) (xy 387.503714 -264.973214) (xy 387.533279 -265.012558) (xy 387.55615 -265.056135)
			(xy 387.571734 -265.102816) (xy 387.579629 -265.151393) (xy 387.580124 -265.176) (xy 387.909066 -265.176)
			(xy 387.913026 -265.126946) (xy 387.924803 -265.079162) (xy 387.944094 -265.033886) (xy 387.970397 -264.99229)
			(xy 388.003032 -264.955453) (xy 388.041153 -264.924328) (xy 388.083774 -264.899721) (xy 388.12979 -264.882269)
			(xy 388.178009 -264.872425) (xy 388.227184 -264.870444) (xy 388.276039 -264.876376) (xy 388.32331 -264.890068)
			(xy 388.367772 -264.911166) (xy 388.408275 -264.939122) (xy 388.443768 -264.973214) (xy 388.473333 -265.012558)
			(xy 388.496204 -265.056135) (xy 388.511788 -265.102816) (xy 388.519683 -265.151393) (xy 388.520178 -265.176)
			(xy 388.838689 -265.176) (xy 388.842784 -265.125272) (xy 388.854963 -265.075858) (xy 388.874911 -265.029038)
			(xy 388.902112 -264.986024) (xy 388.93586 -264.94793) (xy 388.975282 -264.915743) (xy 389.019356 -264.890297)
			(xy 389.066942 -264.87225) (xy 389.116806 -264.86207) (xy 389.167658 -264.860021) (xy 389.218179 -264.866155)
			(xy 389.267063 -264.880315) (xy 389.313042 -264.902132) (xy 389.354926 -264.931042) (xy 389.39163 -264.966297)
			(xy 389.422203 -265.006983) (xy 389.445854 -265.052046) (xy 389.46197 -265.10032) (xy 389.470134 -265.150554)
			(xy 389.470646 -265.176) (xy 389.78892 -265.176) (xy 389.79288 -265.126946) (xy 389.804657 -265.079162)
			(xy 389.823948 -265.033886) (xy 389.850251 -264.99229) (xy 389.882886 -264.955453) (xy 389.921007 -264.924328)
			(xy 389.963628 -264.899721) (xy 390.009644 -264.882269) (xy 390.057863 -264.872425) (xy 390.107038 -264.870444)
			(xy 390.155893 -264.876376) (xy 390.203164 -264.890068) (xy 390.247626 -264.911166) (xy 390.288129 -264.939122)
			(xy 390.323622 -264.973214) (xy 390.353187 -265.012558) (xy 390.376058 -265.056135) (xy 390.391642 -265.102816)
			(xy 390.399537 -265.151393) (xy 390.400032 -265.176) (xy 390.728974 -265.176) (xy 390.732934 -265.126946)
			(xy 390.744711 -265.079162) (xy 390.764002 -265.033886) (xy 390.790305 -264.99229) (xy 390.82294 -264.955453)
			(xy 390.861061 -264.924328) (xy 390.903682 -264.899721) (xy 390.949698 -264.882269) (xy 390.997917 -264.872425)
			(xy 391.047092 -264.870444) (xy 391.095947 -264.876376) (xy 391.143218 -264.890068) (xy 391.18768 -264.911166)
			(xy 391.228183 -264.939122) (xy 391.263676 -264.973214) (xy 391.293241 -265.012558) (xy 391.316112 -265.056135)
			(xy 391.331696 -265.102816) (xy 391.339591 -265.151393) (xy 391.340086 -265.176) (xy 391.669028 -265.176)
			(xy 391.672988 -265.126946) (xy 391.684765 -265.079162) (xy 391.704056 -265.033886) (xy 391.730359 -264.99229)
			(xy 391.762994 -264.955453) (xy 391.801115 -264.924328) (xy 391.843736 -264.899721) (xy 391.889752 -264.882269)
			(xy 391.937971 -264.872425) (xy 391.987146 -264.870444) (xy 392.036001 -264.876376) (xy 392.083272 -264.890068)
			(xy 392.125407 -264.910062) (xy 394.67715 -264.910062) (xy 394.68111 -264.861008) (xy 394.692887 -264.813224)
			(xy 394.712178 -264.767948) (xy 394.738481 -264.726352) (xy 394.771116 -264.689515) (xy 394.809237 -264.65839)
			(xy 394.851858 -264.633783) (xy 394.897874 -264.616331) (xy 394.946093 -264.606487) (xy 394.995268 -264.604506)
			(xy 395.044123 -264.610438) (xy 395.091394 -264.62413) (xy 395.135856 -264.645228) (xy 395.176359 -264.673184)
			(xy 395.211852 -264.707276) (xy 395.241417 -264.74662) (xy 395.264288 -264.790197) (xy 395.279872 -264.836878)
			(xy 395.287767 -264.885455) (xy 395.288262 -264.910062) (xy 395.287767 -264.934669) (xy 395.279872 -264.983246)
			(xy 395.264288 -265.029927) (xy 395.241417 -265.073504) (xy 395.211852 -265.112848) (xy 395.176359 -265.14694)
			(xy 395.135856 -265.174896) (xy 395.091394 -265.195994) (xy 395.044123 -265.209686) (xy 394.995268 -265.215618)
			(xy 394.946093 -265.213637) (xy 394.897874 -265.203793) (xy 394.851858 -265.186341) (xy 394.809237 -265.161734)
			(xy 394.771116 -265.130609) (xy 394.738481 -265.093772) (xy 394.712178 -265.052176) (xy 394.692887 -265.0069)
			(xy 394.68111 -264.959116) (xy 394.67715 -264.910062) (xy 392.125407 -264.910062) (xy 392.127734 -264.911166)
			(xy 392.168237 -264.939122) (xy 392.20373 -264.973214) (xy 392.233295 -265.012558) (xy 392.256166 -265.056135)
			(xy 392.27175 -265.102816) (xy 392.279645 -265.151393) (xy 392.28014 -265.176) (xy 392.279645 -265.200607)
			(xy 392.27175 -265.249184) (xy 392.256166 -265.295865) (xy 392.233295 -265.339442) (xy 392.20373 -265.378786)
			(xy 392.168237 -265.412878) (xy 392.127734 -265.440834) (xy 392.083272 -265.461932) (xy 392.036001 -265.475624)
			(xy 391.987146 -265.481556) (xy 391.937971 -265.479575) (xy 391.889752 -265.469731) (xy 391.843736 -265.452279)
			(xy 391.801115 -265.427672) (xy 391.762994 -265.396547) (xy 391.730359 -265.35971) (xy 391.704056 -265.318114)
			(xy 391.684765 -265.272838) (xy 391.672988 -265.225054) (xy 391.669028 -265.176) (xy 391.340086 -265.176)
			(xy 391.339591 -265.200607) (xy 391.331696 -265.249184) (xy 391.316112 -265.295865) (xy 391.293241 -265.339442)
			(xy 391.263676 -265.378786) (xy 391.228183 -265.412878) (xy 391.18768 -265.440834) (xy 391.143218 -265.461932)
			(xy 391.095947 -265.475624) (xy 391.047092 -265.481556) (xy 390.997917 -265.479575) (xy 390.949698 -265.469731)
			(xy 390.903682 -265.452279) (xy 390.861061 -265.427672) (xy 390.82294 -265.396547) (xy 390.790305 -265.35971)
			(xy 390.764002 -265.318114) (xy 390.744711 -265.272838) (xy 390.732934 -265.225054) (xy 390.728974 -265.176)
			(xy 390.400032 -265.176) (xy 390.399537 -265.200607) (xy 390.391642 -265.249184) (xy 390.376058 -265.295865)
			(xy 390.353187 -265.339442) (xy 390.323622 -265.378786) (xy 390.288129 -265.412878) (xy 390.247626 -265.440834)
			(xy 390.203164 -265.461932) (xy 390.155893 -265.475624) (xy 390.107038 -265.481556) (xy 390.057863 -265.479575)
			(xy 390.009644 -265.469731) (xy 389.963628 -265.452279) (xy 389.921007 -265.427672) (xy 389.882886 -265.396547)
			(xy 389.850251 -265.35971) (xy 389.823948 -265.318114) (xy 389.804657 -265.272838) (xy 389.79288 -265.225054)
			(xy 389.78892 -265.176) (xy 389.470646 -265.176) (xy 389.470134 -265.201446) (xy 389.46197 -265.25168)
			(xy 389.445854 -265.299954) (xy 389.422203 -265.345017) (xy 389.39163 -265.385703) (xy 389.354926 -265.420958)
			(xy 389.313042 -265.449868) (xy 389.267063 -265.471685) (xy 389.218179 -265.485845) (xy 389.167658 -265.491979)
			(xy 389.116806 -265.48993) (xy 389.066942 -265.47975) (xy 389.019356 -265.461703) (xy 388.975282 -265.436257)
			(xy 388.93586 -265.40407) (xy 388.902112 -265.365976) (xy 388.874911 -265.322962) (xy 388.854963 -265.276142)
			(xy 388.842784 -265.226728) (xy 388.838689 -265.176) (xy 388.520178 -265.176) (xy 388.519683 -265.200607)
			(xy 388.511788 -265.249184) (xy 388.496204 -265.295865) (xy 388.473333 -265.339442) (xy 388.443768 -265.378786)
			(xy 388.408275 -265.412878) (xy 388.367772 -265.440834) (xy 388.32331 -265.461932) (xy 388.276039 -265.475624)
			(xy 388.227184 -265.481556) (xy 388.178009 -265.479575) (xy 388.12979 -265.469731) (xy 388.083774 -265.452279)
			(xy 388.041153 -265.427672) (xy 388.003032 -265.396547) (xy 387.970397 -265.35971) (xy 387.944094 -265.318114)
			(xy 387.924803 -265.272838) (xy 387.913026 -265.225054) (xy 387.909066 -265.176) (xy 387.580124 -265.176)
			(xy 387.579629 -265.200607) (xy 387.571734 -265.249184) (xy 387.55615 -265.295865) (xy 387.533279 -265.339442)
			(xy 387.503714 -265.378786) (xy 387.468221 -265.412878) (xy 387.427718 -265.440834) (xy 387.383256 -265.461932)
			(xy 387.335985 -265.475624) (xy 387.28713 -265.481556) (xy 387.237955 -265.479575) (xy 387.189736 -265.469731)
			(xy 387.14372 -265.452279) (xy 387.101099 -265.427672) (xy 387.062978 -265.396547) (xy 387.030343 -265.35971)
			(xy 387.00404 -265.318114) (xy 386.984749 -265.272838) (xy 386.972972 -265.225054) (xy 386.969012 -265.176)
			(xy 386.650484 -265.176) (xy 386.650337 -265.189789) (xy 386.647918 -265.217261) (xy 386.645658 -265.230864)
			(xy 386.643372 -265.243056) (xy 386.650738 -265.266678) (xy 387.293866 -265.909806) (xy 387.297676 -265.913108)
			(xy 387.297676 -265.913362) (xy 387.306954 -265.920142) (xy 387.329252 -265.925561) (xy 387.340602 -265.923776)
			(xy 387.436106 -265.903456) (xy 387.455664 -265.886946) (xy 387.460236 -265.875008) (xy 387.470244 -265.850826)
			(xy 387.497291 -265.806026) (xy 387.53158 -265.766494) (xy 387.572108 -265.733387) (xy 387.617687 -265.707675)
			(xy 387.666982 -265.69011) (xy 387.71855 -265.681207) (xy 387.744716 -265.680698) (xy 387.768954 -265.681164)
			(xy 387.816821 -265.688824) (xy 387.862876 -265.70395) (xy 387.905964 -265.726161) (xy 387.945002 -265.7549)
			(xy 387.97901 -265.789445) (xy 388.007134 -265.828929) (xy 388.028667 -265.87236) (xy 388.043069 -265.918647)
			(xy 388.046976 -265.942572) (xy 388.048754 -265.955526) (xy 388.050278 -265.986006) (xy 388.049919 -266.007702)
			(xy 388.043823 -266.050662) (xy 388.03171 -266.092327) (xy 388.0231 -266.112244) (xy 388.017512 -266.124182)
			(xy 388.019544 -266.149836) (xy 388.07263 -266.232386) (xy 388.077493 -266.239316) (xy 388.09083 -266.24973)
			(xy 388.10684 -266.255205) (xy 388.115302 -266.2555)
		)
		(stroke
			(width 0)
			(type solid)
		)
		(fill yes)
		(layer "In15.Cu")
		(net "PVDDCR_SOC_P0")
	)
)
